(kicad_pcb
	(version 20260206)
	(generator "pcbnew")
	(generator_version "10.0")
	(general
		(thickness 1.6)
		(legacy_teardrops no)
	)
	(paper "A4")
	(layers
		(0 "F.Cu" signal "TOP")
		(4 "In1.Cu" signal "GND")
		(6 "In2.Cu" signal "VCC")
		(8 "In3.Cu" signal "VCC1")
		(10 "In4.Cu" signal "GND1")
		(12 "In5.Cu" signal "IN1")
		(14 "In6.Cu" signal "GND2")
		(16 "In7.Cu" signal "IN2")
		(18 "In8.Cu" signal "GND3")
		(20 "In9.Cu" signal "IN3")
		(22 "In10.Cu" signal "GND4")
		(24 "In11.Cu" signal "IN4")
		(26 "In12.Cu" signal "GND5")
		(28 "In13.Cu" signal "IN5")
		(30 "In14.Cu" signal "GND6")
		(32 "In15.Cu" signal "IN6")
		(34 "In16.Cu" signal "GND7")
		(2 "B.Cu" signal "BOTTOM")
		(9 "F.Adhes" user "F.Adhesive")
		(11 "B.Adhes" user "B.Adhesive")
		(13 "F.Paste" user "Package Geometry/Pastemask Top")
		(15 "B.Paste" user "Package Geometry/Pastemask Bottom")
		(5 "F.SilkS" user "Ref Des/Silkscreen Top")
		(7 "B.SilkS" user "Ref Des/Silkscreen Bottom")
		(1 "F.Mask" user "Board Geometry/Soldermask Top")
		(3 "B.Mask" user "Board Geometry/Soldermask Bottom")
		(17 "Dwgs.User" user "User.Drawings")
		(19 "Cmts.User" user "User.Comments")
		(21 "Eco1.User" user "User.Eco1")
		(23 "Eco2.User" user "User.Eco2")
		(25 "Edge.Cuts" user "Board Geometry/Outline")
		(27 "Margin" user)
		(31 "F.CrtYd" user "Package Geometry/Place Bound Top")
		(29 "B.CrtYd" user "Package Geometry/Place Bound Bottom")
		(35 "F.Fab" user "Ref Des/Assembly Top")
		(33 "B.Fab" user "Ref Des/Assembly Bottom")
	)
	(setup
		(pad_to_mask_clearance 0)
		(allow_soldermask_bridges_in_footprints no)
		(tenting
			(front yes)
			(back yes)
		)
		(covering
			(front no)
			(back no)
		)
		(plugging
			(front no)
			(back no)
		)
		(capping no)
		(filling no)
		(pcbplotparams
			(layerselection 0x00000000_00000000_55555555_5755f5ff)
			(plot_on_all_layers_selection 0x00000000_00000000_00000000_00000000)
			(disableapertmacros no)
			(usegerberextensions no)
			(usegerberattributes yes)
			(usegerberadvancedattributes yes)
			(creategerberjobfile yes)
			(dashed_line_dash_ratio 12)
			(dashed_line_gap_ratio 3)
			(svgprecision 4)
			(plotframeref no)
			(mode 1)
			(useauxorigin no)
			(pdf_front_fp_property_popups yes)
			(pdf_back_fp_property_popups yes)
			(pdf_metadata yes)
			(pdf_single_document no)
			(dxfpolygonmode yes)
			(dxfimperialunits yes)
			(dxfusepcbnewfont yes)
			(psnegative no)
			(psa4output no)
			(plot_black_and_white yes)
			(sketchpadsonfab no)
			(plotpadnumbers no)
			(hidednponfab no)
			(sketchdnponfab yes)
			(crossoutdnponfab yes)
			(subtractmaskfromsilk no)
			(outputformat 1)
			(mirror no)
			(drillshape 1)
			(scaleselection 1)
			(outputdirectory "")
		)
	)
	(gr_poly
		(pts
			(xy 421.21836 -253.239524) (xy 421.228543 -253.239027) (xy 421.247286 -253.231046) (xy 421.254682 -253.22403)
			(xy 421.257476 -253.220982) (xy 421.262556 -253.215648) (xy 421.266112 -253.205996) (xy 421.267757 -253.200959)
			(xy 421.269171 -253.19046) (xy 421.268906 -253.185168) (xy 414.937956 -162.99561) (xy 414.937702 -162.992054)
			(xy 414.524952 -160.062418) (xy 414.454848 -159.566356) (xy 414.4518 -159.554672) (xy 414.449768 -159.549338)
			(xy 414.446212 -159.544258) (xy 414.419641 -159.505396) (xy 414.373114 -159.423549) (xy 414.334509 -159.33768)
			(xy 414.304171 -159.248554) (xy 414.28237 -159.156965) (xy 414.27527 -159.110426) (xy 414.206182 -158.619698)
			(xy 414.201577 -158.585147) (xy 414.196617 -158.515614) (xy 414.196276 -158.48076) (xy 414.1964 -158.460798)
			(xy 414.198053 -158.420908) (xy 414.199578 -158.401004) (xy 414.199832 -158.398718) (xy 414.200086 -158.395416)
			(xy 414.19272 -158.343092) (xy 414.18819 -158.3086) (xy 414.183358 -158.239195) (xy 414.183068 -158.204408)
			(xy 414.183068 -158.2039) (xy 414.183322 -158.175706) (xy 414.18256 -158.172912) (xy 414.180528 -158.167578)
			(xy 414.17205 -158.148188) (xy 414.15655 -158.108805) (xy 414.14954 -158.088838) (xy 414.14573 -158.077662)
			(xy 413.037274 -156.969206) (xy 413.03067 -156.96565) (xy 413.01483 -156.957063) (xy 412.983707 -156.938897)
			(xy 412.96844 -156.929328) (xy 412.966916 -156.929582) (xy 412.949062 -156.932872) (xy 412.912932 -156.936437)
			(xy 412.89478 -156.936694) (xy 412.892494 -156.936694) (xy 412.86529 -156.936139) (xy 412.811452 -156.928267)
			(xy 412.759279 -156.912824) (xy 412.709829 -156.890126) (xy 412.664106 -156.860632) (xy 412.623037 -156.824941)
			(xy 412.587456 -156.783777) (xy 412.558084 -156.737975) (xy 412.535518 -156.688464) (xy 412.520215 -156.63625)
			(xy 412.512487 -156.582391) (xy 412.512002 -156.555186) (xy 412.512002 -156.55417) (xy 412.51248 -156.527007)
			(xy 412.520193 -156.473233) (xy 412.535471 -156.421101) (xy 412.546292 -156.396182) (xy 412.548832 -156.390594)
			(xy 412.550356 -156.382974) (xy 412.550356 -156.382466) (xy 412.536606 -156.336205) (xy 412.517059 -156.241689)
			(xy 412.506726 -156.145727) (xy 412.505652 -156.097478) (xy 412.505652 -156.08173) (xy 412.506922 -156.03474)
			(xy 412.509875 -155.989072) (xy 412.523097 -155.898511) (xy 412.544556 -155.80954) (xy 412.57407 -155.722909)
			(xy 412.592266 -155.680918) (xy 412.595314 -155.671266) (xy 412.59887 -155.656026) (xy 412.59887 -155.65501)
			(xy 412.595314 -155.63977) (xy 412.592266 -155.630118) (xy 412.575588 -155.591715) (xy 412.547984 -155.512664)
			(xy 412.52711 -155.431575) (xy 412.513115 -155.349021) (xy 412.506095 -155.265584) (xy 412.505652 -155.223718)
			(xy 412.505652 -155.22321) (xy 412.505923 -155.190922) (xy 412.510119 -155.126483) (xy 412.514034 -155.094432)
			(xy 412.517535 -155.069027) (xy 412.526811 -155.018583) (xy 412.532576 -154.993594) (xy 412.536593 -154.97708)
			(xy 412.545614 -154.944307) (xy 412.55061 -154.928062) (xy 412.549086 -154.920188) (xy 412.5468 -154.915108)
			(xy 412.535826 -154.890097) (xy 412.520347 -154.837719) (xy 412.512509 -154.783666) (xy 412.512002 -154.756358)
			(xy 412.512002 -154.755088) (xy 412.512489 -154.727838) (xy 412.520247 -154.673892) (xy 412.535603 -154.621599)
			(xy 412.558245 -154.572024) (xy 412.587712 -154.526176) (xy 412.623404 -154.484988) (xy 412.664594 -154.449299)
			(xy 412.710443 -154.419835) (xy 412.76002 -154.397196) (xy 412.812313 -154.381842) (xy 412.86626 -154.374088)
			(xy 412.89351 -154.37358) (xy 412.894272 -154.37358) (xy 412.91229 -154.373816) (xy 412.948163 -154.377254)
			(xy 412.9659 -154.380438) (xy 412.969456 -154.3812) (xy 412.988623 -154.369185) (xy 413.027881 -154.346697)
			(xy 413.047942 -154.336242) (xy 413.04845 -154.336242) (xy 413.060388 -154.329892) (xy 413.06369 -154.32532)
			(xy 413.073088 -154.309826) (xy 413.076497 -154.30383) (xy 413.080235 -154.290558) (xy 413.080454 -154.283664)
			(xy 413.080454 -153.419556) (xy 413.078676 -153.406094) (xy 413.073596 -153.387552) (xy 413.046557 -153.374408)
			(xy 412.993944 -153.345305) (xy 412.96844 -153.329386) (xy 412.966916 -153.32964) (xy 412.949063 -153.33293)
			(xy 412.912932 -153.336496) (xy 412.89478 -153.336752) (xy 412.892494 -153.336752) (xy 412.865289 -153.336198)
			(xy 412.811447 -153.328325) (xy 412.759271 -153.312884) (xy 412.709817 -153.290186) (xy 412.66409 -153.260693)
			(xy 412.623016 -153.225003) (xy 412.587429 -153.183839) (xy 412.558052 -153.138038) (xy 412.535479 -153.088527)
			(xy 412.520169 -153.036312) (xy 412.512432 -152.982451) (xy 412.512002 -152.955244) (xy 412.512002 -152.954228)
			(xy 412.512476 -152.927065) (xy 412.520181 -152.873287) (xy 412.535452 -152.821151) (xy 412.546292 -152.79624)
			(xy 412.548832 -152.790652) (xy 412.550356 -152.783032) (xy 412.550356 -152.782524) (xy 412.53616 -152.734629)
			(xy 412.516281 -152.636725) (xy 412.506273 -152.537327) (xy 412.505652 -152.487376) (xy 412.506093 -152.445511)
			(xy 412.513133 -152.362076) (xy 412.527135 -152.279524) (xy 412.548002 -152.198435) (xy 412.575587 -152.119378)
			(xy 412.592266 -152.080976) (xy 412.595314 -152.071324) (xy 412.59887 -152.056084) (xy 412.59887 -152.055068)
			(xy 412.595314 -152.039828) (xy 412.592266 -152.030176) (xy 412.575586 -151.991773) (xy 412.547977 -151.912723)
			(xy 412.527099 -151.831635) (xy 412.513098 -151.74908) (xy 412.506074 -151.665643) (xy 412.505652 -151.623776)
			(xy 412.505652 -151.623268) (xy 412.505921 -151.59098) (xy 412.510114 -151.52654) (xy 412.514034 -151.49449)
			(xy 412.517536 -151.469085) (xy 412.526814 -151.418642) (xy 412.532576 -151.393652) (xy 412.536593 -151.377137)
			(xy 412.545611 -151.344364) (xy 412.55061 -151.32812) (xy 412.549086 -151.320246) (xy 412.5468 -151.315166)
			(xy 412.535822 -151.290156) (xy 412.520335 -151.237778) (xy 412.512489 -151.183725) (xy 412.512002 -151.156416)
			(xy 412.512002 -151.155146) (xy 412.512462 -151.127891) (xy 412.520214 -151.073936) (xy 412.535566 -151.021633)
			(xy 412.558206 -150.972048) (xy 412.587673 -150.92619) (xy 412.623367 -150.884992) (xy 412.664561 -150.849295)
			(xy 412.710416 -150.819823) (xy 412.759999 -150.797179) (xy 412.812301 -150.781822) (xy 412.866255 -150.774065)
			(xy 412.89351 -150.773638) (xy 412.894272 -150.773638) (xy 412.91229 -150.773874) (xy 412.948164 -150.777312)
			(xy 412.9659 -150.780496) (xy 412.969456 -150.781258) (xy 412.988623 -150.769242) (xy 413.02788 -150.746754)
			(xy 413.047942 -150.7363) (xy 413.04845 -150.7363) (xy 413.060388 -150.72995) (xy 413.06369 -150.725378)
			(xy 413.073088 -150.709884) (xy 413.076492 -150.703887) (xy 413.080219 -150.690615) (xy 413.080454 -150.683722)
			(xy 413.080454 -149.819614) (xy 413.078676 -149.806152) (xy 413.073596 -149.78761) (xy 413.046557 -149.774467)
			(xy 412.993942 -149.745365) (xy 412.96844 -149.729444) (xy 412.966916 -149.729698) (xy 412.949062 -149.732988)
			(xy 412.912932 -149.736553) (xy 412.89478 -149.73681) (xy 412.892494 -149.73681) (xy 412.86529 -149.736256)
			(xy 412.811451 -149.728383) (xy 412.759277 -149.712941) (xy 412.709826 -149.690243) (xy 412.664101 -149.660749)
			(xy 412.623031 -149.625058) (xy 412.587448 -149.583894) (xy 412.558075 -149.538092) (xy 412.535507 -149.488582)
			(xy 412.520202 -149.436367) (xy 412.512471 -149.382508) (xy 412.512002 -149.355302) (xy 412.512002 -149.354286)
			(xy 412.512479 -149.327123) (xy 412.520189 -149.273348) (xy 412.535466 -149.221215) (xy 412.546292 -149.196298)
			(xy 412.548832 -149.19071) (xy 412.550356 -149.18309) (xy 412.550356 -149.182582) (xy 412.536162 -149.134687)
			(xy 412.516287 -149.036783) (xy 412.506283 -148.937384) (xy 412.505652 -148.887434) (xy 412.506095 -148.845569)
			(xy 412.513138 -148.762135) (xy 412.527144 -148.679585) (xy 412.548014 -148.598497) (xy 412.575601 -148.519442)
			(xy 412.592266 -148.481034) (xy 412.595314 -148.471382) (xy 412.59887 -148.456142) (xy 412.59887 -148.455126)
			(xy 412.595314 -148.439886) (xy 412.592266 -148.430234) (xy 412.575588 -148.391831) (xy 412.547982 -148.31278)
			(xy 412.527107 -148.231692) (xy 412.51311 -148.149138) (xy 412.50609 -148.0657) (xy 412.505652 -148.023834)
			(xy 412.505652 -148.023326) (xy 412.505922 -147.991038) (xy 412.510118 -147.926599) (xy 412.514034 -147.894548)
			(xy 412.517535 -147.869143) (xy 412.526809 -147.818699) (xy 412.532576 -147.79371) (xy 412.536593 -147.777196)
			(xy 412.545613 -147.744423) (xy 412.55061 -147.728178) (xy 412.549086 -147.720304) (xy 412.5468 -147.715224)
			(xy 412.535825 -147.690213) (xy 412.520344 -147.637835) (xy 412.512504 -147.583783) (xy 412.512002 -147.556474)
			(xy 412.512002 -147.555204) (xy 412.512465 -147.527951) (xy 412.520222 -147.474) (xy 412.535577 -147.421703)
			(xy 412.55822 -147.372123) (xy 412.587688 -147.32627) (xy 412.623382 -147.285077) (xy 412.664575 -147.249384)
			(xy 412.710428 -147.219917) (xy 412.760008 -147.197275) (xy 412.812306 -147.18192) (xy 412.866257 -147.174165)
			(xy 412.89351 -147.173696) (xy 412.894272 -147.173696) (xy 412.91229 -147.173932) (xy 412.948163 -147.17737)
			(xy 412.9659 -147.180554) (xy 412.969456 -147.181316) (xy 412.988623 -147.169301) (xy 413.027881 -147.146813)
			(xy 413.047942 -147.136358) (xy 413.04845 -147.136358) (xy 413.060388 -147.130008) (xy 413.06369 -147.125436)
			(xy 413.073088 -147.109942) (xy 413.076499 -147.103946) (xy 413.080241 -147.090674) (xy 413.080454 -147.08378)
			(xy 413.080454 -146.219418) (xy 413.078676 -146.205956) (xy 413.073596 -146.187414) (xy 413.046557 -146.174271)
			(xy 412.993942 -146.145169) (xy 412.96844 -146.129248) (xy 412.966916 -146.129502) (xy 412.949062 -146.132792)
			(xy 412.912932 -146.136357) (xy 412.89478 -146.136614) (xy 412.892494 -146.136614) (xy 412.86529 -146.13606)
			(xy 412.81145 -146.128187) (xy 412.759276 -146.112745) (xy 412.709825 -146.090047) (xy 412.6641 -146.060553)
			(xy 412.623029 -146.024863) (xy 412.587446 -145.983699) (xy 412.558073 -145.937897) (xy 412.535504 -145.888386)
			(xy 412.520199 -145.836171) (xy 412.512468 -145.782312) (xy 412.512002 -145.755106) (xy 412.512002 -145.75409)
			(xy 412.512479 -145.726927) (xy 412.520189 -145.673152) (xy 412.535465 -145.621018) (xy 412.546292 -145.596102)
			(xy 412.548832 -145.590514) (xy 412.550356 -145.582894) (xy 412.550356 -145.582386) (xy 412.536162 -145.534491)
			(xy 412.516286 -145.436587) (xy 412.506282 -145.337188) (xy 412.505652 -145.287238) (xy 412.506095 -145.245373)
			(xy 412.513137 -145.161939) (xy 412.527143 -145.079388) (xy 412.548013 -144.998301) (xy 412.5756 -144.919245)
			(xy 412.592266 -144.880838) (xy 412.595314 -144.871186) (xy 412.59887 -144.855946) (xy 412.59887 -144.85493)
			(xy 412.595314 -144.83969) (xy 412.592266 -144.830038) (xy 412.575588 -144.791635) (xy 412.547982 -144.712584)
			(xy 412.527106 -144.631496) (xy 412.513109 -144.548942) (xy 412.506088 -144.465504) (xy 412.505652 -144.423638)
			(xy 412.505652 -144.42313) (xy 412.505922 -144.390842) (xy 412.510117 -144.326403) (xy 412.514034 -144.294352)
			(xy 412.517535 -144.268947) (xy 412.526809 -144.218503) (xy 412.532576 -144.193514) (xy 412.536593 -144.177)
			(xy 412.545613 -144.144227) (xy 412.55061 -144.127982) (xy 412.549086 -144.120108) (xy 412.5468 -144.115028)
			(xy 412.535825 -144.090017) (xy 412.520343 -144.037639) (xy 412.512502 -143.983587) (xy 412.512002 -143.956278)
			(xy 412.512002 -143.955008) (xy 412.512465 -143.927755) (xy 412.520221 -143.873804) (xy 412.535576 -143.821506)
			(xy 412.558219 -143.771925) (xy 412.587686 -143.726072) (xy 412.62338 -143.684879) (xy 412.664573 -143.649185)
			(xy 412.710427 -143.619718) (xy 412.760007 -143.597076) (xy 412.812306 -143.58172) (xy 412.866257 -143.573965)
			(xy 412.89351 -143.5735) (xy 412.894272 -143.5735) (xy 412.91229 -143.573736) (xy 412.948163 -143.577174)
			(xy 412.9659 -143.580358) (xy 412.969456 -143.58112) (xy 412.988623 -143.569105) (xy 413.027881 -143.546617)
			(xy 413.047942 -143.536162) (xy 413.04845 -143.536162) (xy 413.060388 -143.529812) (xy 413.06369 -143.52524)
			(xy 413.073088 -143.509746) (xy 413.076499 -143.50375) (xy 413.080243 -143.490479) (xy 413.080454 -143.483584)
			(xy 413.080454 -137.109454) (xy 413.078676 -137.095992) (xy 413.073596 -137.07745) (xy 413.046557 -137.064306)
			(xy 412.993944 -137.035203) (xy 412.96844 -137.019284) (xy 412.966916 -137.019538) (xy 412.949063 -137.022828)
			(xy 412.912932 -137.026394) (xy 412.89478 -137.02665) (xy 412.892494 -137.02665) (xy 412.865289 -137.026096)
			(xy 412.811448 -137.018223) (xy 412.759271 -137.002782) (xy 412.709818 -136.980084) (xy 412.66409 -136.950591)
			(xy 412.623017 -136.914901) (xy 412.58743 -136.873737) (xy 412.558053 -136.827936) (xy 412.53548 -136.778425)
			(xy 412.52017 -136.726209) (xy 412.512434 -136.672349) (xy 412.512002 -136.645142) (xy 412.512002 -136.644126)
			(xy 412.512476 -136.616963) (xy 412.520181 -136.563185) (xy 412.535453 -136.511049) (xy 412.546292 -136.486138)
			(xy 412.548832 -136.48055) (xy 412.550356 -136.47293) (xy 412.550356 -136.472422) (xy 412.53616 -136.424527)
			(xy 412.516281 -136.326623) (xy 412.506273 -136.227225) (xy 412.505652 -136.177274) (xy 412.506093 -136.135409)
			(xy 412.513133 -136.051974) (xy 412.527136 -135.969422) (xy 412.548003 -135.888333) (xy 412.575588 -135.809276)
			(xy 412.592266 -135.770874) (xy 412.595314 -135.761222) (xy 412.59887 -135.745982) (xy 412.59887 -135.744966)
			(xy 412.595314 -135.729726) (xy 412.592266 -135.720074) (xy 412.575586 -135.681671) (xy 412.547978 -135.602621)
			(xy 412.527099 -135.521533) (xy 412.513099 -135.438978) (xy 412.506075 -135.35554) (xy 412.505652 -135.313674)
			(xy 412.505652 -135.313166) (xy 412.505921 -135.280878) (xy 412.510114 -135.216438) (xy 412.514034 -135.184388)
			(xy 412.517536 -135.158983) (xy 412.526814 -135.10854) (xy 412.532576 -135.08355) (xy 412.536593 -135.067036)
			(xy 412.545611 -135.034262) (xy 412.55061 -135.018018) (xy 412.549086 -135.010144) (xy 412.5468 -135.005064)
			(xy 412.535822 -134.980054) (xy 412.520336 -134.927676) (xy 412.51249 -134.873623) (xy 412.512002 -134.846314)
			(xy 412.512002 -134.845044) (xy 412.512462 -134.817789) (xy 412.520214 -134.763834) (xy 412.535567 -134.711532)
			(xy 412.558207 -134.661947) (xy 412.587674 -134.616089) (xy 412.623368 -134.574892) (xy 412.664561 -134.539194)
			(xy 412.710417 -134.509723) (xy 412.76 -134.487079) (xy 412.812301 -134.471722) (xy 412.866255 -134.463965)
			(xy 412.89351 -134.463536) (xy 412.894272 -134.463536) (xy 412.91229 -134.463772) (xy 412.948164 -134.46721)
			(xy 412.9659 -134.470394) (xy 412.969456 -134.471156) (xy 412.988623 -134.45914) (xy 413.02788 -134.436652)
			(xy 413.047942 -134.426198) (xy 413.04845 -134.426198) (xy 413.060388 -134.419848) (xy 413.06369 -134.415276)
			(xy 413.073088 -134.399782) (xy 413.076492 -134.393785) (xy 413.080218 -134.380513) (xy 413.080454 -134.37362)
			(xy 413.080454 -133.509512) (xy 413.078676 -133.49605) (xy 413.073596 -133.477508) (xy 413.046557 -133.464365)
			(xy 412.993942 -133.435263) (xy 412.96844 -133.419342) (xy 412.966916 -133.419596) (xy 412.949062 -133.422886)
			(xy 412.912932 -133.426451) (xy 412.89478 -133.426708) (xy 412.892494 -133.426708) (xy 412.86529 -133.426154)
			(xy 412.811451 -133.418281) (xy 412.759277 -133.402839) (xy 412.709826 -133.380141) (xy 412.664102 -133.350647)
			(xy 412.623032 -133.314956) (xy 412.587449 -133.273792) (xy 412.558076 -133.22799) (xy 412.535508 -133.17848)
			(xy 412.520204 -133.126265) (xy 412.512473 -133.072406) (xy 412.512002 -133.0452) (xy 412.512002 -133.044184)
			(xy 412.512479 -133.017021) (xy 412.52019 -132.963246) (xy 412.535467 -132.911113) (xy 412.546292 -132.886196)
			(xy 412.548832 -132.880608) (xy 412.550356 -132.872988) (xy 412.550356 -132.87248) (xy 412.536162 -132.824585)
			(xy 412.516287 -132.726681) (xy 412.506283 -132.627282) (xy 412.505652 -132.577332) (xy 412.506095 -132.535467)
			(xy 412.513138 -132.452033) (xy 412.527144 -132.369483) (xy 412.548014 -132.288395) (xy 412.575602 -132.20934)
			(xy 412.592266 -132.170932) (xy 412.595314 -132.16128) (xy 412.59887 -132.14604) (xy 412.59887 -132.145024)
			(xy 412.594298 -132.124958) (xy 412.59252 -132.120894) (xy 412.57579 -132.082424) (xy 412.548095 -132.003231)
			(xy 412.527152 -131.921992) (xy 412.51311 -131.83928) (xy 412.506066 -131.75568) (xy 412.505652 -131.713732)
			(xy 412.505706 -131.697592) (xy 412.506723 -131.665328) (xy 412.507684 -131.649216) (xy 412.510281 -131.614607)
			(xy 412.519689 -131.545837) (xy 412.52648 -131.511802) (xy 412.531508 -131.488123) (xy 412.543576 -131.441238)
			(xy 412.55061 -131.418076) (xy 412.549086 -131.410202) (xy 412.5468 -131.405122) (xy 412.535825 -131.380111)
			(xy 412.520344 -131.327733) (xy 412.512504 -131.273681) (xy 412.512002 -131.246372) (xy 412.512002 -131.245102)
			(xy 412.512465 -131.217849) (xy 412.520222 -131.163899) (xy 412.535578 -131.111601) (xy 412.55822 -131.062021)
			(xy 412.587689 -131.016169) (xy 412.623382 -130.974977) (xy 412.664575 -130.939284) (xy 412.710428 -130.909817)
			(xy 412.760009 -130.887175) (xy 412.812307 -130.87182) (xy 412.866257 -130.864065) (xy 412.89351 -130.863594)
			(xy 412.894272 -130.863594) (xy 412.91229 -130.86383) (xy 412.948163 -130.867268) (xy 412.9659 -130.870452)
			(xy 412.969456 -130.871214) (xy 412.988623 -130.859199) (xy 413.027881 -130.836711) (xy 413.047942 -130.826256)
			(xy 413.04845 -130.826256) (xy 413.060388 -130.819906) (xy 413.06369 -130.815334) (xy 413.073088 -130.79984)
			(xy 413.076499 -130.793844) (xy 413.08024 -130.780572) (xy 413.080454 -130.773678) (xy 413.080454 -125.899418)
			(xy 413.078676 -125.885956) (xy 413.073596 -125.867414) (xy 413.046557 -125.854271) (xy 412.993942 -125.825169)
			(xy 412.96844 -125.809248) (xy 412.966916 -125.809502) (xy 412.949062 -125.812792) (xy 412.912932 -125.816357)
			(xy 412.89478 -125.816614) (xy 412.892494 -125.816614) (xy 412.86529 -125.81606) (xy 412.81145 -125.808187)
			(xy 412.759276 -125.792745) (xy 412.709825 -125.770047) (xy 412.6641 -125.740553) (xy 412.623029 -125.704863)
			(xy 412.587446 -125.663699) (xy 412.558073 -125.617897) (xy 412.535504 -125.568386) (xy 412.520199 -125.516171)
			(xy 412.512468 -125.462312) (xy 412.512002 -125.435106) (xy 412.512002 -125.43409) (xy 412.512479 -125.406927)
			(xy 412.520189 -125.353152) (xy 412.535465 -125.301018) (xy 412.546292 -125.276102) (xy 412.548832 -125.270514)
			(xy 412.550356 -125.262894) (xy 412.550356 -125.262386) (xy 412.536162 -125.214491) (xy 412.516286 -125.116587)
			(xy 412.506282 -125.017188) (xy 412.505652 -124.967238) (xy 412.506095 -124.925373) (xy 412.513137 -124.841939)
			(xy 412.527143 -124.759388) (xy 412.548013 -124.678301) (xy 412.5756 -124.599245) (xy 412.592266 -124.560838)
			(xy 412.595314 -124.551186) (xy 412.59887 -124.535946) (xy 412.59887 -124.53493) (xy 412.594298 -124.514864)
			(xy 412.59252 -124.5108) (xy 412.57579 -124.47233) (xy 412.548094 -124.393138) (xy 412.527151 -124.311898)
			(xy 412.513108 -124.229186) (xy 412.506064 -124.145586) (xy 412.505652 -124.103638) (xy 412.505706 -124.087498)
			(xy 412.506722 -124.055234) (xy 412.507684 -124.039122) (xy 412.510281 -124.004513) (xy 412.519688 -123.935743)
			(xy 412.52648 -123.901708) (xy 412.531508 -123.878029) (xy 412.543576 -123.831144) (xy 412.55061 -123.807982)
			(xy 412.549086 -123.800108) (xy 412.5468 -123.795028) (xy 412.535825 -123.770017) (xy 412.520343 -123.717639)
			(xy 412.512502 -123.663587) (xy 412.512002 -123.636278) (xy 412.512002 -123.635008) (xy 412.512465 -123.607755)
			(xy 412.520221 -123.553804) (xy 412.535576 -123.501506) (xy 412.558219 -123.451925) (xy 412.587686 -123.406072)
			(xy 412.62338 -123.364879) (xy 412.664573 -123.329185) (xy 412.710427 -123.299718) (xy 412.760007 -123.277076)
			(xy 412.812306 -123.26172) (xy 412.866257 -123.253965) (xy 412.89351 -123.2535) (xy 412.894272 -123.2535)
			(xy 412.91229 -123.253736) (xy 412.948163 -123.257174) (xy 412.9659 -123.260358) (xy 412.969456 -123.26112)
			(xy 412.988623 -123.249105) (xy 413.027881 -123.226617) (xy 413.047942 -123.216162) (xy 413.04845 -123.216162)
			(xy 413.060388 -123.209812) (xy 413.06369 -123.20524) (xy 413.073088 -123.189746) (xy 413.076499 -123.18375)
			(xy 413.080243 -123.170479) (xy 413.080454 -123.163584) (xy 413.080454 -122.299476) (xy 413.078676 -122.286014)
			(xy 413.073596 -122.267472) (xy 413.046557 -122.254328) (xy 412.993943 -122.225226) (xy 412.96844 -122.209306)
			(xy 412.966916 -122.20956) (xy 412.949063 -122.21285) (xy 412.912932 -122.216416) (xy 412.89478 -122.216672)
			(xy 412.892494 -122.216672) (xy 412.865291 -122.216117) (xy 412.811454 -122.208244) (xy 412.759282 -122.192802)
			(xy 412.709833 -122.170103) (xy 412.664112 -122.140609) (xy 412.623045 -122.104918) (xy 412.587465 -122.063753)
			(xy 412.558096 -122.017951) (xy 412.535533 -121.968441) (xy 412.520233 -121.916227) (xy 412.512507 -121.862369)
			(xy 412.512002 -121.835164) (xy 412.512002 -121.834148) (xy 412.512482 -121.806986) (xy 412.520197 -121.753212)
			(xy 412.535478 -121.701082) (xy 412.546292 -121.67616) (xy 412.548832 -121.670572) (xy 412.550356 -121.662952)
			(xy 412.550356 -121.662444) (xy 412.536159 -121.614549) (xy 412.516278 -121.516646) (xy 412.506268 -121.417247)
			(xy 412.505652 -121.367296) (xy 412.506097 -121.325431) (xy 412.513143 -121.241999) (xy 412.527151 -121.159449)
			(xy 412.548024 -121.078363) (xy 412.575614 -120.999309) (xy 412.592266 -120.960896) (xy 412.595314 -120.951244)
			(xy 412.59887 -120.936004) (xy 412.59887 -120.934988) (xy 412.594298 -120.914922) (xy 412.59252 -120.910858)
			(xy 412.575791 -120.872388) (xy 412.548099 -120.793195) (xy 412.52716 -120.711955) (xy 412.51312 -120.629243)
			(xy 412.50608 -120.545644) (xy 412.505652 -120.503696) (xy 412.505707 -120.487556) (xy 412.506724 -120.455292)
			(xy 412.507684 -120.43918) (xy 412.510279 -120.404571) (xy 412.519682 -120.3358) (xy 412.52648 -120.301766)
			(xy 412.531509 -120.278087) (xy 412.543579 -120.231203) (xy 412.55061 -120.20804) (xy 412.549086 -120.200166)
			(xy 412.5468 -120.195086) (xy 412.535821 -120.170076) (xy 412.520331 -120.117698) (xy 412.512482 -120.063645)
			(xy 412.512002 -120.036336) (xy 412.512002 -120.035066) (xy 412.512491 -120.007817) (xy 412.520251 -119.953873)
			(xy 412.535609 -119.901583) (xy 412.558252 -119.852011) (xy 412.58772 -119.806166) (xy 412.623411 -119.76498)
			(xy 412.664601 -119.729293) (xy 412.71045 -119.699831) (xy 412.760024 -119.677194) (xy 412.812316 -119.661842)
			(xy 412.866261 -119.654087) (xy 412.89351 -119.653558) (xy 412.894272 -119.653558) (xy 412.91229 -119.653794)
			(xy 412.948164 -119.657232) (xy 412.9659 -119.660416) (xy 412.969456 -119.661178) (xy 412.988623 -119.649162)
			(xy 413.02788 -119.626673) (xy 413.047942 -119.61622) (xy 413.04845 -119.61622) (xy 413.060388 -119.60987)
			(xy 413.06369 -119.605298) (xy 413.073088 -119.589804) (xy 413.076494 -119.583807) (xy 413.080227 -119.570535)
			(xy 413.080454 -119.563642) (xy 413.080454 -118.102888) (xy 413.080943 -118.092879) (xy 413.088604 -118.074383)
			(xy 413.102754 -118.060223) (xy 413.121245 -118.05255) (xy 413.131254 -118.052088) (xy 414.37433 -118.052088)
			(xy 414.385506 -118.05031) (xy 414.389546 -118.049522) (xy 414.397327 -118.046836) (xy 414.401 -118.044976)
			(xy 414.41243 -118.03761) (xy 414.41751 -118.034308) (xy 414.432242 -118.020338) (xy 414.43529 -118.01602)
			(xy 414.450657 -117.994847) (xy 414.486257 -117.956512) (xy 414.526761 -117.923401) (xy 414.571409 -117.896135)
			(xy 414.619364 -117.875225) (xy 414.669727 -117.861064) (xy 414.721552 -117.853917) (xy 414.74771 -117.85346)
			(xy 414.78454 -117.855238) (xy 414.792414 -117.856) (xy 414.796986 -117.856762) (xy 414.798002 -117.856762)
			(xy 414.802828 -117.857524) (xy 414.803082 -117.857524) (xy 414.805622 -117.858032) (xy 414.806638 -117.858032)
			(xy 414.822894 -117.860826) (xy 414.823656 -117.86108) (xy 414.863325 -117.836584) (xy 414.946396 -117.794244)
			(xy 415.033055 -117.75984) (xy 415.122546 -117.73367) (xy 415.214088 -117.715963) (xy 415.306883 -117.706873)
			(xy 415.3535 -117.70614) (xy 415.35731 -117.70614) (xy 415.402258 -117.706662) (xy 415.491784 -117.714802)
			(xy 415.580215 -117.730961) (xy 415.666835 -117.755009) (xy 415.750941 -117.786749) (xy 415.831851 -117.825926)
			(xy 415.870644 -117.848634) (xy 415.87547 -117.851174) (xy 415.90087 -117.858286) (xy 415.908998 -117.857778)
			(xy 415.923326 -117.855748) (xy 415.952186 -117.853588) (xy 415.966656 -117.85346) (xy 415.96691 -117.85346)
			(xy 415.994471 -117.853945) (xy 416.049021 -117.861873) (xy 416.101864 -117.877562) (xy 416.151901 -117.900686)
			(xy 416.198094 -117.930765) (xy 416.239481 -117.967174) (xy 416.25774 -117.987826) (xy 416.257994 -117.98808)
			(xy 416.25901 -117.98935) (xy 416.261296 -117.992144) (xy 416.26409 -117.994834) (xy 416.27034 -117.999425)
			(xy 416.273742 -118.001288) (xy 416.313071 -118.005273) (xy 416.390984 -118.018672) (xy 416.467594 -118.038184)
			(xy 416.505136 -118.050564) (xy 416.517328 -118.052088) (xy 417.717732 -118.052088) (xy 417.731448 -118.050056)
			(xy 417.742624 -118.047008) (xy 417.749228 -118.04523) (xy 417.755324 -118.041674) (xy 417.772221 -118.032046)
			(xy 417.807596 -118.015884) (xy 417.825936 -118.009416) (xy 417.847309 -118.002534) (xy 417.891237 -117.993236)
			(xy 417.913566 -117.990874) (xy 417.924488 -117.989858) (xy 417.95192 -117.974364) (xy 417.957208 -117.971247)
			(xy 417.966206 -117.962901) (xy 417.9697 -117.957854) (xy 418.007292 -117.900196) (xy 418.007546 -117.899942)
			(xy 418.008308 -117.898672) (xy 418.012463 -117.891114) (xy 418.015978 -117.874238) (xy 418.015166 -117.865652)
			(xy 418.013134 -117.854476) (xy 418.01161 -117.850158) (xy 418.005533 -117.832045) (xy 417.996621 -117.79489)
			(xy 417.99383 -117.77599) (xy 417.992381 -117.764993) (xy 417.9906 -117.742881) (xy 417.990274 -117.731794)
			(xy 417.990274 -117.72265) (xy 417.990831 -117.695447) (xy 417.998709 -117.641612) (xy 418.014154 -117.589442)
			(xy 418.036855 -117.539996) (xy 418.06635 -117.494276) (xy 418.10204 -117.45321) (xy 418.143203 -117.41763)
			(xy 418.189003 -117.388259) (xy 418.23851 -117.365693) (xy 418.290722 -117.350388) (xy 418.344578 -117.342656)
			(xy 418.371782 -117.342158) (xy 418.399035 -117.342643) (xy 418.452986 -117.350397) (xy 418.505285 -117.36575)
			(xy 418.554867 -117.38839) (xy 418.600722 -117.417855) (xy 418.641917 -117.453546) (xy 418.677614 -117.494736)
			(xy 418.707085 -117.540587) (xy 418.729732 -117.590166) (xy 418.745092 -117.642463) (xy 418.752854 -117.696413)
			(xy 418.75329 -117.723666) (xy 418.752762 -117.752522) (xy 418.751741 -117.759226) (xy 422.774872 -117.759226)
			(xy 422.774872 -116.895626) (xy 422.775362 -116.865642) (xy 422.78319 -116.806186) (xy 422.798711 -116.748261)
			(xy 422.82166 -116.692857) (xy 422.851644 -116.640923) (xy 422.88815 -116.593347) (xy 422.930555 -116.550942)
			(xy 422.978131 -116.514436) (xy 423.030065 -116.484452) (xy 423.085469 -116.461503) (xy 423.143394 -116.445982)
			(xy 423.20285 -116.438154) (xy 423.262818 -116.438154) (xy 423.322274 -116.445982) (xy 423.380199 -116.461503)
			(xy 423.435603 -116.484452) (xy 423.487537 -116.514436) (xy 423.535113 -116.550942) (xy 423.577518 -116.593347)
			(xy 423.614024 -116.640923) (xy 423.644008 -116.692857) (xy 423.666957 -116.748261) (xy 423.682478 -116.806186)
			(xy 423.690306 -116.865642) (xy 423.690796 -116.895626) (xy 423.690796 -117.759226) (xy 423.690306 -117.78921)
			(xy 423.682478 -117.848666) (xy 423.666957 -117.906591) (xy 423.644008 -117.961995) (xy 423.614024 -118.013929)
			(xy 423.577518 -118.061505) (xy 423.535113 -118.10391) (xy 423.487537 -118.140416) (xy 423.435603 -118.1704)
			(xy 423.380199 -118.193349) (xy 423.322274 -118.20887) (xy 423.262818 -118.216698) (xy 423.20285 -118.216698)
			(xy 423.143394 -118.20887) (xy 423.085469 -118.193349) (xy 423.030065 -118.1704) (xy 422.978131 -118.140416)
			(xy 422.930555 -118.10391) (xy 422.88815 -118.061505) (xy 422.851644 -118.013929) (xy 422.82166 -117.961995)
			(xy 422.798711 -117.906591) (xy 422.78319 -117.848666) (xy 422.775362 -117.78921) (xy 422.774872 -117.759226)
			(xy 418.751741 -117.759226) (xy 418.744069 -117.809575) (xy 418.726878 -117.864667) (xy 418.70158 -117.916539)
			(xy 418.668754 -117.964006) (xy 418.62915 -118.005984) (xy 418.583671 -118.041514) (xy 418.533358 -118.069784)
			(xy 418.479358 -118.090148) (xy 418.422907 -118.102142) (xy 418.394134 -118.104412) (xy 418.386768 -118.105682)
			(xy 418.376608 -118.109238) (xy 418.372759 -118.111248) (xy 418.365741 -118.11636) (xy 418.362638 -118.119398)
			(xy 418.361622 -118.120414) (xy 418.359336 -118.1227) (xy 418.357304 -118.12524) (xy 418.316664 -118.187978)
			(xy 418.315902 -118.189248) (xy 418.305996 -118.203472) (xy 418.304472 -118.215918) (xy 418.302694 -118.228618)
			(xy 418.307012 -118.240048) (xy 418.311076 -118.25224) (xy 418.311076 -118.254526) (xy 418.314378 -118.263162)
			(xy 418.314632 -118.264178) (xy 418.317426 -118.273322) (xy 418.323014 -118.280434) (xy 418.325895 -118.283925)
			(xy 418.332663 -118.289934) (xy 418.336476 -118.292372) (xy 418.340286 -118.294658) (xy 418.341048 -118.29542)
			(xy 418.387276 -118.324122) (xy 418.39515 -118.329202) (xy 418.419026 -118.334028) (xy 418.430202 -118.334282)
			(xy 418.433758 -118.333774) (xy 418.448026 -118.331805) (xy 418.476759 -118.329773) (xy 418.491162 -118.32971)
			(xy 418.491416 -118.32971) (xy 418.518193 -118.330157) (xy 418.571221 -118.337639) (xy 418.62268 -118.352468)
			(xy 418.671558 -118.374351) (xy 418.716893 -118.402858) (xy 418.757793 -118.437428) (xy 418.793454 -118.477381)
			(xy 418.823173 -118.521932) (xy 418.846366 -118.570202) (xy 418.862576 -118.621243) (xy 418.871485 -118.67405)
			(xy 418.87267 -118.700804) (xy 418.872924 -118.704106) (xy 418.872924 -118.711218) (xy 418.872298 -118.743167)
			(xy 418.861692 -118.806177) (xy 418.840729 -118.866537) (xy 418.825934 -118.89486) (xy 418.822886 -118.900448)
			(xy 418.820854 -118.904258) (xy 418.819838 -118.914926) (xy 418.819838 -118.91518) (xy 418.819442 -118.920512)
			(xy 418.820586 -118.931142) (xy 418.822124 -118.936262) (xy 418.834824 -118.971822) (xy 418.834824 -118.97233)
			(xy 418.84727 -119.007636) (xy 418.848564 -119.011081) (xy 418.852001 -119.017587) (xy 418.854128 -119.02059)
			(xy 420.155778 -119.559324) (xy 429.3743 -119.559324) (xy 429.3743 -118.695724) (xy 429.37479 -118.66574)
			(xy 429.382618 -118.606284) (xy 429.398139 -118.548359) (xy 429.421088 -118.492955) (xy 429.451072 -118.441021)
			(xy 429.487578 -118.393445) (xy 429.529983 -118.35104) (xy 429.577559 -118.314534) (xy 429.629493 -118.28455)
			(xy 429.684897 -118.261601) (xy 429.742822 -118.24608) (xy 429.802278 -118.238252) (xy 429.862246 -118.238252)
			(xy 429.921702 -118.24608) (xy 429.979627 -118.261601) (xy 430.035031 -118.28455) (xy 430.086965 -118.314534)
			(xy 430.134541 -118.35104) (xy 430.176946 -118.393445) (xy 430.213452 -118.441021) (xy 430.243436 -118.492955)
			(xy 430.266385 -118.548359) (xy 430.281906 -118.606284) (xy 430.289734 -118.66574) (xy 430.290224 -118.695724)
			(xy 430.290224 -119.559324) (xy 430.289734 -119.589308) (xy 430.281906 -119.648764) (xy 430.266385 -119.706689)
			(xy 430.243436 -119.762093) (xy 430.213452 -119.814027) (xy 430.176946 -119.861603) (xy 430.134541 -119.904008)
			(xy 430.086965 -119.940514) (xy 430.035031 -119.970498) (xy 429.979627 -119.993447) (xy 429.921702 -120.008968)
			(xy 429.862246 -120.016796) (xy 429.802278 -120.016796) (xy 429.742822 -120.008968) (xy 429.684897 -119.993447)
			(xy 429.629493 -119.970498) (xy 429.577559 -119.940514) (xy 429.529983 -119.904008) (xy 429.487578 -119.861603)
			(xy 429.451072 -119.814027) (xy 429.421088 -119.762093) (xy 429.398139 -119.706689) (xy 429.382618 -119.648764)
			(xy 429.37479 -119.589308) (xy 429.3743 -119.559324) (xy 420.155778 -119.559324) (xy 420.27729 -119.609616)
			(xy 420.28999 -119.612156) (xy 420.2938 -119.61241) (xy 420.352982 -119.61241) (xy 420.363045 -119.612848)
			(xy 420.381627 -119.620585) (xy 420.38905 -119.627396) (xy 420.413942 -119.652288) (xy 420.417511 -119.655692)
			(xy 420.425696 -119.661194) (xy 420.430198 -119.66321) (xy 420.43985 -119.667274) (xy 420.46525 -119.667274)
			(xy 420.4716 -119.66575) (xy 420.494692 -119.660135) (xy 420.54182 -119.654017) (xy 420.56558 -119.653558)
			(xy 420.570914 -119.653558) (xy 420.597024 -119.654206) (xy 420.648704 -119.661768) (xy 420.698869 -119.67631)
			(xy 420.746581 -119.697561) (xy 420.790947 -119.725122) (xy 420.831138 -119.758478) (xy 420.866402 -119.797007)
			(xy 420.89608 -119.839986) (xy 420.908226 -119.863108) (xy 420.91229 -119.870982) (xy 420.913814 -119.873014)
			(xy 421.350186 -120.053608) (xy 421.395039 -120.072814) (xy 421.481121 -120.118762) (xy 421.562303 -120.172899)
			(xy 421.637807 -120.234708) (xy 421.672766 -120.268746) (xy 422.773594 -121.365772) (xy 432.016408 -121.365772)
			(xy 432.016408 -120.502172) (xy 432.016898 -120.472188) (xy 432.024726 -120.412732) (xy 432.040247 -120.354807)
			(xy 432.063196 -120.299403) (xy 432.09318 -120.247469) (xy 432.129686 -120.199893) (xy 432.172091 -120.157488)
			(xy 432.219667 -120.120982) (xy 432.271601 -120.090998) (xy 432.327005 -120.068049) (xy 432.38493 -120.052528)
			(xy 432.444386 -120.0447) (xy 432.504354 -120.0447) (xy 432.56381 -120.052528) (xy 432.621735 -120.068049)
			(xy 432.677139 -120.090998) (xy 432.729073 -120.120982) (xy 432.776649 -120.157488) (xy 432.819054 -120.199893)
			(xy 432.85556 -120.247469) (xy 432.885544 -120.299403) (xy 432.908493 -120.354807) (xy 432.924014 -120.412732)
			(xy 432.931842 -120.472188) (xy 432.932332 -120.502172) (xy 432.932332 -121.365772) (xy 432.931842 -121.395756)
			(xy 432.924014 -121.455212) (xy 432.908493 -121.513137) (xy 432.885544 -121.568541) (xy 432.85556 -121.620475)
			(xy 432.819054 -121.668051) (xy 432.776649 -121.710456) (xy 432.729073 -121.746962) (xy 432.677139 -121.776946)
			(xy 432.621735 -121.799895) (xy 432.56381 -121.815416) (xy 432.504354 -121.823244) (xy 432.444386 -121.823244)
			(xy 432.38493 -121.815416) (xy 432.327005 -121.799895) (xy 432.271601 -121.776946) (xy 432.219667 -121.746962)
			(xy 432.172091 -121.710456) (xy 432.129686 -121.668051) (xy 432.09318 -121.620475) (xy 432.063196 -121.568541)
			(xy 432.040247 -121.513137) (xy 432.024726 -121.455212) (xy 432.016898 -121.395756) (xy 432.016408 -121.365772)
			(xy 422.773594 -121.365772) (xy 423.14368 -121.73458) (xy 423.145204 -121.736104) (xy 423.147236 -121.737882)
			(xy 425.053376 -123.159266) (xy 429.3743 -123.159266) (xy 429.3743 -122.295666) (xy 429.37479 -122.265682)
			(xy 429.382618 -122.206226) (xy 429.398139 -122.148301) (xy 429.421088 -122.092897) (xy 429.451072 -122.040963)
			(xy 429.487578 -121.993387) (xy 429.529983 -121.950982) (xy 429.577559 -121.914476) (xy 429.629493 -121.884492)
			(xy 429.684897 -121.861543) (xy 429.742822 -121.846022) (xy 429.802278 -121.838194) (xy 429.862246 -121.838194)
			(xy 429.921702 -121.846022) (xy 429.979627 -121.861543) (xy 430.035031 -121.884492) (xy 430.086965 -121.914476)
			(xy 430.134541 -121.950982) (xy 430.176946 -121.993387) (xy 430.213452 -122.040963) (xy 430.243436 -122.092897)
			(xy 430.266385 -122.148301) (xy 430.281906 -122.206226) (xy 430.289734 -122.265682) (xy 430.290224 -122.295666)
			(xy 430.290224 -123.159266) (xy 430.289734 -123.18925) (xy 430.281906 -123.248706) (xy 430.266385 -123.306631)
			(xy 430.243436 -123.362035) (xy 430.213452 -123.413969) (xy 430.176946 -123.461545) (xy 430.134541 -123.50395)
			(xy 430.086965 -123.540456) (xy 430.035031 -123.57044) (xy 429.979627 -123.593389) (xy 429.921702 -123.60891)
			(xy 429.862246 -123.616738) (xy 429.802278 -123.616738) (xy 429.742822 -123.60891) (xy 429.684897 -123.593389)
			(xy 429.629493 -123.57044) (xy 429.577559 -123.540456) (xy 429.529983 -123.50395) (xy 429.487578 -123.461545)
			(xy 429.451072 -123.413969) (xy 429.421088 -123.362035) (xy 429.398139 -123.306631) (xy 429.382618 -123.248706)
			(xy 429.37479 -123.18925) (xy 429.3743 -123.159266) (xy 425.053376 -123.159266) (xy 427.475905 -124.965714)
			(xy 432.016408 -124.965714) (xy 432.016408 -124.102114) (xy 432.016898 -124.07213) (xy 432.024726 -124.012674)
			(xy 432.040247 -123.954749) (xy 432.063196 -123.899345) (xy 432.09318 -123.847411) (xy 432.129686 -123.799835)
			(xy 432.172091 -123.75743) (xy 432.219667 -123.720924) (xy 432.271601 -123.69094) (xy 432.327005 -123.667991)
			(xy 432.38493 -123.65247) (xy 432.444386 -123.644642) (xy 432.504354 -123.644642) (xy 432.56381 -123.65247)
			(xy 432.621735 -123.667991) (xy 432.677139 -123.69094) (xy 432.729073 -123.720924) (xy 432.776649 -123.75743)
			(xy 432.819054 -123.799835) (xy 432.85556 -123.847411) (xy 432.885544 -123.899345) (xy 432.908493 -123.954749)
			(xy 432.924014 -124.012674) (xy 432.931842 -124.07213) (xy 432.932332 -124.102114) (xy 432.932332 -124.965714)
			(xy 432.931842 -124.995698) (xy 432.924014 -125.055154) (xy 432.908493 -125.113079) (xy 432.885544 -125.168483)
			(xy 432.85556 -125.220417) (xy 432.819054 -125.267993) (xy 432.776649 -125.310398) (xy 432.729073 -125.346904)
			(xy 432.677139 -125.376888) (xy 432.621735 -125.399837) (xy 432.56381 -125.415358) (xy 432.504354 -125.423186)
			(xy 432.444386 -125.423186) (xy 432.38493 -125.415358) (xy 432.327005 -125.399837) (xy 432.271601 -125.376888)
			(xy 432.219667 -125.346904) (xy 432.172091 -125.310398) (xy 432.129686 -125.267993) (xy 432.09318 -125.220417)
			(xy 432.063196 -125.168483) (xy 432.040247 -125.113079) (xy 432.024726 -125.055154) (xy 432.016898 -124.995698)
			(xy 432.016408 -124.965714) (xy 427.475905 -124.965714) (xy 428.771304 -125.931676) (xy 429.483012 -126.462536)
			(xy 429.488092 -126.463806) (xy 429.49495 -126.465584) (xy 433.432966 -126.465584) (xy 433.441094 -126.464822)
			(xy 433.441602 -126.464822) (xy 433.449123 -126.463226) (xy 433.462819 -126.456257) (xy 433.468526 -126.451106)
			(xy 433.81295 -126.106682) (xy 433.819799 -126.099285) (xy 433.827535 -126.080686) (xy 433.827936 -126.070614)
			(xy 433.827936 -120.494552) (xy 433.827502 -120.484487) (xy 433.819769 -120.465901) (xy 433.81295 -120.458484)
			(xy 431.459386 -118.105174) (xy 431.430367 -118.075147) (xy 431.380264 -118.008345) (xy 431.359564 -117.972078)
			(xy 431.356262 -117.965728) (xy 430.8094 -117.418866) (xy 430.786874 -117.395697) (xy 430.746584 -117.345172)
			(xy 430.712204 -117.290454) (xy 430.684167 -117.23223) (xy 430.662824 -117.171234) (xy 430.648445 -117.108231)
			(xy 430.64121 -117.044015) (xy 430.640744 -117.011704) (xy 430.640744 -112.65281) (xy 430.640682 -112.649204)
			(xy 430.639664 -112.642064) (xy 430.638712 -112.638586) (xy 430.637188 -112.634014) (xy 430.633378 -112.62487)
			(xy 427.420024 -109.411516) (xy 427.397495 -109.388348) (xy 427.357199 -109.337825) (xy 427.322813 -109.283108)
			(xy 427.29477 -109.224884) (xy 427.273421 -109.163888) (xy 427.259035 -109.100884) (xy 427.251794 -109.036666)
			(xy 427.251368 -109.004354) (xy 427.251368 -101.368606) (xy 427.25086 -101.361494) (xy 427.248486 -101.349574)
			(xy 427.234417 -101.329802) (xy 427.223936 -101.323648) (xy 427.223428 -101.32314) (xy 427.218856 -101.321108)
			(xy 427.215554 -101.319838) (xy 427.195996 -101.312218) (xy 427.191802 -101.310917) (xy 427.183115 -101.309638)
			(xy 427.178724 -101.309678) (xy 427.178216 -101.309678) (xy 427.167548 -101.309932) (xy 427.136052 -101.324156)
			(xy 427.12894 -101.331522) (xy 427.107768 -101.353124) (xy 427.059845 -101.390023) (xy 427.006702 -101.418902)
			(xy 426.94967 -101.439039) (xy 426.890175 -101.449929) (xy 426.859954 -101.451156) (xy 426.851572 -101.451156)
			(xy 426.824319 -101.450668) (xy 426.770367 -101.442907) (xy 426.718069 -101.427548) (xy 426.668489 -101.404902)
			(xy 426.622637 -101.375432) (xy 426.581445 -101.339736) (xy 426.545752 -101.298541) (xy 426.516284 -101.252686)
			(xy 426.493642 -101.203105) (xy 426.478287 -101.150805) (xy 426.47053 -101.096853) (xy 426.47053 -101.042347)
			(xy 426.478287 -100.988395) (xy 426.493642 -100.936095) (xy 426.516284 -100.886514) (xy 426.545752 -100.840659)
			(xy 426.581445 -100.799464) (xy 426.622637 -100.763768) (xy 426.668489 -100.734298) (xy 426.718069 -100.711652)
			(xy 426.770367 -100.696293) (xy 426.824319 -100.688532) (xy 426.851572 -100.68814) (xy 426.854112 -100.68814)
			(xy 426.868138 -100.688308) (xy 426.896107 -100.690466) (xy 426.909992 -100.692458) (xy 426.914056 -100.69322)
			(xy 426.925034 -100.695142) (xy 426.946764 -100.7001) (xy 426.95749 -100.703126) (xy 426.981824 -100.710578)
			(xy 427.028417 -100.731048) (xy 427.071876 -100.757529) (xy 427.111429 -100.789552) (xy 427.129194 -100.807774)
			(xy 427.132496 -100.81133) (xy 427.136052 -100.81514) (xy 427.157642 -100.825046) (xy 427.169834 -100.82911)
			(xy 427.17593 -100.829872) (xy 427.179232 -100.829872) (xy 427.183578 -100.829759) (xy 427.192132 -100.828219)
			(xy 427.19625 -100.826824) (xy 427.197266 -100.82657) (xy 427.221142 -100.817172) (xy 427.227494 -100.814112)
			(xy 427.238318 -100.805085) (xy 427.242478 -100.799392) (xy 427.24705 -100.792788) (xy 427.249336 -100.785422)
			(xy 427.250098 -100.78212) (xy 427.251368 -100.771198) (xy 427.251368 -99.286314) (xy 427.251828 -99.2542)
			(xy 427.259003 -99.190372) (xy 427.273219 -99.127736) (xy 427.294302 -99.067066) (xy 427.307756 -99.037902)
			(xy 427.30801 -99.03714) (xy 427.310042 -99.031552) (xy 427.310296 -99.030282) (xy 427.310804 -99.029266)
			(xy 427.311755 -99.025787) (xy 427.31278 -99.018648) (xy 427.312836 -99.015042) (xy 427.312836 -98.805238)
			(xy 427.313271 -98.795174) (xy 427.321005 -98.776589) (xy 427.327822 -98.76917) (xy 431.527204 -94.569788)
			(xy 431.534599 -94.562933) (xy 431.553198 -94.555186) (xy 431.563272 -94.554802) (xy 431.718974 -94.554802)
			(xy 431.72484 -94.554635) (xy 431.736257 -94.551938) (xy 431.74158 -94.549468) (xy 431.755042 -94.542864)
			(xy 431.765456 -94.53499) (xy 432.079654 -94.220538) (xy 432.775106 -93.525086) (xy 432.78009 -93.519658)
			(xy 432.786944 -93.50662) (xy 432.788568 -93.499432) (xy 432.788568 -93.498924) (xy 432.789584 -93.489526)
			(xy 432.789584 -88.034114) (xy 432.789353 -88.027161) (xy 432.785623 -88.013764) (xy 432.782218 -88.007698)
			(xy 432.758342 -87.997792) (xy 432.748958 -87.994267) (xy 432.728928 -87.99413) (xy 432.71039 -88.001717)
			(xy 432.70297 -88.00846) (xy 429.932846 -90.778838) (xy 429.926496 -90.789506) (xy 429.924718 -90.795348)
			(xy 429.91627 -90.820916) (xy 429.893191 -90.869565) (xy 429.863506 -90.91449) (xy 429.827803 -90.954798)
			(xy 429.786791 -90.989689) (xy 429.741283 -91.018472) (xy 429.692182 -91.040575) (xy 429.640463 -91.05556)
			(xy 429.587151 -91.06313) (xy 429.560228 -91.063572) (xy 429.532975 -91.063111) (xy 429.479023 -91.055357)
			(xy 429.426724 -91.040003) (xy 429.377142 -91.017361) (xy 429.331288 -90.987893) (xy 429.290095 -90.952199)
			(xy 429.254402 -90.911005) (xy 429.224935 -90.865151) (xy 429.202295 -90.815569) (xy 429.186942 -90.763269)
			(xy 429.179189 -90.709317) (xy 429.17872 -90.682064) (xy 429.178466 -90.682064) (xy 429.178925 -90.655129)
			(xy 429.186493 -90.601795) (xy 429.201488 -90.550055) (xy 429.223612 -90.500938) (xy 429.252424 -90.455422)
			(xy 429.287352 -90.414411) (xy 429.327702 -90.378721) (xy 429.37267 -90.349061) (xy 429.421364 -90.326022)
			(xy 429.446944 -90.317574) (xy 429.447198 -90.317574) (xy 429.453031 -90.315561) (xy 429.463564 -90.309137)
			(xy 429.468026 -90.304874) (xy 432.351942 -87.420958) (xy 432.356925 -87.415457) (xy 432.363759 -87.402288)
			(xy 432.365404 -87.39505) (xy 432.36642 -87.385398) (xy 432.36642 -85.58657) (xy 432.365404 -85.576918)
			(xy 432.361086 -85.563964) (xy 432.35626 -85.55609) (xy 432.347417 -85.544962) (xy 432.324856 -85.527695)
			(xy 432.31181 -85.522054) (xy 432.311302 -85.522054) (xy 432.299813 -85.518037) (xy 432.275678 -85.514947)
			(xy 432.26355 -85.515958) (xy 432.259486 -85.51672) (xy 432.251612 -85.518498) (xy 432.246088 -85.520505)
			(xy 432.236082 -85.526664) (xy 432.2318 -85.53069) (xy 429.84166 -87.92083) (xy 429.840907 -87.927882)
			(xy 429.84285 -87.941925) (xy 429.84547 -87.948516) (xy 429.85944 -87.97544) (xy 429.864245 -87.982805)
			(xy 429.877802 -87.993986) (xy 429.894342 -87.999921) (xy 429.903128 -88.000332) (xy 429.903636 -88.000332)
			(xy 429.906938 -88.000078) (xy 429.937926 -87.999062) (xy 429.939704 -87.999062) (xy 429.968043 -87.999568)
			(xy 430.024144 -88.007634) (xy 430.078525 -88.023603) (xy 430.130081 -88.047148) (xy 430.177761 -88.077791)
			(xy 430.220595 -88.114907) (xy 430.257711 -88.157741) (xy 430.288354 -88.205422) (xy 430.311898 -88.256978)
			(xy 430.327866 -88.31136) (xy 430.335932 -88.36746) (xy 430.335932 -88.424138) (xy 430.327866 -88.480239)
			(xy 430.311899 -88.534621) (xy 430.288354 -88.586177) (xy 430.257712 -88.633858) (xy 430.220596 -88.676692)
			(xy 430.177763 -88.713809) (xy 430.130082 -88.744451) (xy 430.078527 -88.767997) (xy 430.024145 -88.783965)
			(xy 429.968044 -88.792032) (xy 429.911366 -88.792033) (xy 429.855265 -88.783967) (xy 429.800883 -88.768)
			(xy 429.749327 -88.744456) (xy 429.701646 -88.713815) (xy 429.658811 -88.6767) (xy 429.621694 -88.633866)
			(xy 429.591051 -88.586187) (xy 429.567505 -88.534631) (xy 429.551536 -88.48025) (xy 429.543468 -88.424149)
			(xy 429.542956 -88.39581) (xy 429.54363 -88.364677) (xy 429.553477 -88.303191) (xy 429.572789 -88.243992)
			(xy 429.58639 -88.215978) (xy 429.58766 -88.213438) (xy 429.589946 -88.207342) (xy 429.589946 -88.206834)
			(xy 429.5912 -88.202376) (xy 429.592219 -88.193171) (xy 429.591978 -88.188546) (xy 429.591978 -88.188292)
			(xy 429.591724 -88.185752) (xy 429.590708 -88.179656) (xy 429.589184 -88.174576) (xy 429.584104 -88.164162)
			(xy 429.570388 -88.145112) (xy 429.567086 -88.14054) (xy 429.566578 -88.139778) (xy 429.565816 -88.138762)
			(xy 429.558704 -88.128602) (xy 429.54194 -88.104726) (xy 429.538638 -88.100154) (xy 429.538638 -88.0999)
			(xy 429.533812 -88.095582) (xy 429.52416 -88.088724) (xy 429.499776 -88.092026) (xy 429.466756 -88.095582)
			(xy 429.42256 -88.09736) (xy 429.008032 -88.09736) (xy 429.002023 -88.097529) (xy 428.990341 -88.100355)
			(xy 428.984918 -88.102948) (xy 428.981444 -88.104787) (xy 428.975064 -88.10938) (xy 428.972218 -88.112092)
			(xy 428.95139 -88.13292) (xy 428.94471 -88.140331) (xy 428.937137 -88.158767) (xy 428.936658 -88.168734)
			(xy 428.936658 -88.174322) (xy 428.936778 -88.17887) (xy 428.938432 -88.187817) (xy 428.93996 -88.192102)
			(xy 428.9425 -88.196928) (xy 428.956549 -88.224666) (xy 428.976457 -88.283567) (xy 428.986576 -88.344912)
			(xy 428.987204 -88.375998) (xy 428.986741 -88.403251) (xy 428.978984 -88.457202) (xy 428.963628 -88.5095)
			(xy 428.940986 -88.55908) (xy 428.911518 -88.604933) (xy 428.875824 -88.646125) (xy 428.834631 -88.681819)
			(xy 428.788778 -88.711287) (xy 428.739198 -88.733929) (xy 428.6869 -88.749284) (xy 428.632949 -88.757041)
			(xy 428.605696 -88.757506) (xy 428.605188 -88.757506) (xy 428.576 -88.756959) (xy 428.518313 -88.748013)
			(xy 428.462668 -88.730364) (xy 428.436278 -88.717882) (xy 428.424086 -88.711532) (xy 428.416466 -88.707468)
			(xy 428.415958 -88.707214) (xy 428.41418 -88.706198) (xy 428.407142 -88.702771) (xy 428.391754 -88.699935)
			(xy 428.383954 -88.70061) (xy 428.3837 -88.70061) (xy 427.30293 -89.78138) (xy 428.520604 -89.78138)
			(xy 428.524675 -89.725758) (xy 428.536801 -89.671321) (xy 428.556724 -89.61923) (xy 428.58402 -89.570595)
			(xy 428.618106 -89.526452) (xy 428.658255 -89.487743) (xy 428.703613 -89.455292) (xy 428.753213 -89.429791)
			(xy 428.805997 -89.411784) (xy 428.86084 -89.401654) (xy 428.916574 -89.399617) (xy 428.972011 -89.405717)
			(xy 429.025968 -89.419823) (xy 429.077297 -89.441635) (xy 429.124903 -89.470689) (xy 429.167771 -89.506364)
			(xy 429.204988 -89.547901) (xy 429.235761 -89.594414) (xy 429.259433 -89.644911) (xy 429.275501 -89.698318)
			(xy 429.283621 -89.753494) (xy 429.28413 -89.78138) (xy 429.283621 -89.809266) (xy 429.275501 -89.864442)
			(xy 429.259433 -89.917849) (xy 429.235761 -89.968346) (xy 429.204988 -90.014859) (xy 429.167771 -90.056396)
			(xy 429.124903 -90.092071) (xy 429.077297 -90.121125) (xy 429.025968 -90.142937) (xy 428.972011 -90.157043)
			(xy 428.916574 -90.163143) (xy 428.86084 -90.161106) (xy 428.805997 -90.150976) (xy 428.753213 -90.132969)
			(xy 428.703613 -90.107468) (xy 428.658255 -90.075017) (xy 428.618106 -90.036308) (xy 428.58402 -89.992165)
			(xy 428.556724 -89.94353) (xy 428.536801 -89.891439) (xy 428.524675 -89.837002) (xy 428.520604 -89.78138)
			(xy 427.30293 -89.78138) (xy 427.108112 -89.976198) (xy 427.084548 -89.999096) (xy 427.033165 -90.040049)
			(xy 426.977522 -90.074996) (xy 426.918319 -90.103498) (xy 426.856298 -90.125196) (xy 426.792239 -90.139818)
			(xy 426.726945 -90.14718) (xy 426.694092 -90.147648) (xy 425.713144 -90.147648) (xy 425.705436 -90.147879)
			(xy 425.690701 -90.152408) (xy 425.684188 -90.156538) (xy 425.680124 -90.15984) (xy 425.583604 -90.25636)
			(xy 425.54017 -90.300048) (xy 425.516583 -90.322984) (xy 425.465145 -90.364007) (xy 425.409438 -90.399014)
			(xy 425.350161 -90.427563) (xy 425.288061 -90.449297) (xy 425.223918 -90.463941) (xy 425.158539 -90.471312)
			(xy 425.125642 -90.471752) (xy 425.089847 -90.471218) (xy 425.018789 -90.462499) (xy 424.949323 -90.445187)
			(xy 424.882485 -90.419538) (xy 424.81927 -90.385937) (xy 424.760621 -90.344882) (xy 424.707411 -90.296987)
			(xy 424.660434 -90.242965) (xy 424.62039 -90.183621) (xy 424.603672 -90.151966) (xy 424.603672 -90.151712)
			(xy 424.595798 -90.136472) (xy 424.59402 -90.13317) (xy 424.590972 -90.130884) (xy 424.559476 -90.122502)
			(xy 424.558968 -90.122502) (xy 424.543474 -90.118438) (xy 424.537962 -90.117229) (xy 424.526681 -90.116962)
			(xy 424.521122 -90.11793) (xy 424.5102 -90.119962) (xy 424.500802 -90.12682) (xy 424.474602 -90.145055)
			(xy 424.417713 -90.174001) (xy 424.357001 -90.193705) (xy 424.293957 -90.203683) (xy 424.262042 -90.20429)
			(xy 424.232992 -90.203799) (xy 424.175483 -90.195535) (xy 424.119736 -90.17917) (xy 424.066886 -90.155036)
			(xy 424.01801 -90.123625) (xy 423.974102 -90.085576) (xy 423.936057 -90.041666) (xy 423.90465 -89.992787)
			(xy 423.88052 -89.939935) (xy 423.871898 -89.91219) (xy 423.86885 -89.902792) (xy 423.836084 -89.870026)
			(xy 423.830653 -89.868402) (xy 423.819367 -89.867376) (xy 423.813732 -89.867994) (xy 423.755058 -89.926668)
			(xy 423.748708 -89.937336) (xy 423.74693 -89.943178) (xy 423.738318 -89.969294) (xy 423.71464 -90.018926)
			(xy 423.684079 -90.064642) (xy 423.647269 -90.105496) (xy 423.604973 -90.140638) (xy 423.558068 -90.169342)
			(xy 423.507527 -90.191012) (xy 423.454398 -90.205198) (xy 423.427144 -90.208862) (xy 423.412666 -90.210386)
			(xy 423.38244 -90.211656) (xy 423.355394 -90.21119) (xy 423.301842 -90.203568) (xy 423.2499 -90.188471)
			(xy 423.200605 -90.1662) (xy 423.154944 -90.137201) (xy 423.113827 -90.102053) (xy 423.078078 -90.061459)
			(xy 423.048411 -90.016229) (xy 423.036492 -89.991946) (xy 423.03446 -89.987628) (xy 423.031698 -89.983151)
			(xy 423.024664 -89.975334) (xy 423.02049 -89.972134) (xy 423.015156 -89.968324) (xy 423.00906 -89.966038)
			(xy 422.997122 -89.96299) (xy 422.963594 -89.958926) (xy 422.963086 -89.958926) (xy 422.944798 -89.95664)
			(xy 422.938194 -89.956132) (xy 422.90238 -89.956132) (xy 422.891712 -89.957148) (xy 422.88079 -89.960958)
			(xy 422.870884 -89.965784) (xy 422.863518 -89.974928) (xy 422.845289 -89.996526) (xy 422.803545 -90.034625)
			(xy 422.756635 -90.066146) (xy 422.705586 -90.090397) (xy 422.651517 -90.106849) (xy 422.595613 -90.11514)
			(xy 422.567354 -90.115644) (xy 422.566846 -90.115644) (xy 422.549066 -90.115136) (xy 422.53535 -90.11412)
			(xy 422.506437 -90.11116) (xy 422.449922 -90.097599) (xy 422.396118 -90.075626) (xy 422.346266 -90.04575)
			(xy 422.301521 -90.00866) (xy 422.262917 -89.965215) (xy 422.231346 -89.916419) (xy 422.207539 -89.8634)
			(xy 422.192046 -89.807385) (xy 422.188132 -89.778586) (xy 422.187116 -89.768934) (xy 422.185338 -89.734136)
			(xy 422.185338 -89.733628) (xy 422.185812 -89.706707) (xy 422.193406 -89.653401) (xy 422.208418 -89.601693)
			(xy 422.23055 -89.552609) (xy 422.259362 -89.507123) (xy 422.294283 -89.46614) (xy 422.334619 -89.430473)
			(xy 422.379568 -89.400831) (xy 422.428238 -89.377802) (xy 422.453816 -89.369392) (xy 422.45407 -89.369392)
			(xy 422.459906 -89.367382) (xy 422.470444 -89.360964) (xy 422.474898 -89.356692) (xy 423.842688 -87.988902)
			(xy 423.848229 -87.98289) (xy 423.855481 -87.968249) (xy 423.856912 -87.9602) (xy 423.858431 -87.945781)
			(xy 423.854259 -87.917104) (xy 423.842199 -87.890753) (xy 423.823224 -87.86885) (xy 423.79886 -87.853159)
			(xy 423.77107 -87.844942) (xy 423.756582 -87.844376) (xy 423.469308 -87.844376) (xy 423.464898 -87.844468)
			(xy 423.456214 -87.846009) (xy 423.452036 -87.847424) (xy 423.443654 -87.850472) (xy 423.436796 -87.85606)
			(xy 423.434002 -87.858346) (xy 421.489632 -89.802716) (xy 421.487092 -89.806526) (xy 421.471977 -89.827742)
			(xy 421.438527 -89.867681) (xy 421.42029 -89.886282) (xy 417.210748 -94.095824) (xy 417.208043 -94.098675)
			(xy 417.203451 -94.105055) (xy 417.201604 -94.108524) (xy 417.199019 -94.11395) (xy 417.19619 -94.12563)
			(xy 417.196016 -94.131638) (xy 417.196016 -95.17126) (xy 417.19557 -95.203524) (xy 417.194306 -95.214948)
			(xy 419.939229 -95.214948) (xy 419.943184 -95.123111) (xy 419.955019 -95.031954) (xy 419.974646 -94.942151)
			(xy 420.00192 -94.854369) (xy 420.03664 -94.769255) (xy 420.078548 -94.687442) (xy 420.127334 -94.609534)
			(xy 420.182637 -94.536109) (xy 420.244047 -94.467709) (xy 420.311109 -94.404842) (xy 420.383328 -94.347972)
			(xy 420.460168 -94.297521) (xy 420.541061 -94.253862) (xy 420.625407 -94.217319) (xy 420.712583 -94.188162)
			(xy 420.801942 -94.166608) (xy 420.892823 -94.152814) (xy 420.984554 -94.146884) (xy 421.076455 -94.148862)
			(xy 421.167846 -94.158733) (xy 421.25805 -94.176423) (xy 421.346399 -94.201803) (xy 421.432239 -94.234683)
			(xy 421.514935 -94.274821) (xy 421.593875 -94.32192) (xy 421.668473 -94.37563) (xy 421.738179 -94.435554)
			(xy 421.802474 -94.501248) (xy 421.860885 -94.572226) (xy 421.912977 -94.647963) (xy 421.958366 -94.727898)
			(xy 421.996716 -94.811438) (xy 422.027741 -94.897966) (xy 422.051214 -94.986841) (xy 422.06696 -95.077405)
			(xy 422.074862 -95.168987) (xy 422.075356 -95.214948) (xy 422.074862 -95.260909) (xy 422.06696 -95.352491)
			(xy 422.051214 -95.443055) (xy 422.027741 -95.53193) (xy 421.996716 -95.618458) (xy 421.958366 -95.701998)
			(xy 421.912977 -95.781933) (xy 421.860885 -95.85767) (xy 421.802474 -95.928648) (xy 421.742773 -95.989648)
			(xy 423.864022 -95.989648) (xy 423.868093 -95.934026) (xy 423.880219 -95.879589) (xy 423.900142 -95.827498)
			(xy 423.927438 -95.778863) (xy 423.961524 -95.73472) (xy 424.001673 -95.696011) (xy 424.047031 -95.66356)
			(xy 424.096631 -95.638059) (xy 424.149415 -95.620052) (xy 424.204258 -95.609922) (xy 424.259992 -95.607885)
			(xy 424.315429 -95.613985) (xy 424.369386 -95.628091) (xy 424.420715 -95.649903) (xy 424.468321 -95.678957)
			(xy 424.511189 -95.714632) (xy 424.548406 -95.756169) (xy 424.579179 -95.802682) (xy 424.602851 -95.853179)
			(xy 424.618919 -95.906586) (xy 424.627039 -95.961762) (xy 424.627548 -95.989648) (xy 426.469554 -95.989648)
			(xy 426.473625 -95.934026) (xy 426.485751 -95.879589) (xy 426.505674 -95.827498) (xy 426.53297 -95.778863)
			(xy 426.567056 -95.73472) (xy 426.607205 -95.696011) (xy 426.652563 -95.66356) (xy 426.702163 -95.638059)
			(xy 426.754947 -95.620052) (xy 426.80979 -95.609922) (xy 426.865524 -95.607885) (xy 426.920961 -95.613985)
			(xy 426.974918 -95.628091) (xy 427.026247 -95.649903) (xy 427.073853 -95.678957) (xy 427.116721 -95.714632)
			(xy 427.153938 -95.756169) (xy 427.184711 -95.802682) (xy 427.208383 -95.853179) (xy 427.224451 -95.906586)
			(xy 427.232571 -95.961762) (xy 427.23308 -95.989648) (xy 427.232571 -96.017534) (xy 427.224451 -96.07271)
			(xy 427.208383 -96.126117) (xy 427.184711 -96.176614) (xy 427.153938 -96.223127) (xy 427.116721 -96.264664)
			(xy 427.073853 -96.300339) (xy 427.026247 -96.329393) (xy 426.974918 -96.351205) (xy 426.920961 -96.365311)
			(xy 426.865524 -96.371411) (xy 426.80979 -96.369374) (xy 426.754947 -96.359244) (xy 426.702163 -96.341237)
			(xy 426.652563 -96.315736) (xy 426.607205 -96.283285) (xy 426.567056 -96.244576) (xy 426.53297 -96.200433)
			(xy 426.505674 -96.151798) (xy 426.485751 -96.099707) (xy 426.473625 -96.04527) (xy 426.469554 -95.989648)
			(xy 424.627548 -95.989648) (xy 424.627039 -96.017534) (xy 424.618919 -96.07271) (xy 424.602851 -96.126117)
			(xy 424.579179 -96.176614) (xy 424.548406 -96.223127) (xy 424.511189 -96.264664) (xy 424.468321 -96.300339)
			(xy 424.420715 -96.329393) (xy 424.369386 -96.351205) (xy 424.315429 -96.365311) (xy 424.259992 -96.371411)
			(xy 424.204258 -96.369374) (xy 424.149415 -96.359244) (xy 424.096631 -96.341237) (xy 424.047031 -96.315736)
			(xy 424.001673 -96.283285) (xy 423.961524 -96.244576) (xy 423.927438 -96.200433) (xy 423.900142 -96.151798)
			(xy 423.880219 -96.099707) (xy 423.868093 -96.04527) (xy 423.864022 -95.989648) (xy 421.742773 -95.989648)
			(xy 421.738179 -95.994342) (xy 421.668473 -96.054266) (xy 421.593875 -96.107976) (xy 421.514935 -96.155075)
			(xy 421.432239 -96.195213) (xy 421.346399 -96.228093) (xy 421.25805 -96.253473) (xy 421.167846 -96.271163)
			(xy 421.076455 -96.281034) (xy 420.984554 -96.283012) (xy 420.892823 -96.277082) (xy 420.801942 -96.263288)
			(xy 420.712583 -96.241734) (xy 420.625407 -96.212577) (xy 420.541061 -96.176034) (xy 420.460168 -96.132375)
			(xy 420.383328 -96.081924) (xy 420.311109 -96.025054) (xy 420.244047 -95.962187) (xy 420.182637 -95.893787)
			(xy 420.127334 -95.820362) (xy 420.078548 -95.742454) (xy 420.03664 -95.660641) (xy 420.00192 -95.575527)
			(xy 419.974646 -95.487745) (xy 419.955019 -95.397942) (xy 419.943184 -95.306785) (xy 419.939229 -95.214948)
			(xy 417.194306 -95.214948) (xy 417.188473 -95.267661) (xy 417.174371 -95.330629) (xy 417.153436 -95.391667)
			(xy 417.125921 -95.450035) (xy 417.092158 -95.505026) (xy 417.052558 -95.555974) (xy 417.030408 -95.579438)
			(xy 417.002468 -95.608394) (xy 417.002468 -95.62211) (xy 417.384484 -96.003872) (xy 417.407429 -96.027427)
			(xy 417.448448 -96.078826) (xy 417.48345 -96.134498) (xy 417.511995 -96.19374) (xy 417.533722 -96.255808)
			(xy 417.548359 -96.319919) (xy 417.555722 -96.385266) (xy 417.556188 -96.418146) (xy 417.556188 -96.432624)
			(xy 417.555934 -96.438466) (xy 417.554244 -96.473069) (xy 417.543729 -96.541549) (xy 417.525209 -96.608309)
			(xy 417.498941 -96.672418) (xy 417.465292 -96.73298) (xy 417.424734 -96.789149) (xy 417.377832 -96.84014)
			(xy 417.325241 -96.885242) (xy 417.301738 -96.901) (xy 417.621972 -96.901) (xy 417.626043 -96.845378)
			(xy 417.638169 -96.790941) (xy 417.658092 -96.73885) (xy 417.685388 -96.690215) (xy 417.719474 -96.646072)
			(xy 417.759623 -96.607363) (xy 417.804981 -96.574912) (xy 417.854581 -96.549411) (xy 417.907365 -96.531404)
			(xy 417.962208 -96.521274) (xy 418.017942 -96.519237) (xy 418.073379 -96.525337) (xy 418.127336 -96.539443)
			(xy 418.178665 -96.561255) (xy 418.226271 -96.590309) (xy 418.269139 -96.625984) (xy 418.306356 -96.667521)
			(xy 418.337129 -96.714034) (xy 418.360801 -96.764531) (xy 418.376869 -96.817938) (xy 418.384989 -96.873114)
			(xy 418.385498 -96.901) (xy 418.384989 -96.928886) (xy 418.376869 -96.984062) (xy 418.360801 -97.037469)
			(xy 418.359644 -97.039938) (xy 423.025568 -97.039938) (xy 423.029639 -96.984316) (xy 423.041765 -96.929879)
			(xy 423.061688 -96.877788) (xy 423.088984 -96.829153) (xy 423.12307 -96.78501) (xy 423.163219 -96.746301)
			(xy 423.208577 -96.71385) (xy 423.258177 -96.688349) (xy 423.310961 -96.670342) (xy 423.365804 -96.660212)
			(xy 423.421538 -96.658175) (xy 423.476975 -96.664275) (xy 423.530932 -96.678381) (xy 423.582261 -96.700193)
			(xy 423.629867 -96.729247) (xy 423.672735 -96.764922) (xy 423.709952 -96.806459) (xy 423.740725 -96.852972)
			(xy 423.764397 -96.903469) (xy 423.780465 -96.956876) (xy 423.787643 -97.005648) (xy 426.469554 -97.005648)
			(xy 426.473625 -96.950026) (xy 426.485751 -96.895589) (xy 426.505674 -96.843498) (xy 426.53297 -96.794863)
			(xy 426.567056 -96.75072) (xy 426.607205 -96.712011) (xy 426.652563 -96.67956) (xy 426.702163 -96.654059)
			(xy 426.754947 -96.636052) (xy 426.80979 -96.625922) (xy 426.865524 -96.623885) (xy 426.920961 -96.629985)
			(xy 426.974918 -96.644091) (xy 427.026247 -96.665903) (xy 427.073853 -96.694957) (xy 427.116721 -96.730632)
			(xy 427.153938 -96.772169) (xy 427.184711 -96.818682) (xy 427.208383 -96.869179) (xy 427.224451 -96.922586)
			(xy 427.232571 -96.977762) (xy 427.23308 -97.005648) (xy 427.232571 -97.033534) (xy 427.224451 -97.08871)
			(xy 427.208383 -97.142117) (xy 427.184711 -97.192614) (xy 427.153938 -97.239127) (xy 427.116721 -97.280664)
			(xy 427.073853 -97.316339) (xy 427.026247 -97.345393) (xy 426.974918 -97.367205) (xy 426.920961 -97.381311)
			(xy 426.865524 -97.387411) (xy 426.80979 -97.385374) (xy 426.754947 -97.375244) (xy 426.702163 -97.357237)
			(xy 426.652563 -97.331736) (xy 426.607205 -97.299285) (xy 426.567056 -97.260576) (xy 426.53297 -97.216433)
			(xy 426.505674 -97.167798) (xy 426.485751 -97.115707) (xy 426.473625 -97.06127) (xy 426.469554 -97.005648)
			(xy 423.787643 -97.005648) (xy 423.788585 -97.012052) (xy 423.789094 -97.039938) (xy 423.788585 -97.067824)
			(xy 423.780465 -97.123) (xy 423.764397 -97.176407) (xy 423.740725 -97.226904) (xy 423.709952 -97.273417)
			(xy 423.672735 -97.314954) (xy 423.629867 -97.350629) (xy 423.582261 -97.379683) (xy 423.530932 -97.401495)
			(xy 423.476975 -97.415601) (xy 423.421538 -97.421701) (xy 423.365804 -97.419664) (xy 423.310961 -97.409534)
			(xy 423.258177 -97.391527) (xy 423.208577 -97.366026) (xy 423.163219 -97.333575) (xy 423.12307 -97.294866)
			(xy 423.088984 -97.250723) (xy 423.061688 -97.202088) (xy 423.041765 -97.149997) (xy 423.029639 -97.09556)
			(xy 423.025568 -97.039938) (xy 418.359644 -97.039938) (xy 418.337129 -97.087966) (xy 418.306356 -97.134479)
			(xy 418.269139 -97.176016) (xy 418.226271 -97.211691) (xy 418.178665 -97.240745) (xy 418.127336 -97.262557)
			(xy 418.073379 -97.276663) (xy 418.017942 -97.282763) (xy 417.962208 -97.280726) (xy 417.907365 -97.270596)
			(xy 417.854581 -97.252589) (xy 417.804981 -97.227088) (xy 417.759623 -97.194637) (xy 417.719474 -97.155928)
			(xy 417.685388 -97.111785) (xy 417.658092 -97.06315) (xy 417.638169 -97.011059) (xy 417.626043 -96.956622)
			(xy 417.621972 -96.901) (xy 417.301738 -96.901) (xy 417.267696 -96.923824) (xy 417.206001 -96.955347)
			(xy 417.141018 -96.979371) (xy 417.073654 -96.99556) (xy 417.004851 -97.003688) (xy 416.97021 -97.004124)
			(xy 416.937336 -97.003697) (xy 416.871998 -96.996366) (xy 416.807892 -96.981762) (xy 416.745826 -96.96007)
			(xy 416.686581 -96.931561) (xy 416.630902 -96.896594) (xy 416.57949 -96.855611) (xy 416.555936 -96.832674)
			(xy 416.416744 -96.693482) (xy 416.410671 -96.69272) (xy 416.398478 -96.693757) (xy 416.392614 -96.695514)
			(xy 416.383216 -96.698816) (xy 416.369246 -96.706182) (xy 416.366198 -96.708468) (xy 416.34226 -96.725572)
			(xy 416.290207 -96.752987) (xy 416.234562 -96.772087) (xy 416.176645 -96.782419) (xy 416.14725 -96.783652)
			(xy 416.146742 -96.783652) (xy 416.13836 -96.783906) (xy 416.111424 -96.783447) (xy 416.058087 -96.775879)
			(xy 416.006345 -96.760885) (xy 415.957225 -96.738763) (xy 415.911705 -96.709953) (xy 415.870689 -96.675027)
			(xy 415.834993 -96.63468) (xy 415.805326 -96.589713) (xy 415.782278 -96.541022) (xy 415.77387 -96.515428)
			(xy 415.77387 -96.515174) (xy 415.771854 -96.509342) (xy 415.765425 -96.498815) (xy 415.76117 -96.494346)
			(xy 413.29737 -94.030546) (xy 413.279259 -94.011765) (xy 413.248579 -93.969566) (xy 413.224883 -93.923085)
			(xy 413.208756 -93.873467) (xy 413.200595 -93.821936) (xy 413.200088 -93.79585) (xy 413.200088 -89.610438)
			(xy 413.192722 -89.602564) (xy 413.187642 -89.598246) (xy 413.160718 -89.574878) (xy 413.16021 -89.574624)
			(xy 413.13227 -89.550494) (xy 413.125587 -89.545854) (xy 413.110173 -89.540673) (xy 413.102044 -89.540334)
			(xy 413.095186 -89.540334) (xy 413.091884 -89.540842) (xy 413.079429 -89.542328) (xy 413.054389 -89.543856)
			(xy 413.041846 -89.54389) (xy 413.041084 -89.54389) (xy 413.013843 -89.543389) (xy 412.95992 -89.535607)
			(xy 412.907652 -89.520233) (xy 412.858103 -89.49758) (xy 412.812281 -89.468107) (xy 412.771119 -89.432416)
			(xy 412.735452 -89.391231) (xy 412.706008 -89.345391) (xy 412.683385 -89.295828) (xy 412.668043 -89.243551)
			(xy 412.660294 -89.189623) (xy 412.65983 -89.162382) (xy 412.65983 -89.16162) (xy 412.660395 -89.130827)
			(xy 412.670244 -89.070036) (xy 412.689739 -89.011618) (xy 412.703518 -88.984074) (xy 412.706208 -88.978542)
			(xy 412.709151 -88.966601) (xy 412.70936 -88.960452) (xy 412.70936 -66.917824) (xy 412.709844 -66.891736)
			(xy 412.718008 -66.840203) (xy 412.734138 -66.790583) (xy 412.757837 -66.7441) (xy 412.78852 -66.7019)
			(xy 412.806642 -66.683128) (xy 413.968946 -65.520824) (xy 413.987716 -65.50279) (xy 414.029832 -65.472205)
			(xy 414.076208 -65.448573) (xy 414.125705 -65.432474) (xy 414.17711 -65.424304) (xy 414.203134 -65.423796)
			(xy 414.839912 -65.423796) (xy 414.842706 -65.422272) (xy 414.86719 -65.409192) (xy 414.919076 -65.389468)
			(xy 414.973272 -65.377465) (xy 415.028634 -65.373436) (xy 415.083996 -65.377465) (xy 415.138192 -65.389468)
			(xy 415.190078 -65.409192) (xy 415.214562 -65.422272) (xy 415.217356 -65.423796) (xy 418.14877 -65.423796)
			(xy 418.159438 -65.42278) (xy 418.166505 -65.421027) (xy 418.179276 -65.414049) (xy 418.184584 -65.409064)
			(xy 419.733476 -63.859918) (xy 419.752257 -63.841806) (xy 419.794454 -63.811124) (xy 419.840936 -63.787428)
			(xy 419.890554 -63.771301) (xy 419.942085 -63.763143) (xy 419.968172 -63.762636) (xy 420.049452 -63.762636)
			(xy 420.058996 -63.762184) (xy 420.076741 -63.755137) (xy 420.083996 -63.74892) (xy 420.102538 -63.730632)
			(xy 420.119449 -63.714348) (xy 420.157131 -63.686349) (xy 420.198474 -63.664109) (xy 420.220394 -63.655702)
			(xy 420.221664 -63.655702) (xy 420.238174 -63.649352) (xy 420.240206 -63.64859) (xy 420.243762 -63.647574)
			(xy 420.249858 -63.646304) (xy 420.25062 -63.646304) (xy 420.255192 -63.645542) (xy 420.256462 -63.645288)
			(xy 420.257224 -63.645034) (xy 420.257732 -63.645034) (xy 420.267037 -63.642892) (xy 420.285846 -63.639587)
			(xy 420.295324 -63.63843) (xy 420.295578 -63.63843) (xy 420.298118 -63.638176) (xy 420.330122 -63.636652)
			(xy 422.467024 -63.636652) (xy 422.473628 -63.636144) (xy 422.474136 -63.636144) (xy 422.4843 -63.634279)
			(xy 422.502013 -63.623671) (xy 422.508426 -63.61557) (xy 422.514014 -63.605156) (xy 422.525698 -63.576962)
			(xy 422.525698 -63.576454) (xy 422.532048 -63.56096) (xy 422.532048 -63.560706) (xy 422.536366 -63.552324)
			(xy 422.537636 -63.550292) (xy 422.539672 -63.546525) (xy 422.542601 -63.538481) (xy 422.543478 -63.53429)
			(xy 422.543732 -63.532766) (xy 422.547796 -63.506858) (xy 422.548807 -63.499649) (xy 422.547138 -63.485192)
			(xy 422.544494 -63.47841) (xy 422.537128 -63.461392) (xy 422.53027 -63.454534) (xy 422.510357 -63.433627)
			(xy 422.476429 -63.386912) (xy 422.449931 -63.335616) (xy 422.431469 -63.280911) (xy 422.421466 -63.224049)
			(xy 422.420288 -63.1952) (xy 422.420288 -63.180468) (xy 422.42127 -63.151503) (xy 422.430911 -63.094359)
			(xy 422.449085 -63.039329) (xy 422.475373 -62.987683) (xy 422.509172 -62.940607) (xy 422.549702 -62.899185)
			(xy 422.596032 -62.864371) (xy 422.647095 -62.836965) (xy 422.701716 -62.817598) (xy 422.758637 -62.806717)
			(xy 422.787572 -62.805056) (xy 422.787826 -62.805056) (xy 422.801796 -62.804802) (xy 422.802304 -62.804802)
			(xy 422.82793 -62.805233) (xy 422.878715 -62.812133) (xy 422.928117 -62.82578) (xy 422.975242 -62.845929)
			(xy 423.01924 -62.872215) (xy 423.03954 -62.88786) (xy 423.046144 -62.89294) (xy 423.05732 -62.89675)
			(xy 423.070782 -62.898782) (xy 423.092626 -62.898782) (xy 423.098066 -62.898924) (xy 423.108698 -62.90123)
			(xy 423.113708 -62.903354) (xy 423.127424 -62.909704) (xy 423.132129 -62.911765) (xy 423.14211 -62.914188)
			(xy 423.147236 -62.91453) (xy 423.155872 -62.914022) (xy 423.163159 -62.912741) (xy 423.176586 -62.906544)
			(xy 423.182288 -62.90183) (xy 423.182542 -62.901576) (xy 423.202427 -62.884466) (xy 423.246013 -62.855273)
			(xy 423.26941 -62.84341) (xy 423.284142 -62.836552) (xy 423.288714 -62.83452) (xy 423.312051 -62.82517)
			(xy 423.360565 -62.811982) (xy 423.41039 -62.805273) (xy 423.435526 -62.804802) (xy 423.44213 -62.804802)
			(xy 423.471893 -62.805793) (xy 423.53058 -62.815878) (xy 423.55897 -62.824868) (xy 423.589955 -62.836095)
			(xy 423.647813 -62.867639) (xy 423.674032 -62.887606) (xy 423.674286 -62.88786) (xy 423.677334 -62.8904)
			(xy 423.683443 -62.894138) (xy 423.697107 -62.898402) (xy 423.704258 -62.898782) (xy 423.727626 -62.898782)
			(xy 423.733066 -62.898924) (xy 423.743698 -62.90123) (xy 423.748708 -62.903354) (xy 423.762424 -62.909704)
			(xy 423.767129 -62.911765) (xy 423.77711 -62.914188) (xy 423.782236 -62.91453) (xy 423.790872 -62.914022)
			(xy 423.798159 -62.912741) (xy 423.811586 -62.906544) (xy 423.817288 -62.90183) (xy 423.817542 -62.901576)
			(xy 423.838611 -62.883466) (xy 423.885004 -62.852899) (xy 423.935336 -62.82938) (xy 423.988546 -62.813403)
			(xy 424.04351 -62.805306) (xy 424.071288 -62.804802) (xy 424.071796 -62.804802) (xy 424.099049 -62.805265)
			(xy 424.153 -62.813022) (xy 424.205297 -62.828377) (xy 424.254877 -62.85102) (xy 424.30073 -62.880488)
			(xy 424.341923 -62.916182) (xy 424.377616 -62.957375) (xy 424.407083 -63.003228) (xy 424.429725 -63.052808)
			(xy 424.44508 -63.105106) (xy 424.452835 -63.159057) (xy 424.453304 -63.18631) (xy 424.452734 -63.216037)
			(xy 424.443507 -63.27477) (xy 424.425279 -63.33136) (xy 424.39849 -63.384437) (xy 424.363789 -63.432713)
			(xy 424.343322 -63.45428) (xy 424.343068 -63.454534) (xy 424.336718 -63.461138) (xy 424.330622 -63.4746)
			(xy 424.32859 -63.479172) (xy 424.32732 -63.482982) (xy 424.323764 -63.500508) (xy 424.32327 -63.506029)
			(xy 424.324433 -63.51705) (xy 424.32605 -63.522352) (xy 424.347894 -63.576454) (xy 424.347894 -63.576962)
			(xy 424.359324 -63.604902) (xy 424.364333 -63.615633) (xy 424.382079 -63.631272) (xy 424.39336 -63.634874)
			(xy 424.401488 -63.63716) (xy 424.40987 -63.636652) (xy 425.562776 -63.636652) (xy 425.570046 -63.636881)
			(xy 425.583987 -63.64101) (xy 425.590208 -63.64478) (xy 425.598844 -63.650368) (xy 425.63034 -63.655702)
			(xy 425.633819 -63.656142) (xy 425.640831 -63.656142) (xy 425.64431 -63.655702) (xy 425.701968 -63.598044)
			(xy 425.7066 -63.591358) (xy 425.711767 -63.575945) (xy 425.712128 -63.567818) (xy 425.712128 -58.142124)
			(xy 425.711874 -58.137044) (xy 425.710705 -58.128613) (xy 425.703572 -58.113168) (xy 425.697904 -58.106818)
			(xy 425.326556 -57.735724) (xy 425.308522 -57.716954) (xy 425.277938 -57.674838) (xy 425.254308 -57.628462)
			(xy 425.238212 -57.578965) (xy 425.230045 -57.52756) (xy 425.229528 -57.501536) (xy 425.229528 -56.577992)
			(xy 425.224915 -56.572299) (xy 425.213179 -56.563537) (xy 425.206414 -56.56072) (xy 425.16298 -56.544718)
			(xy 425.116752 -56.5277) (xy 425.109132 -56.525668) (xy 425.103373 -56.524687) (xy 425.091699 -56.52507)
			(xy 425.086018 -56.52643) (xy 425.078652 -56.528462) (xy 425.065444 -56.536844) (xy 425.060364 -56.54294)
			(xy 425.042131 -56.563794) (xy 425.000675 -56.600533) (xy 424.954343 -56.630893) (xy 424.904109 -56.654236)
			(xy 424.851027 -56.670072) (xy 424.796215 -56.678068) (xy 424.768518 -56.678576) (xy 424.741265 -56.678114)
			(xy 424.687314 -56.670359) (xy 424.635016 -56.655004) (xy 424.585435 -56.632362) (xy 424.539582 -56.602894)
			(xy 424.49839 -56.5672) (xy 424.462698 -56.526006) (xy 424.433231 -56.480152) (xy 424.410591 -56.430571)
			(xy 424.395238 -56.378272) (xy 424.387485 -56.324321) (xy 424.38701 -56.297068) (xy 424.38751 -56.269329)
			(xy 424.395546 -56.214436) (xy 424.411445 -56.161284) (xy 424.434871 -56.110994) (xy 424.465331 -56.064626)
			(xy 424.502183 -56.023155) (xy 424.54465 -55.987457) (xy 424.591838 -55.958283) (xy 424.642753 -55.936248)
			(xy 424.696321 -55.921815) (xy 424.723814 -55.9181) (xy 424.738546 -55.916576) (xy 424.768518 -55.915306)
			(xy 424.795923 -55.915806) (xy 424.850163 -55.923691) (xy 424.902722 -55.93924) (xy 424.952523 -55.962133)
			(xy 424.998544 -55.991902) (xy 425.039844 -56.027937) (xy 425.058078 -56.048402) (xy 425.059348 -56.049926)
			(xy 425.063666 -56.054244) (xy 425.070229 -56.060371) (xy 425.086499 -56.067932) (xy 425.095416 -56.068976)
			(xy 425.10091 -56.069239) (xy 425.111799 -56.067701) (xy 425.117006 -56.065928) (xy 425.127674 -56.062118)
			(xy 425.20616 -56.033416) (xy 425.216828 -56.028082) (xy 425.220434 -56.025592) (xy 425.226813 -56.019584)
			(xy 425.229528 -56.016144) (xy 425.229528 -55.11292) (xy 425.230058 -55.086897) (xy 425.238228 -55.035496)
			(xy 425.254325 -54.986001) (xy 425.277953 -54.939626) (xy 425.308532 -54.897511) (xy 425.326556 -54.878732)
			(xy 427.250606 -52.954682) (xy 427.256956 -52.944014) (xy 427.258734 -52.938172) (xy 427.267182 -52.912605)
			(xy 427.29026 -52.863957) (xy 427.319945 -52.819035) (xy 427.355649 -52.778729) (xy 427.396662 -52.743841)
			(xy 427.442171 -52.715062) (xy 427.491272 -52.692964) (xy 427.542991 -52.677985) (xy 427.596302 -52.670422)
			(xy 427.623224 -52.669948) (xy 427.650475 -52.670435) (xy 427.704423 -52.678194) (xy 427.756717 -52.693551)
			(xy 427.806294 -52.716193) (xy 427.852145 -52.745659) (xy 427.893336 -52.78135) (xy 427.929029 -52.822539)
			(xy 427.958497 -52.868388) (xy 427.981142 -52.917964) (xy 427.996501 -52.970258) (xy 428.004263 -53.024205)
			(xy 428.004732 -53.051456) (xy 428.004986 -53.051456) (xy 428.004526 -53.078391) (xy 427.996956 -53.131725)
			(xy 427.98196 -53.183465) (xy 427.959836 -53.232582) (xy 427.931025 -53.278099) (xy 427.896098 -53.319112)
			(xy 427.85575 -53.354804) (xy 427.810784 -53.384468) (xy 427.762092 -53.407512) (xy 427.736508 -53.415946)
			(xy 427.736254 -53.415946) (xy 427.730418 -53.417955) (xy 427.71988 -53.424373) (xy 427.715426 -53.428646)
			(xy 427.647521 -53.496551) (xy 432.433464 -53.496551) (xy 432.433464 -53.442049) (xy 432.44122 -53.388101)
			(xy 432.456574 -53.335806) (xy 432.479215 -53.286229) (xy 432.50868 -53.240378) (xy 432.54437 -53.199187)
			(xy 432.585559 -53.163494) (xy 432.631408 -53.134026) (xy 432.680984 -53.111383) (xy 432.733278 -53.096025)
			(xy 432.787225 -53.088265) (xy 432.814476 -53.087778) (xy 432.841847 -53.088239) (xy 432.896027 -53.096055)
			(xy 432.948531 -53.111544) (xy 432.998277 -53.134388) (xy 433.044243 -53.164115) (xy 433.065174 -53.181758)
			(xy 433.065428 -53.182012) (xy 433.07253 -53.187576) (xy 433.089435 -53.193836) (xy 433.098448 -53.194204)
			(xy 433.165504 -53.194204) (xy 433.174521 -53.193848) (xy 433.191438 -53.1876) (xy 433.198524 -53.182012)
			(xy 433.198524 -53.181758) (xy 433.198778 -53.181758) (xy 433.219702 -53.164109) (xy 433.265678 -53.1344)
			(xy 433.315427 -53.111566) (xy 433.367929 -53.096077) (xy 433.422106 -53.088251) (xy 433.449476 -53.087778)
			(xy 433.476729 -53.088268) (xy 433.530681 -53.096022) (xy 433.582979 -53.111375) (xy 433.632561 -53.134015)
			(xy 433.678415 -53.163482) (xy 433.719609 -53.199174) (xy 433.755304 -53.240366) (xy 433.784773 -53.286218)
			(xy 433.807417 -53.335798) (xy 433.822773 -53.388096) (xy 433.830531 -53.442047) (xy 433.830531 -53.496553)
			(xy 433.822773 -53.550504) (xy 433.807417 -53.602802) (xy 433.784773 -53.652382) (xy 433.755304 -53.698234)
			(xy 433.719609 -53.739426) (xy 433.678415 -53.775118) (xy 433.632561 -53.804585) (xy 433.582979 -53.827225)
			(xy 433.530681 -53.842578) (xy 433.476729 -53.850332) (xy 433.449476 -53.850794) (xy 433.422105 -53.850343)
			(xy 433.367925 -53.842522) (xy 433.315422 -53.827029) (xy 433.265675 -53.804184) (xy 433.219709 -53.774457)
			(xy 433.198778 -53.756814) (xy 433.198524 -53.75656) (xy 433.191438 -53.750972) (xy 433.174521 -53.744727)
			(xy 433.165504 -53.744368) (xy 433.098448 -53.744368) (xy 433.089434 -53.744755) (xy 433.072517 -53.750982)
			(xy 433.065428 -53.75656) (xy 433.065428 -53.756814) (xy 433.065174 -53.756814) (xy 433.044227 -53.774434)
			(xy 432.998258 -53.804148) (xy 432.948514 -53.826988) (xy 432.896017 -53.842483) (xy 432.841844 -53.850317)
			(xy 432.814476 -53.850794) (xy 432.787225 -53.850335) (xy 432.733278 -53.842575) (xy 432.680984 -53.827217)
			(xy 432.631408 -53.804574) (xy 432.585559 -53.775106) (xy 432.54437 -53.739413) (xy 432.50868 -53.698222)
			(xy 432.479215 -53.652371) (xy 432.456574 -53.602794) (xy 432.44122 -53.550499) (xy 432.433464 -53.496551)
			(xy 427.647521 -53.496551) (xy 427.12513 -54.018942) (xy 426.154819 -54.989051) (xy 430.201068 -54.989051)
			(xy 430.201068 -54.934549) (xy 430.208824 -54.880603) (xy 430.224178 -54.828309) (xy 430.246817 -54.778733)
			(xy 430.276281 -54.732882) (xy 430.311971 -54.691692) (xy 430.353158 -54.655999) (xy 430.399006 -54.626532)
			(xy 430.448581 -54.603888) (xy 430.500874 -54.58853) (xy 430.554819 -54.58077) (xy 430.58207 -54.580282)
			(xy 430.610161 -54.580801) (xy 430.665737 -54.589023) (xy 430.719505 -54.60531) (xy 430.770303 -54.629309)
			(xy 430.81703 -54.6605) (xy 430.858675 -54.698209) (xy 430.894339 -54.741619) (xy 430.909222 -54.765448)
			(xy 430.914556 -54.774338) (xy 430.931574 -54.78653) (xy 431.024792 -54.80685) (xy 431.045366 -54.802532)
			(xy 431.054002 -54.79669) (xy 431.078063 -54.780686) (xy 431.129996 -54.755344) (xy 431.185154 -54.73812)
			(xy 431.242279 -54.729406) (xy 431.271172 -54.728872) (xy 431.298423 -54.729381) (xy 431.352371 -54.737134)
			(xy 431.404667 -54.752485) (xy 431.454246 -54.775123) (xy 431.500098 -54.804586) (xy 431.541291 -54.840275)
			(xy 431.576985 -54.881463) (xy 431.606454 -54.927312) (xy 431.629098 -54.976888) (xy 431.644456 -55.029182)
			(xy 431.652215 -55.083129) (xy 431.65268 -55.11038) (xy 431.652207 -55.13775) (xy 431.644392 -55.191929)
			(xy 431.628904 -55.244432) (xy 431.606064 -55.294179) (xy 431.576341 -55.340146) (xy 431.5587 -55.361078)
			(xy 431.558446 -55.361332) (xy 431.552875 -55.368429) (xy 431.54662 -55.385338) (xy 431.546254 -55.394352)
			(xy 431.546254 -55.461408) (xy 431.546596 -55.470427) (xy 431.552853 -55.487344) (xy 431.558446 -55.494428)
			(xy 431.5587 -55.494428) (xy 431.5587 -55.494682) (xy 431.57632 -55.515631) (xy 431.606044 -55.561597)
			(xy 431.628888 -55.61134) (xy 431.644385 -55.66384) (xy 431.652215 -55.718016) (xy 431.652217 -55.772754)
			(xy 431.644392 -55.826931) (xy 431.628899 -55.879431) (xy 431.606058 -55.929177) (xy 431.576338 -55.975145)
			(xy 431.5587 -55.996078) (xy 431.558446 -55.996332) (xy 431.552875 -56.003429) (xy 431.54662 -56.020338)
			(xy 431.546254 -56.029352) (xy 431.546254 -56.096408) (xy 431.546596 -56.105427) (xy 431.552853 -56.122344)
			(xy 431.558446 -56.129428) (xy 431.5587 -56.129428) (xy 431.5587 -56.129682) (xy 431.576344 -56.15061)
			(xy 431.606055 -56.196584) (xy 431.62889 -56.246332) (xy 431.64438 -56.298834) (xy 431.652207 -56.353011)
			(xy 431.65268 -56.38038) (xy 431.652194 -56.407631) (xy 431.644438 -56.461579) (xy 431.629083 -56.513874)
			(xy 431.606441 -56.563451) (xy 431.576975 -56.609301) (xy 431.541284 -56.650492) (xy 431.500093 -56.686183)
			(xy 431.454243 -56.715649) (xy 431.404666 -56.738291) (xy 431.352371 -56.753646) (xy 431.298423 -56.761402)
			(xy 431.243921 -56.761402) (xy 431.189973 -56.753646) (xy 431.137678 -56.738291) (xy 431.088101 -56.715649)
			(xy 431.042251 -56.686183) (xy 431.00106 -56.650492) (xy 430.965369 -56.609301) (xy 430.935903 -56.563451)
			(xy 430.913261 -56.513874) (xy 430.897906 -56.461579) (xy 430.89015 -56.407631) (xy 430.889664 -56.38038)
			(xy 430.890103 -56.353009) (xy 430.897925 -56.298828) (xy 430.913419 -56.246324) (xy 430.936268 -56.196577)
			(xy 430.965999 -56.150612) (xy 430.983644 -56.129682) (xy 430.983898 -56.129428) (xy 430.989479 -56.122337)
			(xy 430.995729 -56.105424) (xy 430.99609 -56.096408) (xy 430.99609 -56.029352) (xy 430.99571 -56.020337)
			(xy 430.989479 -56.00342) (xy 430.983898 -55.996332) (xy 430.983644 -55.996332) (xy 430.983644 -55.996078)
			(xy 430.965983 -55.975161) (xy 430.936258 -55.929191) (xy 430.913412 -55.879442) (xy 430.897917 -55.826938)
			(xy 430.89009 -55.772757) (xy 430.890092 -55.718013) (xy 430.897923 -55.663833) (xy 430.913423 -55.611329)
			(xy 430.936272 -55.561582) (xy 430.966001 -55.515614) (xy 430.983644 -55.494682) (xy 430.983898 -55.494428)
			(xy 430.989479 -55.487337) (xy 430.995729 -55.470424) (xy 430.99609 -55.461408) (xy 430.99609 -55.394352)
			(xy 430.99571 -55.385337) (xy 430.989479 -55.36842) (xy 430.983898 -55.361332) (xy 430.983644 -55.360824)
			(xy 430.972697 -55.348092) (xy 430.952858 -55.320999) (xy 430.94402 -55.306722) (xy 430.938686 -55.297832)
			(xy 430.921668 -55.28564) (xy 430.82845 -55.26532) (xy 430.807876 -55.269638) (xy 430.79924 -55.27548)
			(xy 430.775165 -55.291463) (xy 430.723238 -55.31681) (xy 430.668083 -55.334041) (xy 430.610962 -55.342761)
			(xy 430.58207 -55.343298) (xy 430.554819 -55.34283) (xy 430.500874 -55.33507) (xy 430.448581 -55.319712)
			(xy 430.399006 -55.297068) (xy 430.353158 -55.267601) (xy 430.311971 -55.231908) (xy 430.276281 -55.190718)
			(xy 430.246817 -55.144867) (xy 430.224178 -55.095291) (xy 430.208824 -55.042997) (xy 430.201068 -54.989051)
			(xy 426.154819 -54.989051) (xy 425.907708 -55.23611) (xy 425.902896 -55.241289) (xy 425.896075 -55.253665)
			(xy 425.894246 -55.260494) (xy 425.892976 -55.271924) (xy 425.892976 -55.722266) (xy 426.13402 -55.722266)
			(xy 426.138091 -55.666644) (xy 426.150217 -55.612207) (xy 426.17014 -55.560116) (xy 426.197436 -55.511481)
			(xy 426.231522 -55.467338) (xy 426.271671 -55.428629) (xy 426.317029 -55.396178) (xy 426.366629 -55.370677)
			(xy 426.419413 -55.35267) (xy 426.474256 -55.34254) (xy 426.52999 -55.340503) (xy 426.585427 -55.346603)
			(xy 426.639384 -55.360709) (xy 426.690713 -55.382521) (xy 426.738319 -55.411575) (xy 426.749465 -55.420851)
			(xy 428.524668 -55.420851) (xy 428.524668 -55.366349) (xy 428.532424 -55.312403) (xy 428.547778 -55.260109)
			(xy 428.570417 -55.210533) (xy 428.599881 -55.164682) (xy 428.635571 -55.123492) (xy 428.676758 -55.087799)
			(xy 428.722606 -55.058332) (xy 428.772181 -55.035688) (xy 428.824474 -55.02033) (xy 428.878419 -55.01257)
			(xy 428.90567 -55.012082) (xy 428.931985 -55.012509) (xy 428.984115 -55.019753) (xy 429.034759 -55.03408)
			(xy 429.082957 -55.05522) (xy 429.1278 -55.082773) (xy 429.168438 -55.116218) (xy 429.186594 -55.135272)
			(xy 429.19412 -55.142669) (xy 429.213396 -55.151197) (xy 429.223932 -55.151782) (xy 429.298608 -55.151782)
			(xy 429.30916 -55.151276) (xy 429.328456 -55.142725) (xy 429.335946 -55.135272) (xy 429.354081 -55.116196)
			(xy 429.394716 -55.082742) (xy 429.43956 -55.055186) (xy 429.487765 -55.034051) (xy 429.538416 -55.019738)
			(xy 429.590553 -55.012518) (xy 429.61687 -55.012082) (xy 429.644124 -55.012563) (xy 429.698076 -55.020317)
			(xy 429.750376 -55.03567) (xy 429.799959 -55.05831) (xy 429.845815 -55.087776) (xy 429.88701 -55.123469)
			(xy 429.922706 -55.164661) (xy 429.952176 -55.210515) (xy 429.97482 -55.260095) (xy 429.990177 -55.312394)
			(xy 429.997935 -55.366347) (xy 429.997935 -55.420854) (xy 429.990177 -55.474806) (xy 429.97482 -55.527105)
			(xy 429.952176 -55.576685) (xy 429.922706 -55.622539) (xy 429.88701 -55.663731) (xy 429.845815 -55.699424)
			(xy 429.799959 -55.72889) (xy 429.750376 -55.75153) (xy 429.698076 -55.766883) (xy 429.644124 -55.774637)
			(xy 429.61687 -55.775098) (xy 429.590555 -55.774651) (xy 429.538426 -55.767412) (xy 429.487783 -55.753089)
			(xy 429.439584 -55.731953) (xy 429.394741 -55.704403) (xy 429.354102 -55.670961) (xy 429.335946 -55.651908)
			(xy 429.328445 -55.644482) (xy 429.309149 -55.635971) (xy 429.298608 -55.635398) (xy 429.223932 -55.635398)
			(xy 429.213383 -55.635932) (xy 429.194087 -55.644464) (xy 429.186594 -55.651908) (xy 429.168436 -55.670961)
			(xy 429.127807 -55.704418) (xy 429.082967 -55.731977) (xy 429.034767 -55.753116) (xy 428.98412 -55.767434)
			(xy 428.931986 -55.774659) (xy 428.90567 -55.775098) (xy 428.878419 -55.77463) (xy 428.824474 -55.76687)
			(xy 428.772181 -55.751512) (xy 428.722606 -55.728868) (xy 428.676758 -55.699401) (xy 428.635571 -55.663708)
			(xy 428.599881 -55.622518) (xy 428.570417 -55.576667) (xy 428.547778 -55.527091) (xy 428.532424 -55.474797)
			(xy 428.524668 -55.420851) (xy 426.749465 -55.420851) (xy 426.781187 -55.44725) (xy 426.818404 -55.488787)
			(xy 426.849177 -55.5353) (xy 426.872849 -55.585797) (xy 426.888917 -55.639204) (xy 426.897037 -55.69438)
			(xy 426.897546 -55.722266) (xy 426.897037 -55.750152) (xy 426.888917 -55.805328) (xy 426.872849 -55.858735)
			(xy 426.849177 -55.909232) (xy 426.818404 -55.955745) (xy 426.781187 -55.997282) (xy 426.738319 -56.032957)
			(xy 426.690713 -56.062011) (xy 426.639384 -56.083823) (xy 426.585427 -56.097929) (xy 426.52999 -56.104029)
			(xy 426.474256 -56.101992) (xy 426.419413 -56.091862) (xy 426.366629 -56.073855) (xy 426.317029 -56.048354)
			(xy 426.271671 -56.015903) (xy 426.231522 -55.977194) (xy 426.197436 -55.933051) (xy 426.17014 -55.884416)
			(xy 426.150217 -55.832325) (xy 426.138091 -55.777888) (xy 426.13402 -55.722266) (xy 425.892976 -55.722266)
			(xy 425.892976 -56.615584) (xy 425.895652 -56.618937) (xy 425.901908 -56.624807) (xy 425.905422 -56.627268)
			(xy 425.969938 -56.670448) (xy 425.972224 -56.671972) (xy 425.977967 -56.675133) (xy 425.99057 -56.678721)
			(xy 425.997116 -56.679084) (xy 426.023024 -56.679084) (xy 426.03166 -56.675782) (xy 426.053385 -56.667848)
			(xy 426.098268 -56.656686) (xy 426.144171 -56.651021) (xy 426.167296 -56.650636) (xy 426.167804 -56.650636)
			(xy 426.195745 -56.651125) (xy 426.251027 -56.659281) (xy 426.304528 -56.675416) (xy 426.355102 -56.699187)
			(xy 426.401665 -56.730083) (xy 426.443221 -56.767444) (xy 426.47888 -56.810469) (xy 426.507878 -56.858237)
			(xy 426.529595 -56.909726) (xy 426.53712 -56.93664) (xy 426.538898 -56.943498) (xy 426.5422 -56.949086)
			(xy 426.54982 -56.958992) (xy 426.710856 -57.120028) (xy 426.728311 -57.138215) (xy 426.757914 -57.179013)
			(xy 426.780789 -57.223931) (xy 426.796376 -57.271867) (xy 426.804294 -57.321647) (xy 426.804836 -57.34685)
			(xy 426.804836 -57.48528) (xy 430.905918 -57.48528) (xy 430.909989 -57.429658) (xy 430.922115 -57.375221)
			(xy 430.942038 -57.32313) (xy 430.969334 -57.274495) (xy 431.00342 -57.230352) (xy 431.043569 -57.191643)
			(xy 431.088927 -57.159192) (xy 431.138527 -57.133691) (xy 431.191311 -57.115684) (xy 431.246154 -57.105554)
			(xy 431.301888 -57.103517) (xy 431.357325 -57.109617) (xy 431.411282 -57.123723) (xy 431.462611 -57.145535)
			(xy 431.510217 -57.174589) (xy 431.553085 -57.210264) (xy 431.590302 -57.251801) (xy 431.621075 -57.298314)
			(xy 431.644747 -57.348811) (xy 431.660815 -57.402218) (xy 431.668935 -57.457394) (xy 431.669444 -57.48528)
			(xy 431.668935 -57.513166) (xy 431.660815 -57.568342) (xy 431.644747 -57.621749) (xy 431.621075 -57.672246)
			(xy 431.590302 -57.718759) (xy 431.553085 -57.760296) (xy 431.510217 -57.795971) (xy 431.462611 -57.825025)
			(xy 431.411282 -57.846837) (xy 431.357325 -57.860943) (xy 431.301888 -57.867043) (xy 431.246154 -57.865006)
			(xy 431.191311 -57.854876) (xy 431.138527 -57.836869) (xy 431.088927 -57.811368) (xy 431.043569 -57.778917)
			(xy 431.00342 -57.740208) (xy 430.969334 -57.696065) (xy 430.942038 -57.64743) (xy 430.922115 -57.595339)
			(xy 430.909989 -57.540902) (xy 430.905918 -57.48528) (xy 426.804836 -57.48528) (xy 426.804836 -57.67959)
			(xy 426.805262 -57.68868) (xy 426.811715 -57.705681) (xy 426.823702 -57.719355) (xy 426.831506 -57.72404)
			(xy 426.834554 -57.725564) (xy 426.858597 -57.737112) (xy 426.903502 -57.765891) (xy 426.943967 -57.800638)
			(xy 426.979205 -57.840676) (xy 427.008529 -57.885228) (xy 427.031369 -57.933426) (xy 427.039786 -57.958736)
			(xy 427.039786 -57.959244) (xy 427.041832 -57.964905) (xy 427.04812 -57.975167) (xy 427.052232 -57.979564)
			(xy 427.624748 -58.55208) (xy 427.633533 -58.561224) (xy 432.862226 -58.561224) (xy 432.866297 -58.505602)
			(xy 432.878423 -58.451165) (xy 432.898346 -58.399074) (xy 432.925642 -58.350439) (xy 432.959728 -58.306296)
			(xy 432.999877 -58.267587) (xy 433.045235 -58.235136) (xy 433.094835 -58.209635) (xy 433.147619 -58.191628)
			(xy 433.202462 -58.181498) (xy 433.258196 -58.179461) (xy 433.313633 -58.185561) (xy 433.36759 -58.199667)
			(xy 433.418919 -58.221479) (xy 433.466525 -58.250533) (xy 433.509393 -58.286208) (xy 433.54661 -58.327745)
			(xy 433.577383 -58.374258) (xy 433.601055 -58.424755) (xy 433.617123 -58.478162) (xy 433.625243 -58.533338)
			(xy 433.625752 -58.561224) (xy 433.625243 -58.58911) (xy 433.617123 -58.644286) (xy 433.601055 -58.697693)
			(xy 433.577383 -58.74819) (xy 433.54661 -58.794703) (xy 433.509393 -58.83624) (xy 433.466525 -58.871915)
			(xy 433.418919 -58.900969) (xy 433.36759 -58.922781) (xy 433.313633 -58.936887) (xy 433.258196 -58.942987)
			(xy 433.202462 -58.94095) (xy 433.147619 -58.93082) (xy 433.094835 -58.912813) (xy 433.045235 -58.887312)
			(xy 432.999877 -58.854861) (xy 432.959728 -58.816152) (xy 432.925642 -58.772009) (xy 432.898346 -58.723374)
			(xy 432.878423 -58.671283) (xy 432.866297 -58.616846) (xy 432.862226 -58.561224) (xy 427.633533 -58.561224)
			(xy 427.642782 -58.57085) (xy 427.673365 -58.612966) (xy 427.696994 -58.659342) (xy 427.713089 -58.70884)
			(xy 427.721255 -58.760244) (xy 427.721776 -58.786268) (xy 427.721776 -59.174634) (xy 431.39309 -59.174634)
			(xy 431.397161 -59.119012) (xy 431.409287 -59.064575) (xy 431.42921 -59.012484) (xy 431.456506 -58.963849)
			(xy 431.490592 -58.919706) (xy 431.530741 -58.880997) (xy 431.576099 -58.848546) (xy 431.625699 -58.823045)
			(xy 431.678483 -58.805038) (xy 431.733326 -58.794908) (xy 431.78906 -58.792871) (xy 431.844497 -58.798971)
			(xy 431.898454 -58.813077) (xy 431.949783 -58.834889) (xy 431.997389 -58.863943) (xy 432.040257 -58.899618)
			(xy 432.077474 -58.941155) (xy 432.108247 -58.987668) (xy 432.131919 -59.038165) (xy 432.147987 -59.091572)
			(xy 432.156107 -59.146748) (xy 432.156616 -59.174634) (xy 432.156107 -59.20252) (xy 432.147987 -59.257696)
			(xy 432.131919 -59.311103) (xy 432.108247 -59.3616) (xy 432.077474 -59.408113) (xy 432.040257 -59.44965)
			(xy 431.997389 -59.485325) (xy 431.949783 -59.514379) (xy 431.898454 -59.536191) (xy 431.844497 -59.550297)
			(xy 431.78906 -59.556397) (xy 431.733326 -59.55436) (xy 431.678483 -59.54423) (xy 431.625699 -59.526223)
			(xy 431.576099 -59.500722) (xy 431.530741 -59.468271) (xy 431.490592 -59.429562) (xy 431.456506 -59.385419)
			(xy 431.42921 -59.336784) (xy 431.409287 -59.284693) (xy 431.397161 -59.230256) (xy 431.39309 -59.174634)
			(xy 427.721776 -59.174634) (xy 427.721776 -60.633356) (xy 434.09692 -60.633356) (xy 434.100991 -60.577734)
			(xy 434.113117 -60.523297) (xy 434.13304 -60.471206) (xy 434.160336 -60.422571) (xy 434.194422 -60.378428)
			(xy 434.234571 -60.339719) (xy 434.279929 -60.307268) (xy 434.329529 -60.281767) (xy 434.382313 -60.26376)
			(xy 434.437156 -60.25363) (xy 434.49289 -60.251593) (xy 434.548327 -60.257693) (xy 434.602284 -60.271799)
			(xy 434.653613 -60.293611) (xy 434.701219 -60.322665) (xy 434.744087 -60.35834) (xy 434.781304 -60.399877)
			(xy 434.812077 -60.44639) (xy 434.835749 -60.496887) (xy 434.851817 -60.550294) (xy 434.859937 -60.60547)
			(xy 434.860446 -60.633356) (xy 434.859937 -60.661242) (xy 434.851817 -60.716418) (xy 434.835749 -60.769825)
			(xy 434.812077 -60.820322) (xy 434.781304 -60.866835) (xy 434.744087 -60.908372) (xy 434.701219 -60.944047)
			(xy 434.653613 -60.973101) (xy 434.602284 -60.994913) (xy 434.548327 -61.009019) (xy 434.49289 -61.015119)
			(xy 434.437156 -61.013082) (xy 434.382313 -61.002952) (xy 434.329529 -60.984945) (xy 434.279929 -60.959444)
			(xy 434.234571 -60.926993) (xy 434.194422 -60.888284) (xy 434.160336 -60.844141) (xy 434.13304 -60.795506)
			(xy 434.113117 -60.743415) (xy 434.100991 -60.688978) (xy 434.09692 -60.633356) (xy 427.721776 -60.633356)
			(xy 427.721776 -61.487812) (xy 432.604416 -61.487812) (xy 432.608487 -61.43219) (xy 432.620613 -61.377753)
			(xy 432.640536 -61.325662) (xy 432.667832 -61.277027) (xy 432.701918 -61.232884) (xy 432.742067 -61.194175)
			(xy 432.787425 -61.161724) (xy 432.837025 -61.136223) (xy 432.889809 -61.118216) (xy 432.944652 -61.108086)
			(xy 433.000386 -61.106049) (xy 433.055823 -61.112149) (xy 433.10978 -61.126255) (xy 433.161109 -61.148067)
			(xy 433.208715 -61.177121) (xy 433.251583 -61.212796) (xy 433.2888 -61.254333) (xy 433.319573 -61.300846)
			(xy 433.343245 -61.351343) (xy 433.359313 -61.40475) (xy 433.367433 -61.459926) (xy 433.367942 -61.487812)
			(xy 433.367433 -61.515698) (xy 433.359313 -61.570874) (xy 433.343245 -61.624281) (xy 433.319573 -61.674778)
			(xy 433.2888 -61.721291) (xy 433.251583 -61.762828) (xy 433.208715 -61.798503) (xy 433.161109 -61.827557)
			(xy 433.10978 -61.849369) (xy 433.055823 -61.863475) (xy 433.000386 -61.869575) (xy 432.944652 -61.867538)
			(xy 432.889809 -61.857408) (xy 432.837025 -61.839401) (xy 432.787425 -61.8139) (xy 432.742067 -61.781449)
			(xy 432.701918 -61.74274) (xy 432.667832 -61.698597) (xy 432.640536 -61.649962) (xy 432.620613 -61.597871)
			(xy 432.608487 -61.543434) (xy 432.604416 -61.487812) (xy 427.721776 -61.487812) (xy 427.721776 -62.121034)
			(xy 430.54219 -62.121034) (xy 430.546261 -62.065412) (xy 430.558387 -62.010975) (xy 430.57831 -61.958884)
			(xy 430.605606 -61.910249) (xy 430.639692 -61.866106) (xy 430.679841 -61.827397) (xy 430.725199 -61.794946)
			(xy 430.774799 -61.769445) (xy 430.827583 -61.751438) (xy 430.882426 -61.741308) (xy 430.93816 -61.739271)
			(xy 430.993597 -61.745371) (xy 431.047554 -61.759477) (xy 431.098883 -61.781289) (xy 431.146489 -61.810343)
			(xy 431.189357 -61.846018) (xy 431.226574 -61.887555) (xy 431.257347 -61.934068) (xy 431.281019 -61.984565)
			(xy 431.297087 -62.037972) (xy 431.305207 -62.093148) (xy 431.305716 -62.121034) (xy 431.305207 -62.14892)
			(xy 431.297087 -62.204096) (xy 431.281019 -62.257503) (xy 431.257347 -62.308) (xy 431.226574 -62.354513)
			(xy 431.189357 -62.39605) (xy 431.146489 -62.431725) (xy 431.098883 -62.460779) (xy 431.047554 -62.482591)
			(xy 430.993597 -62.496697) (xy 430.93816 -62.502797) (xy 430.882426 -62.50076) (xy 430.827583 -62.49063)
			(xy 430.774799 -62.472623) (xy 430.725199 -62.447122) (xy 430.679841 -62.414671) (xy 430.639692 -62.375962)
			(xy 430.605606 -62.331819) (xy 430.57831 -62.283184) (xy 430.558387 -62.231093) (xy 430.546261 -62.176656)
			(xy 430.54219 -62.121034) (xy 427.721776 -62.121034) (xy 427.721776 -62.707012) (xy 427.725102 -62.711211)
			(xy 427.733167 -62.718257) (xy 427.737778 -62.720982) (xy 427.812962 -62.762892) (xy 427.82109 -62.766448)
			(xy 427.828328 -62.768644) (xy 427.843436 -62.769158) (xy 427.850808 -62.767464) (xy 427.85157 -62.76721)
			(xy 427.859952 -62.764924) (xy 427.860206 -62.76467) (xy 427.86681 -62.762892) (xy 427.872652 -62.759336)
			(xy 427.895009 -62.746394) (xy 427.942465 -62.725988) (xy 427.992238 -62.712162) (xy 428.04342 -62.705168)
			(xy 428.069248 -62.704726) (xy 428.078392 -62.704726) (xy 428.10523 -62.705803) (xy 428.158223 -62.714561)
			(xy 428.209463 -62.730666) (xy 428.257938 -62.753799) (xy 428.302688 -62.783503) (xy 428.34283 -62.81919)
			(xy 428.377568 -62.860156) (xy 428.406217 -62.905589) (xy 428.42821 -62.954592) (xy 428.443111 -63.006195)
			(xy 428.450626 -63.059378) (xy 428.45101 -63.086234) (xy 428.450522 -63.113484) (xy 428.442761 -63.167428)
			(xy 428.427403 -63.219719) (xy 428.40476 -63.269292) (xy 428.402099 -63.273432) (xy 429.87671 -63.273432)
			(xy 429.880781 -63.21781) (xy 429.892907 -63.163373) (xy 429.91283 -63.111282) (xy 429.940126 -63.062647)
			(xy 429.974212 -63.018504) (xy 430.014361 -62.979795) (xy 430.059719 -62.947344) (xy 430.109319 -62.921843)
			(xy 430.162103 -62.903836) (xy 430.216946 -62.893706) (xy 430.27268 -62.891669) (xy 430.328117 -62.897769)
			(xy 430.382074 -62.911875) (xy 430.433403 -62.933687) (xy 430.481009 -62.962741) (xy 430.523877 -62.998416)
			(xy 430.561094 -63.039953) (xy 430.591867 -63.086466) (xy 430.615539 -63.136963) (xy 430.631607 -63.19037)
			(xy 430.639727 -63.245546) (xy 430.640236 -63.273432) (xy 430.639727 -63.301318) (xy 430.631607 -63.356494)
			(xy 430.615539 -63.409901) (xy 430.591867 -63.460398) (xy 430.561094 -63.506911) (xy 430.523877 -63.548448)
			(xy 430.481009 -63.584123) (xy 430.433403 -63.613177) (xy 430.382074 -63.634989) (xy 430.328117 -63.649095)
			(xy 430.27268 -63.655195) (xy 430.216946 -63.653158) (xy 430.162103 -63.643028) (xy 430.109319 -63.625021)
			(xy 430.059719 -63.59952) (xy 430.014361 -63.567069) (xy 429.974212 -63.52836) (xy 429.940126 -63.484217)
			(xy 429.91283 -63.435582) (xy 429.892907 -63.383491) (xy 429.880781 -63.329054) (xy 429.87671 -63.273432)
			(xy 428.402099 -63.273432) (xy 428.375293 -63.315138) (xy 428.339602 -63.356324) (xy 428.298412 -63.392012)
			(xy 428.252564 -63.421476) (xy 428.202989 -63.444115) (xy 428.150697 -63.459468) (xy 428.096752 -63.467224)
			(xy 428.069502 -63.467742) (xy 428.069248 -63.467742) (xy 428.043418 -63.467314) (xy 427.992232 -63.460338)
			(xy 427.942458 -63.446506) (xy 427.895011 -63.426073) (xy 427.872652 -63.413132) (xy 427.870366 -63.411608)
			(xy 427.86681 -63.409576) (xy 427.8503 -63.40475) (xy 427.84143 -63.402978) (xy 427.823472 -63.405051)
			(xy 427.815248 -63.408814) (xy 427.802294 -63.415926) (xy 427.737778 -63.451486) (xy 427.733156 -63.454196)
			(xy 427.725085 -63.461242) (xy 427.721776 -63.465456) (xy 427.721776 -65.124076) (xy 432.407312 -65.124076)
			(xy 432.411383 -65.068454) (xy 432.423509 -65.014017) (xy 432.443432 -64.961926) (xy 432.470728 -64.913291)
			(xy 432.504814 -64.869148) (xy 432.544963 -64.830439) (xy 432.590321 -64.797988) (xy 432.639921 -64.772487)
			(xy 432.692705 -64.75448) (xy 432.747548 -64.74435) (xy 432.803282 -64.742313) (xy 432.858719 -64.748413)
			(xy 432.912676 -64.762519) (xy 432.964005 -64.784331) (xy 433.011611 -64.813385) (xy 433.054479 -64.84906)
			(xy 433.091696 -64.890597) (xy 433.122469 -64.93711) (xy 433.146141 -64.987607) (xy 433.162209 -65.041014)
			(xy 433.170329 -65.09619) (xy 433.170838 -65.124076) (xy 433.170329 -65.151962) (xy 433.162209 -65.207138)
			(xy 433.146141 -65.260545) (xy 433.122469 -65.311042) (xy 433.091696 -65.357555) (xy 433.054479 -65.399092)
			(xy 433.011611 -65.434767) (xy 432.964005 -65.463821) (xy 432.912676 -65.485633) (xy 432.858719 -65.499739)
			(xy 432.803282 -65.505839) (xy 432.747548 -65.503802) (xy 432.692705 -65.493672) (xy 432.639921 -65.475665)
			(xy 432.590321 -65.450164) (xy 432.544963 -65.417713) (xy 432.504814 -65.379004) (xy 432.470728 -65.334861)
			(xy 432.443432 -65.286226) (xy 432.423509 -65.234135) (xy 432.411383 -65.179698) (xy 432.407312 -65.124076)
			(xy 427.721776 -65.124076) (xy 427.721776 -70.836536) (xy 427.726602 -70.842124) (xy 428.255684 -71.371206)
			(xy 428.261116 -71.376182) (xy 428.274158 -71.383018) (xy 428.281338 -71.384668) (xy 428.281846 -71.384668)
			(xy 428.291244 -71.385684) (xy 431.019712 -71.385684) (xy 431.02784 -71.384922) (xy 431.028348 -71.384922)
			(xy 431.035866 -71.38332) (xy 431.049553 -71.376343) (xy 431.055272 -71.371206) (xy 434.56098 -67.865498)
			(xy 434.565968 -67.860071) (xy 434.572828 -67.847034) (xy 434.574442 -67.839844) (xy 434.574442 -67.839336)
			(xy 434.575458 -67.829938) (xy 434.575458 -66.927476) (xy 434.575458 -66.926968) (xy 434.577236 -66.913252)
			(xy 434.579268 -66.906648) (xy 434.579268 -63.136272) (xy 434.57876 -63.135002) (xy 434.568854 -63.127636)
			(xy 434.5686 -63.127636) (xy 434.521356 -63.092076) (xy 434.502814 -63.078106) (xy 434.50129 -63.07709)
			(xy 434.495702 -63.074042) (xy 434.48966 -63.071328) (xy 434.476669 -63.068763) (xy 434.470048 -63.068962)
			(xy 434.462682 -63.069978) (xy 434.45811 -63.071248) (xy 434.431128 -63.078878) (xy 434.375656 -63.087044)
			(xy 434.34762 -63.087504) (xy 434.347112 -63.087504) (xy 434.319859 -63.087041) (xy 434.265907 -63.079286)
			(xy 434.213608 -63.063931) (xy 434.164026 -63.041289) (xy 434.118172 -63.011821) (xy 434.076978 -62.976128)
			(xy 434.041284 -62.934934) (xy 434.011815 -62.889081) (xy 433.989172 -62.8395) (xy 433.973816 -62.787201)
			(xy 433.966059 -62.733249) (xy 433.965604 -62.705996) (xy 433.966089 -62.678768) (xy 433.973833 -62.624866)
			(xy 433.989163 -62.572613) (xy 434.011767 -62.523071) (xy 434.041187 -62.477247) (xy 434.076823 -62.436071)
			(xy 434.117953 -62.400382) (xy 434.163739 -62.370903) (xy 434.213252 -62.348235) (xy 434.265485 -62.332838)
			(xy 434.319377 -62.325024) (xy 434.346604 -62.324488) (xy 434.348636 -62.324488) (xy 434.373187 -62.324983)
			(xy 434.421859 -62.331501) (xy 434.469297 -62.344195) (xy 434.492146 -62.35319) (xy 434.496718 -62.354968)
			(xy 434.506624 -62.357) (xy 434.514454 -62.358327) (xy 434.530235 -62.35664) (xy 434.537612 -62.353698)
			(xy 434.537866 -62.353444) (xy 434.542184 -62.351412) (xy 434.547889 -62.348) (xy 434.557419 -62.338737)
			(xy 434.56098 -62.333124) (xy 434.563774 -62.327028) (xy 434.575204 -62.300358) (xy 434.57665 -62.296821)
			(xy 434.578558 -62.289421) (xy 434.579014 -62.285626) (xy 434.579268 -62.280546) (xy 434.579268 -62.24016)
			(xy 434.576474 -62.234826) (xy 434.568567 -62.220001) (xy 434.555086 -62.189222) (xy 434.54955 -62.173358)
			(xy 434.540369 -62.144361) (xy 434.530283 -62.084383) (xy 434.529484 -62.053978) (xy 434.529484 -62.04712)
			(xy 434.530247 -62.020218) (xy 434.538407 -61.967022) (xy 434.553961 -61.915501) (xy 434.576601 -61.866677)
			(xy 434.605878 -61.821519) (xy 434.641209 -61.780923) (xy 434.681895 -61.745694) (xy 434.727127 -61.716533)
			(xy 434.776009 -61.694017) (xy 434.827569 -61.678594) (xy 434.880786 -61.670569) (xy 434.90769 -61.66993)
			(xy 434.916834 -61.66993) (xy 434.946942 -61.670795) (xy 435.006325 -61.680851) (xy 435.063388 -61.700123)
			(xy 435.090316 -61.713618) (xy 435.095848 -61.716309) (xy 435.107789 -61.719255) (xy 435.113938 -61.71946)
			(xy 435.261512 -61.71946) (xy 435.271164 -61.718444) (xy 435.278407 -61.716814) (xy 435.291571 -61.709968)
			(xy 435.297072 -61.704982) (xy 435.784498 -61.217556) (xy 435.789484 -61.212056) (xy 435.796323 -61.198889)
			(xy 435.79796 -61.191648) (xy 435.798976 -61.181996) (xy 435.798976 -58.853578) (xy 435.798603 -58.844789)
			(xy 435.792648 -58.828252) (xy 435.781446 -58.814705) (xy 435.774084 -58.80989) (xy 435.731412 -58.78449)
			(xy 435.722837 -58.779903) (xy 435.703639 -58.776894) (xy 435.694074 -58.778648) (xy 435.67858 -58.782204)
			(xy 435.672484 -58.785506) (xy 435.644559 -58.799844) (xy 435.585182 -58.820197) (xy 435.523273 -58.830553)
			(xy 435.49189 -58.831226) (xy 435.490874 -58.831226) (xy 435.463623 -58.830738) (xy 435.409675 -58.822979)
			(xy 435.357381 -58.80762) (xy 435.307805 -58.784977) (xy 435.261956 -58.755508) (xy 435.220766 -58.719815)
			(xy 435.185076 -58.678624) (xy 435.155611 -58.632772) (xy 435.13297 -58.583194) (xy 435.117616 -58.530899)
			(xy 435.10986 -58.476951) (xy 435.10986 -58.422449) (xy 435.117616 -58.368501) (xy 435.13297 -58.316206)
			(xy 435.155611 -58.266628) (xy 435.185076 -58.220776) (xy 435.220766 -58.179585) (xy 435.261956 -58.143892)
			(xy 435.307805 -58.114423) (xy 435.357381 -58.09178) (xy 435.409675 -58.076421) (xy 435.463623 -58.068662)
			(xy 435.490874 -58.06821) (xy 435.49189 -58.06821) (xy 435.523316 -58.068867) (xy 435.585313 -58.079206)
			(xy 435.644775 -58.099573) (xy 435.672738 -58.11393) (xy 435.678834 -58.117232) (xy 435.695598 -58.121042)
			(xy 435.703685 -58.122256) (xy 435.719879 -58.120053) (xy 435.727348 -58.116724) (xy 435.77383 -58.089292)
			(xy 435.781259 -58.08453) (xy 435.792562 -58.070996) (xy 435.798574 -58.05442) (xy 435.798976 -58.045604)
			(xy 435.798976 -54.908704) (xy 435.79855 -54.899614) (xy 435.792097 -54.882613) (xy 435.78011 -54.868939)
			(xy 435.772306 -54.864254) (xy 435.767226 -54.862222) (xy 435.760193 -54.859508) (xy 435.745204 -54.857969)
			(xy 435.737762 -54.859174) (xy 435.731158 -54.860444) (xy 435.71795 -54.867556) (xy 432.483768 -58.101738)
			(xy 433.942996 -58.101738) (xy 433.947067 -58.046116) (xy 433.959193 -57.991679) (xy 433.979116 -57.939588)
			(xy 434.006412 -57.890953) (xy 434.040498 -57.84681) (xy 434.080647 -57.808101) (xy 434.126005 -57.77565)
			(xy 434.175605 -57.750149) (xy 434.228389 -57.732142) (xy 434.283232 -57.722012) (xy 434.338966 -57.719975)
			(xy 434.394403 -57.726075) (xy 434.44836 -57.740181) (xy 434.499689 -57.761993) (xy 434.547295 -57.791047)
			(xy 434.590163 -57.826722) (xy 434.62738 -57.868259) (xy 434.658153 -57.914772) (xy 434.681825 -57.965269)
			(xy 434.697893 -58.018676) (xy 434.706013 -58.073852) (xy 434.706522 -58.101738) (xy 434.706013 -58.129624)
			(xy 434.697893 -58.1848) (xy 434.681825 -58.238207) (xy 434.658153 -58.288704) (xy 434.62738 -58.335217)
			(xy 434.590163 -58.376754) (xy 434.547295 -58.412429) (xy 434.499689 -58.441483) (xy 434.44836 -58.463295)
			(xy 434.394403 -58.477401) (xy 434.338966 -58.483501) (xy 434.283232 -58.481464) (xy 434.228389 -58.471334)
			(xy 434.175605 -58.453327) (xy 434.126005 -58.427826) (xy 434.080647 -58.395375) (xy 434.040498 -58.356666)
			(xy 434.006412 -58.312523) (xy 433.979116 -58.263888) (xy 433.959193 -58.211797) (xy 433.947067 -58.15736)
			(xy 433.942996 -58.101738) (xy 432.483768 -58.101738) (xy 432.412648 -58.172858) (xy 432.406298 -58.183526)
			(xy 432.40452 -58.189368) (xy 432.396071 -58.214935) (xy 432.372991 -58.263582) (xy 432.343304 -58.308505)
			(xy 432.307601 -58.348811) (xy 432.266589 -58.3837) (xy 432.221081 -58.412482) (xy 432.171981 -58.434584)
			(xy 432.120263 -58.449568) (xy 432.066953 -58.457138) (xy 432.04003 -58.457592) (xy 432.012776 -58.457131)
			(xy 431.958823 -58.449377) (xy 431.906522 -58.434024) (xy 431.856939 -58.411383) (xy 431.811084 -58.381915)
			(xy 431.769889 -58.346221) (xy 431.734193 -58.305028) (xy 431.704724 -58.259173) (xy 431.682081 -58.209591)
			(xy 431.666726 -58.157291) (xy 431.65897 -58.103338) (xy 431.658522 -58.076084) (xy 431.658268 -58.076084)
			(xy 431.658725 -58.049149) (xy 431.666291 -57.995812) (xy 431.681284 -57.94407) (xy 431.703407 -57.894951)
			(xy 431.732219 -57.849433) (xy 431.767147 -57.80842) (xy 431.807496 -57.772728) (xy 431.852466 -57.743066)
			(xy 431.90116 -57.720025) (xy 431.926746 -57.711594) (xy 431.927 -57.711594) (xy 431.932834 -57.709582)
			(xy 431.943368 -57.703159) (xy 431.947828 -57.698894) (xy 435.426358 -54.220364) (xy 435.43134 -54.214862)
			(xy 435.438174 -54.201694) (xy 435.43982 -54.194456) (xy 435.440836 -54.184804) (xy 435.440836 -46.152308)
			(xy 435.440413 -46.142239) (xy 435.432693 -46.123638) (xy 435.42585 -46.11624) (xy 429.6283 -40.318436)
			(xy 429.624129 -40.314502) (xy 429.614377 -40.308478) (xy 429.608996 -40.306498) (xy 429.604989 -40.305216)
			(xy 429.596692 -40.303815) (xy 429.592486 -40.303704) (xy 426.76699 -40.303704) (xy 426.762672 -40.30599)
			(xy 426.734247 -40.320908) (xy 426.673646 -40.342074) (xy 426.610363 -40.352831) (xy 426.578268 -40.353488)
			(xy 426.57776 -40.353488) (xy 426.550512 -40.352999) (xy 426.496572 -40.345238) (xy 426.444284 -40.329881)
			(xy 426.394715 -40.307238) (xy 426.348872 -40.277773) (xy 426.307689 -40.242083) (xy 426.272003 -40.200896)
			(xy 426.242542 -40.15505) (xy 426.219905 -40.105478) (xy 426.204553 -40.053189) (xy 426.196798 -39.999248)
			(xy 426.196798 -39.944752) (xy 426.204553 -39.890811) (xy 426.219905 -39.838522) (xy 426.242542 -39.78895)
			(xy 426.272003 -39.743104) (xy 426.307689 -39.701917) (xy 426.348872 -39.666227) (xy 426.394715 -39.636762)
			(xy 426.444284 -39.614119) (xy 426.496572 -39.598762) (xy 426.550512 -39.591001) (xy 426.57776 -39.590472)
			(xy 426.578014 -39.590472) (xy 426.602262 -39.590866) (xy 426.650363 -39.597035) (xy 426.6973 -39.609235)
			(xy 426.742318 -39.627268) (xy 426.763688 -39.638732) (xy 426.766482 -39.640256) (xy 429.333914 -39.640256)
			(xy 429.343436 -39.639858) (xy 429.361163 -39.632901) (xy 429.375126 -39.619951) (xy 429.379634 -39.611554)
			(xy 429.380904 -39.608506) (xy 429.383617 -39.601336) (xy 429.385052 -39.586079) (xy 429.383698 -39.578534)
			(xy 429.382428 -39.57193) (xy 429.37557 -39.55923) (xy 426.039788 -36.223448) (xy 426.036937 -36.220742)
			(xy 426.030558 -36.216149) (xy 426.027088 -36.214304) (xy 426.021662 -36.211717) (xy 426.009982 -36.208886)
			(xy 426.003974 -36.208716) (xy 425.038012 -36.208716) (xy 425.02836 -36.218368) (xy 424.997118 -36.261802)
			(xy 424.980608 -36.284916) (xy 424.976868 -36.291024) (xy 424.972598 -36.304689) (xy 424.972226 -36.31184)
			(xy 424.972226 -36.331906) (xy 424.974512 -36.339526) (xy 424.982676 -36.367329) (xy 424.991472 -36.424601)
			(xy 424.992038 -36.453572) (xy 424.991554 -36.480825) (xy 424.983801 -36.534778) (xy 424.968449 -36.587078)
			(xy 424.945809 -36.63666) (xy 424.916344 -36.682516) (xy 424.880653 -36.723712) (xy 424.839463 -36.75941)
			(xy 424.793611 -36.788882) (xy 424.744032 -36.811528) (xy 424.691734 -36.826889) (xy 424.637783 -36.83465)
			(xy 424.61053 -36.83508) (xy 424.583405 -36.834605) (xy 424.529701 -36.826923) (xy 424.477628 -36.811711)
			(xy 424.428235 -36.789276) (xy 424.382518 -36.760069) (xy 424.3414 -36.724679) (xy 424.305711 -36.683822)
			(xy 424.276169 -36.638321) (xy 424.253372 -36.589093) (xy 424.237779 -36.537132) (xy 424.229704 -36.483487)
			(xy 424.229022 -36.456366) (xy 424.229022 -36.45281) (xy 424.229583 -36.423839) (xy 424.238389 -36.366569)
			(xy 424.246548 -36.338764) (xy 424.24731 -36.336224) (xy 424.248834 -36.331398) (xy 424.250358 -36.318444)
			(xy 424.250629 -36.31029) (xy 424.246627 -36.294483) (xy 424.242484 -36.287456) (xy 424.223434 -36.260786)
			(xy 424.192446 -36.21786) (xy 424.183048 -36.208716) (xy 423.672762 -36.208716) (xy 423.666608 -36.208882)
			(xy 423.654658 -36.211828) (xy 423.64914 -36.214558) (xy 423.621581 -36.228298) (xy 423.563163 -36.24777)
			(xy 423.502382 -36.257641) (xy 423.471594 -36.258246) (xy 423.470832 -36.258246) (xy 423.443575 -36.257785)
			(xy 423.389615 -36.250031) (xy 423.337308 -36.234676) (xy 423.287719 -36.212033) (xy 423.241857 -36.182563)
			(xy 423.200657 -36.146866) (xy 423.164956 -36.105668) (xy 423.135482 -36.059809) (xy 423.112835 -36.010222)
			(xy 423.097476 -35.957916) (xy 423.089717 -35.903957) (xy 423.089717 -35.849443) (xy 423.097476 -35.795484)
			(xy 423.112835 -35.743178) (xy 423.135482 -35.693591) (xy 423.164956 -35.647732) (xy 423.200657 -35.606534)
			(xy 423.241857 -35.570837) (xy 423.287719 -35.541367) (xy 423.337308 -35.518724) (xy 423.389615 -35.503369)
			(xy 423.443575 -35.495615) (xy 423.470832 -35.49523) (xy 423.471848 -35.49523) (xy 423.5026 -35.495805)
			(xy 423.563309 -35.505656) (xy 423.621649 -35.525125) (xy 423.64914 -35.538918) (xy 423.65467 -35.541617)
			(xy 423.666611 -35.544581) (xy 423.672762 -35.54476) (xy 425.745656 -35.54476) (xy 425.754749 -35.544339)
			(xy 425.771759 -35.537894) (xy 425.785442 -35.525908) (xy 425.790106 -35.51809) (xy 425.792138 -35.51301)
			(xy 425.794866 -35.505978) (xy 425.796431 -35.490984) (xy 425.795186 -35.483546) (xy 425.793916 -35.476942)
			(xy 425.786804 -35.463734) (xy 423.46372 -33.14065) (xy 423.445686 -33.12188) (xy 423.415102 -33.079764)
			(xy 423.391471 -33.033388) (xy 423.375373 -32.983891) (xy 423.367203 -32.932486) (xy 423.366692 -32.906462)
			(xy 423.366692 -29.707078) (xy 423.367217 -29.681053) (xy 423.375379 -29.629646) (xy 423.391468 -29.580145)
			(xy 423.415089 -29.533762) (xy 423.445662 -29.491637) (xy 423.46372 -29.47289) (xy 424.088052 -28.848812)
			(xy 424.093557 -28.842851) (xy 424.100812 -28.828345) (xy 424.102276 -28.820364) (xy 424.102784 -28.812998)
			(xy 424.102784 -28.658058) (xy 424.100498 -28.65374) (xy 424.092154 -28.638142) (xy 424.078035 -28.605705)
			(xy 424.072304 -28.58897) (xy 424.069256 -28.579318) (xy 424.066462 -28.570428) (xy 423.99966 -28.503626)
			(xy 423.863262 -28.366974) (xy 423.856775 -28.36132) (xy 423.841068 -28.354321) (xy 423.832528 -28.353258)
			(xy 423.82821 -28.353004) (xy 420.92499 -28.353004) (xy 420.898968 -28.352472) (xy 420.847568 -28.344298)
			(xy 420.798075 -28.328199) (xy 420.751703 -28.30457) (xy 420.709588 -28.273991) (xy 420.690802 -28.255976)
			(xy 420.11473 -27.67965) (xy 420.108533 -27.674051) (xy 420.093505 -27.666788) (xy 420.085266 -27.665426)
			(xy 420.07917 -27.665172) (xy 419.035992 -27.665172) (xy 419.00997 -27.66464) (xy 418.958571 -27.656466)
			(xy 418.909079 -27.640366) (xy 418.862707 -27.616736) (xy 418.820595 -27.586154) (xy 418.801804 -27.568144)
			(xy 417.826444 -26.592784) (xy 417.815586 -26.594617) (xy 417.794956 -26.6023) (xy 417.78555 -26.608024)
			(xy 417.775131 -26.615211) (xy 417.757907 -26.633749) (xy 417.745775 -26.655955) (xy 417.73948 -26.680463)
			(xy 417.739068 -26.693114) (xy 417.739068 -27.342846) (xy 417.738578 -27.372814) (xy 417.730755 -27.432236)
			(xy 417.715242 -27.490129) (xy 417.692306 -27.545502) (xy 417.662339 -27.597408) (xy 417.625852 -27.644958)
			(xy 417.583472 -27.687338) (xy 417.535922 -27.723825) (xy 417.484016 -27.753792) (xy 417.428643 -27.776728)
			(xy 417.37075 -27.792241) (xy 417.311328 -27.800064) (xy 417.251392 -27.800064) (xy 417.19197 -27.792241)
			(xy 417.134077 -27.776728) (xy 417.078704 -27.753792) (xy 417.026798 -27.723825) (xy 416.979248 -27.687338)
			(xy 416.936868 -27.644958) (xy 416.900381 -27.597408) (xy 416.870414 -27.545502) (xy 416.847478 -27.490129)
			(xy 416.831965 -27.432236) (xy 416.824142 -27.372814) (xy 416.823652 -27.342846) (xy 416.823652 -26.737818)
			(xy 416.823398 -26.479246) (xy 416.823925 -26.447748) (xy 416.832564 -26.385347) (xy 416.849673 -26.324719)
			(xy 416.874927 -26.267006) (xy 416.907851 -26.213298) (xy 416.947824 -26.164609) (xy 416.994091 -26.121855)
			(xy 417.04578 -26.085845) (xy 417.101916 -26.057257) (xy 417.1315 -26.04643) (xy 417.136072 -26.044906)
			(xy 417.146057 -26.039642) (xy 417.160557 -26.022378) (xy 417.164012 -26.011632) (xy 417.165028 -26.008076)
			(xy 417.17214 -25.976326) (xy 417.17214 -25.975818) (xy 417.172902 -25.972516) (xy 417.174414 -25.964111)
			(xy 417.172412 -25.947161) (xy 417.164988 -25.931792) (xy 417.159186 -25.925526) (xy 416.615372 -25.381458)
			(xy 416.608095 -25.374775) (xy 416.589928 -25.36706) (xy 416.580066 -25.366472) (xy 415.005012 -25.366472)
			(xy 415.00171 -25.366472) (xy 414.992692 -25.367425) (xy 414.976164 -25.374851) (xy 414.969452 -25.38095)
			(xy 414.895538 -25.455118) (xy 414.863788 -25.486868) (xy 414.857438 -25.497536) (xy 414.85566 -25.503378)
			(xy 414.84721 -25.528942) (xy 414.824127 -25.577584) (xy 414.794439 -25.622501) (xy 414.758734 -25.6628)
			(xy 414.717721 -25.697683) (xy 414.672214 -25.726456) (xy 414.623115 -25.748551) (xy 414.571398 -25.763527)
			(xy 414.518091 -25.771088) (xy 414.49117 -25.771602) (xy 414.46392 -25.771114) (xy 414.409976 -25.763354)
			(xy 414.357685 -25.747996) (xy 414.308112 -25.725353) (xy 414.262266 -25.695886) (xy 414.22108 -25.660195)
			(xy 414.185392 -25.619005) (xy 414.155929 -25.573156) (xy 414.133291 -25.523581) (xy 414.117938 -25.471289)
			(xy 414.110183 -25.417344) (xy 414.109662 -25.390094) (xy 414.109408 -25.390094) (xy 414.109865 -25.363157)
			(xy 414.117429 -25.309817) (xy 414.13242 -25.258072) (xy 414.15454 -25.208949) (xy 414.183349 -25.163426)
			(xy 414.218275 -25.122407) (xy 414.258623 -25.086709) (xy 414.303591 -25.05704) (xy 414.352285 -25.03399)
			(xy 414.377886 -25.025604) (xy 414.37814 -25.025604) (xy 414.383978 -25.023598) (xy 414.394521 -25.017185)
			(xy 414.398968 -25.012904) (xy 414.441386 -24.970486) (xy 414.441828 -24.96688) (xy 414.441835 -24.959614)
			(xy 414.441386 -24.956008) (xy 414.089596 -24.604218) (xy 414.06445 -24.578276) (xy 414.020035 -24.521289)
			(xy 413.982955 -24.45928) (xy 413.953771 -24.393186) (xy 413.932925 -24.324008) (xy 413.926274 -24.288496)
			(xy 413.92221 -24.263858) (xy 413.917932 -24.259872) (xy 413.907921 -24.253837) (xy 413.902398 -24.25192)
			(xy 413.89427 -24.24938) (xy 413.852868 -24.236426) (xy 413.814768 -24.224488) (xy 413.809662 -24.223218)
			(xy 413.799161 -24.22257) (xy 413.79394 -24.223218) (xy 413.592518 -24.42464) (xy 413.573748 -24.442674)
			(xy 413.531632 -24.473257) (xy 413.485256 -24.496887) (xy 413.435758 -24.512982) (xy 413.384354 -24.521148)
			(xy 413.35833 -24.521668) (xy 412.170118 -24.521668) (xy 412.1658 -24.523954) (xy 412.137374 -24.538868)
			(xy 412.076772 -24.560025) (xy 412.01349 -24.570771) (xy 411.981396 -24.571452) (xy 411.980888 -24.571452)
			(xy 411.953634 -24.570965) (xy 411.899682 -24.563206) (xy 411.847382 -24.547849) (xy 411.797801 -24.525204)
			(xy 411.751947 -24.495734) (xy 411.710753 -24.460038) (xy 411.675059 -24.418844) (xy 411.64559 -24.372989)
			(xy 411.622947 -24.323407) (xy 411.607591 -24.271107) (xy 411.599834 -24.217154) (xy 411.599834 -24.162646)
			(xy 411.607591 -24.108693) (xy 411.622947 -24.056393) (xy 411.64559 -24.006811) (xy 411.675059 -23.960956)
			(xy 411.710753 -23.919762) (xy 411.751947 -23.884066) (xy 411.797801 -23.854596) (xy 411.847382 -23.831951)
			(xy 411.899682 -23.816594) (xy 411.953634 -23.808835) (xy 411.980888 -23.808436) (xy 411.981142 -23.808436)
			(xy 412.005389 -23.808832) (xy 412.05349 -23.815004) (xy 412.100425 -23.827205) (xy 412.145442 -23.84524)
			(xy 412.166816 -23.856696) (xy 412.16961 -23.85822) (xy 413.199326 -23.85822) (xy 413.202628 -23.85822)
			(xy 413.211651 -23.857277) (xy 413.228193 -23.849864) (xy 413.234886 -23.843742) (xy 413.314896 -23.763478)
			(xy 413.354012 -23.724362) (xy 413.354266 -23.710646) (xy 413.352234 -23.701756) (xy 413.342836 -23.673562)
			(xy 413.342836 -23.673054) (xy 413.3215 -23.603712) (xy 413.314134 -23.597108) (xy 413.289496 -23.59279)
			(xy 413.256648 -23.586394) (xy 413.192573 -23.567078) (xy 413.131118 -23.540584) (xy 413.073083 -23.507256)
			(xy 413.019227 -23.46753) (xy 412.97025 -23.421923) (xy 412.926791 -23.37103) (xy 412.889418 -23.315514)
			(xy 412.858617 -23.2561) (xy 412.846266 -23.224998) (xy 412.837884 -23.203154) (xy 412.833851 -23.200571)
			(xy 412.825027 -23.196853) (xy 412.820358 -23.195788) (xy 412.771082 -23.185374) (xy 412.770574 -23.185374)
			(xy 412.73476 -23.177754) (xy 412.720536 -23.178008) (xy 412.458916 -23.439628) (xy 412.43534 -23.462575)
			(xy 412.3839 -23.503596) (xy 412.32819 -23.5386) (xy 412.268912 -23.567146) (xy 412.20681 -23.588875)
			(xy 412.142665 -23.603514) (xy 412.077285 -23.610879) (xy 412.044388 -23.611332) (xy 412.00896 -23.610797)
			(xy 411.938622 -23.602255) (xy 411.869825 -23.585297) (xy 411.803575 -23.56017) (xy 411.740836 -23.527241)
			(xy 411.682524 -23.48699) (xy 411.629488 -23.440003) (xy 411.582503 -23.386967) (xy 411.542253 -23.328654)
			(xy 411.509325 -23.265914) (xy 411.4842 -23.199663) (xy 411.467243 -23.130867) (xy 411.458702 -23.060528)
			(xy 411.458156 -23.0251) (xy 411.458617 -22.992204) (xy 411.465983 -22.926825) (xy 411.480623 -22.862682)
			(xy 411.502353 -22.800581) (xy 411.530899 -22.741304) (xy 411.565902 -22.685596) (xy 411.606922 -22.634156)
			(xy 411.62986 -22.610572) (xy 412.12262 -22.117812) (xy 412.146194 -22.094861) (xy 412.197632 -22.053831)
			(xy 412.25334 -22.018819) (xy 412.312618 -21.990265) (xy 412.374721 -21.968528) (xy 412.438867 -21.95388)
			(xy 412.50425 -21.946507) (xy 412.537148 -21.946108) (xy 412.558484 -21.946616) (xy 416.307524 -21.946616)
			(xy 416.308032 -21.946616) (xy 416.316659 -21.94624) (xy 416.332897 -21.940398) (xy 416.339782 -21.935186)
			(xy 416.348418 -21.926042) (xy 416.381946 -21.88083) (xy 416.385282 -21.876078) (xy 416.389899 -21.86543)
			(xy 416.39109 -21.859748) (xy 416.393376 -21.848064) (xy 416.38982 -21.836126) (xy 416.382366 -21.809437)
			(xy 416.374337 -21.754611) (xy 416.373818 -21.726906) (xy 416.374339 -21.698167) (xy 416.382961 -21.641339)
			(xy 416.400011 -21.586448) (xy 416.425103 -21.534736) (xy 416.457669 -21.487373) (xy 416.476942 -21.466048)
			(xy 416.484054 -21.458428) (xy 416.487356 -21.449792) (xy 416.488118 -21.448014) (xy 416.489349 -21.444065)
			(xy 416.490623 -21.435894) (xy 416.490658 -21.431758) (xy 416.490658 -21.361654) (xy 416.490593 -21.357521)
			(xy 416.489323 -21.349352) (xy 416.488118 -21.345398) (xy 416.487356 -21.34362) (xy 416.484054 -21.334984)
			(xy 416.476942 -21.327364) (xy 416.45767 -21.306038) (xy 416.425102 -21.258675) (xy 416.400009 -21.206963)
			(xy 416.382957 -21.152072) (xy 416.374333 -21.095244) (xy 416.374333 -21.037765) (xy 416.382955 -20.980936)
			(xy 416.400005 -20.926045) (xy 416.425098 -20.874332) (xy 416.457664 -20.826969) (xy 416.476942 -20.805648)
			(xy 416.484054 -20.798028) (xy 416.487356 -20.789392) (xy 416.488118 -20.787614) (xy 416.489349 -20.783665)
			(xy 416.490623 -20.775494) (xy 416.490658 -20.771358) (xy 416.490658 -20.701254) (xy 416.490593 -20.697121)
			(xy 416.489323 -20.688952) (xy 416.488118 -20.684998) (xy 416.487356 -20.68322) (xy 416.484054 -20.674584)
			(xy 416.476942 -20.666964) (xy 416.45767 -20.645638) (xy 416.425102 -20.598275) (xy 416.400009 -20.546563)
			(xy 416.382957 -20.491672) (xy 416.374333 -20.434844) (xy 416.374333 -20.377365) (xy 416.382955 -20.320536)
			(xy 416.400005 -20.265645) (xy 416.425098 -20.213932) (xy 416.457664 -20.166569) (xy 416.476942 -20.145248)
			(xy 416.484054 -20.137628) (xy 416.487356 -20.128992) (xy 416.488118 -20.127214) (xy 416.489349 -20.123265)
			(xy 416.490623 -20.115094) (xy 416.490658 -20.110958) (xy 416.490658 -20.040854) (xy 416.490593 -20.036721)
			(xy 416.489323 -20.028552) (xy 416.488118 -20.024598) (xy 416.487356 -20.02282) (xy 416.484054 -20.014184)
			(xy 416.476942 -20.006564) (xy 416.45767 -19.985238) (xy 416.425102 -19.937875) (xy 416.400009 -19.886163)
			(xy 416.382957 -19.831272) (xy 416.374333 -19.774444) (xy 416.374333 -19.716965) (xy 416.382955 -19.660136)
			(xy 416.400005 -19.605245) (xy 416.425098 -19.553532) (xy 416.457664 -19.506169) (xy 416.476942 -19.484848)
			(xy 416.484054 -19.477228) (xy 416.487356 -19.468592) (xy 416.488118 -19.466814) (xy 416.489349 -19.462865)
			(xy 416.490623 -19.454694) (xy 416.490658 -19.450558) (xy 416.490658 -19.380454) (xy 416.490593 -19.376321)
			(xy 416.489323 -19.368152) (xy 416.488118 -19.364198) (xy 416.487356 -19.36242) (xy 416.484054 -19.353784)
			(xy 416.476942 -19.346164) (xy 416.457675 -19.324835) (xy 416.425115 -19.277471) (xy 416.400028 -19.225759)
			(xy 416.382981 -19.17087) (xy 416.37436 -19.114044) (xy 416.373818 -19.085306) (xy 416.374304 -19.058055)
			(xy 416.38206 -19.004107) (xy 416.397415 -18.951812) (xy 416.420057 -18.902235) (xy 416.449523 -18.856385)
			(xy 416.485214 -18.815194) (xy 416.526405 -18.779503) (xy 416.572255 -18.750037) (xy 416.621832 -18.727395)
			(xy 416.674127 -18.71204) (xy 416.728075 -18.704284) (xy 416.782577 -18.704284) (xy 416.836525 -18.71204)
			(xy 416.88882 -18.727395) (xy 416.938397 -18.750037) (xy 416.984247 -18.779503) (xy 417.025438 -18.815194)
			(xy 417.061129 -18.856385) (xy 417.090595 -18.902235) (xy 417.113237 -18.951812) (xy 417.128592 -19.004107)
			(xy 417.136348 -19.058055) (xy 417.136834 -19.085306) (xy 417.136312 -19.114044) (xy 417.127687 -19.170871)
			(xy 417.110634 -19.225759) (xy 417.085539 -19.277468) (xy 417.052969 -19.324827) (xy 417.03371 -19.346164)
			(xy 417.026598 -19.353784) (xy 417.023296 -19.36242) (xy 417.022534 -19.364198) (xy 417.021303 -19.368147)
			(xy 417.020029 -19.376318) (xy 417.019994 -19.380454) (xy 417.019994 -19.450558) (xy 417.02006 -19.454691)
			(xy 417.021333 -19.462859) (xy 417.022534 -19.466814) (xy 417.023296 -19.468592) (xy 417.026598 -19.477228)
			(xy 417.03371 -19.484848) (xy 417.052979 -19.506176) (xy 417.08554 -19.553539) (xy 417.110629 -19.60525)
			(xy 417.127676 -19.66014) (xy 417.136297 -19.716966) (xy 417.136297 -19.774443) (xy 417.127674 -19.831268)
			(xy 417.110626 -19.886158) (xy 417.085536 -19.937869) (xy 417.052973 -19.985231) (xy 417.03371 -20.006564)
			(xy 417.026598 -20.014184) (xy 417.023296 -20.02282) (xy 417.022534 -20.024598) (xy 417.021303 -20.028547)
			(xy 417.020029 -20.036718) (xy 417.019994 -20.040854) (xy 417.019994 -20.110958) (xy 417.02006 -20.115091)
			(xy 417.021333 -20.123259) (xy 417.022534 -20.127214) (xy 417.023296 -20.128992) (xy 417.026598 -20.137628)
			(xy 417.03371 -20.145248) (xy 417.052979 -20.166576) (xy 417.08554 -20.213939) (xy 417.110629 -20.26565)
			(xy 417.127676 -20.32054) (xy 417.136297 -20.377366) (xy 417.136297 -20.434843) (xy 417.127674 -20.491668)
			(xy 417.110626 -20.546558) (xy 417.085536 -20.598269) (xy 417.052973 -20.645631) (xy 417.03371 -20.666964)
			(xy 417.026598 -20.674584) (xy 417.023296 -20.68322) (xy 417.022534 -20.684998) (xy 417.021303 -20.688947)
			(xy 417.020029 -20.697118) (xy 417.019994 -20.701254) (xy 417.019994 -20.771358) (xy 417.02006 -20.775491)
			(xy 417.021333 -20.783659) (xy 417.022534 -20.787614) (xy 417.023296 -20.789392) (xy 417.026598 -20.798028)
			(xy 417.03371 -20.805648) (xy 417.052979 -20.826976) (xy 417.08554 -20.874339) (xy 417.110629 -20.92605)
			(xy 417.127676 -20.98094) (xy 417.136297 -21.037766) (xy 417.136297 -21.095243) (xy 417.127674 -21.152068)
			(xy 417.110626 -21.206958) (xy 417.085536 -21.258669) (xy 417.052973 -21.306031) (xy 417.03371 -21.327364)
			(xy 417.026598 -21.334984) (xy 417.023296 -21.34362) (xy 417.022534 -21.345398) (xy 417.021303 -21.349347)
			(xy 417.020029 -21.357518) (xy 417.019994 -21.361654) (xy 417.019994 -21.431758) (xy 417.02006 -21.435891)
			(xy 417.021333 -21.444059) (xy 417.022534 -21.448014) (xy 417.023296 -21.449792) (xy 417.026598 -21.458428)
			(xy 417.03371 -21.466048) (xy 417.052979 -21.487376) (xy 417.085541 -21.534739) (xy 417.110629 -21.586451)
			(xy 417.127677 -21.641341) (xy 417.136298 -21.698168) (xy 417.136834 -21.726906) (xy 417.136339 -21.754613)
			(xy 417.128305 -21.809441) (xy 417.120832 -21.836126) (xy 417.120832 -21.83638) (xy 417.119293 -21.842157)
			(xy 417.118661 -21.854092) (xy 417.119562 -21.860002) (xy 417.121594 -21.871432) (xy 417.162488 -21.926296)
			(xy 417.168076 -21.932392) (xy 417.175265 -21.938774) (xy 417.193022 -21.946099) (xy 417.20262 -21.946616)
			(xy 421.552624 -21.946616) (xy 421.560334 -21.946388) (xy 421.575072 -21.941865) (xy 421.58158 -21.937726)
			(xy 421.585644 -21.934424) (xy 421.928798 -21.59127) (xy 421.929306 -21.583904) (xy 421.929306 -21.567902)
			(xy 421.926258 -21.556218) (xy 421.92194 -21.547836) (xy 421.908408 -21.520574) (xy 421.889215 -21.462819)
			(xy 421.879429 -21.402751) (xy 421.87876 -21.372322) (xy 421.87876 -21.36394) (xy 421.879755 -21.337045)
			(xy 421.888375 -21.283922) (xy 421.904377 -21.232538) (xy 421.927443 -21.183914) (xy 421.957115 -21.139015)
			(xy 421.992804 -21.098733) (xy 422.033801 -21.063867) (xy 422.079293 -21.035111) (xy 422.128374 -21.013035)
			(xy 422.180072 -20.998077) (xy 422.233359 -20.990535) (xy 422.260268 -20.990052) (xy 422.264332 -20.990052)
			(xy 422.273222 -20.990306) (xy 422.279064 -20.990306) (xy 422.28726 -20.990003) (xy 422.302813 -20.98483)
			(xy 422.309544 -20.980146) (xy 422.312592 -20.97786) (xy 422.366948 -20.925536) (xy 422.372536 -20.919186)
			(xy 422.372536 -20.003008) (xy 422.372282 -19.453098) (xy 422.372815 -19.417376) (xy 422.381502 -19.346462)
			(xy 422.398748 -19.277131) (xy 422.424295 -19.21041) (xy 422.457766 -19.147292) (xy 422.498664 -19.088712)
			(xy 422.546381 -19.035539) (xy 422.572942 -19.011646) (xy 422.583864 -19.002248) (xy 422.585896 -18.99793)
			(xy 422.587904 -18.993217) (xy 422.590206 -18.983235) (xy 422.590468 -18.978118) (xy 422.591992 -18.922238)
			(xy 422.591992 -18.921476) (xy 422.5925 -18.906998) (xy 422.543986 -18.858484) (xy 422.521074 -18.834907)
			(xy 422.480095 -18.783495) (xy 422.44513 -18.727818) (xy 422.416618 -18.668577) (xy 422.394916 -18.606516)
			(xy 422.380298 -18.542416) (xy 422.372948 -18.477083) (xy 422.372536 -18.44421) (xy 422.372282 -18.432018)
			(xy 422.373537 -18.397094) (xy 422.383331 -18.327898) (xy 422.401281 -18.260357) (xy 422.427131 -18.195429)
			(xy 422.460517 -18.134034) (xy 422.500963 -18.077042) (xy 422.547898 -18.025262) (xy 422.600654 -17.979428)
			(xy 422.658484 -17.94019) (xy 422.720569 -17.908104) (xy 422.786027 -17.883626) (xy 422.853931 -17.867102)
			(xy 422.923317 -17.858766) (xy 422.95826 -17.858232) (xy 422.967404 -17.858232) (xy 423.004701 -17.85941)
			(xy 423.07856 -17.870064) (xy 423.150467 -17.890015) (xy 423.185082 -17.903952) (xy 423.219826 -17.919177)
			(xy 423.285407 -17.957299) (xy 423.345528 -18.003557) (xy 423.372788 -18.029936) (xy 423.94124 -18.598388)
			(xy 423.964186 -18.621942) (xy 424.005206 -18.673341) (xy 424.040209 -18.729012) (xy 424.068754 -18.788255)
			(xy 424.090482 -18.850323) (xy 424.105118 -18.914434) (xy 424.11248 -18.979782) (xy 424.112944 -19.012662)
			(xy 424.112944 -21.475192) (xy 424.116605 -21.479732) (xy 424.125583 -21.487171) (xy 424.130724 -21.489924)
			(xy 424.202606 -21.520404) (xy 424.203114 -21.520404) (xy 424.22064 -21.527516) (xy 424.227085 -21.529917)
			(xy 424.240731 -21.531595) (xy 424.247564 -21.530818) (xy 424.836844 -20.941538) (xy 424.837352 -20.9296)
			(xy 424.823382 -20.84197) (xy 424.822141 -20.836841) (xy 424.817796 -20.827226) (xy 424.814746 -20.82292)
			(xy 424.809666 -20.816062) (xy 424.804078 -20.813268) (xy 424.779949 -20.801243) (xy 424.735033 -20.771428)
			(xy 424.694743 -20.735608) (xy 424.659876 -20.69449) (xy 424.631121 -20.648888) (xy 424.609047 -20.599704)
			(xy 424.59409 -20.54791) (xy 424.586546 -20.49453) (xy 424.586146 -20.467574) (xy 424.586634 -20.440196)
			(xy 424.594427 -20.385997) (xy 424.609854 -20.333458) (xy 424.6326 -20.28365) (xy 424.662204 -20.237586)
			(xy 424.698062 -20.196204) (xy 424.739444 -20.160346) (xy 424.785508 -20.130742) (xy 424.835316 -20.107996)
			(xy 424.887855 -20.092569) (xy 424.942054 -20.084776) (xy 424.99681 -20.084776) (xy 425.051009 -20.092569)
			(xy 425.103548 -20.107996) (xy 425.153356 -20.130742) (xy 425.19942 -20.160346) (xy 425.240802 -20.196204)
			(xy 425.27666 -20.237586) (xy 425.306264 -20.28365) (xy 425.32901 -20.333458) (xy 425.344437 -20.385997)
			(xy 425.35223 -20.440196) (xy 425.352718 -20.467574) (xy 425.352718 -20.468336) (xy 425.352042 -20.500184)
			(xy 425.341444 -20.562996) (xy 425.331636 -20.593304) (xy 425.328334 -20.602956) (xy 425.32808 -20.604734)
			(xy 425.327748 -20.613161) (xy 425.331885 -20.629498) (xy 425.336208 -20.636738) (xy 425.337478 -20.638516)
			(xy 425.384976 -20.705064) (xy 425.385738 -20.70608) (xy 426.956982 -20.70608) (xy 426.989836 -20.706539)
			(xy 427.055131 -20.713894) (xy 427.104372 -20.72513) (xy 431.48048 -20.72513) (xy 431.48445 -20.594996)
			(xy 431.496346 -20.465346) (xy 431.516125 -20.336663) (xy 431.543711 -20.209424) (xy 431.579004 -20.084105)
			(xy 431.62187 -19.961169) (xy 431.672152 -19.841076) (xy 431.729661 -19.724272) (xy 431.794185 -19.61119)
			(xy 431.865482 -19.502253) (xy 431.943287 -19.397865) (xy 432.027312 -19.298414) (xy 432.117244 -19.204271)
			(xy 432.212748 -19.115786) (xy 432.313468 -19.033287) (xy 432.41903 -18.957082) (xy 432.529042 -18.887455)
			(xy 432.643094 -18.824664) (xy 432.760762 -18.768942) (xy 432.881608 -18.720498) (xy 433.005183 -18.679511)
			(xy 433.131026 -18.646134) (xy 433.258671 -18.620491) (xy 433.387641 -18.602677) (xy 433.517457 -18.592759)
			(xy 433.647636 -18.590774) (xy 433.777695 -18.596728) (xy 433.907148 -18.610601) (xy 434.035515 -18.632339)
			(xy 434.162318 -18.661863) (xy 434.287085 -18.699062) (xy 434.409352 -18.743798) (xy 434.528665 -18.795906)
			(xy 434.644578 -18.855189) (xy 434.756663 -18.92143) (xy 434.8645 -18.99438) (xy 434.967689 -19.073768)
			(xy 435.065847 -19.1593) (xy 435.158608 -19.250657) (xy 435.245627 -19.347499) (xy 435.32658 -19.449466)
			(xy 435.401166 -19.556178) (xy 435.469107 -19.667239) (xy 435.530152 -19.782235) (xy 435.584073 -19.900739)
			(xy 435.630668 -20.02231) (xy 435.669766 -20.146495) (xy 435.70122 -20.272833) (xy 435.724914 -20.400854)
			(xy 435.740758 -20.53008) (xy 435.748696 -20.660033) (xy 435.749192 -20.72513) (xy 435.748696 -20.790227)
			(xy 435.740758 -20.92018) (xy 435.724914 -21.049406) (xy 435.70122 -21.177427) (xy 435.669766 -21.303765)
			(xy 435.630668 -21.42795) (xy 435.584073 -21.549521) (xy 435.530152 -21.668025) (xy 435.469107 -21.783021)
			(xy 435.401166 -21.894082) (xy 435.32658 -22.000794) (xy 435.245627 -22.102761) (xy 435.158608 -22.199603)
			(xy 435.065847 -22.29096) (xy 434.967689 -22.376492) (xy 434.8645 -22.45588) (xy 434.756663 -22.52883)
			(xy 434.644578 -22.595071) (xy 434.528665 -22.654354) (xy 434.409352 -22.706462) (xy 434.287085 -22.751198)
			(xy 434.162318 -22.788397) (xy 434.035515 -22.817921) (xy 433.907148 -22.839659) (xy 433.777695 -22.853532)
			(xy 433.647636 -22.859486) (xy 433.517457 -22.857501) (xy 433.387641 -22.847583) (xy 433.258671 -22.829769)
			(xy 433.131026 -22.804126) (xy 433.005183 -22.770749) (xy 432.881608 -22.729762) (xy 432.760762 -22.681318)
			(xy 432.643094 -22.625596) (xy 432.529042 -22.562805) (xy 432.41903 -22.493178) (xy 432.313468 -22.416973)
			(xy 432.212748 -22.334474) (xy 432.117244 -22.245989) (xy 432.027312 -22.151846) (xy 431.943287 -22.052395)
			(xy 431.865482 -21.948007) (xy 431.794185 -21.83907) (xy 431.729661 -21.725988) (xy 431.672152 -21.609184)
			(xy 431.62187 -21.489091) (xy 431.579004 -21.366155) (xy 431.543711 -21.240836) (xy 431.516125 -21.113597)
			(xy 431.496346 -20.984914) (xy 431.48445 -20.855264) (xy 431.48048 -20.72513) (xy 427.104372 -20.72513)
			(xy 427.119193 -20.728512) (xy 427.181215 -20.750211) (xy 427.240418 -20.778717) (xy 427.296057 -20.813672)
			(xy 427.347432 -20.854637) (xy 427.371002 -20.87753) (xy 427.934882 -21.44141) (xy 427.957776 -21.464976)
			(xy 427.998722 -21.516361) (xy 428.033662 -21.572005) (xy 428.062157 -21.631209) (xy 428.083849 -21.693229)
			(xy 428.098467 -21.757287) (xy 428.105825 -21.822578) (xy 428.106203 -21.847048) (xy 428.372776 -21.847048)
			(xy 428.376847 -21.791426) (xy 428.388973 -21.736989) (xy 428.408896 -21.684898) (xy 428.436192 -21.636263)
			(xy 428.470278 -21.59212) (xy 428.510427 -21.553411) (xy 428.555785 -21.52096) (xy 428.605385 -21.495459)
			(xy 428.658169 -21.477452) (xy 428.713012 -21.467322) (xy 428.768746 -21.465285) (xy 428.824183 -21.471385)
			(xy 428.87814 -21.485491) (xy 428.929469 -21.507303) (xy 428.977075 -21.536357) (xy 429.019943 -21.572032)
			(xy 429.05716 -21.613569) (xy 429.087933 -21.660082) (xy 429.111605 -21.710579) (xy 429.127673 -21.763986)
			(xy 429.135793 -21.819162) (xy 429.136302 -21.847048) (xy 429.135793 -21.874934) (xy 429.127673 -21.93011)
			(xy 429.111605 -21.983517) (xy 429.087933 -22.034014) (xy 429.05716 -22.080527) (xy 429.019943 -22.122064)
			(xy 428.977075 -22.157739) (xy 428.929469 -22.186793) (xy 428.87814 -22.208605) (xy 428.824183 -22.222711)
			(xy 428.768746 -22.228811) (xy 428.713012 -22.226774) (xy 428.658169 -22.216644) (xy 428.605385 -22.198637)
			(xy 428.555785 -22.173136) (xy 428.510427 -22.140685) (xy 428.470278 -22.101976) (xy 428.436192 -22.057833)
			(xy 428.408896 -22.009198) (xy 428.388973 -21.957107) (xy 428.376847 -21.90267) (xy 428.372776 -21.847048)
			(xy 428.106203 -21.847048) (xy 428.106332 -21.85543) (xy 428.106332 -21.855684) (xy 428.10582 -21.891084)
			(xy 428.097288 -21.961367) (xy 428.080346 -22.030109) (xy 428.055242 -22.096308) (xy 428.022342 -22.158998)
			(xy 427.982124 -22.217265) (xy 427.935177 -22.27026) (xy 427.882184 -22.31721) (xy 427.823918 -22.357429)
			(xy 427.76123 -22.390332) (xy 427.695032 -22.415439) (xy 427.62629 -22.432383) (xy 427.556008 -22.440918)
			(xy 427.520608 -22.441408) (xy 427.520354 -22.441408) (xy 427.487499 -22.440951) (xy 427.422202 -22.4336)
			(xy 427.358139 -22.418984) (xy 427.296114 -22.397288) (xy 427.236909 -22.368784) (xy 427.181267 -22.33383)
			(xy 427.129889 -22.292866) (xy 427.106334 -22.269958) (xy 427.035722 -22.199092) (xy 427.025308 -22.198584)
			(xy 426.994828 -22.224238) (xy 426.968392 -22.245837) (xy 426.911384 -22.283397) (xy 426.850396 -22.314074)
			(xy 426.786256 -22.337453) (xy 426.719832 -22.353218) (xy 426.652026 -22.361153) (xy 426.617892 -22.361652)
			(xy 426.460158 -22.361652) (xy 426.451014 -22.370542) (xy 426.432472 -22.393656) (xy 426.399452 -22.43455)
			(xy 426.396912 -22.438614) (xy 426.39234 -22.450552) (xy 426.389038 -22.463252) (xy 426.389546 -22.46503)
			(xy 426.391578 -22.47519) (xy 426.395412 -22.494395) (xy 426.399607 -22.533333) (xy 426.39996 -22.552914)
			(xy 426.39996 -22.553422) (xy 426.39996 -22.559264) (xy 426.399197 -22.586806) (xy 426.390724 -22.641248)
			(xy 426.37451 -22.693906) (xy 426.350893 -22.743685) (xy 426.320364 -22.789551) (xy 426.283557 -22.830551)
			(xy 426.241237 -22.865832) (xy 426.194285 -22.894662) (xy 426.143674 -22.916441) (xy 426.090458 -22.930716)
			(xy 426.063156 -22.934422) (xy 426.048932 -22.935946) (xy 426.018452 -22.937216) (xy 425.990304 -22.936717)
			(xy 425.934618 -22.928456) (xy 425.880749 -22.912106) (xy 425.829866 -22.888022) (xy 425.783071 -22.856725)
			(xy 425.761912 -22.838156) (xy 425.761404 -22.837648) (xy 425.755909 -22.833066) (xy 425.743017 -22.826875)
			(xy 425.736004 -22.825456) (xy 425.728892 -22.82444) (xy 425.72178 -22.825202) (xy 425.718106 -22.825749)
			(xy 425.710964 -22.827789) (xy 425.707556 -22.829266) (xy 425.690284 -22.836886) (xy 425.62145 -22.867366)
			(xy 425.615903 -22.870163) (xy 425.606262 -22.877994) (xy 425.6024 -22.88286) (xy 425.6024 -23.965154)
			(xy 426.377352 -23.965154) (xy 426.381423 -23.909532) (xy 426.393549 -23.855095) (xy 426.413472 -23.803004)
			(xy 426.440768 -23.754369) (xy 426.474854 -23.710226) (xy 426.515003 -23.671517) (xy 426.560361 -23.639066)
			(xy 426.609961 -23.613565) (xy 426.662745 -23.595558) (xy 426.717588 -23.585428) (xy 426.773322 -23.583391)
			(xy 426.828759 -23.589491) (xy 426.882716 -23.603597) (xy 426.934045 -23.625409) (xy 426.981651 -23.654463)
			(xy 427.024519 -23.690138) (xy 427.061736 -23.731675) (xy 427.092509 -23.778188) (xy 427.116181 -23.828685)
			(xy 427.132249 -23.882092) (xy 427.140369 -23.937268) (xy 427.140544 -23.946866) (xy 427.380398 -23.946866)
			(xy 427.384469 -23.891244) (xy 427.396595 -23.836807) (xy 427.416518 -23.784716) (xy 427.443814 -23.736081)
			(xy 427.4779 -23.691938) (xy 427.518049 -23.653229) (xy 427.563407 -23.620778) (xy 427.613007 -23.595277)
			(xy 427.665791 -23.57727) (xy 427.720634 -23.56714) (xy 427.776368 -23.565103) (xy 427.831805 -23.571203)
			(xy 427.885762 -23.585309) (xy 427.937091 -23.607121) (xy 427.984697 -23.636175) (xy 428.027565 -23.67185)
			(xy 428.064782 -23.713387) (xy 428.095555 -23.7599) (xy 428.119227 -23.810397) (xy 428.135295 -23.863804)
			(xy 428.143415 -23.91898) (xy 428.143924 -23.946866) (xy 428.143484 -23.970996) (xy 428.372776 -23.970996)
			(xy 428.376847 -23.915374) (xy 428.388973 -23.860937) (xy 428.408896 -23.808846) (xy 428.436192 -23.760211)
			(xy 428.470278 -23.716068) (xy 428.510427 -23.677359) (xy 428.555785 -23.644908) (xy 428.605385 -23.619407)
			(xy 428.658169 -23.6014) (xy 428.713012 -23.59127) (xy 428.768746 -23.589233) (xy 428.824183 -23.595333)
			(xy 428.87814 -23.609439) (xy 428.929469 -23.631251) (xy 428.977075 -23.660305) (xy 429.019943 -23.69598)
			(xy 429.05716 -23.737517) (xy 429.087933 -23.78403) (xy 429.111605 -23.834527) (xy 429.127673 -23.887934)
			(xy 429.135793 -23.94311) (xy 429.136302 -23.970996) (xy 429.135793 -23.998882) (xy 429.127673 -24.054058)
			(xy 429.111605 -24.107465) (xy 429.087933 -24.157962) (xy 429.05716 -24.204475) (xy 429.019943 -24.246012)
			(xy 428.977075 -24.281687) (xy 428.929469 -24.310741) (xy 428.87814 -24.332553) (xy 428.824183 -24.346659)
			(xy 428.768746 -24.352759) (xy 428.713012 -24.350722) (xy 428.658169 -24.340592) (xy 428.605385 -24.322585)
			(xy 428.555785 -24.297084) (xy 428.510427 -24.264633) (xy 428.470278 -24.225924) (xy 428.436192 -24.181781)
			(xy 428.408896 -24.133146) (xy 428.388973 -24.081055) (xy 428.376847 -24.026618) (xy 428.372776 -23.970996)
			(xy 428.143484 -23.970996) (xy 428.143415 -23.974752) (xy 428.135295 -24.029928) (xy 428.119227 -24.083335)
			(xy 428.095555 -24.133832) (xy 428.064782 -24.180345) (xy 428.027565 -24.221882) (xy 427.984697 -24.257557)
			(xy 427.937091 -24.286611) (xy 427.885762 -24.308423) (xy 427.831805 -24.322529) (xy 427.776368 -24.328629)
			(xy 427.720634 -24.326592) (xy 427.665791 -24.316462) (xy 427.613007 -24.298455) (xy 427.563407 -24.272954)
			(xy 427.518049 -24.240503) (xy 427.4779 -24.201794) (xy 427.443814 -24.157651) (xy 427.416518 -24.109016)
			(xy 427.396595 -24.056925) (xy 427.384469 -24.002488) (xy 427.380398 -23.946866) (xy 427.140544 -23.946866)
			(xy 427.140878 -23.965154) (xy 427.140369 -23.99304) (xy 427.132249 -24.048216) (xy 427.116181 -24.101623)
			(xy 427.092509 -24.15212) (xy 427.061736 -24.198633) (xy 427.024519 -24.24017) (xy 426.981651 -24.275845)
			(xy 426.934045 -24.304899) (xy 426.882716 -24.326711) (xy 426.828759 -24.340817) (xy 426.773322 -24.346917)
			(xy 426.717588 -24.34488) (xy 426.662745 -24.33475) (xy 426.609961 -24.316743) (xy 426.560361 -24.291242)
			(xy 426.515003 -24.258791) (xy 426.474854 -24.220082) (xy 426.440768 -24.175939) (xy 426.413472 -24.127304)
			(xy 426.393549 -24.075213) (xy 426.381423 -24.020776) (xy 426.377352 -23.965154) (xy 425.6024 -23.965154)
			(xy 425.6024 -24.807418) (xy 432.671218 -24.807418) (xy 432.675289 -24.751796) (xy 432.687415 -24.697359)
			(xy 432.707338 -24.645268) (xy 432.734634 -24.596633) (xy 432.76872 -24.55249) (xy 432.808869 -24.513781)
			(xy 432.854227 -24.48133) (xy 432.903827 -24.455829) (xy 432.956611 -24.437822) (xy 433.011454 -24.427692)
			(xy 433.067188 -24.425655) (xy 433.122625 -24.431755) (xy 433.176582 -24.445861) (xy 433.227911 -24.467673)
			(xy 433.275517 -24.496727) (xy 433.318385 -24.532402) (xy 433.355602 -24.573939) (xy 433.386375 -24.620452)
			(xy 433.410047 -24.670949) (xy 433.426115 -24.724356) (xy 433.434235 -24.779532) (xy 433.434744 -24.807418)
			(xy 433.434235 -24.835304) (xy 433.426115 -24.89048) (xy 433.410047 -24.943887) (xy 433.386375 -24.994384)
			(xy 433.355602 -25.040897) (xy 433.318385 -25.082434) (xy 433.275517 -25.118109) (xy 433.227911 -25.147163)
			(xy 433.176582 -25.168975) (xy 433.122625 -25.183081) (xy 433.067188 -25.189181) (xy 433.011454 -25.187144)
			(xy 432.956611 -25.177014) (xy 432.903827 -25.159007) (xy 432.854227 -25.133506) (xy 432.808869 -25.101055)
			(xy 432.76872 -25.062346) (xy 432.734634 -25.018203) (xy 432.707338 -24.969568) (xy 432.687415 -24.917477)
			(xy 432.675289 -24.86304) (xy 432.671218 -24.807418) (xy 425.6024 -24.807418) (xy 425.6024 -25.93467)
			(xy 425.606681 -25.940005) (xy 425.6175 -25.948368) (xy 425.623736 -25.95118) (xy 425.631864 -25.95372)
			(xy 425.659202 -25.962325) (xy 425.711131 -25.986577) (xy 425.758857 -26.018308) (xy 425.775864 -26.03373)
			(xy 431.567842 -26.03373) (xy 431.571913 -25.978108) (xy 431.584039 -25.923671) (xy 431.603962 -25.87158)
			(xy 431.631258 -25.822945) (xy 431.665344 -25.778802) (xy 431.705493 -25.740093) (xy 431.750851 -25.707642)
			(xy 431.800451 -25.682141) (xy 431.853235 -25.664134) (xy 431.908078 -25.654004) (xy 431.963812 -25.651967)
			(xy 432.019249 -25.658067) (xy 432.073206 -25.672173) (xy 432.124535 -25.693985) (xy 432.172141 -25.723039)
			(xy 432.215009 -25.758714) (xy 432.252226 -25.800251) (xy 432.282999 -25.846764) (xy 432.306671 -25.897261)
			(xy 432.322739 -25.950668) (xy 432.330859 -26.005844) (xy 432.331368 -26.03373) (xy 432.330859 -26.061616)
			(xy 432.322739 -26.116792) (xy 432.306671 -26.170199) (xy 432.282999 -26.220696) (xy 432.252226 -26.267209)
			(xy 432.215009 -26.308746) (xy 432.172141 -26.344421) (xy 432.124535 -26.373475) (xy 432.073206 -26.395287)
			(xy 432.019249 -26.409393) (xy 431.963812 -26.415493) (xy 431.908078 -26.413456) (xy 431.853235 -26.403326)
			(xy 431.800451 -26.385319) (xy 431.750851 -26.359818) (xy 431.705493 -26.327367) (xy 431.665344 -26.288658)
			(xy 431.631258 -26.244515) (xy 431.603962 -26.19588) (xy 431.584039 -26.143789) (xy 431.571913 -26.089352)
			(xy 431.567842 -26.03373) (xy 425.775864 -26.03373) (xy 425.801313 -26.056807) (xy 425.819824 -26.078688)
			(xy 425.834824 -26.097717) (xy 425.860408 -26.138868) (xy 425.880583 -26.182923) (xy 425.88815 -26.205942)
			(xy 425.888658 -26.206958) (xy 425.888912 -26.207974) (xy 425.890974 -26.213414) (xy 425.897135 -26.223278)
			(xy 425.901104 -26.227532) (xy 426.841666 -27.168094) (xy 426.859783 -27.186873) (xy 426.890477 -27.229067)
			(xy 426.914187 -27.275548) (xy 426.930326 -27.325167) (xy 426.938497 -27.376701) (xy 426.938948 -27.40279)
			(xy 426.938948 -28.139136) (xy 428.697896 -28.139136) (xy 428.701967 -28.083514) (xy 428.714093 -28.029077)
			(xy 428.734016 -27.976986) (xy 428.761312 -27.928351) (xy 428.795398 -27.884208) (xy 428.835547 -27.845499)
			(xy 428.880905 -27.813048) (xy 428.930505 -27.787547) (xy 428.983289 -27.76954) (xy 429.038132 -27.75941)
			(xy 429.093866 -27.757373) (xy 429.149303 -27.763473) (xy 429.20326 -27.777579) (xy 429.254589 -27.799391)
			(xy 429.302195 -27.828445) (xy 429.345063 -27.86412) (xy 429.38228 -27.905657) (xy 429.413053 -27.95217)
			(xy 429.436725 -28.002667) (xy 429.452793 -28.056074) (xy 429.460913 -28.11125) (xy 429.461422 -28.139136)
			(xy 429.967896 -28.139136) (xy 429.971967 -28.083514) (xy 429.984093 -28.029077) (xy 430.004016 -27.976986)
			(xy 430.031312 -27.928351) (xy 430.065398 -27.884208) (xy 430.105547 -27.845499) (xy 430.150905 -27.813048)
			(xy 430.200505 -27.787547) (xy 430.253289 -27.76954) (xy 430.308132 -27.75941) (xy 430.363866 -27.757373)
			(xy 430.419303 -27.763473) (xy 430.47326 -27.777579) (xy 430.524589 -27.799391) (xy 430.572195 -27.828445)
			(xy 430.615063 -27.86412) (xy 430.65228 -27.905657) (xy 430.683053 -27.95217) (xy 430.706725 -28.002667)
			(xy 430.722793 -28.056074) (xy 430.730913 -28.11125) (xy 430.731422 -28.139136) (xy 430.730913 -28.167022)
			(xy 430.722793 -28.222198) (xy 430.706725 -28.275605) (xy 430.683053 -28.326102) (xy 430.65228 -28.372615)
			(xy 430.615063 -28.414152) (xy 430.572195 -28.449827) (xy 430.524589 -28.478881) (xy 430.47326 -28.500693)
			(xy 430.419303 -28.514799) (xy 430.363866 -28.520899) (xy 430.308132 -28.518862) (xy 430.253289 -28.508732)
			(xy 430.200505 -28.490725) (xy 430.150905 -28.465224) (xy 430.105547 -28.432773) (xy 430.065398 -28.394064)
			(xy 430.031312 -28.349921) (xy 430.004016 -28.301286) (xy 429.984093 -28.249195) (xy 429.971967 -28.194758)
			(xy 429.967896 -28.139136) (xy 429.461422 -28.139136) (xy 429.460913 -28.167022) (xy 429.452793 -28.222198)
			(xy 429.436725 -28.275605) (xy 429.413053 -28.326102) (xy 429.38228 -28.372615) (xy 429.345063 -28.414152)
			(xy 429.302195 -28.449827) (xy 429.254589 -28.478881) (xy 429.20326 -28.500693) (xy 429.149303 -28.514799)
			(xy 429.093866 -28.520899) (xy 429.038132 -28.518862) (xy 428.983289 -28.508732) (xy 428.930505 -28.490725)
			(xy 428.880905 -28.465224) (xy 428.835547 -28.432773) (xy 428.795398 -28.394064) (xy 428.761312 -28.349921)
			(xy 428.734016 -28.301286) (xy 428.714093 -28.249195) (xy 428.701967 -28.194758) (xy 428.697896 -28.139136)
			(xy 426.938948 -28.139136) (xy 426.938948 -30.187138) (xy 426.938459 -30.213224) (xy 426.930287 -30.264752)
			(xy 426.91415 -30.314366) (xy 426.890446 -30.360843) (xy 426.878786 -30.376876) (xy 427.188884 -30.376876)
			(xy 427.189425 -30.34796) (xy 427.198145 -30.290788) (xy 427.215396 -30.235588) (xy 427.240784 -30.183626)
			(xy 427.273725 -30.136092) (xy 427.313465 -30.094076) (xy 427.33595 -30.075886) (xy 427.344762 -30.068284)
			(xy 427.354941 -30.047379) (xy 427.355508 -30.035754) (xy 427.355508 -29.955998) (xy 427.354953 -29.944368)
			(xy 427.344775 -29.923459) (xy 427.33595 -29.915866) (xy 427.31344 -29.897707) (xy 427.273709 -29.855679)
			(xy 427.240774 -29.808137) (xy 427.215391 -29.75617) (xy 427.19814 -29.700967) (xy 427.189416 -29.643794)
			(xy 427.188884 -29.614876) (xy 427.18937 -29.587625) (xy 427.197126 -29.533677) (xy 427.212481 -29.481382)
			(xy 427.235123 -29.431805) (xy 427.264589 -29.385955) (xy 427.30028 -29.344764) (xy 427.341471 -29.309073)
			(xy 427.387321 -29.279607) (xy 427.436898 -29.256965) (xy 427.489193 -29.24161) (xy 427.543141 -29.233854)
			(xy 427.597643 -29.233854) (xy 427.651591 -29.24161) (xy 427.703886 -29.256965) (xy 427.753463 -29.279607)
			(xy 427.799313 -29.309073) (xy 427.840504 -29.344764) (xy 427.876195 -29.385955) (xy 427.905661 -29.431805)
			(xy 427.928303 -29.481382) (xy 427.943658 -29.533677) (xy 427.951414 -29.587625) (xy 427.9519 -29.614876)
			(xy 427.951364 -29.643792) (xy 427.942639 -29.700963) (xy 427.925384 -29.756161) (xy 427.899996 -29.808123)
			(xy 427.867056 -29.855657) (xy 427.827318 -29.897675) (xy 427.804834 -29.915866) (xy 427.796041 -29.923486)
			(xy 427.785852 -29.944378) (xy 427.785276 -29.955998) (xy 427.785276 -30.035754) (xy 427.785772 -30.047392)
			(xy 427.795988 -30.068303) (xy 427.804834 -30.075886) (xy 427.827318 -30.094076) (xy 427.867051 -30.136097)
			(xy 427.899989 -30.183633) (xy 427.925377 -30.235594) (xy 427.942634 -30.290791) (xy 427.951364 -30.34796)
			(xy 427.9519 -30.376876) (xy 427.951414 -30.404127) (xy 427.943658 -30.458075) (xy 427.928303 -30.51037)
			(xy 427.905661 -30.559947) (xy 427.876195 -30.605797) (xy 427.840504 -30.646988) (xy 427.799313 -30.682679)
			(xy 427.753463 -30.712145) (xy 427.703886 -30.734787) (xy 427.651591 -30.750142) (xy 427.597643 -30.757898)
			(xy 427.543141 -30.757898) (xy 427.489193 -30.750142) (xy 427.436898 -30.734787) (xy 427.387321 -30.712145)
			(xy 427.341471 -30.682679) (xy 427.30028 -30.646988) (xy 427.264589 -30.605797) (xy 427.235123 -30.559947)
			(xy 427.212481 -30.51037) (xy 427.197126 -30.458075) (xy 427.18937 -30.404127) (xy 427.188884 -30.376876)
			(xy 426.878786 -30.376876) (xy 426.85976 -30.403036) (xy 426.841666 -30.421834) (xy 425.883832 -31.379414)
			(xy 425.87855 -31.385131) (xy 425.871444 -31.39897) (xy 425.869862 -31.406592) (xy 425.8691 -31.415228)
			(xy 425.8691 -31.567882) (xy 427.29861 -31.567882) (xy 427.302681 -31.51226) (xy 427.314807 -31.457823)
			(xy 427.33473 -31.405732) (xy 427.362026 -31.357097) (xy 427.396112 -31.312954) (xy 427.436261 -31.274245)
			(xy 427.481619 -31.241794) (xy 427.531219 -31.216293) (xy 427.584003 -31.198286) (xy 427.638846 -31.188156)
			(xy 427.69458 -31.186119) (xy 427.750017 -31.192219) (xy 427.803974 -31.206325) (xy 427.855303 -31.228137)
			(xy 427.902909 -31.257191) (xy 427.945777 -31.292866) (xy 427.982994 -31.334403) (xy 428.013767 -31.380916)
			(xy 428.037439 -31.431413) (xy 428.053507 -31.48482) (xy 428.061627 -31.539996) (xy 428.062136 -31.567882)
			(xy 428.061627 -31.595768) (xy 428.053507 -31.650944) (xy 428.037439 -31.704351) (xy 428.030447 -31.719266)
			(xy 428.585374 -31.719266) (xy 428.589445 -31.663644) (xy 428.601571 -31.609207) (xy 428.621494 -31.557116)
			(xy 428.64879 -31.508481) (xy 428.682876 -31.464338) (xy 428.723025 -31.425629) (xy 428.768383 -31.393178)
			(xy 428.817983 -31.367677) (xy 428.870767 -31.34967) (xy 428.92561 -31.33954) (xy 428.981344 -31.337503)
			(xy 429.036781 -31.343603) (xy 429.090738 -31.357709) (xy 429.142067 -31.379521) (xy 429.189673 -31.408575)
			(xy 429.232541 -31.44425) (xy 429.269758 -31.485787) (xy 429.300531 -31.5323) (xy 429.324203 -31.582797)
			(xy 429.340271 -31.636204) (xy 429.344421 -31.664402) (xy 429.860962 -31.664402) (xy 429.865033 -31.60878)
			(xy 429.877159 -31.554343) (xy 429.897082 -31.502252) (xy 429.924378 -31.453617) (xy 429.958464 -31.409474)
			(xy 429.998613 -31.370765) (xy 430.043971 -31.338314) (xy 430.093571 -31.312813) (xy 430.146355 -31.294806)
			(xy 430.201198 -31.284676) (xy 430.256932 -31.282639) (xy 430.312369 -31.288739) (xy 430.366326 -31.302845)
			(xy 430.417655 -31.324657) (xy 430.465261 -31.353711) (xy 430.508129 -31.389386) (xy 430.545346 -31.430923)
			(xy 430.576119 -31.477436) (xy 430.599791 -31.527933) (xy 430.615859 -31.58134) (xy 430.623979 -31.636516)
			(xy 430.624488 -31.664402) (xy 430.623979 -31.692288) (xy 430.615859 -31.747464) (xy 430.599791 -31.800871)
			(xy 430.576119 -31.851368) (xy 430.545346 -31.897881) (xy 430.508129 -31.939418) (xy 430.465261 -31.975093)
			(xy 430.417655 -32.004147) (xy 430.366326 -32.025959) (xy 430.312369 -32.040065) (xy 430.256932 -32.046165)
			(xy 430.201198 -32.044128) (xy 430.146355 -32.033998) (xy 430.093571 -32.015991) (xy 430.043971 -31.99049)
			(xy 429.998613 -31.958039) (xy 429.958464 -31.91933) (xy 429.924378 -31.875187) (xy 429.897082 -31.826552)
			(xy 429.877159 -31.774461) (xy 429.865033 -31.720024) (xy 429.860962 -31.664402) (xy 429.344421 -31.664402)
			(xy 429.348391 -31.69138) (xy 429.3489 -31.719266) (xy 429.348391 -31.747152) (xy 429.340271 -31.802328)
			(xy 429.324203 -31.855735) (xy 429.300531 -31.906232) (xy 429.269758 -31.952745) (xy 429.232541 -31.994282)
			(xy 429.189673 -32.029957) (xy 429.142067 -32.059011) (xy 429.090738 -32.080823) (xy 429.036781 -32.094929)
			(xy 428.981344 -32.101029) (xy 428.92561 -32.098992) (xy 428.870767 -32.088862) (xy 428.817983 -32.070855)
			(xy 428.768383 -32.045354) (xy 428.723025 -32.012903) (xy 428.682876 -31.974194) (xy 428.64879 -31.930051)
			(xy 428.621494 -31.881416) (xy 428.601571 -31.829325) (xy 428.589445 -31.774888) (xy 428.585374 -31.719266)
			(xy 428.030447 -31.719266) (xy 428.013767 -31.754848) (xy 427.982994 -31.801361) (xy 427.945777 -31.842898)
			(xy 427.902909 -31.878573) (xy 427.855303 -31.907627) (xy 427.803974 -31.929439) (xy 427.750017 -31.943545)
			(xy 427.69458 -31.949645) (xy 427.638846 -31.947608) (xy 427.584003 -31.937478) (xy 427.531219 -31.919471)
			(xy 427.481619 -31.89397) (xy 427.436261 -31.861519) (xy 427.396112 -31.82281) (xy 427.362026 -31.778667)
			(xy 427.33473 -31.730032) (xy 427.314807 -31.677941) (xy 427.302681 -31.623504) (xy 427.29861 -31.567882)
			(xy 425.8691 -31.567882) (xy 425.8691 -31.985458) (xy 425.869403 -31.993654) (xy 425.874575 -32.009208)
			(xy 425.87926 -32.015938) (xy 429.128031 -35.264852) (xy 430.202338 -35.264852) (xy 430.206409 -35.20923)
			(xy 430.218535 -35.154793) (xy 430.238458 -35.102702) (xy 430.265754 -35.054067) (xy 430.29984 -35.009924)
			(xy 430.339989 -34.971215) (xy 430.385347 -34.938764) (xy 430.434947 -34.913263) (xy 430.487731 -34.895256)
			(xy 430.542574 -34.885126) (xy 430.598308 -34.883089) (xy 430.653745 -34.889189) (xy 430.707702 -34.903295)
			(xy 430.759031 -34.925107) (xy 430.806637 -34.954161) (xy 430.849505 -34.989836) (xy 430.886722 -35.031373)
			(xy 430.917495 -35.077886) (xy 430.941167 -35.128383) (xy 430.957235 -35.18179) (xy 430.965355 -35.236966)
			(xy 430.965864 -35.264852) (xy 430.965355 -35.292738) (xy 430.957235 -35.347914) (xy 430.941167 -35.401321)
			(xy 430.917495 -35.451818) (xy 430.886722 -35.498331) (xy 430.849505 -35.539868) (xy 430.806637 -35.575543)
			(xy 430.759031 -35.604597) (xy 430.707702 -35.626409) (xy 430.653745 -35.640515) (xy 430.598308 -35.646615)
			(xy 430.542574 -35.644578) (xy 430.487731 -35.634448) (xy 430.434947 -35.616441) (xy 430.385347 -35.59094)
			(xy 430.339989 -35.558489) (xy 430.29984 -35.51978) (xy 430.265754 -35.475637) (xy 430.238458 -35.427002)
			(xy 430.218535 -35.374911) (xy 430.206409 -35.320474) (xy 430.202338 -35.264852) (xy 429.128031 -35.264852)
			(xy 430.150082 -36.286948) (xy 431.500278 -36.286948) (xy 431.504349 -36.231326) (xy 431.516475 -36.176889)
			(xy 431.536398 -36.124798) (xy 431.563694 -36.076163) (xy 431.59778 -36.03202) (xy 431.637929 -35.993311)
			(xy 431.683287 -35.96086) (xy 431.732887 -35.935359) (xy 431.785671 -35.917352) (xy 431.840514 -35.907222)
			(xy 431.896248 -35.905185) (xy 431.951685 -35.911285) (xy 432.005642 -35.925391) (xy 432.056971 -35.947203)
			(xy 432.104577 -35.976257) (xy 432.147445 -36.011932) (xy 432.184662 -36.053469) (xy 432.215435 -36.099982)
			(xy 432.239107 -36.150479) (xy 432.255175 -36.203886) (xy 432.263295 -36.259062) (xy 432.263804 -36.286948)
			(xy 432.263295 -36.314834) (xy 432.255175 -36.37001) (xy 432.239107 -36.423417) (xy 432.215435 -36.473914)
			(xy 432.184662 -36.520427) (xy 432.147445 -36.561964) (xy 432.104577 -36.597639) (xy 432.056971 -36.626693)
			(xy 432.005642 -36.648505) (xy 431.951685 -36.662611) (xy 431.896248 -36.668711) (xy 431.840514 -36.666674)
			(xy 431.785671 -36.656544) (xy 431.732887 -36.638537) (xy 431.683287 -36.613036) (xy 431.637929 -36.580585)
			(xy 431.59778 -36.541876) (xy 431.563694 -36.497733) (xy 431.536398 -36.449098) (xy 431.516475 -36.397007)
			(xy 431.504349 -36.34257) (xy 431.500278 -36.286948) (xy 430.150082 -36.286948) (xy 431.630074 -37.767006)
			(xy 431.634721 -37.767522) (xy 431.644056 -37.767018) (xy 431.648616 -37.76599) (xy 431.678842 -37.756846)
			(xy 431.67935 -37.756846) (xy 431.726848 -37.742114) (xy 431.73523 -37.73805) (xy 431.745644 -37.729922)
			(xy 431.755296 -37.719) (xy 431.755804 -37.718492) (xy 431.763932 -37.709602) (xy 431.770282 -37.69995)
			(xy 431.773584 -37.6936) (xy 431.7746 -37.689536) (xy 431.775108 -37.686996) (xy 431.782125 -37.65944)
			(xy 431.803205 -37.606631) (xy 431.831884 -37.557533) (xy 431.867526 -37.51323) (xy 431.909345 -37.474702)
			(xy 431.956414 -37.442803) (xy 432.007694 -37.418236) (xy 432.06205 -37.401545) (xy 432.11828 -37.393099)
			(xy 432.14671 -37.39261) (xy 432.173962 -37.393074) (xy 432.227911 -37.400832) (xy 432.280206 -37.416189)
			(xy 432.329784 -37.438833) (xy 432.375635 -37.468301) (xy 432.416825 -37.503995) (xy 432.452516 -37.545188)
			(xy 432.481981 -37.59104) (xy 432.50462 -37.64062) (xy 432.519974 -37.692917) (xy 432.527728 -37.746866)
			(xy 432.528218 -37.774118) (xy 432.527693 -37.802547) (xy 432.519257 -37.858775) (xy 432.502573 -37.91313)
			(xy 432.478011 -37.96441) (xy 432.446115 -38.011478) (xy 432.40759 -38.053295) (xy 432.363288 -38.088934)
			(xy 432.31419 -38.117608) (xy 432.261381 -38.138681) (xy 432.233832 -38.14572) (xy 432.233578 -38.14572)
			(xy 432.226466 -38.147498) (xy 432.216052 -38.152832) (xy 432.209194 -38.158928) (xy 432.20894 -38.159182)
			(xy 432.202336 -38.165024) (xy 432.201828 -38.165532) (xy 432.190906 -38.175184) (xy 432.182778 -38.185598)
			(xy 432.178714 -38.19398) (xy 432.163982 -38.241478) (xy 432.163982 -38.241986) (xy 432.154838 -38.272212)
			(xy 432.153848 -38.276778) (xy 432.153345 -38.286106) (xy 432.153822 -38.290754) (xy 433.232814 -39.369746)
			(xy 433.238417 -39.374159) (xy 433.251441 -39.379957) (xy 433.258468 -39.381176) (xy 433.274051 -39.382801)
			(xy 433.304933 -39.377615) (xy 433.332812 -39.363358) (xy 433.34432 -39.352728) (xy 433.344828 -39.35222)
			(xy 433.354988 -39.340028) (xy 433.359145 -39.333515) (xy 433.363801 -39.318791) (xy 433.364132 -39.311072)
			(xy 433.364132 -36.711128) (xy 433.361338 -36.699698) (xy 433.358544 -36.694364) (xy 433.35321 -36.68395)
			(xy 433.348638 -36.674044) (xy 433.343764 -36.663049) (xy 433.335249 -36.640553) (xy 433.33162 -36.629086)
			(xy 433.33162 -36.628324) (xy 433.329572 -36.622664) (xy 433.32328 -36.612406) (xy 433.319174 -36.608004)
			(xy 431.828702 -35.117532) (xy 431.810591 -35.098751) (xy 431.779909 -35.056553) (xy 431.756212 -35.010072)
			(xy 431.740086 -34.960454) (xy 431.731927 -34.908923) (xy 431.73142 -34.882836) (xy 431.73142 -32.410654)
			(xy 431.727102 -32.405574) (xy 431.674524 -32.362394) (xy 431.663348 -32.35325) (xy 431.66049 -32.350959)
			(xy 431.654242 -32.347135) (xy 431.650902 -32.34563) (xy 431.62982 -32.350202) (xy 431.599762 -32.356212)
			(xy 431.538804 -32.362699) (xy 431.508154 -32.363156) (xy 431.472743 -32.362619) (xy 431.402439 -32.354077)
			(xy 431.333677 -32.337123) (xy 431.26746 -32.312005) (xy 431.204753 -32.279089) (xy 431.146471 -32.238854)
			(xy 431.093464 -32.191888) (xy 431.046504 -32.138875) (xy 431.006276 -32.080588) (xy 430.973367 -32.017878)
			(xy 430.948256 -31.951658) (xy 430.931311 -31.882894) (xy 430.922777 -31.812589) (xy 430.922176 -31.777178)
			(xy 430.922176 -30.776164) (xy 430.91976 -30.773071) (xy 430.914149 -30.767584) (xy 430.911 -30.765242)
			(xy 430.876202 -30.743906) (xy 430.83861 -30.720792) (xy 430.828196 -30.715966) (xy 430.82591 -30.715204)
			(xy 430.816661 -30.712963) (xy 430.797732 -30.714795) (xy 430.78908 -30.71876) (xy 430.788826 -30.71876)
			(xy 430.778158 -30.724094) (xy 430.751929 -30.736186) (xy 430.696754 -30.753258) (xy 430.63965 -30.761911)
			(xy 430.610772 -30.762448) (xy 430.610518 -30.762448) (xy 430.582975 -30.761981) (xy 430.528448 -30.754143)
			(xy 430.475593 -30.738625) (xy 430.425484 -30.715742) (xy 430.379141 -30.68596) (xy 430.33751 -30.649886)
			(xy 430.301436 -30.608254) (xy 430.271655 -30.561911) (xy 430.248773 -30.511802) (xy 430.233255 -30.458946)
			(xy 430.225419 -30.404419) (xy 430.224946 -30.376876) (xy 430.225469 -30.347906) (xy 430.234145 -30.29062)
			(xy 430.251297 -30.235277) (xy 430.276539 -30.183124) (xy 430.309302 -30.135338) (xy 430.348849 -30.092993)
			(xy 430.37125 -30.074616) (xy 430.375622 -30.070963) (xy 430.382808 -30.062125) (xy 430.385474 -30.05709)
			(xy 430.390046 -30.047692) (xy 430.3903 -30.047184) (xy 430.392764 -30.041859) (xy 430.395462 -30.030443)
			(xy 430.395634 -30.024578) (xy 430.395634 -29.967682) (xy 430.395492 -29.962242) (xy 430.393184 -29.951611)
			(xy 430.391062 -29.9466) (xy 430.38776 -29.939742) (xy 430.38776 -29.939234) (xy 430.380902 -29.925518)
			(xy 430.37252 -29.914088) (xy 430.367694 -29.909262) (xy 430.365916 -29.907738) (xy 430.344891 -29.889498)
			(xy 430.307831 -29.847972) (xy 430.277192 -29.801505) (xy 430.253623 -29.751083) (xy 430.237623 -29.697773)
			(xy 430.229532 -29.642705) (xy 430.22901 -29.614876) (xy 430.229498 -29.587626) (xy 430.237257 -29.533682)
			(xy 430.252615 -29.481391) (xy 430.275257 -29.431818) (xy 430.304725 -29.385972) (xy 430.340416 -29.344787)
			(xy 430.381606 -29.309099) (xy 430.427455 -29.279637) (xy 430.477031 -29.257) (xy 430.529323 -29.241648)
			(xy 430.583268 -29.233895) (xy 430.610518 -29.233368) (xy 430.635946 -29.23379) (xy 430.686351 -29.240548)
			(xy 430.735411 -29.253943) (xy 430.782257 -29.273737) (xy 430.826058 -29.299579) (xy 430.866038 -29.331011)
			(xy 430.884076 -29.348938) (xy 430.890934 -29.35605) (xy 430.926494 -29.371798) (xy 430.93894 -29.37129)
			(xy 430.962054 -29.37002) (xy 430.968345 -29.369593) (xy 430.980424 -29.365983) (xy 430.98593 -29.362908)
			(xy 430.99101 -29.35986) (xy 430.999646 -29.351224) (xy 431.003202 -29.345128) (xy 431.022531 -29.313411)
			(xy 431.068007 -29.254683) (xy 431.09388 -29.228034) (xy 432.409854 -27.912314) (xy 433.53482 -26.787094)
			(xy 433.538122 -26.78303) (xy 433.542259 -26.77652) (xy 433.546788 -26.761784) (xy 433.547012 -26.754074)
			(xy 433.547012 -24.158194) (xy 433.547507 -24.124108) (xy 433.555422 -24.056398) (xy 433.571143 -23.990064)
			(xy 433.594459 -23.926004) (xy 433.625054 -23.865084) (xy 433.662515 -23.808127) (xy 433.706335 -23.755905)
			(xy 433.755921 -23.709123) (xy 433.810603 -23.668414) (xy 433.869641 -23.634328) (xy 433.932237 -23.607327)
			(xy 433.997544 -23.587775) (xy 434.06468 -23.575937) (xy 434.132736 -23.571974) (xy 434.200792 -23.575937)
			(xy 434.267928 -23.587775) (xy 434.333235 -23.607327) (xy 434.395831 -23.634328) (xy 434.454869 -23.668414)
			(xy 434.509551 -23.709123) (xy 434.559137 -23.755905) (xy 434.602957 -23.808127) (xy 434.640418 -23.865084)
			(xy 434.671013 -23.926004) (xy 434.694329 -23.990064) (xy 434.71005 -24.056398) (xy 434.717965 -24.124108)
			(xy 434.71846 -24.158194) (xy 434.71846 -24.807418) (xy 434.920134 -24.807418) (xy 434.924205 -24.751796)
			(xy 434.936331 -24.697359) (xy 434.956254 -24.645268) (xy 434.98355 -24.596633) (xy 435.017636 -24.55249)
			(xy 435.057785 -24.513781) (xy 435.103143 -24.48133) (xy 435.152743 -24.455829) (xy 435.205527 -24.437822)
			(xy 435.26037 -24.427692) (xy 435.316104 -24.425655) (xy 435.371541 -24.431755) (xy 435.425498 -24.445861)
			(xy 435.476827 -24.467673) (xy 435.524433 -24.496727) (xy 435.567301 -24.532402) (xy 435.604518 -24.573939)
			(xy 435.635291 -24.620452) (xy 435.658963 -24.670949) (xy 435.675031 -24.724356) (xy 435.683151 -24.779532)
			(xy 435.68366 -24.807418) (xy 435.683151 -24.835304) (xy 435.675031 -24.89048) (xy 435.658963 -24.943887)
			(xy 435.635291 -24.994384) (xy 435.604518 -25.040897) (xy 435.567301 -25.082434) (xy 435.524433 -25.118109)
			(xy 435.476827 -25.147163) (xy 435.425498 -25.168975) (xy 435.371541 -25.183081) (xy 435.316104 -25.189181)
			(xy 435.26037 -25.187144) (xy 435.205527 -25.177014) (xy 435.152743 -25.159007) (xy 435.103143 -25.133506)
			(xy 435.057785 -25.101055) (xy 435.017636 -25.062346) (xy 434.98355 -25.018203) (xy 434.956254 -24.969568)
			(xy 434.936331 -24.917477) (xy 434.924205 -24.86304) (xy 434.920134 -24.807418) (xy 434.71846 -24.807418)
			(xy 434.71846 -26.724356) (xy 434.720673 -26.727204) (xy 434.725771 -26.732305) (xy 434.72862 -26.734516)
			(xy 434.995066 -26.734516) (xy 434.998735 -26.734468) (xy 435.006002 -26.733444) (xy 435.009544 -26.732484)
			(xy 435.02961 -26.726388) (xy 435.034944 -26.72334) (xy 435.035452 -26.722832) (xy 435.043072 -26.71826)
			(xy 435.04866 -26.715212) (xy 435.060852 -26.703274) (xy 435.062884 -26.701242) (xy 435.0639 -26.699972)
			(xy 435.070379 -26.692027) (xy 435.076944 -26.672625) (xy 435.0766 -26.66238) (xy 435.075838 -26.652474)
			(xy 435.071012 -26.643076) (xy 435.066694 -26.636726) (xy 435.05755 -26.626312) (xy 435.04231 -26.613104)
			(xy 435.036214 -26.610056) (xy 435.012331 -26.598009) (xy 434.967896 -26.56823) (xy 434.92805 -26.532542)
			(xy 434.893573 -26.491644) (xy 434.86514 -26.446336) (xy 434.843306 -26.397504) (xy 434.828499 -26.346103)
			(xy 434.821009 -26.293139) (xy 434.820568 -26.266394) (xy 434.821054 -26.239143) (xy 434.82881 -26.185195)
			(xy 434.844165 -26.1329) (xy 434.866807 -26.083323) (xy 434.896273 -26.037473) (xy 434.931964 -25.996282)
			(xy 434.973155 -25.960591) (xy 435.019005 -25.931125) (xy 435.068582 -25.908483) (xy 435.120877 -25.893128)
			(xy 435.174825 -25.885372) (xy 435.229327 -25.885372) (xy 435.283275 -25.893128) (xy 435.33557 -25.908483)
			(xy 435.385147 -25.931125) (xy 435.430997 -25.960591) (xy 435.472188 -25.996282) (xy 435.507879 -26.037473)
			(xy 435.537345 -26.083323) (xy 435.559987 -26.1329) (xy 435.575342 -26.185195) (xy 435.583098 -26.239143)
			(xy 435.583584 -26.266394) (xy 435.58305 -26.295311) (xy 435.574324 -26.352482) (xy 435.55707 -26.407682)
			(xy 435.531684 -26.459646) (xy 435.498747 -26.507183) (xy 435.459013 -26.549207) (xy 435.436518 -26.567384)
			(xy 435.431946 -26.57094) (xy 435.422548 -26.58237) (xy 435.420044 -26.585497) (xy 435.415958 -26.592387)
			(xy 435.41442 -26.596086) (xy 435.412556 -26.601145) (xy 435.410766 -26.611777) (xy 435.410864 -26.617168)
			(xy 435.412388 -26.649934) (xy 435.412388 -26.650442) (xy 435.413404 -26.672794) (xy 435.414239 -26.681492)
			(xy 435.420995 -26.697595) (xy 435.426612 -26.70429) (xy 435.427374 -26.705306) (xy 435.439058 -26.71699)
			(xy 435.4449 -26.720292) (xy 435.470365 -26.735858) (xy 435.516811 -26.773337) (xy 435.557194 -26.817281)
			(xy 435.590625 -26.866721) (xy 435.616365 -26.920566) (xy 435.633848 -26.97763) (xy 435.642687 -27.036653)
			(xy 435.643274 -27.066494) (xy 435.642788 -27.095125) (xy 435.634639 -27.151805) (xy 435.618506 -27.206747)
			(xy 435.594718 -27.258834) (xy 435.563758 -27.307006) (xy 435.526258 -27.35028) (xy 435.48298 -27.387777)
			(xy 435.434806 -27.418733) (xy 435.382717 -27.442517) (xy 435.327773 -27.458646) (xy 435.271093 -27.46679)
			(xy 435.242462 -27.467306) (xy 435.213913 -27.466806) (xy 435.157391 -27.458713) (xy 435.102589 -27.442684)
			(xy 435.050616 -27.41904) (xy 435.026308 -27.40406) (xy 435.017164 -27.398472) (xy 434.878226 -27.398472)
			(xy 434.8734 -27.403552) (xy 434.871622 -27.405076) (xy 434.870352 -27.406092) (xy 433.154074 -29.12237)
			(xy 434.906928 -29.12237) (xy 434.906928 -28.25877) (xy 434.907418 -28.228802) (xy 434.915241 -28.16938)
			(xy 434.930754 -28.111487) (xy 434.95369 -28.056114) (xy 434.983657 -28.004208) (xy 435.020144 -27.956658)
			(xy 435.062524 -27.914278) (xy 435.110074 -27.877791) (xy 435.16198 -27.847824) (xy 435.217353 -27.824888)
			(xy 435.275246 -27.809375) (xy 435.334668 -27.801552) (xy 435.394604 -27.801552) (xy 435.454026 -27.809375)
			(xy 435.511919 -27.824888) (xy 435.567292 -27.847824) (xy 435.619198 -27.877791) (xy 435.666748 -27.914278)
			(xy 435.709128 -27.956658) (xy 435.745615 -28.004208) (xy 435.775582 -28.056114) (xy 435.798518 -28.111487)
			(xy 435.814031 -28.16938) (xy 435.821854 -28.228802) (xy 435.822344 -28.25877) (xy 435.822344 -29.114242)
			(xy 445.147192 -29.114242) (xy 445.147192 -28.250642) (xy 445.147682 -28.220658) (xy 445.15551 -28.161202)
			(xy 445.171031 -28.103277) (xy 445.19398 -28.047873) (xy 445.223964 -27.995939) (xy 445.26047 -27.948363)
			(xy 445.302875 -27.905958) (xy 445.350451 -27.869452) (xy 445.402385 -27.839468) (xy 445.457789 -27.816519)
			(xy 445.515714 -27.800998) (xy 445.57517 -27.79317) (xy 445.635138 -27.79317) (xy 445.694594 -27.800998)
			(xy 445.752519 -27.816519) (xy 445.807923 -27.839468) (xy 445.859857 -27.869452) (xy 445.907433 -27.905958)
			(xy 445.949838 -27.948363) (xy 445.986344 -27.995939) (xy 446.016328 -28.047873) (xy 446.039277 -28.103277)
			(xy 446.054798 -28.161202) (xy 446.062626 -28.220658) (xy 446.063116 -28.250642) (xy 446.063116 -29.114242)
			(xy 446.062626 -29.144226) (xy 446.054798 -29.203682) (xy 446.039277 -29.261607) (xy 446.016328 -29.317011)
			(xy 445.986344 -29.368945) (xy 445.949838 -29.416521) (xy 445.907433 -29.458926) (xy 445.859857 -29.495432)
			(xy 445.807923 -29.525416) (xy 445.752519 -29.548365) (xy 445.694594 -29.563886) (xy 445.635138 -29.571714)
			(xy 445.57517 -29.571714) (xy 445.515714 -29.563886) (xy 445.457789 -29.548365) (xy 445.402385 -29.525416)
			(xy 445.350451 -29.495432) (xy 445.302875 -29.458926) (xy 445.26047 -29.416521) (xy 445.223964 -29.368945)
			(xy 445.19398 -29.317011) (xy 445.171031 -29.261607) (xy 445.15551 -29.203682) (xy 445.147682 -29.144226)
			(xy 445.147192 -29.114242) (xy 435.822344 -29.114242) (xy 435.822344 -29.12237) (xy 435.821854 -29.152338)
			(xy 435.814031 -29.21176) (xy 435.798518 -29.269653) (xy 435.775582 -29.325026) (xy 435.745615 -29.376932)
			(xy 435.709128 -29.424482) (xy 435.666748 -29.466862) (xy 435.619198 -29.503349) (xy 435.567292 -29.533316)
			(xy 435.511919 -29.556252) (xy 435.454026 -29.571765) (xy 435.394604 -29.579588) (xy 435.334668 -29.579588)
			(xy 435.275246 -29.571765) (xy 435.217353 -29.556252) (xy 435.16198 -29.533316) (xy 435.110074 -29.503349)
			(xy 435.062524 -29.466862) (xy 435.020144 -29.424482) (xy 434.983657 -29.376932) (xy 434.95369 -29.325026)
			(xy 434.930754 -29.269653) (xy 434.915241 -29.21176) (xy 434.907418 -29.152338) (xy 434.906928 -29.12237)
			(xy 433.154074 -29.12237) (xy 432.397154 -29.87929) (xy 432.395376 -29.881576) (xy 432.395376 -30.922468)
			(xy 433.052728 -30.922468) (xy 433.052728 -30.058868) (xy 433.053218 -30.0289) (xy 433.061041 -29.969478)
			(xy 433.076554 -29.911585) (xy 433.09949 -29.856212) (xy 433.129457 -29.804306) (xy 433.165944 -29.756756)
			(xy 433.208324 -29.714376) (xy 433.255874 -29.677889) (xy 433.30778 -29.647922) (xy 433.363153 -29.624986)
			(xy 433.421046 -29.609473) (xy 433.480468 -29.60165) (xy 433.540404 -29.60165) (xy 433.599826 -29.609473)
			(xy 433.657719 -29.624986) (xy 433.713092 -29.647922) (xy 433.764998 -29.677889) (xy 433.812548 -29.714376)
			(xy 433.854928 -29.756756) (xy 433.891415 -29.804306) (xy 433.921382 -29.856212) (xy 433.944318 -29.911585)
			(xy 433.959831 -29.969478) (xy 433.967654 -30.0289) (xy 433.968144 -30.058868) (xy 433.968144 -30.92069)
			(xy 447.7893 -30.92069) (xy 447.7893 -30.05709) (xy 447.78979 -30.027106) (xy 447.797618 -29.96765)
			(xy 447.813139 -29.909725) (xy 447.836088 -29.854321) (xy 447.866072 -29.802387) (xy 447.902578 -29.754811)
			(xy 447.944983 -29.712406) (xy 447.992559 -29.6759) (xy 448.044493 -29.645916) (xy 448.099897 -29.622967)
			(xy 448.157822 -29.607446) (xy 448.217278 -29.599618) (xy 448.277246 -29.599618) (xy 448.336702 -29.607446)
			(xy 448.394627 -29.622967) (xy 448.450031 -29.645916) (xy 448.501965 -29.6759) (xy 448.549541 -29.712406)
			(xy 448.591946 -29.754811) (xy 448.628452 -29.802387) (xy 448.658436 -29.854321) (xy 448.681385 -29.909725)
			(xy 448.696906 -29.96765) (xy 448.704734 -30.027106) (xy 448.705224 -30.05709) (xy 448.705224 -30.92069)
			(xy 448.704734 -30.950674) (xy 448.696906 -31.01013) (xy 448.681385 -31.068055) (xy 448.658436 -31.123459)
			(xy 448.628452 -31.175393) (xy 448.591946 -31.222969) (xy 448.549541 -31.265374) (xy 448.501965 -31.30188)
			(xy 448.450031 -31.331864) (xy 448.394627 -31.354813) (xy 448.336702 -31.370334) (xy 448.277246 -31.378162)
			(xy 448.217278 -31.378162) (xy 448.157822 -31.370334) (xy 448.099897 -31.354813) (xy 448.044493 -31.331864)
			(xy 447.992559 -31.30188) (xy 447.944983 -31.265374) (xy 447.902578 -31.222969) (xy 447.866072 -31.175393)
			(xy 447.836088 -31.123459) (xy 447.813139 -31.068055) (xy 447.797618 -31.01013) (xy 447.78979 -30.950674)
			(xy 447.7893 -30.92069) (xy 433.968144 -30.92069) (xy 433.968144 -30.922468) (xy 433.967654 -30.952436)
			(xy 433.959831 -31.011858) (xy 433.944318 -31.069751) (xy 433.921382 -31.125124) (xy 433.891415 -31.17703)
			(xy 433.854928 -31.22458) (xy 433.812548 -31.26696) (xy 433.764998 -31.303447) (xy 433.713092 -31.333414)
			(xy 433.657719 -31.35635) (xy 433.599826 -31.371863) (xy 433.540404 -31.379686) (xy 433.480468 -31.379686)
			(xy 433.421046 -31.371863) (xy 433.363153 -31.35635) (xy 433.30778 -31.333414) (xy 433.255874 -31.303447)
			(xy 433.208324 -31.26696) (xy 433.165944 -31.22458) (xy 433.129457 -31.17703) (xy 433.09949 -31.125124)
			(xy 433.076554 -31.069751) (xy 433.061041 -31.011858) (xy 433.053218 -30.952436) (xy 433.052728 -30.922468)
			(xy 432.395376 -30.922468) (xy 432.395376 -32.722312) (xy 434.906928 -32.722312) (xy 434.906928 -31.858712)
			(xy 434.907418 -31.828744) (xy 434.915241 -31.769322) (xy 434.930754 -31.711429) (xy 434.95369 -31.656056)
			(xy 434.983657 -31.60415) (xy 435.020144 -31.5566) (xy 435.062524 -31.51422) (xy 435.110074 -31.477733)
			(xy 435.16198 -31.447766) (xy 435.217353 -31.42483) (xy 435.275246 -31.409317) (xy 435.334668 -31.401494)
			(xy 435.394604 -31.401494) (xy 435.454026 -31.409317) (xy 435.511919 -31.42483) (xy 435.567292 -31.447766)
			(xy 435.619198 -31.477733) (xy 435.666748 -31.51422) (xy 435.709128 -31.5566) (xy 435.745615 -31.60415)
			(xy 435.775582 -31.656056) (xy 435.798518 -31.711429) (xy 435.814031 -31.769322) (xy 435.821854 -31.828744)
			(xy 435.822344 -31.858712) (xy 435.822344 -32.714184) (xy 445.147192 -32.714184) (xy 445.147192 -31.850584)
			(xy 445.147682 -31.8206) (xy 445.15551 -31.761144) (xy 445.171031 -31.703219) (xy 445.19398 -31.647815)
			(xy 445.223964 -31.595881) (xy 445.26047 -31.548305) (xy 445.302875 -31.5059) (xy 445.350451 -31.469394)
			(xy 445.402385 -31.43941) (xy 445.457789 -31.416461) (xy 445.515714 -31.40094) (xy 445.57517 -31.393112)
			(xy 445.635138 -31.393112) (xy 445.694594 -31.40094) (xy 445.752519 -31.416461) (xy 445.807923 -31.43941)
			(xy 445.859857 -31.469394) (xy 445.907433 -31.5059) (xy 445.949838 -31.548305) (xy 445.986344 -31.595881)
			(xy 446.016328 -31.647815) (xy 446.039277 -31.703219) (xy 446.054798 -31.761144) (xy 446.062626 -31.8206)
			(xy 446.063116 -31.850584) (xy 446.063116 -32.714184) (xy 446.062626 -32.744168) (xy 446.054798 -32.803624)
			(xy 446.039277 -32.861549) (xy 446.016328 -32.916953) (xy 445.986344 -32.968887) (xy 445.949838 -33.016463)
			(xy 445.907433 -33.058868) (xy 445.859857 -33.095374) (xy 445.807923 -33.125358) (xy 445.752519 -33.148307)
			(xy 445.694594 -33.163828) (xy 445.635138 -33.171656) (xy 445.57517 -33.171656) (xy 445.515714 -33.163828)
			(xy 445.457789 -33.148307) (xy 445.402385 -33.125358) (xy 445.350451 -33.095374) (xy 445.302875 -33.058868)
			(xy 445.26047 -33.016463) (xy 445.223964 -32.968887) (xy 445.19398 -32.916953) (xy 445.171031 -32.861549)
			(xy 445.15551 -32.803624) (xy 445.147682 -32.744168) (xy 445.147192 -32.714184) (xy 435.822344 -32.714184)
			(xy 435.822344 -32.722312) (xy 435.821854 -32.75228) (xy 435.814031 -32.811702) (xy 435.798518 -32.869595)
			(xy 435.775582 -32.924968) (xy 435.745615 -32.976874) (xy 435.709128 -33.024424) (xy 435.666748 -33.066804)
			(xy 435.619198 -33.103291) (xy 435.567292 -33.133258) (xy 435.511919 -33.156194) (xy 435.454026 -33.171707)
			(xy 435.394604 -33.17953) (xy 435.334668 -33.17953) (xy 435.275246 -33.171707) (xy 435.217353 -33.156194)
			(xy 435.16198 -33.133258) (xy 435.110074 -33.103291) (xy 435.062524 -33.066804) (xy 435.020144 -33.024424)
			(xy 434.983657 -32.976874) (xy 434.95369 -32.924968) (xy 434.930754 -32.869595) (xy 434.915241 -32.811702)
			(xy 434.907418 -32.75228) (xy 434.906928 -32.722312) (xy 432.395376 -32.722312) (xy 432.395376 -34.52241)
			(xy 433.052728 -34.52241) (xy 433.052728 -33.65881) (xy 433.053218 -33.628842) (xy 433.061041 -33.56942)
			(xy 433.076554 -33.511527) (xy 433.09949 -33.456154) (xy 433.129457 -33.404248) (xy 433.165944 -33.356698)
			(xy 433.208324 -33.314318) (xy 433.255874 -33.277831) (xy 433.30778 -33.247864) (xy 433.363153 -33.224928)
			(xy 433.421046 -33.209415) (xy 433.480468 -33.201592) (xy 433.540404 -33.201592) (xy 433.599826 -33.209415)
			(xy 433.657719 -33.224928) (xy 433.713092 -33.247864) (xy 433.764998 -33.277831) (xy 433.812548 -33.314318)
			(xy 433.854928 -33.356698) (xy 433.891415 -33.404248) (xy 433.921382 -33.456154) (xy 433.944318 -33.511527)
			(xy 433.959831 -33.56942) (xy 433.967654 -33.628842) (xy 433.968144 -33.65881) (xy 433.968144 -34.520886)
			(xy 447.7893 -34.520886) (xy 447.7893 -33.657286) (xy 447.78979 -33.627302) (xy 447.797618 -33.567846)
			(xy 447.813139 -33.509921) (xy 447.836088 -33.454517) (xy 447.866072 -33.402583) (xy 447.902578 -33.355007)
			(xy 447.944983 -33.312602) (xy 447.992559 -33.276096) (xy 448.044493 -33.246112) (xy 448.099897 -33.223163)
			(xy 448.157822 -33.207642) (xy 448.217278 -33.199814) (xy 448.277246 -33.199814) (xy 448.336702 -33.207642)
			(xy 448.394627 -33.223163) (xy 448.450031 -33.246112) (xy 448.501965 -33.276096) (xy 448.549541 -33.312602)
			(xy 448.591946 -33.355007) (xy 448.628452 -33.402583) (xy 448.658436 -33.454517) (xy 448.681385 -33.509921)
			(xy 448.696906 -33.567846) (xy 448.704734 -33.627302) (xy 448.705224 -33.657286) (xy 448.705224 -34.520886)
			(xy 448.704734 -34.55087) (xy 448.696906 -34.610326) (xy 448.681385 -34.668251) (xy 448.658436 -34.723655)
			(xy 448.628452 -34.775589) (xy 448.591946 -34.823165) (xy 448.549541 -34.86557) (xy 448.501965 -34.902076)
			(xy 448.450031 -34.93206) (xy 448.394627 -34.955009) (xy 448.336702 -34.97053) (xy 448.277246 -34.978358)
			(xy 448.217278 -34.978358) (xy 448.157822 -34.97053) (xy 448.099897 -34.955009) (xy 448.044493 -34.93206)
			(xy 447.992559 -34.902076) (xy 447.944983 -34.86557) (xy 447.902578 -34.823165) (xy 447.866072 -34.775589)
			(xy 447.836088 -34.723655) (xy 447.813139 -34.668251) (xy 447.797618 -34.610326) (xy 447.78979 -34.55087)
			(xy 447.7893 -34.520886) (xy 433.968144 -34.520886) (xy 433.968144 -34.52241) (xy 433.967654 -34.552378)
			(xy 433.959831 -34.6118) (xy 433.944318 -34.669693) (xy 433.921382 -34.725066) (xy 433.891415 -34.776972)
			(xy 433.854928 -34.824522) (xy 433.812548 -34.866902) (xy 433.764998 -34.903389) (xy 433.713092 -34.933356)
			(xy 433.657719 -34.956292) (xy 433.599826 -34.971805) (xy 433.540404 -34.979628) (xy 433.480468 -34.979628)
			(xy 433.421046 -34.971805) (xy 433.363153 -34.956292) (xy 433.30778 -34.933356) (xy 433.255874 -34.903389)
			(xy 433.208324 -34.866902) (xy 433.165944 -34.824522) (xy 433.129457 -34.776972) (xy 433.09949 -34.725066)
			(xy 433.076554 -34.669693) (xy 433.061041 -34.6118) (xy 433.053218 -34.552378) (xy 433.052728 -34.52241)
			(xy 432.395376 -34.52241) (xy 432.395376 -34.72434) (xy 432.396392 -34.733992) (xy 432.398023 -34.741234)
			(xy 432.404868 -34.754399) (xy 432.409854 -34.7599) (xy 433.792884 -36.14293) (xy 433.803552 -36.14928)
			(xy 433.809394 -36.151058) (xy 433.8357 -36.159757) (xy 433.88567 -36.183687) (xy 433.931654 -36.214593)
			(xy 433.972684 -36.251825) (xy 434.007898 -36.2946) (xy 434.036555 -36.342019) (xy 434.058052 -36.393083)
			(xy 434.065426 -36.41979) (xy 434.067204 -36.426648) (xy 434.071268 -36.433506) (xy 434.078888 -36.443412)
			(xy 434.235614 -36.60013) (xy 438.298597 -36.60013) (xy 438.302601 -36.512245) (xy 438.314581 -36.425088)
			(xy 438.334436 -36.339381) (xy 438.362003 -36.255836) (xy 438.397053 -36.175143) (xy 438.439295 -36.097971)
			(xy 438.48838 -36.024961) (xy 438.543901 -35.956717) (xy 438.605398 -35.893804) (xy 438.67236 -35.836744)
			(xy 438.744234 -35.78601) (xy 438.820424 -35.742022) (xy 438.900298 -35.705144) (xy 438.983195 -35.675683)
			(xy 439.068427 -35.653881) (xy 439.155289 -35.639921) (xy 439.24306 -35.633917) (xy 439.331014 -35.63592)
			(xy 439.418421 -35.645912) (xy 439.504557 -35.663812) (xy 439.588709 -35.68947) (xy 439.670179 -35.722674)
			(xy 439.748292 -35.763148) (xy 439.8224 -35.810559) (xy 439.891891 -35.864512) (xy 439.956187 -35.92456)
			(xy 440.014756 -35.990207) (xy 440.067113 -36.060907) (xy 440.112825 -36.136076) (xy 440.151511 -36.21509)
			(xy 440.182852 -36.297295) (xy 440.206587 -36.382009) (xy 440.222521 -36.46853) (xy 440.230521 -36.556142)
			(xy 440.231022 -36.60013) (xy 440.230521 -36.644118) (xy 440.222521 -36.73173) (xy 440.206587 -36.818251)
			(xy 440.182852 -36.902965) (xy 440.151511 -36.98517) (xy 440.112825 -37.064184) (xy 440.067113 -37.139353)
			(xy 440.014756 -37.210053) (xy 439.956187 -37.2757) (xy 439.891891 -37.335748) (xy 439.8224 -37.389701)
			(xy 439.748292 -37.437112) (xy 439.670179 -37.477586) (xy 439.588709 -37.51079) (xy 439.504557 -37.536448)
			(xy 439.418421 -37.554348) (xy 439.331014 -37.56434) (xy 439.24306 -37.566343) (xy 439.155289 -37.560339)
			(xy 439.068427 -37.546379) (xy 438.983195 -37.524577) (xy 438.900298 -37.495116) (xy 438.820424 -37.458238)
			(xy 438.744234 -37.41425) (xy 438.67236 -37.363516) (xy 438.605398 -37.306456) (xy 438.543901 -37.243543)
			(xy 438.48838 -37.175299) (xy 438.439295 -37.102289) (xy 438.397053 -37.025117) (xy 438.362003 -36.944424)
			(xy 438.334436 -36.860879) (xy 438.314581 -36.775172) (xy 438.302601 -36.688015) (xy 438.298597 -36.60013)
			(xy 434.235614 -36.60013) (xy 438.904483 -41.268753) (xy 442.14385 -41.268753) (xy 442.14385 -41.214247)
			(xy 442.151607 -41.160296) (xy 442.166963 -41.107997) (xy 442.189605 -41.058417) (xy 442.219073 -41.012563)
			(xy 442.254767 -40.97137) (xy 442.29596 -40.935676) (xy 442.341813 -40.906207) (xy 442.391394 -40.883564)
			(xy 442.443692 -40.868208) (xy 442.497643 -40.86045) (xy 442.524896 -40.859964) (xy 442.553634 -40.8605)
			(xy 442.610461 -40.869121) (xy 442.665351 -40.886169) (xy 442.717063 -40.911257) (xy 442.764426 -40.943819)
			(xy 442.785754 -40.963088) (xy 442.792612 -40.969692) (xy 442.810646 -40.976804) (xy 442.899546 -40.976804)
			(xy 442.91758 -40.969692) (xy 442.924438 -40.963088) (xy 442.945774 -40.943827) (xy 442.993133 -40.911258)
			(xy 443.044842 -40.886163) (xy 443.099731 -40.86911) (xy 443.156557 -40.860485) (xy 443.185296 -40.859964)
			(xy 443.212547 -40.860483) (xy 443.266494 -40.868239) (xy 443.318789 -40.883593) (xy 443.368366 -40.906234)
			(xy 443.414216 -40.9357) (xy 443.455406 -40.971391) (xy 443.491098 -41.012581) (xy 443.520564 -41.058431)
			(xy 443.543205 -41.108007) (xy 443.55856 -41.160302) (xy 443.566317 -41.214249) (xy 443.566317 -41.268751)
			(xy 443.55856 -41.322698) (xy 443.543205 -41.374993) (xy 443.520564 -41.424569) (xy 443.491098 -41.470419)
			(xy 443.455406 -41.511609) (xy 443.414216 -41.5473) (xy 443.368366 -41.576766) (xy 443.318789 -41.599407)
			(xy 443.266494 -41.614761) (xy 443.212547 -41.622517) (xy 443.185296 -41.62298) (xy 443.156558 -41.622437)
			(xy 443.099732 -41.613816) (xy 443.044843 -41.596769) (xy 442.993131 -41.571683) (xy 442.945767 -41.539123)
			(xy 442.924438 -41.519856) (xy 442.91758 -41.513252) (xy 442.899546 -41.50614) (xy 442.810646 -41.50614)
			(xy 442.792612 -41.513252) (xy 442.785754 -41.519856) (xy 442.764428 -41.539128) (xy 442.717066 -41.571694)
			(xy 442.665354 -41.596786) (xy 442.610463 -41.613837) (xy 442.553635 -41.622459) (xy 442.524896 -41.62298)
			(xy 442.497643 -41.62255) (xy 442.443692 -41.614792) (xy 442.391394 -41.599436) (xy 442.341813 -41.576793)
			(xy 442.29596 -41.547324) (xy 442.254767 -41.51163) (xy 442.219073 -41.470437) (xy 442.189605 -41.424583)
			(xy 442.166963 -41.375003) (xy 442.151607 -41.322704) (xy 442.14385 -41.268753) (xy 438.904483 -41.268753)
			(xy 438.91327 -41.27754) (xy 438.930825 -41.295755) (xy 438.960563 -41.336678) (xy 438.983527 -41.381752)
			(xy 438.999152 -41.429865) (xy 439.007052 -41.479831) (xy 439.007504 -41.505124) (xy 439.007504 -43.305222)
			(xy 444.607188 -43.305222) (xy 444.60767 -43.277852) (xy 444.615484 -43.223674) (xy 444.63097 -43.171171)
			(xy 444.653808 -43.121424) (xy 444.683529 -43.075456) (xy 444.701168 -43.054524) (xy 444.701422 -43.05427)
			(xy 444.706988 -43.047169) (xy 444.713246 -43.030263) (xy 444.713614 -43.02125) (xy 444.713614 -42.954194)
			(xy 444.713257 -42.945177) (xy 444.707009 -42.92826) (xy 444.701422 -42.921174) (xy 444.701168 -42.921174)
			(xy 444.701168 -42.92092) (xy 444.68352 -42.899995) (xy 444.65381 -42.85402) (xy 444.630977 -42.804271)
			(xy 444.615488 -42.751768) (xy 444.607661 -42.697592) (xy 444.607188 -42.670222) (xy 444.607728 -42.641484)
			(xy 444.616347 -42.584657) (xy 444.633394 -42.529767) (xy 444.658482 -42.478055) (xy 444.691043 -42.430691)
			(xy 444.710312 -42.409364) (xy 444.716916 -42.402506) (xy 444.724028 -42.384472) (xy 444.724028 -42.295572)
			(xy 444.716916 -42.277538) (xy 444.710312 -42.27068) (xy 444.691064 -42.249334) (xy 444.658499 -42.201975)
			(xy 444.633407 -42.150266) (xy 444.616356 -42.095378) (xy 444.607731 -42.038554) (xy 444.607729 -41.981078)
			(xy 444.616348 -41.924253) (xy 444.633395 -41.869364) (xy 444.658482 -41.817653) (xy 444.691043 -41.770291)
			(xy 444.710312 -41.748964) (xy 444.716916 -41.742106) (xy 444.724028 -41.724072) (xy 444.724028 -41.635172)
			(xy 444.716916 -41.617138) (xy 444.710312 -41.61028) (xy 444.691047 -41.588948) (xy 444.658481 -41.541587)
			(xy 444.633388 -41.489876) (xy 444.616336 -41.434987) (xy 444.607711 -41.378161) (xy 444.607188 -41.349422)
			(xy 444.607674 -41.322171) (xy 444.61543 -41.268223) (xy 444.630785 -41.215928) (xy 444.653427 -41.166351)
			(xy 444.682893 -41.120501) (xy 444.718584 -41.07931) (xy 444.759775 -41.043619) (xy 444.805625 -41.014153)
			(xy 444.855202 -40.991511) (xy 444.907497 -40.976156) (xy 444.961445 -40.9684) (xy 445.015947 -40.9684)
			(xy 445.069895 -40.976156) (xy 445.12219 -40.991511) (xy 445.171767 -41.014153) (xy 445.217617 -41.043619)
			(xy 445.258808 -41.07931) (xy 445.294499 -41.120501) (xy 445.323965 -41.166351) (xy 445.346607 -41.215928)
			(xy 445.361962 -41.268223) (xy 445.369718 -41.322171) (xy 445.370204 -41.349422) (xy 445.369693 -41.378161)
			(xy 445.361067 -41.434989) (xy 445.344014 -41.48988) (xy 445.31892 -41.541592) (xy 445.286352 -41.588954)
			(xy 445.26708 -41.61028) (xy 445.260476 -41.617138) (xy 445.253364 -41.635172) (xy 445.253364 -41.724072)
			(xy 445.260476 -41.742106) (xy 445.26708 -41.748964) (xy 445.286372 -41.770272) (xy 445.318937 -41.817638)
			(xy 445.344027 -41.869353) (xy 445.361075 -41.924246) (xy 445.369695 -41.981076) (xy 445.369693 -42.038556)
			(xy 445.361068 -42.095385) (xy 445.344015 -42.150277) (xy 445.31892 -42.20199) (xy 445.286352 -42.249353)
			(xy 445.26708 -42.27068) (xy 445.260476 -42.277538) (xy 445.253364 -42.295572) (xy 445.253364 -42.384472)
			(xy 445.260476 -42.402506) (xy 445.26708 -42.409364) (xy 445.286364 -42.430679) (xy 445.318928 -42.478045)
			(xy 445.344017 -42.52976) (xy 445.361065 -42.584653) (xy 445.369685 -42.641482) (xy 445.370204 -42.670222)
			(xy 445.36975 -42.697593) (xy 445.361929 -42.751772) (xy 445.346437 -42.804275) (xy 445.325882 -42.849038)
			(xy 447.19189 -42.849038) (xy 447.195961 -42.793416) (xy 447.208087 -42.738979) (xy 447.22801 -42.686888)
			(xy 447.255306 -42.638253) (xy 447.289392 -42.59411) (xy 447.329541 -42.555401) (xy 447.374899 -42.52295)
			(xy 447.424499 -42.497449) (xy 447.477283 -42.479442) (xy 447.532126 -42.469312) (xy 447.58786 -42.467275)
			(xy 447.643297 -42.473375) (xy 447.697254 -42.487481) (xy 447.748583 -42.509293) (xy 447.796189 -42.538347)
			(xy 447.839057 -42.574022) (xy 447.876274 -42.615559) (xy 447.907047 -42.662072) (xy 447.930719 -42.712569)
			(xy 447.946787 -42.765976) (xy 447.954907 -42.821152) (xy 447.955416 -42.849038) (xy 447.954907 -42.876924)
			(xy 447.946787 -42.9321) (xy 447.930719 -42.985507) (xy 447.907047 -43.036004) (xy 447.876274 -43.082517)
			(xy 447.839057 -43.124054) (xy 447.796189 -43.159729) (xy 447.748583 -43.188783) (xy 447.697254 -43.210595)
			(xy 447.643297 -43.224701) (xy 447.58786 -43.230801) (xy 447.532126 -43.228764) (xy 447.477283 -43.218634)
			(xy 447.424499 -43.200627) (xy 447.374899 -43.175126) (xy 447.329541 -43.142675) (xy 447.289392 -43.103966)
			(xy 447.255306 -43.059823) (xy 447.22801 -43.011188) (xy 447.208087 -42.959097) (xy 447.195961 -42.90466)
			(xy 447.19189 -42.849038) (xy 445.325882 -42.849038) (xy 445.323593 -42.854022) (xy 445.293866 -42.899989)
			(xy 445.276224 -42.92092) (xy 445.27597 -42.921174) (xy 445.270385 -42.928261) (xy 445.264138 -42.945178)
			(xy 445.263778 -42.954194) (xy 445.263778 -43.02125) (xy 445.264164 -43.030264) (xy 445.270392 -43.047181)
			(xy 445.27597 -43.05427) (xy 445.276224 -43.05427) (xy 445.276224 -43.054524) (xy 445.293845 -43.075471)
			(xy 445.323558 -43.12144) (xy 445.346398 -43.171184) (xy 445.361893 -43.223681) (xy 445.369727 -43.277854)
			(xy 445.370204 -43.305222) (xy 445.369718 -43.332473) (xy 445.361962 -43.386421) (xy 445.346607 -43.438716)
			(xy 445.323965 -43.488293) (xy 445.294499 -43.534143) (xy 445.258808 -43.575334) (xy 445.217617 -43.611025)
			(xy 445.171767 -43.640491) (xy 445.12219 -43.663133) (xy 445.069895 -43.678488) (xy 445.015947 -43.686244)
			(xy 444.961445 -43.686244) (xy 444.907497 -43.678488) (xy 444.855202 -43.663133) (xy 444.805625 -43.640491)
			(xy 444.759775 -43.611025) (xy 444.718584 -43.575334) (xy 444.682893 -43.534143) (xy 444.653427 -43.488293)
			(xy 444.630785 -43.438716) (xy 444.61543 -43.386421) (xy 444.607674 -43.332473) (xy 444.607188 -43.305222)
			(xy 439.007504 -43.305222) (xy 439.007504 -43.73626) (xy 446.512948 -43.73626) (xy 446.517019 -43.680638)
			(xy 446.529145 -43.626201) (xy 446.549068 -43.57411) (xy 446.576364 -43.525475) (xy 446.61045 -43.481332)
			(xy 446.650599 -43.442623) (xy 446.695957 -43.410172) (xy 446.745557 -43.384671) (xy 446.798341 -43.366664)
			(xy 446.853184 -43.356534) (xy 446.908918 -43.354497) (xy 446.964355 -43.360597) (xy 447.018312 -43.374703)
			(xy 447.069641 -43.396515) (xy 447.117247 -43.425569) (xy 447.160115 -43.461244) (xy 447.197332 -43.502781)
			(xy 447.228105 -43.549294) (xy 447.251777 -43.599791) (xy 447.267845 -43.653198) (xy 447.275965 -43.708374)
			(xy 447.276474 -43.73626) (xy 447.275965 -43.764146) (xy 447.267845 -43.819322) (xy 447.251777 -43.872729)
			(xy 447.228105 -43.923226) (xy 447.197332 -43.969739) (xy 447.160115 -44.011276) (xy 447.117247 -44.046951)
			(xy 447.069641 -44.076005) (xy 447.018312 -44.097817) (xy 446.964355 -44.111923) (xy 446.908918 -44.118023)
			(xy 446.853184 -44.115986) (xy 446.798341 -44.105856) (xy 446.745557 -44.087849) (xy 446.695957 -44.062348)
			(xy 446.650599 -44.029897) (xy 446.61045 -43.991188) (xy 446.576364 -43.947045) (xy 446.549068 -43.89841)
			(xy 446.529145 -43.846319) (xy 446.517019 -43.791882) (xy 446.512948 -43.73626) (xy 439.007504 -43.73626)
			(xy 439.007504 -44.433998) (xy 439.007622 -44.438953) (xy 439.009541 -44.448674) (xy 439.011314 -44.453302)
			(xy 439.015124 -44.462446) (xy 439.01741 -44.464732) (xy 439.036382 -44.483664) (xy 439.068575 -44.526511)
			(xy 439.093475 -44.57397) (xy 439.110436 -44.624809) (xy 439.119019 -44.677711) (xy 439.119518 -44.704508)
			(xy 439.119264 -44.716192) (xy 439.119264 -45.114464) (xy 446.365374 -45.114464) (xy 446.369445 -45.058842)
			(xy 446.381571 -45.004405) (xy 446.401494 -44.952314) (xy 446.42879 -44.903679) (xy 446.462876 -44.859536)
			(xy 446.503025 -44.820827) (xy 446.548383 -44.788376) (xy 446.597983 -44.762875) (xy 446.650767 -44.744868)
			(xy 446.70561 -44.734738) (xy 446.761344 -44.732701) (xy 446.816781 -44.738801) (xy 446.870738 -44.752907)
			(xy 446.922067 -44.774719) (xy 446.969673 -44.803773) (xy 447.012541 -44.839448) (xy 447.049758 -44.880985)
			(xy 447.080531 -44.927498) (xy 447.104203 -44.977995) (xy 447.120271 -45.031402) (xy 447.128391 -45.086578)
			(xy 447.1289 -45.114464) (xy 447.128391 -45.14235) (xy 447.120271 -45.197526) (xy 447.104203 -45.250933)
			(xy 447.080531 -45.30143) (xy 447.049758 -45.347943) (xy 447.012541 -45.38948) (xy 446.969673 -45.425155)
			(xy 446.922067 -45.454209) (xy 446.870738 -45.476021) (xy 446.816781 -45.490127) (xy 446.761344 -45.496227)
			(xy 446.70561 -45.49419) (xy 446.650767 -45.48406) (xy 446.597983 -45.466053) (xy 446.548383 -45.440552)
			(xy 446.503025 -45.408101) (xy 446.462876 -45.369392) (xy 446.42879 -45.325249) (xy 446.401494 -45.276614)
			(xy 446.381571 -45.224523) (xy 446.369445 -45.170086) (xy 446.365374 -45.114464) (xy 439.119264 -45.114464)
			(xy 439.119264 -46.082204) (xy 444.352426 -46.082204) (xy 444.352859 -46.05495) (xy 444.360616 -46.000996)
			(xy 444.375974 -45.948695) (xy 444.398618 -45.899113) (xy 444.428089 -45.853258) (xy 444.463786 -45.812065)
			(xy 444.504982 -45.776371) (xy 444.550839 -45.746904) (xy 444.600424 -45.724263) (xy 444.652725 -45.70891)
			(xy 444.70668 -45.701157) (xy 444.733934 -45.700696) (xy 444.760837 -45.701132) (xy 444.814109 -45.708709)
			(xy 444.865787 -45.723693) (xy 444.914849 -45.745787) (xy 444.960321 -45.774553) (xy 445.001302 -45.809422)
			(xy 445.036979 -45.849701) (xy 445.052196 -45.871892) (xy 445.059308 -45.882814) (xy 445.082168 -45.894752)
			(xy 445.194436 -45.89272) (xy 445.216788 -45.879766) (xy 445.223646 -45.86859) (xy 445.23855 -45.844977)
			(xy 445.274232 -45.802025) (xy 445.315793 -45.764733) (xy 445.362346 -45.733897) (xy 445.412896 -45.710175)
			(xy 445.466364 -45.694075) (xy 445.521608 -45.68594) (xy 445.549528 -45.685456) (xy 445.576522 -45.685901)
			(xy 445.629971 -45.693511) (xy 445.681814 -45.708575) (xy 445.731019 -45.730792) (xy 445.776602 -45.75972)
			(xy 445.797432 -45.776896) (xy 445.80556 -45.784008) (xy 445.826134 -45.790104) (xy 445.911478 -45.779182)
			(xy 445.922022 -45.777407) (xy 445.940305 -45.766353) (xy 445.946784 -45.757846) (xy 445.962154 -45.736628)
			(xy 445.997738 -45.698175) (xy 446.038252 -45.664955) (xy 446.082933 -45.637595) (xy 446.130938 -45.616609)
			(xy 446.181364 -45.602394) (xy 446.233262 -45.595215) (xy 446.259458 -45.594778) (xy 446.286712 -45.595266)
			(xy 446.340665 -45.603018) (xy 446.392966 -45.61837) (xy 446.44255 -45.641009) (xy 446.488407 -45.670475)
			(xy 446.529603 -45.706168) (xy 446.5653 -45.74736) (xy 446.59477 -45.793213) (xy 446.617415 -45.842794)
			(xy 446.632773 -45.895094) (xy 446.640531 -45.949046) (xy 446.640531 -46.003554) (xy 446.632773 -46.057506)
			(xy 446.617415 -46.109806) (xy 446.59477 -46.159387) (xy 446.5653 -46.20524) (xy 446.529603 -46.246432)
			(xy 446.488407 -46.282125) (xy 446.44255 -46.311591) (xy 446.392966 -46.33423) (xy 446.340665 -46.349582)
			(xy 446.286712 -46.357334) (xy 446.259458 -46.357794) (xy 446.232464 -46.357345) (xy 446.179016 -46.349735)
			(xy 446.127173 -46.334671) (xy 446.077969 -46.312454) (xy 446.032385 -46.283528) (xy 446.011554 -46.266354)
			(xy 446.003426 -46.259242) (xy 445.982852 -46.253146) (xy 445.897508 -46.264068) (xy 445.886967 -46.265854)
			(xy 445.868684 -46.276901) (xy 445.862202 -46.285404) (xy 445.844586 -46.309702) (xy 445.802992 -46.352963)
			(xy 445.779398 -46.37151) (xy 445.771524 -46.377352) (xy 445.76111 -46.394878) (xy 445.747902 -46.485302)
			(xy 445.752728 -46.504606) (xy 445.75857 -46.51248) (xy 445.75857 -46.512734) (xy 445.776072 -46.537479)
			(xy 445.803875 -46.591331) (xy 445.822812 -46.648903) (xy 445.832405 -46.708745) (xy 445.832992 -46.739048)
			(xy 445.832567 -46.766301) (xy 445.824803 -46.820252) (xy 445.809441 -46.872549) (xy 445.786793 -46.922127)
			(xy 445.757321 -46.967978) (xy 445.721623 -47.009168) (xy 445.680427 -47.044859) (xy 445.634571 -47.074324)
			(xy 445.584989 -47.096964) (xy 445.532689 -47.112317) (xy 445.478737 -47.120071) (xy 445.451484 -47.120556)
			(xy 445.42545 -47.120111) (xy 445.373868 -47.113022) (xy 445.323726 -47.098992) (xy 445.275955 -47.078281)
			(xy 445.23144 -47.051272) (xy 445.210946 -47.035212) (xy 445.203182 -47.029481) (xy 445.184777 -47.023734)
			(xy 445.175132 -47.024036) (xy 445.095376 -47.030386) (xy 445.077596 -47.039022) (xy 445.071246 -47.046388)
			(xy 445.053065 -47.066034) (xy 445.012157 -47.100556) (xy 444.966828 -47.129025) (xy 444.917967 -47.150882)
			(xy 444.866531 -47.1657) (xy 444.81353 -47.173187) (xy 444.786766 -47.173642) (xy 444.759515 -47.173154)
			(xy 444.70557 -47.165394) (xy 444.653277 -47.150036) (xy 444.603702 -47.127393) (xy 444.557853 -47.097927)
			(xy 444.516664 -47.062236) (xy 444.480973 -47.021047) (xy 444.451507 -46.975198) (xy 444.428864 -46.925623)
			(xy 444.413506 -46.87333) (xy 444.405746 -46.819385) (xy 444.405258 -46.792134) (xy 444.405794 -46.763361)
			(xy 444.414444 -46.706467) (xy 444.431538 -46.651517) (xy 444.456689 -46.599757) (xy 444.489326 -46.55236)
			(xy 444.508636 -46.531022) (xy 444.516002 -46.523148) (xy 444.523114 -46.503336) (xy 444.515748 -46.40707)
			(xy 444.505842 -46.388274) (xy 444.49746 -46.38167) (xy 444.475284 -46.363435) (xy 444.436071 -46.321503)
			(xy 444.403583 -46.27417) (xy 444.378553 -46.222504) (xy 444.361546 -46.167671) (xy 444.352944 -46.110909)
			(xy 444.352426 -46.082204) (xy 439.119264 -46.082204) (xy 439.119264 -48.753014) (xy 447.468242 -48.753014)
			(xy 447.472313 -48.697392) (xy 447.484439 -48.642955) (xy 447.504362 -48.590864) (xy 447.531658 -48.542229)
			(xy 447.565744 -48.498086) (xy 447.605893 -48.459377) (xy 447.651251 -48.426926) (xy 447.700851 -48.401425)
			(xy 447.753635 -48.383418) (xy 447.808478 -48.373288) (xy 447.864212 -48.371251) (xy 447.919649 -48.377351)
			(xy 447.973606 -48.391457) (xy 448.024935 -48.413269) (xy 448.072541 -48.442323) (xy 448.115409 -48.477998)
			(xy 448.152626 -48.519535) (xy 448.183399 -48.566048) (xy 448.207071 -48.616545) (xy 448.223139 -48.669952)
			(xy 448.231259 -48.725128) (xy 448.231768 -48.753014) (xy 448.231259 -48.7809) (xy 448.223139 -48.836076)
			(xy 448.212495 -48.871453) (xy 448.488255 -48.871453) (xy 448.488255 -48.816947) (xy 448.496013 -48.762995)
			(xy 448.511369 -48.710697) (xy 448.534012 -48.661116) (xy 448.563481 -48.615263) (xy 448.599175 -48.57407)
			(xy 448.640369 -48.538376) (xy 448.686223 -48.508908) (xy 448.735804 -48.486266) (xy 448.788103 -48.470911)
			(xy 448.842055 -48.463155) (xy 448.869308 -48.462692) (xy 448.896949 -48.463172) (xy 448.951651 -48.471151)
			(xy 449.004628 -48.486942) (xy 449.054773 -48.510214) (xy 449.101033 -48.540479) (xy 449.142441 -48.577103)
			(xy 449.17813 -48.61932) (xy 449.193158 -48.642524) (xy 449.200524 -48.654208) (xy 449.224654 -48.666908)
			(xy 449.34124 -48.661066) (xy 449.364354 -48.64608) (xy 449.37045 -48.633634) (xy 449.384973 -48.605104)
			(xy 449.419332 -48.551083) (xy 449.459378 -48.501132) (xy 449.481702 -48.478186) (xy 450.088254 -47.871634)
			(xy 450.095065 -47.864211) (xy 450.102803 -47.84563) (xy 450.10324 -47.835566) (xy 450.10324 -44.504356)
			(xy 450.102853 -44.494282) (xy 450.095107 -44.475684) (xy 450.088254 -44.468288) (xy 449.601082 -43.981116)
			(xy 449.578193 -43.957542) (xy 449.537224 -43.906169) (xy 449.502265 -43.850531) (xy 449.473755 -43.791329)
			(xy 449.452053 -43.729308) (xy 449.437432 -43.665246) (xy 449.430076 -43.59995) (xy 449.429632 -43.567096)
			(xy 449.429632 -43.566842) (xy 449.430195 -43.531439) (xy 449.438723 -43.46115) (xy 449.455659 -43.3924)
			(xy 449.480757 -43.326193) (xy 449.513651 -43.263492) (xy 449.553861 -43.205212) (xy 449.600801 -43.152203)
			(xy 449.653787 -43.105237) (xy 449.712047 -43.064999) (xy 449.774732 -43.032075) (xy 449.840927 -43.006944)
			(xy 449.909668 -42.989975) (xy 449.979954 -42.981413) (xy 450.015356 -42.980864) (xy 450.048237 -42.981314)
			(xy 450.113585 -42.988678) (xy 450.177697 -43.003316) (xy 450.239765 -43.025046) (xy 450.299007 -43.053594)
			(xy 450.354678 -43.088599) (xy 450.406076 -43.129621) (xy 450.42963 -43.152568) (xy 450.932042 -43.65498)
			(xy 450.940356 -43.66239) (xy 450.961299 -43.669895) (xy 450.972428 -43.669458) (xy 451.061582 -43.66133)
			(xy 451.08114 -43.6499) (xy 451.08749 -43.640502) (xy 451.102837 -43.619041) (xy 451.138464 -43.580127)
			(xy 451.179114 -43.546494) (xy 451.22401 -43.518783) (xy 451.272297 -43.497524) (xy 451.323052 -43.483121)
			(xy 451.375308 -43.475849) (xy 451.401688 -43.475402) (xy 451.428942 -43.475844) (xy 451.482896 -43.4836)
			(xy 451.535197 -43.498955) (xy 451.58478 -43.521598) (xy 451.630635 -43.551066) (xy 451.671831 -43.586761)
			(xy 451.707527 -43.627955) (xy 451.736997 -43.67381) (xy 451.759641 -43.723392) (xy 451.774998 -43.775692)
			(xy 451.782755 -43.829646) (xy 451.782755 -43.884154) (xy 451.774998 -43.938108) (xy 451.759641 -43.990408)
			(xy 451.736997 -44.03999) (xy 451.707527 -44.085845) (xy 451.671831 -44.127039) (xy 451.630635 -44.162734)
			(xy 451.58478 -44.192202) (xy 451.535197 -44.214845) (xy 451.482896 -44.2302) (xy 451.428942 -44.237956)
			(xy 451.401688 -44.238418) (xy 451.401434 -44.238418) (xy 451.381876 -44.23791) (xy 451.381622 -44.23791)
			(xy 451.371323 -44.237889) (xy 451.352055 -44.245119) (xy 451.344284 -44.25188) (xy 451.290944 -44.30268)
			(xy 451.283818 -44.310179) (xy 451.275687 -44.329178) (xy 451.275196 -44.33951) (xy 451.275196 -44.871132)
			(xy 451.275594 -44.881296) (xy 451.283477 -44.900033) (xy 451.290436 -44.907454) (xy 451.349364 -44.965366)
			(xy 451.368414 -44.972986) (xy 451.378574 -44.972732) (xy 451.385686 -44.972732) (xy 451.412942 -44.973114)
			(xy 451.466901 -44.98087) (xy 451.519206 -44.996227) (xy 451.568793 -45.018871) (xy 451.614652 -45.048341)
			(xy 451.655851 -45.084039) (xy 451.69155 -45.125236) (xy 451.721023 -45.171095) (xy 451.743668 -45.220681)
			(xy 451.759027 -45.272986) (xy 451.766785 -45.326944) (xy 451.766785 -45.381456) (xy 451.759027 -45.435414)
			(xy 451.743668 -45.487719) (xy 451.721023 -45.537305) (xy 451.69155 -45.583164) (xy 451.655851 -45.624361)
			(xy 451.614652 -45.660059) (xy 451.568793 -45.689529) (xy 451.519206 -45.712173) (xy 451.466901 -45.72753)
			(xy 451.412942 -45.735286) (xy 451.385686 -45.735748) (xy 451.378574 -45.735748) (xy 451.368414 -45.735494)
			(xy 451.349364 -45.743114) (xy 451.290436 -45.801026) (xy 451.283508 -45.808465) (xy 451.275647 -45.827193)
			(xy 451.275196 -45.837348) (xy 451.275196 -46.211236) (xy 451.275652 -46.220963) (xy 451.282972 -46.238991)
			(xy 451.28942 -46.246288) (xy 451.337934 -46.297088) (xy 451.34506 -46.303824) (xy 451.362958 -46.311795)
			(xy 451.372732 -46.312582) (xy 451.399259 -46.314147) (xy 451.451549 -46.323587) (xy 451.502023 -46.340191)
			(xy 451.549705 -46.363638) (xy 451.593673 -46.393474) (xy 451.633076 -46.429122) (xy 451.667151 -46.469892)
			(xy 451.695239 -46.514996) (xy 451.716798 -46.563562) (xy 451.731409 -46.614648) (xy 451.738791 -46.667268)
			(xy 451.739254 -46.693836) (xy 451.738788 -46.720264) (xy 451.731477 -46.772612) (xy 451.717002 -46.823447)
			(xy 451.69564 -46.871793) (xy 451.682104 -46.894496) (xy 451.68185 -46.89475) (xy 451.676513 -46.904768)
			(xy 451.674256 -46.927318) (xy 451.677532 -46.938184) (xy 451.703694 -47.01286) (xy 451.708059 -47.023385)
			(xy 451.724161 -47.03947) (xy 451.734682 -47.043848) (xy 451.734936 -47.043848) (xy 451.759443 -47.052923)
			(xy 451.805895 -47.076865) (xy 451.848648 -47.106919) (xy 451.8869 -47.142526) (xy 451.919937 -47.183018)
			(xy 451.947141 -47.227638) (xy 451.968003 -47.275553) (xy 451.982133 -47.325866) (xy 451.989267 -47.377636)
			(xy 451.989698 -47.403766) (xy 451.989213 -47.431018) (xy 451.98146 -47.484969) (xy 451.966108 -47.537267)
			(xy 451.943469 -47.586848) (xy 451.914004 -47.632702) (xy 451.878312 -47.673895) (xy 451.837121 -47.709589)
			(xy 451.791269 -47.739057) (xy 451.74169 -47.7617) (xy 451.689393 -47.777055) (xy 451.635442 -47.784811)
			(xy 451.60819 -47.785274) (xy 451.57638 -47.784617) (xy 451.513643 -47.774058) (xy 451.453528 -47.753234)
			(xy 451.42531 -47.738538) (xy 451.417444 -47.734698) (xy 451.400151 -47.732066) (xy 451.382979 -47.735404)
			(xy 451.375272 -47.739554) (xy 451.300088 -47.784004) (xy 451.292713 -47.788802) (xy 451.281516 -47.802357)
			(xy 451.275566 -47.818901) (xy 451.275196 -47.827692) (xy 451.275196 -47.902368) (xy 451.297548 -47.930054)
			(xy 451.315328 -47.933864) (xy 451.343446 -47.940381) (xy 451.397438 -47.960778) (xy 451.447743 -47.989074)
			(xy 451.493212 -48.024624) (xy 451.532807 -48.066618) (xy 451.565626 -48.114096) (xy 451.590918 -48.165976)
			(xy 451.608108 -48.221073) (xy 451.616803 -48.278132) (xy 451.617334 -48.30699) (xy 451.616813 -48.33424)
			(xy 451.609058 -48.388185) (xy 451.593706 -48.440477) (xy 451.571067 -48.490053) (xy 451.541605 -48.535902)
			(xy 451.505917 -48.577091) (xy 451.464731 -48.612783) (xy 451.418884 -48.64225) (xy 451.369311 -48.664893)
			(xy 451.31702 -48.68025) (xy 451.263076 -48.68801) (xy 451.235826 -48.688498) (xy 451.209852 -48.688064)
			(xy 451.158384 -48.681022) (xy 451.108346 -48.667065) (xy 451.060664 -48.646451) (xy 451.038214 -48.63338)
			(xy 451.022974 -48.624236) (xy 450.98843 -48.628554) (xy 450.982588 -48.634396) (xy 450.998653 -48.654888)
			(xy 451.025673 -48.699398) (xy 451.046389 -48.747169) (xy 451.060415 -48.797313) (xy 451.067492 -48.848899)
			(xy 451.067932 -48.874934) (xy 451.067454 -48.902185) (xy 451.059693 -48.956132) (xy 451.044335 -49.008425)
			(xy 451.021692 -49.058001) (xy 450.992224 -49.10385) (xy 450.956532 -49.145039) (xy 450.915342 -49.18073)
			(xy 450.869492 -49.210197) (xy 450.819916 -49.232839) (xy 450.767622 -49.248196) (xy 450.713675 -49.255955)
			(xy 450.686424 -49.256442) (xy 450.658979 -49.255981) (xy 450.604656 -49.248105) (xy 450.552027 -49.232511)
			(xy 450.502182 -49.209524) (xy 450.478906 -49.194974) (xy 450.468852 -49.189086) (xy 450.445738 -49.186315)
			(xy 450.423752 -49.193968) (xy 450.415152 -49.201832) (xy 450.31025 -49.306734) (xy 450.286695 -49.32967)
			(xy 450.235285 -49.370655) (xy 450.179606 -49.405622) (xy 450.120361 -49.434132) (xy 450.058294 -49.455825)
			(xy 449.994189 -49.470428) (xy 449.92885 -49.477757) (xy 449.895976 -49.478184) (xy 449.860616 -49.477575)
			(xy 449.79041 -49.469063) (xy 449.721738 -49.452167) (xy 449.655597 -49.427132) (xy 449.592949 -49.394321)
			(xy 449.534703 -49.354211) (xy 449.481706 -49.307385) (xy 449.434728 -49.254523) (xy 449.394451 -49.196393)
			(xy 449.361461 -49.133839) (xy 449.348352 -49.100994) (xy 449.343526 -49.08804) (xy 449.32219 -49.070768)
			(xy 449.20662 -49.054004) (xy 449.18122 -49.064418) (xy 449.172838 -49.075594) (xy 449.154682 -49.098514)
			(xy 449.112551 -49.139053) (xy 449.064725 -49.172686) (xy 449.012325 -49.198625) (xy 448.95658 -49.21626)
			(xy 448.898796 -49.22518) (xy 448.869562 -49.225708) (xy 448.869308 -49.225708) (xy 448.842055 -49.225245)
			(xy 448.788103 -49.217489) (xy 448.735804 -49.202134) (xy 448.686223 -49.179492) (xy 448.640369 -49.150024)
			(xy 448.599175 -49.11433) (xy 448.563481 -49.073137) (xy 448.534012 -49.027284) (xy 448.511369 -48.977703)
			(xy 448.496013 -48.925405) (xy 448.488255 -48.871453) (xy 448.212495 -48.871453) (xy 448.207071 -48.889483)
			(xy 448.183399 -48.93998) (xy 448.152626 -48.986493) (xy 448.115409 -49.02803) (xy 448.072541 -49.063705)
			(xy 448.024935 -49.092759) (xy 447.973606 -49.114571) (xy 447.919649 -49.128677) (xy 447.864212 -49.134777)
			(xy 447.808478 -49.13274) (xy 447.753635 -49.12261) (xy 447.700851 -49.104603) (xy 447.651251 -49.079102)
			(xy 447.605893 -49.046651) (xy 447.565744 -49.007942) (xy 447.531658 -48.963799) (xy 447.504362 -48.915164)
			(xy 447.484439 -48.863073) (xy 447.472313 -48.808636) (xy 447.468242 -48.753014) (xy 439.119264 -48.753014)
			(xy 439.119264 -51.019456) (xy 451.049388 -51.019456) (xy 451.053459 -50.963834) (xy 451.065585 -50.909397)
			(xy 451.085508 -50.857306) (xy 451.112804 -50.808671) (xy 451.14689 -50.764528) (xy 451.187039 -50.725819)
			(xy 451.232397 -50.693368) (xy 451.281997 -50.667867) (xy 451.334781 -50.64986) (xy 451.389624 -50.63973)
			(xy 451.445358 -50.637693) (xy 451.500795 -50.643793) (xy 451.554752 -50.657899) (xy 451.606081 -50.679711)
			(xy 451.653687 -50.708765) (xy 451.696555 -50.74444) (xy 451.733772 -50.785977) (xy 451.764545 -50.83249)
			(xy 451.788217 -50.882987) (xy 451.804285 -50.936394) (xy 451.812405 -50.99157) (xy 451.812914 -51.019456)
			(xy 451.812405 -51.047342) (xy 451.804285 -51.102518) (xy 451.788217 -51.155925) (xy 451.764545 -51.206422)
			(xy 451.733772 -51.252935) (xy 451.696555 -51.294472) (xy 451.653687 -51.330147) (xy 451.606081 -51.359201)
			(xy 451.554752 -51.381013) (xy 451.500795 -51.395119) (xy 451.445358 -51.401219) (xy 451.389624 -51.399182)
			(xy 451.334781 -51.389052) (xy 451.281997 -51.371045) (xy 451.232397 -51.345544) (xy 451.187039 -51.313093)
			(xy 451.14689 -51.274384) (xy 451.112804 -51.230241) (xy 451.085508 -51.181606) (xy 451.065585 -51.129515)
			(xy 451.053459 -51.075078) (xy 451.049388 -51.019456) (xy 439.119264 -51.019456) (xy 439.119264 -54.731412)
			(xy 439.820558 -54.731412) (xy 439.821017 -54.704041) (xy 439.828834 -54.649861) (xy 439.844324 -54.597358)
			(xy 439.867168 -54.547611) (xy 439.896895 -54.501645) (xy 439.914538 -54.480714) (xy 439.914792 -54.48046)
			(xy 439.920359 -54.47336) (xy 439.926618 -54.456454) (xy 439.926984 -54.44744) (xy 439.926984 -54.380384)
			(xy 439.926638 -54.371366) (xy 439.920383 -54.354449) (xy 439.914792 -54.347364) (xy 439.914538 -54.347364)
			(xy 439.914538 -54.34711) (xy 439.896909 -54.326168) (xy 439.867182 -54.280202) (xy 439.844336 -54.230457)
			(xy 439.828838 -54.177957) (xy 439.821008 -54.123779) (xy 439.821007 -54.069039) (xy 439.828834 -54.014861)
			(xy 439.844329 -53.96236) (xy 439.867174 -53.912614) (xy 439.896898 -53.866647) (xy 439.914538 -53.845714)
			(xy 439.914792 -53.84546) (xy 439.920359 -53.83836) (xy 439.926618 -53.821454) (xy 439.926984 -53.81244)
			(xy 439.926984 -53.745384) (xy 439.926638 -53.736366) (xy 439.920383 -53.719449) (xy 439.914792 -53.712364)
			(xy 439.914538 -53.712364) (xy 439.914538 -53.71211) (xy 439.896909 -53.691168) (xy 439.867182 -53.645202)
			(xy 439.844336 -53.595457) (xy 439.828838 -53.542957) (xy 439.821008 -53.488779) (xy 439.821007 -53.434039)
			(xy 439.828834 -53.379861) (xy 439.844329 -53.32736) (xy 439.867174 -53.277614) (xy 439.896898 -53.231647)
			(xy 439.914538 -53.210714) (xy 439.914792 -53.21046) (xy 439.920359 -53.20336) (xy 439.926618 -53.186454)
			(xy 439.926984 -53.17744) (xy 439.926984 -53.110384) (xy 439.926638 -53.101366) (xy 439.920383 -53.084449)
			(xy 439.914792 -53.077364) (xy 439.914538 -53.077364) (xy 439.914538 -53.07711) (xy 439.896896 -53.05618)
			(xy 439.867183 -53.010207) (xy 439.844347 -52.960459) (xy 439.828857 -52.907958) (xy 439.821031 -52.853781)
			(xy 439.820558 -52.826412) (xy 439.821044 -52.799161) (xy 439.8288 -52.745213) (xy 439.844155 -52.692918)
			(xy 439.866797 -52.643341) (xy 439.896263 -52.597491) (xy 439.931954 -52.5563) (xy 439.973145 -52.520609)
			(xy 440.018995 -52.491143) (xy 440.068572 -52.468501) (xy 440.120867 -52.453146) (xy 440.174815 -52.44539)
			(xy 440.229317 -52.44539) (xy 440.283265 -52.453146) (xy 440.33556 -52.468501) (xy 440.385137 -52.491143)
			(xy 440.430987 -52.520609) (xy 440.472178 -52.5563) (xy 440.507869 -52.597491) (xy 440.537335 -52.643341)
			(xy 440.559977 -52.692918) (xy 440.575332 -52.745213) (xy 440.583088 -52.799161) (xy 440.583574 -52.826412)
			(xy 440.583121 -52.853783) (xy 440.575301 -52.907963) (xy 440.559809 -52.960466) (xy 440.536965 -53.010213)
			(xy 440.507237 -53.056179) (xy 440.489594 -53.07711) (xy 440.48934 -53.077364) (xy 440.483755 -53.084452)
			(xy 440.477509 -53.101368) (xy 440.477148 -53.110384) (xy 440.477148 -53.17744) (xy 440.477475 -53.18646)
			(xy 440.483742 -53.203377) (xy 440.48934 -53.21046) (xy 440.489594 -53.21046) (xy 440.489594 -53.210714)
			(xy 440.507246 -53.231638) (xy 440.536968 -53.277608) (xy 440.559812 -53.327355) (xy 440.575306 -53.379859)
			(xy 440.583133 -53.434038) (xy 440.583132 -53.48878) (xy 440.575302 -53.542959) (xy 440.559805 -53.595462)
			(xy 440.53696 -53.645208) (xy 440.507235 -53.691177) (xy 440.489594 -53.71211) (xy 440.48934 -53.712364)
			(xy 440.483755 -53.719452) (xy 440.477509 -53.736368) (xy 440.477148 -53.745384) (xy 440.477148 -53.81244)
			(xy 440.477475 -53.82146) (xy 440.483742 -53.838377) (xy 440.48934 -53.84546) (xy 440.489594 -53.84546)
			(xy 440.489594 -53.845714) (xy 440.507246 -53.866638) (xy 440.536968 -53.912608) (xy 440.559812 -53.962355)
			(xy 440.575306 -54.014859) (xy 440.583133 -54.069038) (xy 440.583132 -54.12378) (xy 440.575302 -54.177959)
			(xy 440.559805 -54.230462) (xy 440.53696 -54.280208) (xy 440.507235 -54.326177) (xy 440.489594 -54.34711)
			(xy 440.48934 -54.347364) (xy 440.483755 -54.354452) (xy 440.477509 -54.371368) (xy 440.477148 -54.380384)
			(xy 440.477148 -54.44744) (xy 440.477475 -54.45646) (xy 440.483742 -54.473377) (xy 440.48934 -54.48046)
			(xy 440.489594 -54.48046) (xy 440.489594 -54.480714) (xy 440.507205 -54.501668) (xy 440.536922 -54.547635)
			(xy 440.559763 -54.597377) (xy 440.57526 -54.649873) (xy 440.583096 -54.704044) (xy 440.583574 -54.731412)
			(xy 440.583088 -54.758663) (xy 440.578424 -54.791102) (xy 442.476382 -54.791102) (xy 442.476829 -54.763731)
			(xy 442.484649 -54.70955) (xy 442.500141 -54.657046) (xy 442.522987 -54.607299) (xy 442.552718 -54.561334)
			(xy 442.570362 -54.540404) (xy 442.570616 -54.54015) (xy 442.57619 -54.533055) (xy 442.582444 -54.516145)
			(xy 442.582808 -54.50713) (xy 442.582808 -54.440074) (xy 442.582461 -54.431056) (xy 442.576206 -54.414139)
			(xy 442.570616 -54.407054) (xy 442.570362 -54.407054) (xy 442.570362 -54.4068) (xy 442.552722 -54.385866)
			(xy 442.522994 -54.3399) (xy 442.500147 -54.290154) (xy 442.484649 -54.237651) (xy 442.476819 -54.183472)
			(xy 442.476819 -54.128731) (xy 442.484648 -54.074551) (xy 442.500146 -54.022049) (xy 442.522993 -53.972303)
			(xy 442.55272 -53.926336) (xy 442.570362 -53.905404) (xy 442.570616 -53.90515) (xy 442.57619 -53.898055)
			(xy 442.582444 -53.881145) (xy 442.582808 -53.87213) (xy 442.582808 -53.805074) (xy 442.582461 -53.796056)
			(xy 442.576206 -53.779139) (xy 442.570616 -53.772054) (xy 442.570362 -53.772054) (xy 442.570362 -53.7718)
			(xy 442.552722 -53.750866) (xy 442.522994 -53.7049) (xy 442.500147 -53.655154) (xy 442.484649 -53.602651)
			(xy 442.476819 -53.548472) (xy 442.476819 -53.493731) (xy 442.484648 -53.439551) (xy 442.500146 -53.387049)
			(xy 442.522993 -53.337303) (xy 442.55272 -53.291336) (xy 442.570362 -53.270404) (xy 442.570616 -53.27015)
			(xy 442.57619 -53.263055) (xy 442.582444 -53.246145) (xy 442.582808 -53.23713) (xy 442.582808 -53.170074)
			(xy 442.582461 -53.161056) (xy 442.576206 -53.144139) (xy 442.570616 -53.137054) (xy 442.570362 -53.137054)
			(xy 442.570362 -53.1368) (xy 442.552703 -53.115884) (xy 442.522995 -53.069906) (xy 442.500164 -53.020155)
			(xy 442.484677 -52.967651) (xy 442.476853 -52.913472) (xy 442.476382 -52.886102) (xy 442.476868 -52.858851)
			(xy 442.484624 -52.804903) (xy 442.499979 -52.752608) (xy 442.522621 -52.703031) (xy 442.552087 -52.657181)
			(xy 442.587778 -52.61599) (xy 442.628969 -52.580299) (xy 442.674819 -52.550833) (xy 442.724396 -52.528191)
			(xy 442.776691 -52.512836) (xy 442.830639 -52.50508) (xy 442.885141 -52.50508) (xy 442.939089 -52.512836)
			(xy 442.991384 -52.528191) (xy 443.030497 -52.546054) (xy 447.979473 -52.546054) (xy 447.979473 -52.491546)
			(xy 447.987231 -52.437594) (xy 448.002589 -52.385295) (xy 448.025234 -52.335714) (xy 448.054705 -52.289861)
			(xy 448.090401 -52.248669) (xy 448.131598 -52.212977) (xy 448.177454 -52.183512) (xy 448.227038 -52.160873)
			(xy 448.279339 -52.145521) (xy 448.333292 -52.13777) (xy 448.360546 -52.13731) (xy 448.387915 -52.137805)
			(xy 448.442093 -52.145616) (xy 448.494596 -52.161098) (xy 448.544343 -52.183933) (xy 448.590311 -52.213652)
			(xy 448.611244 -52.23129) (xy 448.611498 -52.231544) (xy 448.618577 -52.237141) (xy 448.6355 -52.24338)
			(xy 448.644518 -52.243736) (xy 448.711574 -52.243736) (xy 448.720589 -52.243359) (xy 448.737505 -52.237124)
			(xy 448.744594 -52.231544) (xy 448.744594 -52.23129) (xy 448.744848 -52.23129) (xy 448.765781 -52.213649)
			(xy 448.811749 -52.183925) (xy 448.861495 -52.161079) (xy 448.913997 -52.145583) (xy 448.968175 -52.137754)
			(xy 449.022917 -52.137754) (xy 449.077095 -52.145583) (xy 449.129597 -52.161079) (xy 449.179343 -52.183925)
			(xy 449.225311 -52.213649) (xy 449.246244 -52.23129) (xy 449.246498 -52.231544) (xy 449.253577 -52.237141)
			(xy 449.2705 -52.24338) (xy 449.279518 -52.243736) (xy 449.346574 -52.243736) (xy 449.355589 -52.243359)
			(xy 449.372505 -52.237124) (xy 449.379594 -52.231544) (xy 449.379594 -52.23129) (xy 449.379848 -52.23129)
			(xy 449.400788 -52.21366) (xy 449.446758 -52.183947) (xy 449.496504 -52.16111) (xy 449.549003 -52.145616)
			(xy 449.603177 -52.137786) (xy 449.630546 -52.13731) (xy 449.657796 -52.137763) (xy 449.711742 -52.145525)
			(xy 449.764033 -52.160885) (xy 449.813607 -52.18353) (xy 449.859454 -52.212999) (xy 449.900641 -52.248692)
			(xy 449.936329 -52.289883) (xy 449.965792 -52.335733) (xy 449.988431 -52.38531) (xy 450.003785 -52.437603)
			(xy 450.01154 -52.49155) (xy 450.01154 -52.54605) (xy 450.005596 -52.587398) (xy 451.05523 -52.587398)
			(xy 451.059301 -52.531776) (xy 451.071427 -52.477339) (xy 451.09135 -52.425248) (xy 451.118646 -52.376613)
			(xy 451.152732 -52.33247) (xy 451.192881 -52.293761) (xy 451.238239 -52.26131) (xy 451.287839 -52.235809)
			(xy 451.340623 -52.217802) (xy 451.395466 -52.207672) (xy 451.4512 -52.205635) (xy 451.506637 -52.211735)
			(xy 451.560594 -52.225841) (xy 451.611923 -52.247653) (xy 451.659529 -52.276707) (xy 451.702397 -52.312382)
			(xy 451.739614 -52.353919) (xy 451.770387 -52.400432) (xy 451.794059 -52.450929) (xy 451.810127 -52.504336)
			(xy 451.818247 -52.559512) (xy 451.818756 -52.587398) (xy 451.818247 -52.615284) (xy 451.810127 -52.67046)
			(xy 451.794059 -52.723867) (xy 451.770387 -52.774364) (xy 451.739614 -52.820877) (xy 451.702397 -52.862414)
			(xy 451.659529 -52.898089) (xy 451.611923 -52.927143) (xy 451.560594 -52.948955) (xy 451.506637 -52.963061)
			(xy 451.4512 -52.969161) (xy 451.395466 -52.967124) (xy 451.340623 -52.956994) (xy 451.287839 -52.938987)
			(xy 451.238239 -52.913486) (xy 451.192881 -52.881035) (xy 451.152732 -52.842326) (xy 451.118646 -52.798183)
			(xy 451.09135 -52.749548) (xy 451.071427 -52.697457) (xy 451.059301 -52.64302) (xy 451.05523 -52.587398)
			(xy 450.005596 -52.587398) (xy 450.003785 -52.599997) (xy 449.988431 -52.65229) (xy 449.965792 -52.701867)
			(xy 449.936329 -52.747717) (xy 449.900641 -52.788908) (xy 449.859454 -52.824601) (xy 449.813607 -52.85407)
			(xy 449.764033 -52.876715) (xy 449.711742 -52.892075) (xy 449.657796 -52.899837) (xy 449.630546 -52.900326)
			(xy 449.603176 -52.899851) (xy 449.548996 -52.892038) (xy 449.496493 -52.876552) (xy 449.446746 -52.853712)
			(xy 449.400779 -52.823988) (xy 449.379848 -52.806346) (xy 449.379594 -52.806092) (xy 449.372514 -52.800496)
			(xy 449.355592 -52.794255) (xy 449.346574 -52.7939) (xy 449.279518 -52.7939) (xy 449.270502 -52.794266)
			(xy 449.253585 -52.800507) (xy 449.246498 -52.806092) (xy 449.246244 -52.806346) (xy 449.225311 -52.823987)
			(xy 449.179343 -52.853711) (xy 449.129597 -52.876557) (xy 449.077095 -52.892053) (xy 449.022917 -52.899882)
			(xy 448.968175 -52.899882) (xy 448.913997 -52.892053) (xy 448.861495 -52.876557) (xy 448.811749 -52.853711)
			(xy 448.765781 -52.823987) (xy 448.744848 -52.806346) (xy 448.744594 -52.806092) (xy 448.737514 -52.800496)
			(xy 448.720592 -52.794255) (xy 448.711574 -52.7939) (xy 448.644518 -52.7939) (xy 448.635502 -52.794266)
			(xy 448.618585 -52.800507) (xy 448.611498 -52.806092) (xy 448.611498 -52.806346) (xy 448.611244 -52.806346)
			(xy 448.590299 -52.82397) (xy 448.544331 -52.853686) (xy 448.494587 -52.876525) (xy 448.442088 -52.89202)
			(xy 448.387914 -52.899851) (xy 448.360546 -52.900326) (xy 448.333292 -52.89983) (xy 448.279339 -52.892079)
			(xy 448.227038 -52.876727) (xy 448.177454 -52.854088) (xy 448.131598 -52.824623) (xy 448.090401 -52.788931)
			(xy 448.054705 -52.747739) (xy 448.025234 -52.701886) (xy 448.002589 -52.652305) (xy 447.987231 -52.600006)
			(xy 447.979473 -52.546054) (xy 443.030497 -52.546054) (xy 443.040961 -52.550833) (xy 443.086811 -52.580299)
			(xy 443.128002 -52.61599) (xy 443.163693 -52.657181) (xy 443.193159 -52.703031) (xy 443.215801 -52.752608)
			(xy 443.231156 -52.804903) (xy 443.238912 -52.858851) (xy 443.239398 -52.886102) (xy 443.238934 -52.913472)
			(xy 443.231115 -52.967651) (xy 443.215626 -53.020155) (xy 443.192784 -53.069901) (xy 443.163059 -53.115868)
			(xy 443.145418 -53.1368) (xy 443.145164 -53.137054) (xy 443.139587 -53.144147) (xy 443.133335 -53.161059)
			(xy 443.132972 -53.170074) (xy 443.132972 -53.23713) (xy 443.133321 -53.246148) (xy 443.139575 -53.263064)
			(xy 443.145164 -53.27015) (xy 443.145418 -53.27015) (xy 443.145418 -53.270404) (xy 443.163059 -53.291336)
			(xy 443.19278 -53.337305) (xy 443.215623 -53.387052) (xy 443.231117 -53.439553) (xy 443.238944 -53.493731)
			(xy 443.238944 -53.548472) (xy 443.231116 -53.602649) (xy 443.215621 -53.655151) (xy 443.192779 -53.704898)
			(xy 443.163057 -53.750866) (xy 443.146488 -53.77053) (xy 443.51067 -53.77053) (xy 443.511183 -53.741613)
			(xy 443.51991 -53.68444) (xy 443.537167 -53.62924) (xy 443.562559 -53.577278) (xy 443.595505 -53.529744)
			(xy 443.635249 -53.487729) (xy 443.657736 -53.46954) (xy 443.666521 -53.461912) (xy 443.676715 -53.441027)
			(xy 443.677294 -53.429408) (xy 443.677294 -53.349652) (xy 443.67677 -53.338018) (xy 443.666571 -53.317109)
			(xy 443.657736 -53.30952) (xy 443.63527 -53.291309) (xy 443.595532 -53.249294) (xy 443.56259 -53.201764)
			(xy 443.537198 -53.149806) (xy 443.519938 -53.094612) (xy 443.511206 -53.037445) (xy 443.51067 -53.00853)
			(xy 443.511183 -52.981279) (xy 443.518935 -52.927331) (xy 443.534287 -52.875035) (xy 443.556924 -52.825457)
			(xy 443.586387 -52.779605) (xy 443.622075 -52.738412) (xy 443.663263 -52.702718) (xy 443.709111 -52.673249)
			(xy 443.758687 -52.650605) (xy 443.81098 -52.635247) (xy 443.864927 -52.627487) (xy 443.892178 -52.627022)
			(xy 443.918492 -52.627497) (xy 443.97062 -52.634729) (xy 444.021263 -52.649046) (xy 444.069462 -52.670177)
			(xy 444.114306 -52.697723) (xy 444.154946 -52.731161) (xy 444.173102 -52.750212) (xy 444.180619 -52.757618)
			(xy 444.199903 -52.76614) (xy 444.21044 -52.766722) (xy 444.285116 -52.766722) (xy 444.295667 -52.766208)
			(xy 444.314962 -52.757662) (xy 444.322454 -52.750212) (xy 444.340593 -52.73114) (xy 444.381226 -52.697683)
			(xy 444.426069 -52.670126) (xy 444.474274 -52.648991) (xy 444.524924 -52.634677) (xy 444.577061 -52.627458)
			(xy 444.603378 -52.627022) (xy 444.630632 -52.627476) (xy 444.684585 -52.635231) (xy 444.736884 -52.650585)
			(xy 444.786466 -52.673228) (xy 444.832321 -52.702696) (xy 444.873515 -52.738391) (xy 444.909209 -52.779585)
			(xy 444.938676 -52.825441) (xy 444.961317 -52.875023) (xy 444.976671 -52.927323) (xy 444.984425 -52.981276)
			(xy 444.984886 -53.00853) (xy 444.984404 -53.036196) (xy 444.9764 -53.090947) (xy 444.960578 -53.14397)
			(xy 444.937271 -53.194154) (xy 444.906965 -53.240449) (xy 444.870295 -53.281887) (xy 444.828029 -53.317598)
			(xy 444.8048 -53.332634) (xy 444.795119 -53.339266) (xy 444.782674 -53.35913) (xy 444.780924 -53.370734)
			(xy 444.77305 -53.450744) (xy 444.772399 -53.462383) (xy 444.780492 -53.484221) (xy 444.788544 -53.492654)
			(xy 444.788798 -53.492908) (xy 444.807365 -53.511003) (xy 444.839945 -53.551332) (xy 444.86676 -53.595703)
			(xy 444.887315 -53.643299) (xy 444.901231 -53.693241) (xy 444.908252 -53.744608) (xy 444.908686 -53.77053)
			(xy 444.90825 -53.797783) (xy 444.900489 -53.851734) (xy 444.885129 -53.904031) (xy 444.862483 -53.953609)
			(xy 444.833011 -53.999461) (xy 444.797314 -54.040651) (xy 444.756119 -54.076342) (xy 444.710264 -54.105808)
			(xy 444.660682 -54.128447) (xy 444.608383 -54.1438) (xy 444.554431 -54.151554) (xy 444.527178 -54.152038)
			(xy 444.499807 -54.1516) (xy 444.445626 -54.143778) (xy 444.393122 -54.128283) (xy 444.343375 -54.105435)
			(xy 444.29741 -54.075703) (xy 444.27648 -54.058058) (xy 444.276226 -54.057804) (xy 444.269136 -54.052223)
			(xy 444.252222 -54.045973) (xy 444.243206 -54.045612) (xy 444.17615 -54.045612) (xy 444.167135 -54.045991)
			(xy 444.150218 -54.052223) (xy 444.14313 -54.057804) (xy 444.14313 -54.058058) (xy 444.142876 -54.058058)
			(xy 444.121921 -54.075668) (xy 444.075955 -54.105386) (xy 444.026213 -54.128228) (xy 443.973718 -54.143726)
			(xy 443.919546 -54.151561) (xy 443.892178 -54.152038) (xy 443.864928 -54.151543) (xy 443.810982 -54.143784)
			(xy 443.758689 -54.128428) (xy 443.709114 -54.105786) (xy 443.663265 -54.07632) (xy 443.622076 -54.04063)
			(xy 443.586384 -53.999442) (xy 443.556918 -53.953593) (xy 443.534275 -53.904018) (xy 443.518918 -53.851726)
			(xy 443.511158 -53.79778) (xy 443.51067 -53.77053) (xy 443.146488 -53.77053) (xy 443.145418 -53.7718)
			(xy 443.145164 -53.772054) (xy 443.139587 -53.779147) (xy 443.133335 -53.796059) (xy 443.132972 -53.805074)
			(xy 443.132972 -53.87213) (xy 443.133321 -53.881148) (xy 443.139575 -53.898064) (xy 443.145164 -53.90515)
			(xy 443.145418 -53.90515) (xy 443.145418 -53.905404) (xy 443.163059 -53.926336) (xy 443.19278 -53.972305)
			(xy 443.215623 -54.022052) (xy 443.231117 -54.074553) (xy 443.238944 -54.128731) (xy 443.238944 -54.183472)
			(xy 443.231116 -54.237649) (xy 443.215621 -54.290151) (xy 443.20183 -54.320186) (xy 445.430402 -54.320186)
			(xy 445.430859 -54.292815) (xy 445.438679 -54.238636) (xy 445.45417 -54.186133) (xy 445.477014 -54.136386)
			(xy 445.50674 -54.09042) (xy 445.524382 -54.069488) (xy 445.524636 -54.069234) (xy 445.530218 -54.062145)
			(xy 445.536467 -54.04523) (xy 445.536828 -54.036214) (xy 445.536828 -53.969158) (xy 445.536437 -53.960145)
			(xy 445.530212 -53.943228) (xy 445.524636 -53.936138) (xy 445.524382 -53.936138) (xy 445.524382 -53.935884)
			(xy 445.506766 -53.914933) (xy 445.477051 -53.868965) (xy 445.454211 -53.819223) (xy 445.438715 -53.766726)
			(xy 445.43088 -53.712554) (xy 445.430402 -53.685186) (xy 445.430888 -53.657935) (xy 445.438644 -53.603987)
			(xy 445.453999 -53.551692) (xy 445.476641 -53.502115) (xy 445.506107 -53.456265) (xy 445.541798 -53.415074)
			(xy 445.582989 -53.379383) (xy 445.628839 -53.349917) (xy 445.678416 -53.327275) (xy 445.730711 -53.31192)
			(xy 445.784659 -53.304164) (xy 445.839161 -53.304164) (xy 445.893109 -53.31192) (xy 445.945404 -53.327275)
			(xy 445.994981 -53.349917) (xy 446.040831 -53.379383) (xy 446.082022 -53.415074) (xy 446.117713 -53.456265)
			(xy 446.147179 -53.502115) (xy 446.169821 -53.551692) (xy 446.185176 -53.603987) (xy 446.192932 -53.657935)
			(xy 446.193418 -53.685186) (xy 446.192964 -53.712557) (xy 446.185146 -53.766737) (xy 446.169655 -53.819241)
			(xy 446.14681 -53.868988) (xy 446.117082 -53.914954) (xy 446.099438 -53.935884) (xy 446.099184 -53.936138)
			(xy 446.093615 -53.943237) (xy 446.087358 -53.960144) (xy 446.086992 -53.969158) (xy 446.086992 -54.036214)
			(xy 446.087344 -54.045231) (xy 446.093595 -54.062148) (xy 446.099184 -54.069234) (xy 446.099438 -54.069234)
			(xy 446.099438 -54.069488) (xy 446.117091 -54.090409) (xy 446.1468 -54.136385) (xy 446.169632 -54.186136)
			(xy 446.18512 -54.238639) (xy 446.192946 -54.292816) (xy 446.193418 -54.320186) (xy 446.192932 -54.347437)
			(xy 446.185176 -54.401385) (xy 446.169821 -54.45368) (xy 446.147179 -54.503257) (xy 446.117713 -54.549107)
			(xy 446.082022 -54.590298) (xy 446.040831 -54.625989) (xy 445.994981 -54.655455) (xy 445.945404 -54.678097)
			(xy 445.893109 -54.693452) (xy 445.839161 -54.701208) (xy 445.784659 -54.701208) (xy 445.730711 -54.693452)
			(xy 445.678416 -54.678097) (xy 445.628839 -54.655455) (xy 445.582989 -54.625989) (xy 445.541798 -54.590298)
			(xy 445.506107 -54.549107) (xy 445.476641 -54.503257) (xy 445.453999 -54.45368) (xy 445.438644 -54.401385)
			(xy 445.430888 -54.347437) (xy 445.430402 -54.320186) (xy 443.20183 -54.320186) (xy 443.192779 -54.339898)
			(xy 443.163057 -54.385866) (xy 443.145418 -54.4068) (xy 443.145164 -54.407054) (xy 443.139587 -54.414147)
			(xy 443.133335 -54.431059) (xy 443.132972 -54.440074) (xy 443.132972 -54.50713) (xy 443.133321 -54.516148)
			(xy 443.139575 -54.533064) (xy 443.145164 -54.54015) (xy 443.145418 -54.54015) (xy 443.145418 -54.540404)
			(xy 443.163075 -54.561321) (xy 443.192784 -54.607299) (xy 443.215616 -54.65705) (xy 443.231103 -54.709554)
			(xy 443.238926 -54.763732) (xy 443.239043 -54.770528) (xy 446.370964 -54.770528) (xy 446.371431 -54.743158)
			(xy 446.379246 -54.688978) (xy 446.394734 -54.636474) (xy 446.417576 -54.586727) (xy 446.447302 -54.540761)
			(xy 446.464944 -54.51983) (xy 446.465198 -54.519576) (xy 446.470801 -54.5125) (xy 446.477038 -54.495575)
			(xy 446.47739 -54.486556) (xy 446.47739 -54.4195) (xy 446.477035 -54.410483) (xy 446.470786 -54.393566)
			(xy 446.465198 -54.38648) (xy 446.464944 -54.38648) (xy 446.464944 -54.386226) (xy 446.44731 -54.365289)
			(xy 446.417596 -54.319318) (xy 446.394759 -54.269572) (xy 446.379266 -54.217072) (xy 446.371438 -54.162897)
			(xy 446.370964 -54.135528) (xy 446.37145 -54.108277) (xy 446.379206 -54.054329) (xy 446.394561 -54.002034)
			(xy 446.417203 -53.952457) (xy 446.446669 -53.906607) (xy 446.48236 -53.865416) (xy 446.523551 -53.829725)
			(xy 446.569401 -53.800259) (xy 446.618978 -53.777617) (xy 446.671273 -53.762262) (xy 446.725221 -53.754506)
			(xy 446.779723 -53.754506) (xy 446.833671 -53.762262) (xy 446.885966 -53.777617) (xy 446.935543 -53.800259)
			(xy 446.981393 -53.829725) (xy 447.022584 -53.865416) (xy 447.058275 -53.906607) (xy 447.087741 -53.952457)
			(xy 447.092816 -53.96357) (xy 451.071994 -53.96357) (xy 451.076065 -53.907948) (xy 451.088191 -53.853511)
			(xy 451.108114 -53.80142) (xy 451.13541 -53.752785) (xy 451.169496 -53.708642) (xy 451.209645 -53.669933)
			(xy 451.255003 -53.637482) (xy 451.304603 -53.611981) (xy 451.357387 -53.593974) (xy 451.41223 -53.583844)
			(xy 451.467964 -53.581807) (xy 451.523401 -53.587907) (xy 451.577358 -53.602013) (xy 451.628687 -53.623825)
			(xy 451.676293 -53.652879) (xy 451.719161 -53.688554) (xy 451.756378 -53.730091) (xy 451.787151 -53.776604)
			(xy 451.810823 -53.827101) (xy 451.826891 -53.880508) (xy 451.835011 -53.935684) (xy 451.83552 -53.96357)
			(xy 451.835011 -53.991456) (xy 451.826891 -54.046632) (xy 451.810823 -54.100039) (xy 451.787151 -54.150536)
			(xy 451.756378 -54.197049) (xy 451.719161 -54.238586) (xy 451.676293 -54.274261) (xy 451.628687 -54.303315)
			(xy 451.577358 -54.325127) (xy 451.523401 -54.339233) (xy 451.467964 -54.345333) (xy 451.41223 -54.343296)
			(xy 451.357387 -54.333166) (xy 451.304603 -54.315159) (xy 451.255003 -54.289658) (xy 451.209645 -54.257207)
			(xy 451.169496 -54.218498) (xy 451.13541 -54.174355) (xy 451.108114 -54.12572) (xy 451.088191 -54.073629)
			(xy 451.076065 -54.019192) (xy 451.071994 -53.96357) (xy 447.092816 -53.96357) (xy 447.110383 -54.002034)
			(xy 447.125738 -54.054329) (xy 447.133494 -54.108277) (xy 447.13398 -54.135528) (xy 447.133535 -54.162899)
			(xy 447.125713 -54.217079) (xy 447.110219 -54.269583) (xy 447.087373 -54.319329) (xy 447.057643 -54.365295)
			(xy 447.04 -54.386226) (xy 447.039746 -54.38648) (xy 447.034155 -54.393563) (xy 447.027912 -54.410483)
			(xy 447.027554 -54.4195) (xy 447.027554 -54.486556) (xy 447.02792 -54.495572) (xy 447.03416 -54.51249)
			(xy 447.039746 -54.519576) (xy 447.04 -54.519576) (xy 447.04 -54.51983) (xy 447.05762 -54.540778)
			(xy 447.087334 -54.586746) (xy 447.110174 -54.63649) (xy 447.12567 -54.688987) (xy 447.133503 -54.74316)
			(xy 447.13398 -54.770528) (xy 447.133494 -54.797779) (xy 447.125738 -54.851727) (xy 447.110383 -54.904022)
			(xy 447.087741 -54.953599) (xy 447.058275 -54.999449) (xy 447.022584 -55.04064) (xy 446.981393 -55.076331)
			(xy 446.935543 -55.105797) (xy 446.885966 -55.128439) (xy 446.833671 -55.143794) (xy 446.779723 -55.15155)
			(xy 446.725221 -55.15155) (xy 446.671273 -55.143794) (xy 446.618978 -55.128439) (xy 446.569401 -55.105797)
			(xy 446.523551 -55.076331) (xy 446.48236 -55.04064) (xy 446.446669 -54.999449) (xy 446.417203 -54.953599)
			(xy 446.394561 -54.904022) (xy 446.379206 -54.851727) (xy 446.37145 -54.797779) (xy 446.370964 -54.770528)
			(xy 443.239043 -54.770528) (xy 443.239398 -54.791102) (xy 443.238912 -54.818353) (xy 443.231156 -54.872301)
			(xy 443.215801 -54.924596) (xy 443.193159 -54.974173) (xy 443.163693 -55.020023) (xy 443.128002 -55.061214)
			(xy 443.086811 -55.096905) (xy 443.040961 -55.126371) (xy 442.991384 -55.149013) (xy 442.939089 -55.164368)
			(xy 442.885141 -55.172124) (xy 442.830639 -55.172124) (xy 442.776691 -55.164368) (xy 442.724396 -55.149013)
			(xy 442.674819 -55.126371) (xy 442.628969 -55.096905) (xy 442.587778 -55.061214) (xy 442.552087 -55.020023)
			(xy 442.522621 -54.974173) (xy 442.499979 -54.924596) (xy 442.484624 -54.872301) (xy 442.476868 -54.818353)
			(xy 442.476382 -54.791102) (xy 440.578424 -54.791102) (xy 440.575332 -54.812611) (xy 440.559977 -54.864906)
			(xy 440.537335 -54.914483) (xy 440.507869 -54.960333) (xy 440.472178 -55.001524) (xy 440.430987 -55.037215)
			(xy 440.385137 -55.066681) (xy 440.33556 -55.089323) (xy 440.283265 -55.104678) (xy 440.229317 -55.112434)
			(xy 440.174815 -55.112434) (xy 440.120867 -55.104678) (xy 440.068572 -55.089323) (xy 440.018995 -55.066681)
			(xy 439.973145 -55.037215) (xy 439.931954 -55.001524) (xy 439.896263 -54.960333) (xy 439.866797 -54.914483)
			(xy 439.844155 -54.864906) (xy 439.8288 -54.812611) (xy 439.821044 -54.758663) (xy 439.820558 -54.731412)
			(xy 439.119264 -54.731412) (xy 439.119264 -57.002934) (xy 447.863468 -57.002934) (xy 447.863996 -56.974844)
			(xy 447.872218 -56.919268) (xy 447.888504 -56.865501) (xy 447.912501 -56.814703) (xy 447.943691 -56.767976)
			(xy 447.981398 -56.72633) (xy 448.024806 -56.690666) (xy 448.048634 -56.675782) (xy 448.057524 -56.670448)
			(xy 448.069716 -56.65343) (xy 448.090036 -56.560212) (xy 448.085718 -56.539638) (xy 448.079876 -56.531002)
			(xy 448.063872 -56.506941) (xy 448.038531 -56.455008) (xy 448.021306 -56.399849) (xy 448.012592 -56.342725)
			(xy 448.012058 -56.313832) (xy 448.012608 -56.286583) (xy 448.020359 -56.232639) (xy 448.035709 -56.180348)
			(xy 448.058343 -56.130773) (xy 448.087803 -56.084924) (xy 448.123488 -56.043735) (xy 448.164672 -56.008043)
			(xy 448.210515 -55.978575) (xy 448.260086 -55.955932) (xy 448.312375 -55.940573) (xy 448.366317 -55.932813)
			(xy 448.393566 -55.932324) (xy 448.420936 -55.932804) (xy 448.475115 -55.940618) (xy 448.527618 -55.956103)
			(xy 448.577365 -55.978942) (xy 448.623332 -56.008664) (xy 448.644264 -56.026304) (xy 448.644518 -56.026558)
			(xy 448.65159 -56.032165) (xy 448.668518 -56.038398) (xy 448.677538 -56.03875) (xy 448.744594 -56.03875)
			(xy 448.753612 -56.038401) (xy 448.770529 -56.032149) (xy 448.777614 -56.026558) (xy 448.777614 -56.026304)
			(xy 448.777868 -56.026304) (xy 448.798801 -56.008663) (xy 448.844769 -55.978939) (xy 448.894515 -55.956093)
			(xy 448.947017 -55.940597) (xy 449.001195 -55.932768) (xy 449.055937 -55.932768) (xy 449.110115 -55.940597)
			(xy 449.162617 -55.956093) (xy 449.212363 -55.978939) (xy 449.258331 -56.008663) (xy 449.279264 -56.026304)
			(xy 449.279518 -56.026558) (xy 449.28659 -56.032165) (xy 449.303518 -56.038398) (xy 449.312538 -56.03875)
			(xy 449.379594 -56.03875) (xy 449.388612 -56.038401) (xy 449.405529 -56.032149) (xy 449.412614 -56.026558)
			(xy 449.412614 -56.026304) (xy 449.412868 -56.026304) (xy 449.433802 -56.008667) (xy 449.479774 -55.978955)
			(xy 449.529521 -55.956118) (xy 449.582021 -55.940627) (xy 449.636197 -55.932798) (xy 449.663566 -55.932324)
			(xy 449.690823 -55.932721) (xy 449.744782 -55.940474) (xy 449.797088 -55.955829) (xy 449.846677 -55.978471)
			(xy 449.892538 -56.007941) (xy 449.933738 -56.043637) (xy 449.969439 -56.084835) (xy 449.998913 -56.130693)
			(xy 450.021559 -56.18028) (xy 450.036918 -56.232585) (xy 450.044677 -56.286543) (xy 450.044677 -56.341057)
			(xy 450.036918 -56.395015) (xy 450.021559 -56.44732) (xy 449.998913 -56.496907) (xy 449.969439 -56.542765)
			(xy 449.933738 -56.583963) (xy 449.892538 -56.619659) (xy 449.846677 -56.649129) (xy 449.797088 -56.671771)
			(xy 449.744782 -56.687126) (xy 449.690823 -56.694879) (xy 449.663566 -56.69534) (xy 449.636194 -56.694908)
			(xy 449.582013 -56.687085) (xy 449.529509 -56.671588) (xy 449.479763 -56.648738) (xy 449.433798 -56.619005)
			(xy 449.412868 -56.60136) (xy 449.412614 -56.601106) (xy 449.405527 -56.59552) (xy 449.388611 -56.589273)
			(xy 449.379594 -56.588914) (xy 449.312538 -56.588914) (xy 449.303523 -56.589286) (xy 449.286605 -56.595523)
			(xy 449.279518 -56.601106) (xy 449.279518 -56.60136) (xy 449.279264 -56.60136) (xy 449.258331 -56.619001)
			(xy 449.212363 -56.648725) (xy 449.162617 -56.671571) (xy 449.110115 -56.687067) (xy 449.055937 -56.694896)
			(xy 449.001195 -56.694896) (xy 448.947017 -56.687067) (xy 448.894515 -56.671571) (xy 448.844769 -56.648725)
			(xy 448.798801 -56.619001) (xy 448.777868 -56.60136) (xy 448.777614 -56.601106) (xy 448.770527 -56.59552)
			(xy 448.753611 -56.589273) (xy 448.744594 -56.588914) (xy 448.677538 -56.588914) (xy 448.668523 -56.589286)
			(xy 448.651605 -56.595523) (xy 448.644518 -56.601106) (xy 448.64401 -56.60136) (xy 448.631279 -56.612308)
			(xy 448.604185 -56.632147) (xy 448.589908 -56.640984) (xy 448.581018 -56.646318) (xy 448.568826 -56.663336)
			(xy 448.548506 -56.756554) (xy 448.552824 -56.777128) (xy 448.558666 -56.785764) (xy 448.574649 -56.809839)
			(xy 448.599997 -56.861766) (xy 448.617227 -56.916921) (xy 448.625947 -56.974042) (xy 448.626484 -57.002934)
			(xy 448.625998 -57.030185) (xy 448.618242 -57.084133) (xy 448.602887 -57.136428) (xy 448.580245 -57.186005)
			(xy 448.550779 -57.231855) (xy 448.515088 -57.273046) (xy 448.473897 -57.308737) (xy 448.428047 -57.338203)
			(xy 448.37847 -57.360845) (xy 448.326175 -57.3762) (xy 448.272227 -57.383956) (xy 448.217725 -57.383956)
			(xy 448.163777 -57.3762) (xy 448.111482 -57.360845) (xy 448.061905 -57.338203) (xy 448.016055 -57.308737)
			(xy 447.974864 -57.273046) (xy 447.939173 -57.231855) (xy 447.909707 -57.186005) (xy 447.887065 -57.136428)
			(xy 447.87171 -57.084133) (xy 447.863954 -57.030185) (xy 447.863468 -57.002934) (xy 439.119264 -57.002934)
			(xy 439.119264 -58.679334) (xy 448.295268 -58.679334) (xy 448.295702 -58.653019) (xy 448.302945 -58.600889)
			(xy 448.317271 -58.550246) (xy 448.33841 -58.502048) (xy 448.365962 -58.457205) (xy 448.399405 -58.416566)
			(xy 448.418458 -58.39841) (xy 448.425851 -58.390881) (xy 448.434382 -58.371607) (xy 448.434968 -58.361072)
			(xy 448.434968 -58.286396) (xy 448.434464 -58.275843) (xy 448.425912 -58.256548) (xy 448.418458 -58.249058)
			(xy 448.399381 -58.230924) (xy 448.365927 -58.190289) (xy 448.338372 -58.145444) (xy 448.317238 -58.097239)
			(xy 448.302925 -58.046588) (xy 448.295704 -57.994451) (xy 448.295268 -57.968134) (xy 448.295754 -57.940883)
			(xy 448.30351 -57.886935) (xy 448.318865 -57.83464) (xy 448.341507 -57.785063) (xy 448.370973 -57.739213)
			(xy 448.406664 -57.698022) (xy 448.447855 -57.662331) (xy 448.493705 -57.632865) (xy 448.543282 -57.610223)
			(xy 448.595577 -57.594868) (xy 448.649525 -57.587112) (xy 448.704027 -57.587112) (xy 448.757975 -57.594868)
			(xy 448.81027 -57.610223) (xy 448.859847 -57.632865) (xy 448.905697 -57.662331) (xy 448.946888 -57.698022)
			(xy 448.982579 -57.739213) (xy 449.012045 -57.785063) (xy 449.034687 -57.83464) (xy 449.050042 -57.886935)
			(xy 449.057798 -57.940883) (xy 449.058284 -57.968134) (xy 449.057844 -57.994449) (xy 449.050605 -58.046579)
			(xy 449.03628 -58.097222) (xy 449.015143 -58.145421) (xy 448.987592 -58.190264) (xy 448.954148 -58.230902)
			(xy 448.935094 -58.249058) (xy 448.927708 -58.256593) (xy 448.919175 -58.275863) (xy 448.918584 -58.286396)
			(xy 448.918584 -58.361072) (xy 448.91912 -58.371621) (xy 448.927651 -58.390916) (xy 448.935094 -58.39841)
			(xy 448.954146 -58.416569) (xy 448.987604 -58.457198) (xy 449.015164 -58.502037) (xy 449.036303 -58.550237)
			(xy 449.05062 -58.600884) (xy 449.057845 -58.653018) (xy 449.058284 -58.679334) (xy 449.057798 -58.706585)
			(xy 449.050042 -58.760533) (xy 449.034687 -58.812828) (xy 449.012045 -58.862405) (xy 448.982579 -58.908255)
			(xy 448.946888 -58.949446) (xy 448.905697 -58.985137) (xy 448.859847 -59.014603) (xy 448.81027 -59.037245)
			(xy 448.757975 -59.0526) (xy 448.704027 -59.060356) (xy 448.649525 -59.060356) (xy 448.595577 -59.0526)
			(xy 448.543282 -59.037245) (xy 448.493705 -59.014603) (xy 448.447855 -58.985137) (xy 448.406664 -58.949446)
			(xy 448.370973 -58.908255) (xy 448.341507 -58.862405) (xy 448.318865 -58.812828) (xy 448.30351 -58.760533)
			(xy 448.295754 -58.706585) (xy 448.295268 -58.679334) (xy 439.119264 -58.679334) (xy 439.119264 -60.019254)
			(xy 448.435661 -60.019254) (xy 448.435661 -59.964746) (xy 448.443419 -59.910794) (xy 448.458776 -59.858494)
			(xy 448.481421 -59.808913) (xy 448.510891 -59.763059) (xy 448.546587 -59.721866) (xy 448.587783 -59.686173)
			(xy 448.633639 -59.656706) (xy 448.683222 -59.634066) (xy 448.735523 -59.618713) (xy 448.789476 -59.610959)
			(xy 448.81673 -59.610498) (xy 448.844101 -59.610947) (xy 448.898281 -59.618769) (xy 448.950784 -59.634262)
			(xy 449.00053 -59.657108) (xy 449.046497 -59.686835) (xy 449.067428 -59.704478) (xy 449.067682 -59.704732)
			(xy 449.074767 -59.710321) (xy 449.091685 -59.716565) (xy 449.100702 -59.716924) (xy 449.167758 -59.716924)
			(xy 449.176772 -59.716542) (xy 449.193689 -59.710311) (xy 449.200778 -59.704732) (xy 449.200778 -59.704478)
			(xy 449.201032 -59.704478) (xy 449.221965 -59.686837) (xy 449.267933 -59.657113) (xy 449.317679 -59.634267)
			(xy 449.370181 -59.618771) (xy 449.424359 -59.610942) (xy 449.479101 -59.610942) (xy 449.533279 -59.618771)
			(xy 449.585781 -59.634267) (xy 449.635527 -59.657113) (xy 449.681495 -59.686837) (xy 449.702428 -59.704478)
			(xy 449.702682 -59.704732) (xy 449.709767 -59.710321) (xy 449.726685 -59.716565) (xy 449.735702 -59.716924)
			(xy 449.802758 -59.716924) (xy 449.811772 -59.716542) (xy 449.828689 -59.710311) (xy 449.835778 -59.704732)
			(xy 449.835778 -59.704478) (xy 449.836032 -59.704478) (xy 449.856976 -59.686854) (xy 449.902946 -59.657141)
			(xy 449.95269 -59.634302) (xy 450.005188 -59.618807) (xy 450.059362 -59.610975) (xy 450.08673 -59.610498)
			(xy 450.11398 -59.610974) (xy 450.167926 -59.618734) (xy 450.220218 -59.634092) (xy 450.269792 -59.656735)
			(xy 450.315639 -59.686203) (xy 450.356826 -59.721895) (xy 450.392515 -59.763085) (xy 450.421979 -59.808935)
			(xy 450.444619 -59.858511) (xy 450.459972 -59.910804) (xy 450.467728 -59.96475) (xy 450.467728 -60.01925)
			(xy 450.459972 -60.073196) (xy 450.444619 -60.125489) (xy 450.421979 -60.175065) (xy 450.392515 -60.220915)
			(xy 450.356826 -60.262105) (xy 450.315639 -60.297797) (xy 450.269792 -60.327265) (xy 450.220218 -60.349908)
			(xy 450.167926 -60.365266) (xy 450.11398 -60.373026) (xy 450.08673 -60.373514) (xy 450.059361 -60.373027)
			(xy 450.005183 -60.365214) (xy 449.95268 -60.349729) (xy 449.902933 -60.326892) (xy 449.856965 -60.297173)
			(xy 449.836032 -60.279534) (xy 449.835778 -60.27928) (xy 449.828704 -60.273676) (xy 449.811777 -60.26744)
			(xy 449.802758 -60.267088) (xy 449.735702 -60.267088) (xy 449.726686 -60.267449) (xy 449.709769 -60.273694)
			(xy 449.702682 -60.27928) (xy 449.702428 -60.279534) (xy 449.681495 -60.297175) (xy 449.635527 -60.326899)
			(xy 449.585781 -60.349745) (xy 449.533279 -60.365241) (xy 449.479101 -60.37307) (xy 449.424359 -60.37307)
			(xy 449.370181 -60.365241) (xy 449.317679 -60.349745) (xy 449.267933 -60.326899) (xy 449.221965 -60.297175)
			(xy 449.201032 -60.279534) (xy 449.200778 -60.27928) (xy 449.193704 -60.273676) (xy 449.176777 -60.26744)
			(xy 449.167758 -60.267088) (xy 449.100702 -60.267088) (xy 449.091686 -60.267449) (xy 449.074769 -60.273694)
			(xy 449.067682 -60.27928) (xy 449.067682 -60.279534) (xy 449.067428 -60.279534) (xy 449.046501 -60.297179)
			(xy 449.000526 -60.326889) (xy 448.950777 -60.349723) (xy 448.898276 -60.365213) (xy 448.844099 -60.37304)
			(xy 448.81673 -60.373514) (xy 448.789476 -60.373041) (xy 448.735523 -60.365287) (xy 448.683222 -60.349934)
			(xy 448.633639 -60.327294) (xy 448.587783 -60.297827) (xy 448.546587 -60.262134) (xy 448.510891 -60.220941)
			(xy 448.481421 -60.175087) (xy 448.458776 -60.125506) (xy 448.443419 -60.073206) (xy 448.435661 -60.019254)
			(xy 439.119264 -60.019254) (xy 439.119264 -67.128953) (xy 440.666575 -67.128953) (xy 440.666575 -67.074447)
			(xy 440.674333 -67.020496) (xy 440.68969 -66.968199) (xy 440.712333 -66.918619) (xy 440.741803 -66.872767)
			(xy 440.777498 -66.831575) (xy 440.818692 -66.795883) (xy 440.864547 -66.766418) (xy 440.914129 -66.743778)
			(xy 440.966428 -66.728426) (xy 441.020379 -66.720673) (xy 441.047632 -66.720212) (xy 441.075003 -66.720656)
			(xy 441.129183 -66.728479) (xy 441.181687 -66.743973) (xy 441.231433 -66.76682) (xy 441.277399 -66.796549)
			(xy 441.29833 -66.814192) (xy 441.298584 -66.814446) (xy 441.305667 -66.820038) (xy 441.322587 -66.82628)
			(xy 441.331604 -66.826638) (xy 441.39866 -66.826638) (xy 441.407674 -66.826254) (xy 441.424591 -66.820024)
			(xy 441.43168 -66.814446) (xy 441.43168 -66.814192) (xy 441.431934 -66.814192) (xy 441.452879 -66.796569)
			(xy 441.498848 -66.766855) (xy 441.548593 -66.744016) (xy 441.60109 -66.728521) (xy 441.655264 -66.720689)
			(xy 441.682632 -66.720212) (xy 441.709883 -66.72066) (xy 441.76383 -66.728421) (xy 441.816124 -66.743779)
			(xy 441.8657 -66.766423) (xy 441.911549 -66.795892) (xy 441.952737 -66.831586) (xy 441.988427 -66.872777)
			(xy 442.017892 -66.918628) (xy 442.040532 -66.968206) (xy 442.055886 -67.020501) (xy 442.063642 -67.074449)
			(xy 442.063642 -67.128951) (xy 442.055886 -67.182899) (xy 442.040532 -67.235194) (xy 442.017892 -67.284772)
			(xy 441.988427 -67.330623) (xy 441.952737 -67.371814) (xy 441.911549 -67.407508) (xy 441.8657 -67.436977)
			(xy 441.816124 -67.459621) (xy 441.76383 -67.474979) (xy 441.709883 -67.48274) (xy 441.682632 -67.483228)
			(xy 441.655262 -67.482761) (xy 441.601082 -67.474946) (xy 441.548578 -67.459458) (xy 441.498831 -67.436616)
			(xy 441.452865 -67.40689) (xy 441.431934 -67.389248) (xy 441.43168 -67.388994) (xy 441.424604 -67.383392)
			(xy 441.407679 -67.377155) (xy 441.39866 -67.376802) (xy 441.331604 -67.376802) (xy 441.322587 -67.37716)
			(xy 441.30567 -67.383407) (xy 441.298584 -67.388994) (xy 441.298584 -67.389248) (xy 441.29833 -67.389248)
			(xy 441.277391 -67.406878) (xy 441.231421 -67.436593) (xy 441.181675 -67.459432) (xy 441.129176 -67.474925)
			(xy 441.075001 -67.482754) (xy 441.047632 -67.483228) (xy 441.020379 -67.482727) (xy 440.966428 -67.474974)
			(xy 440.914129 -67.459622) (xy 440.864547 -67.436982) (xy 440.818692 -67.407516) (xy 440.777498 -67.371825)
			(xy 440.741803 -67.330633) (xy 440.712333 -67.284781) (xy 440.68969 -67.235201) (xy 440.674333 -67.182904)
			(xy 440.666575 -67.128953) (xy 439.119264 -67.128953) (xy 439.119264 -67.488054) (xy 445.079118 -67.488054)
			(xy 445.083189 -67.432432) (xy 445.095315 -67.377995) (xy 445.115238 -67.325904) (xy 445.142534 -67.277269)
			(xy 445.17662 -67.233126) (xy 445.216769 -67.194417) (xy 445.262127 -67.161966) (xy 445.311727 -67.136465)
			(xy 445.364511 -67.118458) (xy 445.419354 -67.108328) (xy 445.475088 -67.106291) (xy 445.530525 -67.112391)
			(xy 445.584482 -67.126497) (xy 445.635811 -67.148309) (xy 445.683417 -67.177363) (xy 445.726285 -67.213038)
			(xy 445.763502 -67.254575) (xy 445.794275 -67.301088) (xy 445.817947 -67.351585) (xy 445.834015 -67.404992)
			(xy 445.842135 -67.460168) (xy 445.842644 -67.488054) (xy 445.842135 -67.51594) (xy 445.83895 -67.537584)
			(xy 446.371216 -67.537584) (xy 446.375287 -67.481962) (xy 446.387413 -67.427525) (xy 446.407336 -67.375434)
			(xy 446.434632 -67.326799) (xy 446.468718 -67.282656) (xy 446.508867 -67.243947) (xy 446.554225 -67.211496)
			(xy 446.603825 -67.185995) (xy 446.656609 -67.167988) (xy 446.711452 -67.157858) (xy 446.767186 -67.155821)
			(xy 446.822623 -67.161921) (xy 446.87658 -67.176027) (xy 446.927909 -67.197839) (xy 446.975515 -67.226893)
			(xy 447.018383 -67.262568) (xy 447.0556 -67.304105) (xy 447.086373 -67.350618) (xy 447.110045 -67.401115)
			(xy 447.126113 -67.454522) (xy 447.134233 -67.509698) (xy 447.134742 -67.537584) (xy 447.134233 -67.56547)
			(xy 447.130188 -67.592956) (xy 447.64528 -67.592956) (xy 447.649351 -67.537334) (xy 447.661477 -67.482897)
			(xy 447.6814 -67.430806) (xy 447.708696 -67.382171) (xy 447.742782 -67.338028) (xy 447.782931 -67.299319)
			(xy 447.828289 -67.266868) (xy 447.877889 -67.241367) (xy 447.930673 -67.22336) (xy 447.985516 -67.21323)
			(xy 448.04125 -67.211193) (xy 448.096687 -67.217293) (xy 448.150644 -67.231399) (xy 448.201973 -67.253211)
			(xy 448.249579 -67.282265) (xy 448.292447 -67.31794) (xy 448.329664 -67.359477) (xy 448.360437 -67.40599)
			(xy 448.384109 -67.456487) (xy 448.400177 -67.509894) (xy 448.408294 -67.565051) (xy 450.746593 -67.565051)
			(xy 450.746593 -67.510549) (xy 450.75435 -67.456601) (xy 450.769706 -67.404307) (xy 450.792348 -67.35473)
			(xy 450.821815 -67.308881) (xy 450.857507 -67.267692) (xy 450.898698 -67.232001) (xy 450.94455 -67.202537)
			(xy 450.994128 -67.179898) (xy 451.046423 -67.164545) (xy 451.100371 -67.156792) (xy 451.127622 -67.15633)
			(xy 451.154993 -67.156776) (xy 451.209173 -67.164597) (xy 451.261677 -67.180091) (xy 451.311423 -67.202937)
			(xy 451.357389 -67.232666) (xy 451.37832 -67.25031) (xy 451.378574 -67.250564) (xy 451.385658 -67.256153)
			(xy 451.402577 -67.262397) (xy 451.411594 -67.262756) (xy 451.47865 -67.262756) (xy 451.487666 -67.262385)
			(xy 451.504583 -67.256148) (xy 451.51167 -67.250564) (xy 451.51167 -67.25031) (xy 451.511924 -67.25031)
			(xy 451.532875 -67.232695) (xy 451.578843 -67.202979) (xy 451.628585 -67.180138) (xy 451.681082 -67.164642)
			(xy 451.735254 -67.156807) (xy 451.762622 -67.15633) (xy 451.789875 -67.156741) (xy 451.843826 -67.164501)
			(xy 451.896123 -67.17986) (xy 451.945702 -67.202504) (xy 451.991555 -67.231974) (xy 452.032746 -67.267669)
			(xy 452.068439 -67.308863) (xy 452.097906 -67.354717) (xy 452.120548 -67.404298) (xy 452.135903 -67.456596)
			(xy 452.14366 -67.510547) (xy 452.14366 -67.565053) (xy 452.135903 -67.619004) (xy 452.120548 -67.671302)
			(xy 452.097906 -67.720883) (xy 452.068439 -67.766737) (xy 452.032746 -67.807931) (xy 451.991555 -67.843626)
			(xy 451.945702 -67.873096) (xy 451.896123 -67.89574) (xy 451.843826 -67.911099) (xy 451.789875 -67.918859)
			(xy 451.762622 -67.919346) (xy 451.735252 -67.91888) (xy 451.681072 -67.911064) (xy 451.628568 -67.895576)
			(xy 451.578821 -67.872734) (xy 451.532855 -67.843008) (xy 451.511924 -67.825366) (xy 451.51167 -67.825112)
			(xy 451.504567 -67.81955) (xy 451.487663 -67.813288) (xy 451.47865 -67.81292) (xy 451.411594 -67.81292)
			(xy 451.402576 -67.81327) (xy 451.385659 -67.819522) (xy 451.378574 -67.825112) (xy 451.378574 -67.825366)
			(xy 451.37832 -67.825366) (xy 451.357387 -67.843004) (xy 451.311415 -67.872717) (xy 451.261668 -67.895554)
			(xy 451.209167 -67.911045) (xy 451.154991 -67.918873) (xy 451.127622 -67.919346) (xy 451.100371 -67.918808)
			(xy 451.046423 -67.911055) (xy 450.994128 -67.895702) (xy 450.94455 -67.873063) (xy 450.898698 -67.843599)
			(xy 450.857507 -67.807908) (xy 450.821815 -67.766719) (xy 450.792348 -67.72087) (xy 450.769706 -67.671293)
			(xy 450.75435 -67.618999) (xy 450.746593 -67.565051) (xy 448.408294 -67.565051) (xy 448.408297 -67.56507)
			(xy 448.408806 -67.592956) (xy 448.408297 -67.620842) (xy 448.400177 -67.676018) (xy 448.384109 -67.729425)
			(xy 448.360437 -67.779922) (xy 448.329664 -67.826435) (xy 448.292447 -67.867972) (xy 448.249579 -67.903647)
			(xy 448.201973 -67.932701) (xy 448.150644 -67.954513) (xy 448.096687 -67.968619) (xy 448.04125 -67.974719)
			(xy 447.985516 -67.972682) (xy 447.930673 -67.962552) (xy 447.877889 -67.944545) (xy 447.828289 -67.919044)
			(xy 447.782931 -67.886593) (xy 447.742782 -67.847884) (xy 447.708696 -67.803741) (xy 447.6814 -67.755106)
			(xy 447.661477 -67.703015) (xy 447.649351 -67.648578) (xy 447.64528 -67.592956) (xy 447.130188 -67.592956)
			(xy 447.126113 -67.620646) (xy 447.110045 -67.674053) (xy 447.086373 -67.72455) (xy 447.0556 -67.771063)
			(xy 447.018383 -67.8126) (xy 446.975515 -67.848275) (xy 446.927909 -67.877329) (xy 446.87658 -67.899141)
			(xy 446.822623 -67.913247) (xy 446.767186 -67.919347) (xy 446.711452 -67.91731) (xy 446.656609 -67.90718)
			(xy 446.603825 -67.889173) (xy 446.554225 -67.863672) (xy 446.508867 -67.831221) (xy 446.468718 -67.792512)
			(xy 446.434632 -67.748369) (xy 446.407336 -67.699734) (xy 446.387413 -67.647643) (xy 446.375287 -67.593206)
			(xy 446.371216 -67.537584) (xy 445.83895 -67.537584) (xy 445.834015 -67.571116) (xy 445.817947 -67.624523)
			(xy 445.794275 -67.67502) (xy 445.763502 -67.721533) (xy 445.726285 -67.76307) (xy 445.683417 -67.798745)
			(xy 445.635811 -67.827799) (xy 445.584482 -67.849611) (xy 445.530525 -67.863717) (xy 445.475088 -67.869817)
			(xy 445.419354 -67.86778) (xy 445.364511 -67.85765) (xy 445.311727 -67.839643) (xy 445.262127 -67.814142)
			(xy 445.216769 -67.781691) (xy 445.17662 -67.742982) (xy 445.142534 -67.698839) (xy 445.115238 -67.650204)
			(xy 445.095315 -67.598113) (xy 445.083189 -67.543676) (xy 445.079118 -67.488054) (xy 439.119264 -67.488054)
			(xy 439.119264 -68.586604) (xy 442.9252 -68.586604) (xy 442.925668 -68.559234) (xy 442.933486 -68.505055)
			(xy 442.948974 -68.452552) (xy 442.971815 -68.402805) (xy 443.001539 -68.356838) (xy 443.01918 -68.335906)
			(xy 443.019434 -68.335652) (xy 443.025009 -68.328557) (xy 443.031261 -68.311647) (xy 443.031626 -68.302632)
			(xy 443.031626 -68.235576) (xy 443.031275 -68.226559) (xy 443.025023 -68.209642) (xy 443.019434 -68.202556)
			(xy 443.01918 -68.202556) (xy 443.01918 -68.202302) (xy 443.001525 -68.181383) (xy 442.971816 -68.135406)
			(xy 442.948984 -68.085655) (xy 442.933496 -68.033152) (xy 442.925672 -67.978974) (xy 442.9252 -67.951604)
			(xy 442.925659 -67.924351) (xy 442.933416 -67.870399) (xy 442.948772 -67.818101) (xy 442.971414 -67.76852)
			(xy 443.000883 -67.722667) (xy 443.036577 -67.681474) (xy 443.07777 -67.64578) (xy 443.123624 -67.616312)
			(xy 443.173205 -67.59367) (xy 443.225503 -67.578315) (xy 443.279455 -67.570559) (xy 443.306708 -67.570096)
			(xy 443.333022 -67.570559) (xy 443.385151 -67.577795) (xy 443.435793 -67.592115) (xy 443.483992 -67.613248)
			(xy 443.528836 -67.640795) (xy 443.569475 -67.674234) (xy 443.587632 -67.693286) (xy 443.595142 -67.700702)
			(xy 443.614431 -67.709218) (xy 443.62497 -67.709796) (xy 443.699646 -67.709796) (xy 443.710194 -67.709253)
			(xy 443.72949 -67.700728) (xy 443.736984 -67.693286) (xy 443.755152 -67.674243) (xy 443.795779 -67.640785)
			(xy 443.840617 -67.613225) (xy 443.888815 -67.592084) (xy 443.93946 -67.577764) (xy 443.991593 -67.570536)
			(xy 444.017908 -67.570096) (xy 444.045278 -67.570558) (xy 444.099458 -67.578377) (xy 444.151961 -67.593867)
			(xy 444.201707 -67.61671) (xy 444.247674 -67.646435) (xy 444.268606 -67.664076) (xy 444.26886 -67.66433)
			(xy 444.275951 -67.669909) (xy 444.292865 -67.676159) (xy 444.30188 -67.676522) (xy 444.368936 -67.676522)
			(xy 444.377954 -67.676178) (xy 444.394871 -67.669921) (xy 444.401956 -67.66433) (xy 444.401956 -67.664076)
			(xy 444.40221 -67.664076) (xy 444.423124 -67.646415) (xy 444.469102 -67.616707) (xy 444.518854 -67.593876)
			(xy 444.571359 -67.57839) (xy 444.625538 -67.570567) (xy 444.652908 -67.570096) (xy 444.68016 -67.57057)
			(xy 444.734108 -67.578328) (xy 444.786403 -67.593684) (xy 444.835981 -67.616327) (xy 444.881831 -67.645794)
			(xy 444.923022 -67.681487) (xy 444.958713 -67.722678) (xy 444.988179 -67.76853) (xy 445.01082 -67.818108)
			(xy 445.026174 -67.870404) (xy 445.03393 -67.924352) (xy 445.034416 -67.951604) (xy 445.033973 -67.978975)
			(xy 445.026153 -68.033156) (xy 445.010659 -68.08566) (xy 444.987812 -68.135407) (xy 444.958081 -68.181372)
			(xy 444.940436 -68.202302) (xy 444.940182 -68.202556) (xy 444.934606 -68.20965) (xy 444.928353 -68.226561)
			(xy 444.92799 -68.235576) (xy 444.92799 -68.302632) (xy 444.928334 -68.31165) (xy 444.934591 -68.328567)
			(xy 444.940182 -68.335652) (xy 444.940436 -68.335652) (xy 444.940436 -68.335906) (xy 444.958097 -68.35682)
			(xy 444.987804 -68.402799) (xy 445.010635 -68.452551) (xy 445.026121 -68.505055) (xy 445.033945 -68.559234)
			(xy 445.034416 -68.586604) (xy 445.033926 -68.613855) (xy 445.026169 -68.667802) (xy 445.010814 -68.720096)
			(xy 444.994175 -68.75653) (xy 448.470274 -68.75653) (xy 448.47074 -68.72916) (xy 448.478555 -68.67498)
			(xy 448.494043 -68.622476) (xy 448.516885 -68.572729) (xy 448.546612 -68.526763) (xy 448.564254 -68.505832)
			(xy 448.564508 -68.505578) (xy 448.570111 -68.498503) (xy 448.576347 -68.481577) (xy 448.5767 -68.472558)
			(xy 448.5767 -68.405502) (xy 448.576342 -68.396485) (xy 448.570095 -68.379568) (xy 448.564508 -68.372482)
			(xy 448.564254 -68.372482) (xy 448.564254 -68.372228) (xy 448.546623 -68.351289) (xy 448.516908 -68.305319)
			(xy 448.49407 -68.255573) (xy 448.478577 -68.203074) (xy 448.470748 -68.148899) (xy 448.470274 -68.12153)
			(xy 448.470783 -68.094279) (xy 448.478536 -68.04033) (xy 448.493887 -67.988034) (xy 448.516525 -67.938456)
			(xy 448.545988 -67.892603) (xy 448.581677 -67.851411) (xy 448.622865 -67.815717) (xy 448.668713 -67.786248)
			(xy 448.718289 -67.763604) (xy 448.770583 -67.748246) (xy 448.824531 -67.740487) (xy 448.851782 -67.740022)
			(xy 448.879152 -67.740493) (xy 448.933331 -67.748309) (xy 448.985834 -67.763797) (xy 449.035581 -67.786637)
			(xy 449.081548 -67.816361) (xy 449.10248 -67.834002) (xy 449.102734 -67.834256) (xy 449.10983 -67.839828)
			(xy 449.12674 -67.846082) (xy 449.135754 -67.846448) (xy 449.20281 -67.846448) (xy 449.211829 -67.846107)
			(xy 449.228746 -67.839849) (xy 449.23583 -67.834256) (xy 449.23583 -67.834002) (xy 449.236084 -67.834002)
			(xy 449.257012 -67.816357) (xy 449.302986 -67.786646) (xy 449.352734 -67.763811) (xy 449.405236 -67.748322)
			(xy 449.459413 -67.740495) (xy 449.486782 -67.740022) (xy 449.513096 -67.740494) (xy 449.565224 -67.747727)
			(xy 449.615867 -67.762045) (xy 449.664067 -67.783176) (xy 449.70891 -67.810722) (xy 449.74955 -67.84416)
			(xy 449.767706 -67.863212) (xy 449.775222 -67.87062) (xy 449.794506 -67.879141) (xy 449.805044 -67.879722)
			(xy 449.87972 -67.879722) (xy 449.890265 -67.879157) (xy 449.909561 -67.870646) (xy 449.917058 -67.863212)
			(xy 449.935195 -67.844138) (xy 449.975828 -67.810682) (xy 450.020672 -67.783125) (xy 450.068877 -67.76199)
			(xy 450.119528 -67.747677) (xy 450.171665 -67.740457) (xy 450.197982 -67.740022) (xy 450.225236 -67.740472)
			(xy 450.279189 -67.748227) (xy 450.331489 -67.763583) (xy 450.381071 -67.786225) (xy 450.426925 -67.815694)
			(xy 450.468119 -67.851389) (xy 450.503813 -67.892584) (xy 450.53328 -67.93844) (xy 450.555921 -67.988023)
			(xy 450.571275 -68.040323) (xy 450.579029 -68.094276) (xy 450.57949 -68.12153) (xy 450.579044 -68.148901)
			(xy 450.571222 -68.203081) (xy 450.555728 -68.255584) (xy 450.532882 -68.305331) (xy 450.503153 -68.351297)
			(xy 450.48551 -68.372228) (xy 450.485256 -68.372482) (xy 450.479666 -68.379566) (xy 450.473422 -68.396485)
			(xy 450.473064 -68.405502) (xy 450.473064 -68.472558) (xy 450.473449 -68.481572) (xy 450.479678 -68.498489)
			(xy 450.485256 -68.505578) (xy 450.48551 -68.505578) (xy 450.48551 -68.505832) (xy 450.503132 -68.526778)
			(xy 450.532846 -68.572747) (xy 450.555685 -68.622491) (xy 450.57118 -68.674989) (xy 450.579013 -68.729162)
			(xy 450.57949 -68.75653) (xy 450.57905 -68.783783) (xy 450.571289 -68.837733) (xy 450.555929 -68.89003)
			(xy 450.533283 -68.939608) (xy 450.503812 -68.985459) (xy 450.468116 -69.02665) (xy 450.426921 -69.062341)
			(xy 450.381066 -69.091806) (xy 450.331485 -69.114446) (xy 450.279186 -69.129799) (xy 450.225235 -69.137553)
			(xy 450.197982 -69.138038) (xy 450.171667 -69.137602) (xy 450.119536 -69.130364) (xy 450.068892 -69.11604)
			(xy 450.020693 -69.094902) (xy 449.97585 -69.067349) (xy 449.935213 -69.033903) (xy 449.917058 -69.014848)
			(xy 449.909547 -69.007433) (xy 449.890259 -68.998915) (xy 449.87972 -68.998338) (xy 449.805044 -68.998338)
			(xy 449.794494 -68.998866) (xy 449.775198 -69.007401) (xy 449.767706 -69.014848) (xy 449.74955 -69.033903)
			(xy 449.708919 -69.067358) (xy 449.664079 -69.094916) (xy 449.615878 -69.116054) (xy 449.565231 -69.130372)
			(xy 449.513098 -69.137598) (xy 449.486782 -69.138038) (xy 449.459411 -69.137598) (xy 449.40523 -69.129776)
			(xy 449.352726 -69.114282) (xy 449.302979 -69.091434) (xy 449.257014 -69.061703) (xy 449.236084 -69.044058)
			(xy 449.23583 -69.043804) (xy 449.228739 -69.038224) (xy 449.211826 -69.031973) (xy 449.20281 -69.031612)
			(xy 449.135754 -69.031612) (xy 449.126739 -69.031992) (xy 449.109822 -69.038224) (xy 449.102734 -69.043804)
			(xy 449.102734 -69.044058) (xy 449.10248 -69.044058) (xy 449.081523 -69.061667) (xy 449.035558 -69.091384)
			(xy 448.985817 -69.114227) (xy 448.933321 -69.129725) (xy 448.87915 -69.13756) (xy 448.851782 -69.138038)
			(xy 448.824532 -69.137539) (xy 448.770586 -69.129781) (xy 448.718293 -69.114425) (xy 448.668718 -69.091784)
			(xy 448.622869 -69.062319) (xy 448.58168 -69.026629) (xy 448.545989 -68.98544) (xy 448.516522 -68.939593)
			(xy 448.493879 -68.890018) (xy 448.478522 -68.837726) (xy 448.470762 -68.78378) (xy 448.470274 -68.75653)
			(xy 444.994175 -68.75653) (xy 444.988173 -68.769673) (xy 444.958707 -68.815523) (xy 444.923016 -68.856713)
			(xy 444.881826 -68.892404) (xy 444.835977 -68.921871) (xy 444.7864 -68.944512) (xy 444.734106 -68.959868)
			(xy 444.680159 -68.967626) (xy 444.652908 -68.968112) (xy 444.625538 -68.967638) (xy 444.571359 -68.959822)
			(xy 444.518857 -68.944334) (xy 444.46911 -68.921494) (xy 444.423142 -68.891772) (xy 444.40221 -68.874132)
			(xy 444.401956 -68.873878) (xy 444.394859 -68.868306) (xy 444.37795 -68.862051) (xy 444.368936 -68.861686)
			(xy 444.30188 -68.861686) (xy 444.292863 -68.862037) (xy 444.275946 -68.868289) (xy 444.26886 -68.873878)
			(xy 444.26886 -68.874132) (xy 444.268606 -68.874132) (xy 444.247687 -68.891787) (xy 444.20171 -68.921495)
			(xy 444.151959 -68.944328) (xy 444.099456 -68.959815) (xy 444.045278 -68.96764) (xy 444.017908 -68.968112)
			(xy 443.991594 -68.967635) (xy 443.939466 -68.960402) (xy 443.888824 -68.946084) (xy 443.840625 -68.924954)
			(xy 443.795781 -68.897409) (xy 443.755141 -68.863973) (xy 443.736984 -68.844922) (xy 443.729467 -68.837515)
			(xy 443.710184 -68.828993) (xy 443.699646 -68.828412) (xy 443.62497 -68.828412) (xy 443.614423 -68.828962)
			(xy 443.595127 -68.837482) (xy 443.587632 -68.844922) (xy 443.569507 -68.864008) (xy 443.52887 -68.897461)
			(xy 443.484023 -68.925016) (xy 443.435817 -68.946149) (xy 443.385164 -68.96046) (xy 443.333026 -68.967677)
			(xy 443.306708 -68.968112) (xy 443.279456 -68.967637) (xy 443.225505 -68.959881) (xy 443.173208 -68.944527)
			(xy 443.123628 -68.921885) (xy 443.077775 -68.892419) (xy 443.036582 -68.856726) (xy 443.000889 -68.815535)
			(xy 442.97142 -68.769683) (xy 442.948778 -68.720103) (xy 442.933421 -68.667807) (xy 442.925664 -68.613856)
			(xy 442.9252 -68.586604) (xy 439.119264 -68.586604) (xy 439.119264 -68.896992) (xy 439.119518 -68.908676)
			(xy 439.118974 -68.935468) (xy 439.110374 -68.988358) (xy 439.093409 -69.039185) (xy 439.068517 -69.086637)
			(xy 439.036342 -69.129486) (xy 439.01741 -69.148452) (xy 439.015124 -69.150738) (xy 439.011314 -69.159882)
			(xy 439.00954 -69.16451) (xy 439.007618 -69.174231) (xy 439.007504 -69.179186) (xy 439.007504 -69.808598)
			(xy 439.007009 -69.833888) (xy 438.999101 -69.883846) (xy 438.983479 -69.931954) (xy 438.960527 -69.977027)
			(xy 438.93081 -70.017957) (xy 438.91327 -70.036182) (xy 437.393588 -71.555864) (xy 445.494408 -71.555864)
			(xy 445.498479 -71.500242) (xy 445.510605 -71.445805) (xy 445.530528 -71.393714) (xy 445.557824 -71.345079)
			(xy 445.59191 -71.300936) (xy 445.632059 -71.262227) (xy 445.677417 -71.229776) (xy 445.727017 -71.204275)
			(xy 445.779801 -71.186268) (xy 445.834644 -71.176138) (xy 445.890378 -71.174101) (xy 445.945815 -71.180201)
			(xy 445.999772 -71.194307) (xy 446.051101 -71.216119) (xy 446.098707 -71.245173) (xy 446.141575 -71.280848)
			(xy 446.178792 -71.322385) (xy 446.209565 -71.368898) (xy 446.233237 -71.419395) (xy 446.249305 -71.472802)
			(xy 446.257425 -71.527978) (xy 446.257934 -71.555864) (xy 446.257425 -71.58375) (xy 446.251586 -71.623428)
			(xy 447.003422 -71.623428) (xy 447.007493 -71.567806) (xy 447.019619 -71.513369) (xy 447.039542 -71.461278)
			(xy 447.066838 -71.412643) (xy 447.100924 -71.3685) (xy 447.141073 -71.329791) (xy 447.186431 -71.29734)
			(xy 447.236031 -71.271839) (xy 447.288815 -71.253832) (xy 447.343658 -71.243702) (xy 447.399392 -71.241665)
			(xy 447.454829 -71.247765) (xy 447.508786 -71.261871) (xy 447.560115 -71.283683) (xy 447.607721 -71.312737)
			(xy 447.650589 -71.348412) (xy 447.687806 -71.389949) (xy 447.718579 -71.436462) (xy 447.742251 -71.486959)
			(xy 447.758319 -71.540366) (xy 447.766439 -71.595542) (xy 447.766948 -71.623428) (xy 447.766439 -71.651314)
			(xy 447.758319 -71.70649) (xy 447.742251 -71.759897) (xy 447.718579 -71.810394) (xy 447.687806 -71.856907)
			(xy 447.650589 -71.898444) (xy 447.607721 -71.934119) (xy 447.560115 -71.963173) (xy 447.508786 -71.984985)
			(xy 447.454829 -71.999091) (xy 447.399392 -72.005191) (xy 447.343658 -72.003154) (xy 447.288815 -71.993024)
			(xy 447.236031 -71.975017) (xy 447.186431 -71.949516) (xy 447.141073 -71.917065) (xy 447.100924 -71.878356)
			(xy 447.066838 -71.834213) (xy 447.039542 -71.785578) (xy 447.019619 -71.733487) (xy 447.007493 -71.67905)
			(xy 447.003422 -71.623428) (xy 446.251586 -71.623428) (xy 446.249305 -71.638926) (xy 446.233237 -71.692333)
			(xy 446.209565 -71.74283) (xy 446.178792 -71.789343) (xy 446.141575 -71.83088) (xy 446.098707 -71.866555)
			(xy 446.051101 -71.895609) (xy 445.999772 -71.917421) (xy 445.945815 -71.931527) (xy 445.890378 -71.937627)
			(xy 445.834644 -71.93559) (xy 445.779801 -71.92546) (xy 445.727017 -71.907453) (xy 445.677417 -71.881952)
			(xy 445.632059 -71.849501) (xy 445.59191 -71.810792) (xy 445.557824 -71.766649) (xy 445.530528 -71.718014)
			(xy 445.510605 -71.665923) (xy 445.498479 -71.611486) (xy 445.494408 -71.555864) (xy 437.393588 -71.555864)
			(xy 432.020472 -76.92898) (xy 432.003561 -76.945264) (xy 431.965879 -76.973263) (xy 431.924536 -76.995503)
			(xy 431.902616 -77.00391) (xy 431.901346 -77.00391) (xy 431.884582 -77.01026) (xy 431.877978 -77.012038)
			(xy 431.877724 -77.012038) (xy 431.875184 -77.012546) (xy 431.87239 -77.013308) (xy 431.852838 -77.017896)
			(xy 431.81297 -77.02274) (xy 431.792888 -77.02296) (xy 431.777902 -77.02296) (xy 431.767891 -77.023447)
			(xy 431.749392 -77.031105) (xy 431.735228 -77.045257) (xy 431.727555 -77.06375) (xy 431.727102 -77.07376)
			(xy 431.727102 -77.082142) (xy 431.729642 -77.089762) (xy 431.738055 -77.117976) (xy 431.747107 -77.17615)
			(xy 431.747676 -77.205586) (xy 431.747676 -77.206348) (xy 431.747186 -77.233596) (xy 431.739424 -77.287537)
			(xy 431.724065 -77.339824) (xy 431.70142 -77.389393) (xy 431.671952 -77.435235) (xy 431.63626 -77.476417)
			(xy 431.595071 -77.5121) (xy 431.549223 -77.541559) (xy 431.499649 -77.564193) (xy 431.447359 -77.579541)
			(xy 431.393416 -77.587292) (xy 431.366168 -77.587856) (xy 431.33894 -77.58737) (xy 431.285038 -77.579623)
			(xy 431.232785 -77.564291) (xy 431.183242 -77.541686) (xy 431.137417 -77.512267) (xy 431.09624 -77.476631)
			(xy 431.060548 -77.435503) (xy 431.031066 -77.389718) (xy 431.008392 -77.340207) (xy 430.992989 -77.287975)
			(xy 430.985168 -77.234083) (xy 430.98466 -77.206856) (xy 430.98466 -77.205586) (xy 430.98478 -77.190216)
			(xy 430.987198 -77.159571) (xy 430.989486 -77.144372) (xy 430.98974 -77.143102) (xy 430.990502 -77.135736)
			(xy 430.990655 -77.131365) (xy 430.989639 -77.122678) (xy 430.98847 -77.118464) (xy 430.985422 -77.108558)
			(xy 430.978564 -77.10043) (xy 430.970436 -77.090778) (xy 430.970436 -77.09027) (xy 430.92878 -77.040994)
			(xy 430.921193 -77.032851) (xy 430.901034 -77.023483) (xy 430.889918 -77.02296) (xy 430.238662 -77.02296)
			(xy 430.233074 -77.023214) (xy 430.229408 -77.023697) (xy 430.222265 -77.025606) (xy 430.21885 -77.027024)
			(xy 430.210722 -77.03058) (xy 430.203864 -77.037184) (xy 430.200816 -77.039724) (xy 430.19853 -77.041502)
			(xy 428.505366 -78.734666) (xy 428.498456 -78.74231) (xy 428.490872 -78.761447) (xy 428.490634 -78.77175)
			(xy 428.492412 -78.804516) (xy 428.494952 -78.84922) (xy 428.495346 -78.853743) (xy 428.497516 -78.862558)
			(xy 428.49927 -78.866746) (xy 428.50054 -78.869286) (xy 428.50308 -78.874112) (xy 428.505874 -78.879192)
			(xy 428.513748 -78.885796) (xy 428.535373 -78.903985) (xy 428.57353 -78.94566) (xy 428.605109 -78.992516)
			(xy 428.629417 -79.043525) (xy 428.64592 -79.097567) (xy 428.654255 -79.153453) (xy 428.654718 -79.181706)
			(xy 428.654718 -79.189072) (xy 428.653698 -79.217143) (xy 428.64443 -79.272544) (xy 428.627137 -79.325986)
			(xy 428.602192 -79.376313) (xy 428.570134 -79.422437) (xy 428.531659 -79.463361) (xy 428.509938 -79.481172)
			(xy 428.507398 -79.483204) (xy 428.503588 -79.487014) (xy 428.499833 -79.490998) (xy 428.493931 -79.500217)
			(xy 428.491904 -79.505302) (xy 428.488094 -79.515208) (xy 428.488856 -79.526384) (xy 428.494698 -79.613252)
			(xy 428.495458 -79.618252) (xy 428.498656 -79.627846) (xy 428.501048 -79.632302) (xy 428.505112 -79.63789)
			(xy 428.505366 -79.638398) (xy 428.51705 -79.649066) (xy 428.517812 -79.649574) (xy 428.520606 -79.651352)
			(xy 428.522384 -79.652114) (xy 428.546675 -79.666933) (xy 428.590984 -79.70263) (xy 428.629514 -79.744499)
			(xy 428.661412 -79.791617) (xy 428.685975 -79.842942) (xy 428.70266 -79.89734) (xy 428.711099 -79.95361)
			(xy 428.711614 -79.98206) (xy 428.711153 -80.009315) (xy 428.703401 -80.06327) (xy 428.688049 -80.115573)
			(xy 428.665408 -80.165159) (xy 428.635942 -80.211018) (xy 428.600248 -80.252215) (xy 428.559054 -80.287914)
			(xy 428.513199 -80.317386) (xy 428.463617 -80.340032) (xy 428.411315 -80.355391) (xy 428.357361 -80.36315)
			(xy 428.330106 -80.363568) (xy 428.329344 -80.363568) (xy 428.306965 -80.363188) (xy 428.262527 -80.357844)
			(xy 428.240698 -80.3529) (xy 428.238412 -80.352392) (xy 428.227744 -80.349852) (xy 428.214282 -80.352138)
			(xy 428.209378 -80.353419) (xy 428.200164 -80.357639) (xy 428.195994 -80.36052) (xy 428.167038 -80.378808)
			(xy 428.16653 -80.378808) (xy 428.137066 -80.39735) (xy 428.13277 -80.400213) (xy 428.125345 -80.407381)
			(xy 428.122334 -80.411574) (xy 428.116492 -80.419956) (xy 428.114714 -80.428084) (xy 428.114206 -80.43037)
			(xy 428.114206 -80.430624) (xy 428.111724 -80.441861) (xy 428.105368 -80.46398) (xy 428.101506 -80.47482)
			(xy 428.101252 -80.475328) (xy 428.096172 -80.488028) (xy 428.083852 -80.51568) (xy 428.050479 -80.566177)
			(xy 428.029878 -80.588358) (xy 428.02937 -80.588866) (xy 428.029116 -80.58912) (xy 428.027338 -80.590898)
			(xy 427.467268 -81.150968) (xy 427.450357 -81.167252) (xy 427.412675 -81.195252) (xy 427.371332 -81.217492)
			(xy 427.349412 -81.225898) (xy 427.348142 -81.225898) (xy 427.331378 -81.232248) (xy 427.324774 -81.234026)
			(xy 427.32452 -81.234026) (xy 427.32198 -81.234534) (xy 427.319186 -81.235296) (xy 427.299634 -81.239884)
			(xy 427.259766 -81.244728) (xy 427.239684 -81.244948) (xy 426.146214 -81.244948) (xy 426.140626 -81.245202)
			(xy 426.136961 -81.245689) (xy 426.12982 -81.247603) (xy 426.126402 -81.249012) (xy 426.118274 -81.252568)
			(xy 426.111416 -81.259172) (xy 426.108368 -81.261712) (xy 426.106082 -81.26349) (xy 424.955208 -82.414364)
			(xy 425.781722 -82.414364) (xy 425.785793 -82.358742) (xy 425.797919 -82.304305) (xy 425.817842 -82.252214)
			(xy 425.845138 -82.203579) (xy 425.879224 -82.159436) (xy 425.919373 -82.120727) (xy 425.964731 -82.088276)
			(xy 426.014331 -82.062775) (xy 426.067115 -82.044768) (xy 426.121958 -82.034638) (xy 426.177692 -82.032601)
			(xy 426.233129 -82.038701) (xy 426.287086 -82.052807) (xy 426.338415 -82.074619) (xy 426.386021 -82.103673)
			(xy 426.428889 -82.139348) (xy 426.466106 -82.180885) (xy 426.496879 -82.227398) (xy 426.520551 -82.277895)
			(xy 426.536619 -82.331302) (xy 426.544739 -82.386478) (xy 426.545248 -82.414364) (xy 426.545007 -82.427572)
			(xy 427.232824 -82.427572) (xy 427.236895 -82.37195) (xy 427.249021 -82.317513) (xy 427.268944 -82.265422)
			(xy 427.29624 -82.216787) (xy 427.330326 -82.172644) (xy 427.370475 -82.133935) (xy 427.415833 -82.101484)
			(xy 427.465433 -82.075983) (xy 427.518217 -82.057976) (xy 427.57306 -82.047846) (xy 427.628794 -82.045809)
			(xy 427.684231 -82.051909) (xy 427.738188 -82.066015) (xy 427.789517 -82.087827) (xy 427.837123 -82.116881)
			(xy 427.879991 -82.152556) (xy 427.917208 -82.194093) (xy 427.947981 -82.240606) (xy 427.971653 -82.291103)
			(xy 427.987721 -82.34451) (xy 427.995841 -82.399686) (xy 427.99635 -82.427572) (xy 427.995841 -82.455458)
			(xy 427.987721 -82.510634) (xy 427.971653 -82.564041) (xy 427.947981 -82.614538) (xy 427.917208 -82.661051)
			(xy 427.879991 -82.702588) (xy 427.837123 -82.738263) (xy 427.789517 -82.767317) (xy 427.738188 -82.789129)
			(xy 427.684231 -82.803235) (xy 427.628794 -82.809335) (xy 427.57306 -82.807298) (xy 427.518217 -82.797168)
			(xy 427.465433 -82.779161) (xy 427.415833 -82.75366) (xy 427.370475 -82.721209) (xy 427.330326 -82.6825)
			(xy 427.29624 -82.638357) (xy 427.268944 -82.589722) (xy 427.249021 -82.537631) (xy 427.236895 -82.483194)
			(xy 427.232824 -82.427572) (xy 426.545007 -82.427572) (xy 426.544739 -82.44225) (xy 426.536619 -82.497426)
			(xy 426.520551 -82.550833) (xy 426.496879 -82.60133) (xy 426.466106 -82.647843) (xy 426.428889 -82.68938)
			(xy 426.386021 -82.725055) (xy 426.338415 -82.754109) (xy 426.287086 -82.775921) (xy 426.233129 -82.790027)
			(xy 426.177692 -82.796127) (xy 426.121958 -82.79409) (xy 426.067115 -82.78396) (xy 426.014331 -82.765953)
			(xy 425.964731 -82.740452) (xy 425.919373 -82.708001) (xy 425.879224 -82.669292) (xy 425.845138 -82.625149)
			(xy 425.817842 -82.576514) (xy 425.797919 -82.524423) (xy 425.785793 -82.469986) (xy 425.781722 -82.414364)
			(xy 424.955208 -82.414364) (xy 423.837354 -83.532218) (xy 424.611544 -83.532218) (xy 424.615615 -83.476596)
			(xy 424.627741 -83.422159) (xy 424.647664 -83.370068) (xy 424.67496 -83.321433) (xy 424.709046 -83.27729)
			(xy 424.749195 -83.238581) (xy 424.794553 -83.20613) (xy 424.844153 -83.180629) (xy 424.896937 -83.162622)
			(xy 424.95178 -83.152492) (xy 425.007514 -83.150455) (xy 425.062951 -83.156555) (xy 425.116908 -83.170661)
			(xy 425.168237 -83.192473) (xy 425.215843 -83.221527) (xy 425.258711 -83.257202) (xy 425.295928 -83.298739)
			(xy 425.326701 -83.345252) (xy 425.350373 -83.395749) (xy 425.366441 -83.449156) (xy 425.374561 -83.504332)
			(xy 425.37507 -83.532218) (xy 425.374561 -83.560104) (xy 425.366441 -83.61528) (xy 425.350373 -83.668687)
			(xy 425.326701 -83.719184) (xy 425.295928 -83.765697) (xy 425.258711 -83.807234) (xy 425.215843 -83.842909)
			(xy 425.168237 -83.871963) (xy 425.116908 -83.893775) (xy 425.062951 -83.907881) (xy 425.007514 -83.913981)
			(xy 424.95178 -83.911944) (xy 424.896937 -83.901814) (xy 424.844153 -83.883807) (xy 424.794553 -83.858306)
			(xy 424.749195 -83.825855) (xy 424.709046 -83.787146) (xy 424.67496 -83.743003) (xy 424.647664 -83.694368)
			(xy 424.627741 -83.642277) (xy 424.615615 -83.58784) (xy 424.611544 -83.532218) (xy 423.837354 -83.532218)
			(xy 423.643298 -83.726274) (xy 423.640592 -83.729125) (xy 423.636 -83.735504) (xy 423.634154 -83.738974)
			(xy 423.631572 -83.744401) (xy 423.628752 -83.756081) (xy 423.628566 -83.762088) (xy 423.628566 -84.452968)
			(xy 423.629177 -84.464819) (xy 423.63976 -84.486026) (xy 423.648886 -84.493608) (xy 426.127164 -84.493608)
			(xy 426.132244 -84.48929) (xy 426.55236 -84.069174) (xy 426.575501 -84.046678) (xy 426.625964 -84.006442)
			(xy 426.680615 -83.972109) (xy 426.738766 -83.94411) (xy 426.799686 -83.922797) (xy 426.862609 -83.908439)
			(xy 426.926744 -83.901215) (xy 426.959014 -83.900772) (xy 428.238158 -83.900772) (xy 428.24273 -83.90001)
			(xy 428.268543 -83.895632) (xy 428.320691 -83.89093) (xy 428.34687 -83.890612) (xy 428.347632 -83.890612)
			(xy 428.383029 -83.891127) (xy 428.453305 -83.899664) (xy 428.522041 -83.91661) (xy 428.588232 -83.941717)
			(xy 428.650915 -83.97462) (xy 428.709175 -84.014839) (xy 428.762162 -84.061787) (xy 428.809103 -84.114779)
			(xy 428.849315 -84.173043) (xy 428.882211 -84.23573) (xy 428.90731 -84.301924) (xy 428.924248 -84.370661)
			(xy 428.932777 -84.440939) (xy 428.933356 -84.476336) (xy 428.933356 -84.47659) (xy 428.932896 -84.509444)
			(xy 428.925541 -84.574739) (xy 428.910923 -84.638801) (xy 428.889224 -84.700823) (xy 428.860719 -84.760026)
			(xy 428.825765 -84.815666) (xy 428.784802 -84.867043) (xy 428.761906 -84.89061) (xy 428.15891 -85.493606)
			(xy 428.136546 -85.515404) (xy 428.087926 -85.554603) (xy 428.061882 -85.571838) (xy 428.054026 -85.577399)
			(xy 428.042836 -85.59304) (xy 428.038178 -85.6117) (xy 428.040704 -85.630765) (xy 428.050061 -85.647568)
			(xy 428.064938 -85.659756) (xy 428.083253 -85.665623) (xy 428.09287 -85.66531) (xy 428.116492 -85.664548)
			(xy 428.636176 -85.664548) (xy 428.640789 -85.664451) (xy 428.649865 -85.662799) (xy 428.65421 -85.661246)
			(xy 428.659138 -85.65922) (xy 428.668094 -85.653452) (xy 428.67199 -85.649816) (xy 437.62549 -76.696062)
			(xy 437.626506 -76.695046) (xy 437.640034 -76.681917) (xy 437.669568 -76.65849) (xy 437.685434 -76.64831)
			(xy 437.690514 -76.645262) (xy 437.839866 -76.49591) (xy 437.847268 -76.489073) (xy 437.865866 -76.481361)
			(xy 437.875934 -76.480924) (xy 452.835772 -76.480924) (xy 452.845424 -76.479908) (xy 452.852671 -76.478285)
			(xy 452.865849 -76.471453) (xy 452.871332 -76.466446) (xy 453.948292 -75.389486) (xy 453.953281 -75.383988)
			(xy 453.960129 -75.370822) (xy 453.961754 -75.363578) (xy 453.96277 -75.353926) (xy 453.96277 -73.295256)
			(xy 453.96277 -73.294748) (xy 453.964548 -73.281032) (xy 453.96658 -73.274428) (xy 453.96658 -67.15125)
			(xy 453.9615 -67.146424) (xy 453.959976 -67.144646) (xy 453.958198 -67.14236) (xy 453.349106 -66.533268)
			(xy 453.346256 -66.53056) (xy 453.339879 -66.525964) (xy 453.336406 -66.524124) (xy 453.330978 -66.521545)
			(xy 453.319299 -66.518732) (xy 453.313292 -66.518536) (xy 447.910458 -66.518536) (xy 447.883005 -66.51811)
			(xy 447.828857 -66.509041) (xy 447.802762 -66.500502) (xy 447.802508 -66.500248) (xy 447.801746 -66.499994)
			(xy 447.799968 -66.499232) (xy 447.797428 -66.498216) (xy 447.79692 -66.497962) (xy 447.778886 -66.490596)
			(xy 447.683382 -66.424048) (xy 447.676524 -66.418206) (xy 447.228214 -65.969642) (xy 447.224404 -65.967356)
			(xy 447.22288 -65.96634) (xy 447.207173 -65.956319) (xy 447.177891 -65.933279) (xy 447.16446 -65.920366)
			(xy 447.163444 -65.91935) (xy 446.717674 -65.47358) (xy 446.707006 -65.46723) (xy 446.701164 -65.465452)
			(xy 446.67373 -65.456331) (xy 446.62177 -65.430984) (xy 446.574224 -65.398098) (xy 446.532175 -65.358423)
			(xy 446.496585 -65.312864) (xy 446.468266 -65.262464) (xy 446.447865 -65.208371) (xy 446.441322 -65.18021)
			(xy 446.435657 -65.150847) (xy 446.43246 -65.091136) (xy 446.434972 -65.061338) (xy 446.435988 -65.05067)
			(xy 446.43294 -65.040764) (xy 446.431505 -65.036605) (xy 446.427419 -65.028814) (xy 446.424812 -65.02527)
			(xy 446.378584 -64.9732) (xy 446.370964 -64.964564) (xy 446.366686 -64.960348) (xy 446.356538 -64.95393)
			(xy 446.350898 -64.951864) (xy 446.34023 -64.948816) (xy 445.815212 -64.948816) (xy 445.811606 -64.948878)
			(xy 445.804466 -64.949895) (xy 445.800988 -64.950848) (xy 445.796416 -64.952372) (xy 445.787272 -64.956182)
			(xy 444.76035 -65.983104) (xy 444.743479 -65.999377) (xy 444.705882 -66.027371) (xy 444.664629 -66.049628)
			(xy 444.642748 -66.058034) (xy 444.63208 -66.06159) (xy 444.62446 -66.064384) (xy 444.617348 -66.066416)
			(xy 444.61557 -66.06667) (xy 444.612522 -66.067432) (xy 444.611252 -66.067686) (xy 444.59201 -66.0722)
			(xy 444.552783 -66.077044) (xy 444.53302 -66.077338) (xy 444.527178 -66.077338) (xy 444.524892 -66.077084)
			(xy 444.51143 -66.077084) (xy 444.505588 -66.078354) (xy 444.486811 -66.082503) (xy 444.448615 -66.086964)
			(xy 444.429388 -66.087244) (xy 441.217812 -66.087244) (xy 441.213494 -66.08953) (xy 441.185068 -66.104444)
			(xy 441.124467 -66.125602) (xy 441.061184 -66.136347) (xy 441.02909 -66.137028) (xy 441.028582 -66.137028)
			(xy 441.00133 -66.136541) (xy 440.947382 -66.128782) (xy 440.895086 -66.113424) (xy 440.845509 -66.090781)
			(xy 440.799658 -66.061313) (xy 440.758468 -66.025619) (xy 440.722776 -65.984427) (xy 440.69331 -65.938576)
			(xy 440.670669 -65.888997) (xy 440.655314 -65.836701) (xy 440.647558 -65.782752) (xy 440.647558 -65.728248)
			(xy 440.655314 -65.674299) (xy 440.670669 -65.622003) (xy 440.69331 -65.572424) (xy 440.722776 -65.526573)
			(xy 440.758468 -65.485381) (xy 440.799658 -65.449687) (xy 440.845509 -65.420219) (xy 440.895086 -65.397576)
			(xy 440.947382 -65.382218) (xy 441.00133 -65.374459) (xy 441.028582 -65.374012) (xy 441.028836 -65.374012)
			(xy 441.053083 -65.374408) (xy 441.101185 -65.380578) (xy 441.14812 -65.392778) (xy 441.193138 -65.410812)
			(xy 441.21451 -65.422272) (xy 441.217304 -65.423796) (xy 444.270638 -65.423796) (xy 444.280036 -65.423034)
			(xy 444.287469 -65.421395) (xy 444.300923 -65.414294) (xy 444.306452 -65.409064) (xy 445.41059 -64.304672)
			(xy 445.433958 -64.281304) (xy 445.454286 -64.261813) (xy 445.500253 -64.229282) (xy 445.551051 -64.204978)
			(xy 445.577976 -64.196722) (xy 445.590982 -64.193181) (xy 445.617432 -64.187972) (xy 445.630808 -64.186308)
			(xy 445.63157 -64.186308) (xy 445.639802 -64.185036) (xy 445.654849 -64.177916) (xy 445.661034 -64.172338)
			(xy 446.096644 -63.736474) (xy 446.097406 -63.735458) (xy 446.117567 -63.715281) (xy 446.163642 -63.68167)
			(xy 446.214916 -63.656696) (xy 446.242186 -63.648336) (xy 446.24498 -63.647828) (xy 446.247774 -63.647066)
			(xy 446.267852 -63.642052) (xy 446.308872 -63.636573) (xy 446.329562 -63.636144) (xy 448.468242 -63.636144)
			(xy 448.475394 -63.635764) (xy 448.489066 -63.631515) (xy 448.495166 -63.627762) (xy 448.502024 -63.622936)
			(xy 448.506596 -63.618872) (xy 448.511113 -63.614055) (xy 448.517672 -63.602598) (xy 448.51955 -63.596266)
			(xy 448.523106 -63.583312) (xy 448.527424 -63.572898) (xy 448.531996 -63.56096) (xy 448.533759 -63.556817)
			(xy 448.538484 -63.549155) (xy 448.541394 -63.54572) (xy 448.54241 -63.54445) (xy 448.546716 -63.538999)
			(xy 448.552502 -63.526376) (xy 448.55384 -63.519558) (xy 448.554856 -63.5127) (xy 448.554094 -63.505842)
			(xy 448.553545 -63.502169) (xy 448.551499 -63.495029) (xy 448.55003 -63.491618) (xy 448.541394 -63.472314)
			(xy 448.541394 -63.471806) (xy 448.536822 -63.461392) (xy 448.530218 -63.454534) (xy 448.529964 -63.45428)
			(xy 448.529456 -63.453772) (xy 448.509223 -63.432376) (xy 448.474924 -63.38451) (xy 448.448385 -63.331944)
			(xy 448.430236 -63.275924) (xy 448.420909 -63.217782) (xy 448.420236 -63.188342) (xy 448.420236 -63.180214)
			(xy 448.421236 -63.151261) (xy 448.430907 -63.094143) (xy 448.449101 -63.039144) (xy 448.475402 -62.987528)
			(xy 448.509204 -62.940482) (xy 448.54973 -62.899086) (xy 448.596048 -62.864294) (xy 448.647095 -62.836904)
			(xy 448.701695 -62.817546) (xy 448.758595 -62.806665) (xy 448.78752 -62.805056) (xy 448.787774 -62.805056)
			(xy 448.801744 -62.804802) (xy 448.802252 -62.804802) (xy 448.827879 -62.805229) (xy 448.878667 -62.812123)
			(xy 448.928073 -62.825765) (xy 448.975203 -62.845909) (xy 449.019205 -62.872191) (xy 449.039488 -62.88786)
			(xy 449.046092 -62.89294) (xy 449.057268 -62.89675) (xy 449.07073 -62.898782) (xy 449.092574 -62.898782)
			(xy 449.098015 -62.898919) (xy 449.108652 -62.901215) (xy 449.113656 -62.903354) (xy 449.127372 -62.909704)
			(xy 449.132076 -62.911769) (xy 449.142057 -62.914202) (xy 449.147184 -62.91453) (xy 449.15582 -62.914022)
			(xy 449.163104 -62.912734) (xy 449.176522 -62.906528) (xy 449.182236 -62.90183) (xy 449.18249 -62.901576)
			(xy 449.202377 -62.884469) (xy 449.245965 -62.85528) (xy 449.269358 -62.84341) (xy 449.28409 -62.836552)
			(xy 449.288662 -62.83452) (xy 449.311998 -62.825167) (xy 449.360512 -62.811973) (xy 449.410337 -62.805257)
			(xy 449.435474 -62.804802) (xy 449.442078 -62.804802) (xy 449.471842 -62.805789) (xy 449.530531 -62.815866)
			(xy 449.558918 -62.824868) (xy 449.589905 -62.836091) (xy 449.647768 -62.86763) (xy 449.67398 -62.887606)
			(xy 449.674234 -62.88786) (xy 449.677282 -62.8904) (xy 449.683392 -62.894131) (xy 449.697057 -62.898383)
			(xy 449.704206 -62.898782) (xy 449.727574 -62.898782) (xy 449.733015 -62.898919) (xy 449.743652 -62.901215)
			(xy 449.748656 -62.903354) (xy 449.762372 -62.909704) (xy 449.767076 -62.911769) (xy 449.777057 -62.914202)
			(xy 449.782184 -62.91453) (xy 449.79082 -62.914022) (xy 449.798104 -62.912734) (xy 449.811522 -62.906528)
			(xy 449.817236 -62.90183) (xy 449.81749 -62.901576) (xy 449.83856 -62.883468) (xy 449.884954 -62.852908)
			(xy 449.935287 -62.829394) (xy 449.988497 -62.813424) (xy 450.043459 -62.805334) (xy 450.071236 -62.804802)
			(xy 450.071744 -62.804802) (xy 450.098993 -62.805291) (xy 450.152935 -62.813053) (xy 450.205224 -62.828412)
			(xy 450.254795 -62.851056) (xy 450.300639 -62.880523) (xy 450.341823 -62.916215) (xy 450.377509 -62.957404)
			(xy 450.40697 -63.003252) (xy 450.429607 -63.052827) (xy 450.444959 -63.105118) (xy 450.452713 -63.159061)
			(xy 450.453252 -63.18631) (xy 450.452682 -63.216036) (xy 450.443454 -63.274769) (xy 450.425224 -63.331358)
			(xy 450.398432 -63.384432) (xy 450.363728 -63.432705) (xy 450.34327 -63.45428) (xy 450.343016 -63.454534)
			(xy 450.33692 -63.460884) (xy 450.332856 -63.46952) (xy 450.329046 -63.477648) (xy 450.327014 -63.483744)
			(xy 450.323966 -63.497968) (xy 450.3231 -63.504155) (xy 450.323986 -63.516612) (xy 450.325744 -63.522606)
			(xy 450.344794 -63.569342) (xy 450.344794 -63.56985) (xy 450.360288 -63.606934) (xy 450.367146 -63.617856)
			(xy 450.37475 -63.626112) (xy 450.395051 -63.63562) (xy 450.406262 -63.636144) (xy 451.594982 -63.636144)
			(xy 451.60311 -63.635382) (xy 451.603618 -63.635382) (xy 451.611137 -63.633782) (xy 451.624826 -63.626807)
			(xy 451.630542 -63.621666) (xy 451.707504 -63.544704) (xy 451.712076 -63.53937) (xy 451.712076 -58.161682)
			(xy 451.710806 -58.159904) (xy 451.70852 -58.15711) (xy 451.375018 -57.823608) (xy 451.359858 -57.80794)
			(xy 451.333475 -57.773232) (xy 451.312031 -57.735273) (xy 451.303644 -57.71515) (xy 451.301104 -57.709562)
			(xy 451.296786 -57.701688) (xy 451.280957 -57.679954) (xy 451.255809 -57.632434) (xy 451.238666 -57.581476)
			(xy 451.229977 -57.528418) (xy 451.229476 -57.501536) (xy 451.229476 -56.577992) (xy 451.224865 -56.572295)
			(xy 451.213133 -56.563523) (xy 451.206362 -56.56072) (xy 451.162928 -56.544718) (xy 451.1167 -56.5277)
			(xy 451.10908 -56.525668) (xy 451.103321 -56.524693) (xy 451.091651 -56.525087) (xy 451.085966 -56.52643)
			(xy 451.0786 -56.528462) (xy 451.065392 -56.536844) (xy 451.060312 -56.54294) (xy 451.04208 -56.563797)
			(xy 451.000625 -56.600541) (xy 450.954294 -56.630907) (xy 450.90406 -56.654256) (xy 450.850978 -56.670099)
			(xy 450.796164 -56.678102) (xy 450.768466 -56.678576) (xy 450.741219 -56.678087) (xy 450.687279 -56.670328)
			(xy 450.634993 -56.654971) (xy 450.585424 -56.63233) (xy 450.539582 -56.602865) (xy 450.498399 -56.567177)
			(xy 450.462715 -56.525991) (xy 450.433254 -56.480146) (xy 450.410617 -56.430575) (xy 450.395265 -56.378288)
			(xy 450.38751 -56.324347) (xy 450.38751 -56.269853) (xy 450.395265 -56.215912) (xy 450.410617 -56.163625)
			(xy 450.433254 -56.114054) (xy 450.462715 -56.068209) (xy 450.498399 -56.027023) (xy 450.539582 -55.991335)
			(xy 450.585424 -55.96187) (xy 450.634993 -55.939229) (xy 450.687279 -55.923872) (xy 450.741219 -55.916113)
			(xy 450.768466 -55.91556) (xy 450.795444 -55.916022) (xy 450.848864 -55.923609) (xy 450.900685 -55.938636)
			(xy 450.949876 -55.960806) (xy 450.995458 -55.989675) (xy 451.036526 -56.024672) (xy 451.054724 -56.044592)
			(xy 451.060566 -56.051196) (xy 451.073774 -56.060086) (xy 451.080378 -56.063388) (xy 451.080886 -56.063896)
			(xy 451.089813 -56.067457) (xy 451.108996 -56.068363) (xy 451.118224 -56.065674) (xy 451.118986 -56.06542)
			(xy 451.206362 -56.033416) (xy 451.213142 -56.030718) (xy 451.224892 -56.022075) (xy 451.229476 -56.016398)
			(xy 451.229476 -55.11292) (xy 451.230006 -55.086897) (xy 451.238177 -55.035497) (xy 451.254276 -54.986003)
			(xy 451.277906 -54.939631) (xy 451.308489 -54.897518) (xy 451.326504 -54.878732) (xy 453.250554 -52.954682)
			(xy 453.256904 -52.944014) (xy 453.258682 -52.938172) (xy 453.268176 -52.909708) (xy 453.294778 -52.855928)
			(xy 453.329462 -52.806969) (xy 453.371375 -52.764036) (xy 453.39508 -52.74564) (xy 453.419326 -52.728279)
			(xy 453.47209 -52.7005) (xy 453.52853 -52.681257) (xy 453.587275 -52.671017) (xy 453.617076 -52.669948)
			(xy 453.622918 -52.669694) (xy 453.65416 -52.655978) (xy 453.655176 -52.655216) (xy 453.720708 -52.589684)
			(xy 453.727405 -52.582243) (xy 453.735007 -52.563745) (xy 453.734985 -52.543745) (xy 453.73163 -52.534312)
			(xy 453.731122 -52.533296) (xy 453.703436 -52.470812) (xy 453.703436 -52.470304) (xy 453.695562 -52.453286)
			(xy 453.694546 -52.450746) (xy 453.68972 -52.441856) (xy 453.684964 -52.434404) (xy 453.671439 -52.42304)
			(xy 453.654862 -52.416938) (xy 453.646032 -52.416456) (xy 453.641714 -52.416456) (xy 453.623172 -52.416964)
			(xy 453.595925 -52.416476) (xy 453.541986 -52.408717) (xy 453.489701 -52.393361) (xy 453.440132 -52.370721)
			(xy 453.394291 -52.341257) (xy 453.353109 -52.305569) (xy 453.317424 -52.264384) (xy 453.287964 -52.218539)
			(xy 453.265328 -52.168969) (xy 453.249976 -52.116682) (xy 453.242222 -52.062743) (xy 453.242222 -52.008249)
			(xy 453.249978 -51.95431) (xy 453.265331 -51.902023) (xy 453.287968 -51.852454) (xy 453.317429 -51.80661)
			(xy 453.353114 -51.765426) (xy 453.394297 -51.729739) (xy 453.44014 -51.700276) (xy 453.489708 -51.677636)
			(xy 453.541994 -51.662281) (xy 453.595933 -51.654524) (xy 453.650427 -51.654521) (xy 453.704367 -51.662273)
			(xy 453.756654 -51.677622) (xy 453.806225 -51.700256) (xy 453.852071 -51.729715) (xy 453.893257 -51.765397)
			(xy 453.928947 -51.806578) (xy 453.958413 -51.852418) (xy 453.981055 -51.901986) (xy 453.996414 -51.954271)
			(xy 454.004175 -52.008209) (xy 454.00468 -52.035456) (xy 454.00468 -52.035964) (xy 454.003986 -52.069367)
			(xy 453.992356 -52.135154) (xy 453.981566 -52.166774) (xy 453.980042 -52.170838) (xy 453.978264 -52.17922)
			(xy 453.976961 -52.187625) (xy 453.979348 -52.204455) (xy 453.987078 -52.219594) (xy 453.992996 -52.225702)
			(xy 453.998584 -52.23002) (xy 454.002394 -52.232814) (xy 454.0123 -52.239926) (xy 454.020229 -52.244806)
			(xy 454.038338 -52.249059) (xy 454.056772 -52.246564) (xy 454.065132 -52.242466) (xy 454.072244 -52.238148)
			(xy 454.095866 -52.214526) (xy 454.100839 -52.209092) (xy 454.107669 -52.19605) (xy 454.109328 -52.188872)
			(xy 454.109328 -52.188364) (xy 454.110344 -52.178966) (xy 454.110344 -50.309018) (xy 454.110173 -50.303009)
			(xy 454.107345 -50.291329) (xy 454.104756 -50.285904) (xy 454.102916 -50.28243) (xy 454.098322 -50.276052)
			(xy 454.095612 -50.273204) (xy 454.01484 -50.192432) (xy 454.006458 -50.191924) (xy 453.933052 -50.193702)
			(xy 453.928898 -50.193865) (xy 453.920729 -50.195404) (xy 453.916796 -50.19675) (xy 453.91324 -50.198274)
			(xy 453.903842 -50.202592) (xy 453.89673 -50.210212) (xy 453.878609 -50.229418) (xy 453.837983 -50.263147)
			(xy 453.793088 -50.29094) (xy 453.744783 -50.312266) (xy 453.693996 -50.326714) (xy 453.641699 -50.334008)
			(xy 453.615298 -50.334418) (xy 453.615044 -50.334418) (xy 453.587789 -50.333958) (xy 453.533833 -50.326206)
			(xy 453.481529 -50.310854) (xy 453.431942 -50.288214) (xy 453.386083 -50.258748) (xy 453.344884 -50.223054)
			(xy 453.309185 -50.18186) (xy 453.279712 -50.136005) (xy 453.257065 -50.086422) (xy 453.241705 -50.03412)
			(xy 453.233946 -49.980165) (xy 453.233536 -49.95291) (xy 453.234091 -49.92336) (xy 453.243209 -49.864968)
			(xy 453.261228 -49.808683) (xy 453.287716 -49.755852) (xy 453.322039 -49.707741) (xy 453.363375 -49.665502)
			(xy 453.386698 -49.647348) (xy 453.39 -49.644808) (xy 453.395842 -49.638712) (xy 453.39635 -49.638204)
			(xy 453.396858 -49.637442) (xy 453.403999 -49.628951) (xy 453.410836 -49.607871) (xy 453.410066 -49.596802)
			(xy 453.40905 -49.589182) (xy 453.408796 -49.586388) (xy 453.173592 -49.351438) (xy 453.150647 -49.327883)
			(xy 453.109629 -49.276483) (xy 453.074628 -49.220811) (xy 453.046083 -49.161569) (xy 453.024356 -49.099502)
			(xy 453.009718 -49.035391) (xy 453.002355 -48.970044) (xy 453.001888 -48.937164) (xy 453.001888 -48.922178)
			(xy 453.002142 -48.916082) (xy 453.00391 -48.880968) (xy 453.014801 -48.811508) (xy 453.033927 -48.74385)
			(xy 453.061013 -48.678968) (xy 453.095671 -48.617795) (xy 453.137401 -48.561209) (xy 453.185605 -48.510025)
			(xy 453.239588 -48.464979) (xy 453.298574 -48.426717) (xy 453.361716 -48.395791) (xy 453.428106 -48.372645)
			(xy 453.496789 -48.357611) (xy 453.531732 -48.353726) (xy 453.541384 -48.352964) (xy 453.55002 -48.348392)
			(xy 453.553965 -48.346287) (xy 453.561122 -48.340926) (xy 453.564244 -48.337724) (xy 453.569324 -48.332136)
			(xy 453.570086 -48.331374) (xy 453.573388 -48.328072) (xy 453.578581 -48.322393) (xy 453.585559 -48.308687)
			(xy 453.587104 -48.301148) (xy 453.587104 -48.30064) (xy 453.587866 -48.292512) (xy 453.587866 -48.184054)
			(xy 453.588299 -48.173989) (xy 453.596033 -48.155403) (xy 453.602852 -48.147986) (xy 453.756014 -47.994824)
			(xy 453.762944 -47.987145) (xy 453.770555 -47.967933) (xy 453.770026 -47.947274) (xy 453.766174 -47.937674)
			(xy 453.734678 -47.869602) (xy 453.730106 -47.85995) (xy 453.725538 -47.85168) (xy 453.71164 -47.838906)
			(xy 453.694075 -47.831993) (xy 453.68464 -47.831502) (xy 453.679814 -47.831502) (xy 453.677528 -47.831756)
			(xy 453.643746 -47.83328) (xy 453.615764 -47.832808) (xy 453.56037 -47.824849) (xy 453.506672 -47.809088)
			(xy 453.455764 -47.785844) (xy 453.408683 -47.755592) (xy 453.366386 -47.718946) (xy 453.329736 -47.676654)
			(xy 453.299478 -47.629576) (xy 453.276228 -47.578671) (xy 453.26046 -47.524975) (xy 453.252495 -47.469582)
			(xy 453.252495 -47.413618) (xy 453.26046 -47.358225) (xy 453.276228 -47.304529) (xy 453.299478 -47.253624)
			(xy 453.329736 -47.206546) (xy 453.366386 -47.164254) (xy 453.408683 -47.127608) (xy 453.455764 -47.097356)
			(xy 453.506672 -47.074112) (xy 453.56037 -47.058351) (xy 453.615764 -47.050392) (xy 453.643746 -47.049944)
			(xy 453.644254 -47.049944) (xy 453.674038 -47.05052) (xy 453.732913 -47.059581) (xy 453.789736 -47.077455)
			(xy 453.81672 -47.090076) (xy 453.826444 -47.094252) (xy 453.847564 -47.095169) (xy 453.857614 -47.091854)
			(xy 453.863202 -47.089568) (xy 453.864726 -47.088552) (xy 453.91959 -47.053754) (xy 453.928734 -47.047912)
			(xy 453.935343 -47.043482) (xy 453.945576 -47.031309) (xy 453.9488 -47.024036) (xy 453.950225 -47.020305)
			(xy 453.95201 -47.012521) (xy 453.952356 -47.008542) (xy 453.952356 -45.297598) (xy 453.952014 -45.288997)
			(xy 453.946289 -45.272777) (xy 453.94118 -45.265848) (xy 453.940672 -45.26534) (xy 453.937624 -45.261784)
			(xy 453.92594 -45.2501) (xy 453.920352 -45.246798) (xy 453.90562 -45.238162) (xy 453.905112 -45.237908)
			(xy 453.901151 -45.235441) (xy 453.894114 -45.229313) (xy 453.891142 -45.225716) (xy 453.884792 -45.217334)
			(xy 453.873362 -45.211238) (xy 453.868212 -45.20885) (xy 453.857189 -45.206149) (xy 453.851518 -45.205904)
			(xy 453.813926 -45.205904) (xy 453.801734 -45.207428) (xy 453.795638 -45.208952) (xy 453.767701 -45.223239)
			(xy 453.708315 -45.243493) (xy 453.646416 -45.253762) (xy 453.615044 -45.254418) (xy 453.587788 -45.253958)
			(xy 453.533831 -45.246206) (xy 453.481527 -45.230853) (xy 453.43194 -45.208213) (xy 453.38608 -45.178745)
			(xy 453.344881 -45.143051) (xy 453.309181 -45.101856) (xy 453.279708 -45.055999) (xy 453.257062 -45.006415)
			(xy 453.241703 -44.954112) (xy 453.233945 -44.900156) (xy 453.233945 -44.845644) (xy 453.241703 -44.791688)
			(xy 453.257062 -44.739385) (xy 453.279708 -44.689801) (xy 453.309181 -44.643944) (xy 453.344881 -44.602749)
			(xy 453.38608 -44.567055) (xy 453.43194 -44.537587) (xy 453.481527 -44.514947) (xy 453.533831 -44.499594)
			(xy 453.587788 -44.491842) (xy 453.615044 -44.491402) (xy 453.639364 -44.491787) (xy 453.687609 -44.497976)
			(xy 453.734676 -44.510246) (xy 453.779802 -44.528399) (xy 453.801226 -44.539916) (xy 453.80148 -44.54017)
			(xy 453.807323 -44.543175) (xy 453.820057 -44.546388) (xy 453.826626 -44.54652) (xy 453.840088 -44.546266)
			(xy 453.89038 -44.516802) (xy 453.92721 -44.495212) (xy 453.934644 -44.490452) (xy 453.945956 -44.476921)
			(xy 453.951978 -44.460343) (xy 453.952356 -44.451524) (xy 453.952356 -43.265598) (xy 453.952014 -43.256997)
			(xy 453.946289 -43.240777) (xy 453.94118 -43.233848) (xy 453.940672 -43.23334) (xy 453.937624 -43.229784)
			(xy 453.92594 -43.2181) (xy 453.920352 -43.214798) (xy 453.90562 -43.206162) (xy 453.905112 -43.205908)
			(xy 453.901151 -43.203441) (xy 453.894114 -43.197313) (xy 453.891142 -43.193716) (xy 453.884792 -43.185334)
			(xy 453.873362 -43.179238) (xy 453.868212 -43.17685) (xy 453.857189 -43.174149) (xy 453.851518 -43.173904)
			(xy 453.813926 -43.173904) (xy 453.801734 -43.175428) (xy 453.795638 -43.176952) (xy 453.767701 -43.191239)
			(xy 453.708315 -43.211493) (xy 453.646416 -43.221762) (xy 453.615044 -43.222418) (xy 453.587788 -43.221958)
			(xy 453.533831 -43.214206) (xy 453.481527 -43.198853) (xy 453.43194 -43.176213) (xy 453.38608 -43.146745)
			(xy 453.344881 -43.111051) (xy 453.309181 -43.069856) (xy 453.279708 -43.023999) (xy 453.257062 -42.974415)
			(xy 453.241703 -42.922112) (xy 453.233945 -42.868156) (xy 453.233945 -42.813644) (xy 453.241703 -42.759688)
			(xy 453.257062 -42.707385) (xy 453.279708 -42.657801) (xy 453.309181 -42.611944) (xy 453.344881 -42.570749)
			(xy 453.38608 -42.535055) (xy 453.43194 -42.505587) (xy 453.481527 -42.482947) (xy 453.533831 -42.467594)
			(xy 453.587788 -42.459842) (xy 453.615044 -42.459402) (xy 453.639364 -42.459787) (xy 453.687609 -42.465976)
			(xy 453.734676 -42.478246) (xy 453.779802 -42.496399) (xy 453.801226 -42.507916) (xy 453.80148 -42.50817)
			(xy 453.807323 -42.511175) (xy 453.820057 -42.514388) (xy 453.826626 -42.51452) (xy 453.840088 -42.514266)
			(xy 453.89038 -42.484802) (xy 453.92721 -42.463212) (xy 453.934644 -42.458452) (xy 453.945956 -42.444921)
			(xy 453.951978 -42.428343) (xy 453.952356 -42.419524) (xy 453.952356 -37.535612) (xy 453.952185 -37.529603)
			(xy 453.949356 -37.517924) (xy 453.946768 -37.512498) (xy 453.944928 -37.509024) (xy 453.940334 -37.502646)
			(xy 453.937624 -37.499798) (xy 449.463668 -33.025842) (xy 449.445632 -33.007073) (xy 449.415045 -32.964958)
			(xy 449.391412 -32.918582) (xy 449.375312 -32.869084) (xy 449.367143 -32.817679) (xy 449.36664 -32.791654)
			(xy 449.36664 -29.642562) (xy 449.367166 -29.616538) (xy 449.375331 -29.565133) (xy 449.391424 -29.515635)
			(xy 449.415049 -29.469256) (xy 449.445626 -29.427136) (xy 449.463668 -29.408374) (xy 449.99529 -28.877006)
			(xy 450.001778 -28.869547) (xy 450.009032 -28.851178) (xy 450.008838 -28.831429) (xy 450.00545 -28.822142)
			(xy 450.001188 -28.813119) (xy 449.987095 -28.799022) (xy 449.968681 -28.791389) (xy 449.958714 -28.7909)
			(xy 447.614294 -28.7909) (xy 447.589004 -28.790404) (xy 447.539047 -28.782495) (xy 447.49094 -28.766872)
			(xy 447.445868 -28.743919) (xy 447.404939 -28.714202) (xy 447.38671 -28.696666) (xy 447.176144 -28.4861)
			(xy 447.170556 -28.482798) (xy 447.152464 -28.471816) (xy 447.118962 -28.445955) (xy 447.103754 -28.431236)
			(xy 446.372996 -27.700224) (xy 446.367114 -27.694819) (xy 446.352889 -27.687567) (xy 446.345056 -27.686)
			(xy 446.337182 -27.685492) (xy 445.054482 -27.685492) (xy 445.028457 -27.684967) (xy 444.97705 -27.676806)
			(xy 444.927549 -27.660717) (xy 444.881167 -27.637095) (xy 444.839042 -27.606521) (xy 444.820294 -27.588464)
			(xy 444.123572 -26.891742) (xy 443.84722 -26.615644) (xy 443.838397 -26.607752) (xy 443.815954 -26.600309)
			(xy 443.792542 -26.603615) (xy 443.78245 -26.609802) (xy 443.77737 -26.613866) (xy 443.776862 -26.613866)
			(xy 443.76534 -26.623761) (xy 443.748315 -26.648896) (xy 443.739456 -26.677933) (xy 443.739016 -26.693114)
			(xy 443.739016 -27.342846) (xy 443.738526 -27.372814) (xy 443.730703 -27.432236) (xy 443.71519 -27.490129)
			(xy 443.692254 -27.545502) (xy 443.662287 -27.597408) (xy 443.6258 -27.644958) (xy 443.58342 -27.687338)
			(xy 443.53587 -27.723825) (xy 443.483964 -27.753792) (xy 443.428591 -27.776728) (xy 443.370698 -27.792241)
			(xy 443.311276 -27.800064) (xy 443.25134 -27.800064) (xy 443.191918 -27.792241) (xy 443.134025 -27.776728)
			(xy 443.078652 -27.753792) (xy 443.026746 -27.723825) (xy 442.979196 -27.687338) (xy 442.936816 -27.644958)
			(xy 442.900329 -27.597408) (xy 442.870362 -27.545502) (xy 442.847426 -27.490129) (xy 442.831913 -27.432236)
			(xy 442.82409 -27.372814) (xy 442.8236 -27.342846) (xy 442.8236 -26.737818) (xy 442.823346 -26.479246)
			(xy 442.823873 -26.447747) (xy 442.832512 -26.385344) (xy 442.849619 -26.324714) (xy 442.874872 -26.266999)
			(xy 442.907794 -26.213288) (xy 442.947765 -26.164595) (xy 442.994031 -26.121837) (xy 443.045719 -26.085822)
			(xy 443.101853 -26.057228) (xy 443.131448 -26.04643) (xy 443.13602 -26.044906) (xy 443.146013 -26.039648)
			(xy 443.160527 -26.022387) (xy 443.16396 -26.011632) (xy 443.164976 -26.008076) (xy 443.172088 -25.976326)
			(xy 443.172088 -25.975818) (xy 443.173866 -25.968198) (xy 443.175441 -25.959509) (xy 443.173268 -25.941997)
			(xy 443.165312 -25.926246) (xy 443.159134 -25.919938) (xy 443.126114 -25.892252) (xy 443.10427 -25.87244)
			(xy 442.602874 -25.371044) (xy 442.600022 -25.368339) (xy 442.593643 -25.363748) (xy 442.590174 -25.3619)
			(xy 442.584748 -25.359315) (xy 442.573068 -25.356487) (xy 442.56706 -25.356312) (xy 441.015374 -25.356312)
			(xy 441.009364 -25.356477) (xy 440.997679 -25.359296) (xy 440.99226 -25.3619) (xy 440.988787 -25.363741)
			(xy 440.98241 -25.368336) (xy 440.97956 -25.371044) (xy 440.863736 -25.486868) (xy 440.857386 -25.497536)
			(xy 440.855608 -25.503378) (xy 440.847158 -25.528944) (xy 440.824077 -25.577589) (xy 440.79439 -25.62251)
			(xy 440.758686 -25.662813) (xy 440.717673 -25.697701) (xy 440.672166 -25.72648) (xy 440.623067 -25.74858)
			(xy 440.571349 -25.763563) (xy 440.51804 -25.77113) (xy 440.491118 -25.771602) (xy 440.463864 -25.77114)
			(xy 440.409912 -25.763385) (xy 440.357612 -25.74803) (xy 440.30803 -25.725389) (xy 440.262175 -25.695921)
			(xy 440.220981 -25.660228) (xy 440.185286 -25.619034) (xy 440.155817 -25.57318) (xy 440.133174 -25.523599)
			(xy 440.117818 -25.4713) (xy 440.110061 -25.417348) (xy 440.10961 -25.390094) (xy 440.109356 -25.390094)
			(xy 440.109813 -25.363158) (xy 440.117377 -25.30982) (xy 440.132369 -25.258076) (xy 440.154491 -25.208956)
			(xy 440.183302 -25.163436) (xy 440.218229 -25.122421) (xy 440.258579 -25.086726) (xy 440.303548 -25.057063)
			(xy 440.352242 -25.034019) (xy 440.377834 -25.025604) (xy 440.378342 -25.025604) (xy 440.384184 -25.023572)
			(xy 440.394344 -25.017476) (xy 440.40679 -25.00503) (xy 440.441334 -24.97074) (xy 440.441803 -24.967072)
			(xy 440.441799 -24.959677) (xy 440.441334 -24.956008) (xy 440.089544 -24.604218) (xy 440.064396 -24.578277)
			(xy 440.019978 -24.521292) (xy 439.982894 -24.459283) (xy 439.953708 -24.393189) (xy 439.93286 -24.324011)
			(xy 439.926222 -24.288496) (xy 439.922158 -24.263858) (xy 439.917878 -24.259876) (xy 439.907864 -24.253852)
			(xy 439.902346 -24.25192) (xy 439.894218 -24.24938) (xy 439.852816 -24.236426) (xy 439.814716 -24.224488)
			(xy 439.80961 -24.223223) (xy 439.799111 -24.222586) (xy 439.793888 -24.223218) (xy 439.592466 -24.42464)
			(xy 439.573697 -24.442677) (xy 439.531583 -24.473266) (xy 439.485207 -24.496903) (xy 439.435709 -24.513005)
			(xy 439.384303 -24.521178) (xy 439.358278 -24.521668) (xy 438.170066 -24.521668) (xy 438.165748 -24.523954)
			(xy 438.137323 -24.538872) (xy 438.076722 -24.560036) (xy 438.013439 -24.57079) (xy 437.981344 -24.571452)
			(xy 437.980836 -24.571452) (xy 437.953578 -24.570992) (xy 437.899617 -24.563238) (xy 437.847309 -24.547883)
			(xy 437.797719 -24.52524) (xy 437.751856 -24.49577) (xy 437.710654 -24.460072) (xy 437.674952 -24.418873)
			(xy 437.645477 -24.373013) (xy 437.62283 -24.323425) (xy 437.60747 -24.271118) (xy 437.599711 -24.217158)
			(xy 437.599711 -24.162642) (xy 437.60747 -24.108682) (xy 437.62283 -24.056375) (xy 437.645477 -24.006787)
			(xy 437.674952 -23.960927) (xy 437.710654 -23.919728) (xy 437.751856 -23.88403) (xy 437.797719 -23.85456)
			(xy 437.847309 -23.831917) (xy 437.899617 -23.816562) (xy 437.953578 -23.808808) (xy 437.980836 -23.808436)
			(xy 437.98109 -23.808436) (xy 438.005338 -23.808829) (xy 438.053441 -23.814994) (xy 438.10038 -23.82719)
			(xy 438.1454 -23.84522) (xy 438.166764 -23.856696) (xy 438.169558 -23.85822) (xy 439.199274 -23.85822)
			(xy 439.202576 -23.85822) (xy 439.211595 -23.85727) (xy 439.228126 -23.849845) (xy 439.234834 -23.843742)
			(xy 439.314844 -23.763478) (xy 439.35396 -23.724362) (xy 439.354214 -23.710646) (xy 439.352182 -23.701756)
			(xy 439.342784 -23.673562) (xy 439.342784 -23.673054) (xy 439.321448 -23.603712) (xy 439.314082 -23.597108)
			(xy 439.289444 -23.59279) (xy 439.256598 -23.586392) (xy 439.192527 -23.567071) (xy 439.131076 -23.540573)
			(xy 439.073046 -23.507243) (xy 439.019194 -23.467514) (xy 438.970222 -23.421906) (xy 438.926767 -23.371013)
			(xy 438.889398 -23.315498) (xy 438.8586 -23.256086) (xy 438.846214 -23.224998) (xy 438.837832 -23.203154)
			(xy 438.833797 -23.200575) (xy 438.824971 -23.196867) (xy 438.820306 -23.195788) (xy 438.77103 -23.185374)
			(xy 438.770522 -23.185374) (xy 438.734708 -23.177754) (xy 438.720484 -23.178008) (xy 438.458864 -23.439628)
			(xy 438.435277 -23.462565) (xy 438.38384 -23.503589) (xy 438.328132 -23.538596) (xy 438.268856 -23.567146)
			(xy 438.206756 -23.588879) (xy 438.142612 -23.603523) (xy 438.077233 -23.610894) (xy 438.044336 -23.611332)
			(xy 438.008905 -23.610821) (xy 437.93856 -23.602283) (xy 437.869756 -23.585328) (xy 437.803498 -23.560204)
			(xy 437.740752 -23.527275) (xy 437.682433 -23.487023) (xy 437.62939 -23.440035) (xy 437.582399 -23.386996)
			(xy 437.542143 -23.328679) (xy 437.509211 -23.265935) (xy 437.484082 -23.199678) (xy 437.467123 -23.130876)
			(xy 437.458582 -23.060531) (xy 437.458104 -23.0251) (xy 437.458548 -22.992203) (xy 437.465915 -22.926823)
			(xy 437.480556 -22.862679) (xy 437.502288 -22.800577) (xy 437.530836 -22.7413) (xy 437.565842 -22.685592)
			(xy 437.606866 -22.634153) (xy 437.629808 -22.610572) (xy 438.122568 -22.117812) (xy 438.146143 -22.094863)
			(xy 438.197582 -22.053838) (xy 438.253291 -22.01883) (xy 438.312569 -21.990281) (xy 438.374672 -21.968548)
			(xy 438.438817 -21.953906) (xy 438.504198 -21.946539) (xy 438.537096 -21.946108) (xy 438.558432 -21.946616)
			(xy 442.307472 -21.946616) (xy 442.30798 -21.946616) (xy 442.316604 -21.946232) (xy 442.332832 -21.940379)
			(xy 442.33973 -21.935186) (xy 442.348366 -21.926042) (xy 442.381894 -21.88083) (xy 442.385233 -21.87608)
			(xy 442.389855 -21.865432) (xy 442.391038 -21.859748) (xy 442.393324 -21.848064) (xy 442.389768 -21.836126)
			(xy 442.382315 -21.809437) (xy 442.374286 -21.754611) (xy 442.373766 -21.726906) (xy 442.374287 -21.698167)
			(xy 442.38291 -21.64134) (xy 442.399962 -21.58645) (xy 442.425056 -21.53474) (xy 442.457625 -21.487381)
			(xy 442.47689 -21.466048) (xy 442.484002 -21.458428) (xy 442.487304 -21.449792) (xy 442.488066 -21.448014)
			(xy 442.489298 -21.444066) (xy 442.490574 -21.435894) (xy 442.490606 -21.431758) (xy 442.490606 -21.361654)
			(xy 442.490541 -21.357521) (xy 442.48927 -21.349353) (xy 442.488066 -21.345398) (xy 442.487304 -21.34362)
			(xy 442.484002 -21.334984) (xy 442.47689 -21.327364) (xy 442.45762 -21.306036) (xy 442.425057 -21.258673)
			(xy 442.399967 -21.206961) (xy 442.382918 -21.15207) (xy 442.374295 -21.095243) (xy 442.374294 -21.037766)
			(xy 442.382916 -20.980938) (xy 442.399964 -20.926047) (xy 442.425053 -20.874335) (xy 442.457615 -20.82697)
			(xy 442.47689 -20.805648) (xy 442.484002 -20.798028) (xy 442.487304 -20.789392) (xy 442.488066 -20.787614)
			(xy 442.489298 -20.783666) (xy 442.490574 -20.775494) (xy 442.490606 -20.771358) (xy 442.490606 -20.701254)
			(xy 442.490541 -20.697121) (xy 442.48927 -20.688953) (xy 442.488066 -20.684998) (xy 442.487304 -20.68322)
			(xy 442.484002 -20.674584) (xy 442.47689 -20.666964) (xy 442.45762 -20.645636) (xy 442.425057 -20.598273)
			(xy 442.399967 -20.546561) (xy 442.382918 -20.49167) (xy 442.374295 -20.434843) (xy 442.374294 -20.377366)
			(xy 442.382916 -20.320538) (xy 442.399964 -20.265647) (xy 442.425053 -20.213935) (xy 442.457615 -20.16657)
			(xy 442.47689 -20.145248) (xy 442.484002 -20.137628) (xy 442.487304 -20.128992) (xy 442.488066 -20.127214)
			(xy 442.489298 -20.123266) (xy 442.490574 -20.115094) (xy 442.490606 -20.110958) (xy 442.490606 -20.040854)
			(xy 442.490541 -20.036721) (xy 442.48927 -20.028553) (xy 442.488066 -20.024598) (xy 442.487304 -20.02282)
			(xy 442.484002 -20.014184) (xy 442.47689 -20.006564) (xy 442.45762 -19.985236) (xy 442.425057 -19.937873)
			(xy 442.399967 -19.886161) (xy 442.382918 -19.83127) (xy 442.374295 -19.774443) (xy 442.374294 -19.716966)
			(xy 442.382916 -19.660138) (xy 442.399964 -19.605247) (xy 442.425053 -19.553535) (xy 442.457615 -19.50617)
			(xy 442.47689 -19.484848) (xy 442.484002 -19.477228) (xy 442.487304 -19.468592) (xy 442.488066 -19.466814)
			(xy 442.489298 -19.462866) (xy 442.490574 -19.454694) (xy 442.490606 -19.450558) (xy 442.490606 -19.380454)
			(xy 442.490541 -19.376321) (xy 442.48927 -19.368153) (xy 442.488066 -19.364198) (xy 442.487304 -19.36242)
			(xy 442.484002 -19.353784) (xy 442.47689 -19.346164) (xy 442.45762 -19.324837) (xy 442.425057 -19.277473)
			(xy 442.399967 -19.225762) (xy 442.382918 -19.170871) (xy 442.374295 -19.114045) (xy 442.373766 -19.085306)
			(xy 442.374252 -19.058055) (xy 442.382008 -19.004107) (xy 442.397363 -18.951812) (xy 442.420005 -18.902235)
			(xy 442.449471 -18.856385) (xy 442.485162 -18.815194) (xy 442.526353 -18.779503) (xy 442.572203 -18.750037)
			(xy 442.62178 -18.727395) (xy 442.674075 -18.71204) (xy 442.728023 -18.704284) (xy 442.782525 -18.704284)
			(xy 442.836473 -18.71204) (xy 442.888768 -18.727395) (xy 442.938345 -18.750037) (xy 442.984195 -18.779503)
			(xy 443.025386 -18.815194) (xy 443.061077 -18.856385) (xy 443.090543 -18.902235) (xy 443.113185 -18.951812)
			(xy 443.12854 -19.004107) (xy 443.136296 -19.058055) (xy 443.136782 -19.085306) (xy 443.136261 -19.114045)
			(xy 443.127637 -19.170872) (xy 443.110585 -19.225762) (xy 443.085492 -19.277473) (xy 443.052925 -19.324834)
			(xy 443.033658 -19.346164) (xy 443.026546 -19.353784) (xy 443.023244 -19.36242) (xy 443.022482 -19.364198)
			(xy 443.021252 -19.368147) (xy 443.01998 -19.376318) (xy 443.019942 -19.380454) (xy 443.019942 -19.450558)
			(xy 443.020008 -19.454691) (xy 443.02128 -19.462859) (xy 443.022482 -19.466814) (xy 443.023244 -19.468592)
			(xy 443.026546 -19.477228) (xy 443.033658 -19.484848) (xy 443.052929 -19.506174) (xy 443.085495 -19.553536)
			(xy 443.110587 -19.605248) (xy 443.127637 -19.660138) (xy 443.136259 -19.716966) (xy 443.136259 -19.774443)
			(xy 443.127635 -19.83127) (xy 443.110584 -19.88616) (xy 443.085491 -19.937871) (xy 443.052924 -19.985232)
			(xy 443.033658 -20.006564) (xy 443.026546 -20.014184) (xy 443.023244 -20.02282) (xy 443.022482 -20.024598)
			(xy 443.021252 -20.028547) (xy 443.01998 -20.036718) (xy 443.019942 -20.040854) (xy 443.019942 -20.110958)
			(xy 443.020008 -20.115091) (xy 443.02128 -20.123259) (xy 443.022482 -20.127214) (xy 443.023244 -20.128992)
			(xy 443.026546 -20.137628) (xy 443.033658 -20.145248) (xy 443.052929 -20.166574) (xy 443.085495 -20.213936)
			(xy 443.110587 -20.265648) (xy 443.127637 -20.320538) (xy 443.136259 -20.377366) (xy 443.136259 -20.434843)
			(xy 443.127635 -20.49167) (xy 443.110584 -20.54656) (xy 443.085491 -20.598271) (xy 443.052924 -20.645632)
			(xy 443.033658 -20.666964) (xy 443.026546 -20.674584) (xy 443.023244 -20.68322) (xy 443.022482 -20.684998)
			(xy 443.021252 -20.688947) (xy 443.01998 -20.697118) (xy 443.019942 -20.701254) (xy 443.019942 -20.771358)
			(xy 443.020008 -20.775491) (xy 443.02128 -20.783659) (xy 443.022482 -20.787614) (xy 443.023244 -20.789392)
			(xy 443.026546 -20.798028) (xy 443.033658 -20.805648) (xy 443.052929 -20.826974) (xy 443.085495 -20.874336)
			(xy 443.110587 -20.926048) (xy 443.127637 -20.980938) (xy 443.136259 -21.037766) (xy 443.136259 -21.095243)
			(xy 443.127635 -21.15207) (xy 443.110584 -21.20696) (xy 443.085491 -21.258671) (xy 443.052924 -21.306032)
			(xy 443.033658 -21.327364) (xy 443.026546 -21.334984) (xy 443.023244 -21.34362) (xy 443.022482 -21.345398)
			(xy 443.021252 -21.349347) (xy 443.01998 -21.357518) (xy 443.019942 -21.361654) (xy 443.019942 -21.431758)
			(xy 443.020008 -21.435891) (xy 443.02128 -21.444059) (xy 443.022482 -21.448014) (xy 443.023244 -21.449792)
			(xy 443.026546 -21.458428) (xy 443.033658 -21.466048) (xy 443.052925 -21.487377) (xy 443.085482 -21.534741)
			(xy 443.110568 -21.586453) (xy 443.127613 -21.641343) (xy 443.136233 -21.698168) (xy 443.136782 -21.726906)
			(xy 443.136287 -21.754613) (xy 443.128251 -21.809441) (xy 443.12078 -21.836126) (xy 443.12078 -21.83638)
			(xy 443.11924 -21.842157) (xy 443.118607 -21.854092) (xy 443.11951 -21.860002) (xy 443.121542 -21.871432)
			(xy 443.162436 -21.926296) (xy 443.168024 -21.932392) (xy 443.175215 -21.938767) (xy 443.192973 -21.946076)
			(xy 443.202568 -21.946616) (xy 447.552572 -21.946616) (xy 447.560279 -21.946381) (xy 447.575009 -21.941846)
			(xy 447.581528 -21.937726) (xy 447.585592 -21.934424) (xy 447.928746 -21.59127) (xy 447.929254 -21.583904)
			(xy 447.929254 -21.567902) (xy 447.926206 -21.556218) (xy 447.921888 -21.547836) (xy 447.908354 -21.520574)
			(xy 447.889159 -21.46282) (xy 447.879372 -21.402751) (xy 447.878708 -21.372322) (xy 447.878708 -21.36394)
			(xy 447.879703 -21.337044) (xy 447.888323 -21.283918) (xy 447.904324 -21.232531) (xy 447.927389 -21.183904)
			(xy 447.957061 -21.139001) (xy 447.992749 -21.098714) (xy 448.033746 -21.063844) (xy 448.079236 -21.035082)
			(xy 448.128318 -21.013) (xy 448.180017 -20.998036) (xy 448.233306 -20.990487) (xy 448.260216 -20.990052)
			(xy 448.26428 -20.990052) (xy 448.27317 -20.990306) (xy 448.279012 -20.990306) (xy 448.287205 -20.989995)
			(xy 448.302749 -20.984811) (xy 448.309492 -20.980146) (xy 448.31254 -20.97786) (xy 448.366896 -20.925536)
			(xy 448.372484 -20.919186) (xy 448.372484 -20.003008) (xy 448.37223 -19.453098) (xy 448.372763 -19.417376)
			(xy 448.381451 -19.346463) (xy 448.398697 -19.277133) (xy 448.424247 -19.210414) (xy 448.45772 -19.147297)
			(xy 448.498619 -19.088719) (xy 448.546339 -19.035549) (xy 448.57289 -19.011646) (xy 448.583812 -19.002248)
			(xy 448.585844 -18.99793) (xy 448.587851 -18.993216) (xy 448.59015 -18.983234) (xy 448.590416 -18.978118)
			(xy 448.59194 -18.922238) (xy 448.59194 -18.921476) (xy 448.592448 -18.906998) (xy 448.543934 -18.858484)
			(xy 448.521024 -18.834906) (xy 448.480049 -18.783492) (xy 448.445087 -18.727815) (xy 448.416576 -18.668574)
			(xy 448.394877 -18.606514) (xy 448.380261 -18.542415) (xy 448.372911 -18.477082) (xy 448.372484 -18.44421)
			(xy 448.37223 -18.432018) (xy 448.373485 -18.397095) (xy 448.383279 -18.327902) (xy 448.401229 -18.260363)
			(xy 448.427081 -18.195437) (xy 448.460467 -18.134044) (xy 448.500914 -18.077056) (xy 448.547849 -18.025279)
			(xy 448.600606 -17.979449) (xy 448.658436 -17.940215) (xy 448.720521 -17.908134) (xy 448.785978 -17.88366)
			(xy 448.853881 -17.867142) (xy 448.923267 -17.858812) (xy 448.958208 -17.858232) (xy 448.967352 -17.858232)
			(xy 449.004649 -17.859413) (xy 449.078505 -17.870073) (xy 449.150409 -17.890029) (xy 449.18503 -17.903952)
			(xy 449.219775 -17.919175) (xy 449.285361 -17.957292) (xy 449.345486 -18.003546) (xy 449.372736 -18.029936)
			(xy 449.607432 -18.264632) (xy 454.446638 -18.264632) (xy 454.450709 -18.20901) (xy 454.462835 -18.154573)
			(xy 454.482758 -18.102482) (xy 454.510054 -18.053847) (xy 454.54414 -18.009704) (xy 454.584289 -17.970995)
			(xy 454.629647 -17.938544) (xy 454.679247 -17.913043) (xy 454.732031 -17.895036) (xy 454.786874 -17.884906)
			(xy 454.842608 -17.882869) (xy 454.898045 -17.888969) (xy 454.952002 -17.903075) (xy 455.003331 -17.924887)
			(xy 455.050937 -17.953941) (xy 455.093805 -17.989616) (xy 455.131022 -18.031153) (xy 455.161795 -18.077666)
			(xy 455.185467 -18.128163) (xy 455.201535 -18.18157) (xy 455.209655 -18.236746) (xy 455.210164 -18.264632)
			(xy 455.209655 -18.292518) (xy 455.201535 -18.347694) (xy 455.185467 -18.401101) (xy 455.161795 -18.451598)
			(xy 455.131022 -18.498111) (xy 455.093805 -18.539648) (xy 455.050937 -18.575323) (xy 455.003331 -18.604377)
			(xy 454.952002 -18.626189) (xy 454.898045 -18.640295) (xy 454.842608 -18.646395) (xy 454.786874 -18.644358)
			(xy 454.732031 -18.634228) (xy 454.679247 -18.616221) (xy 454.629647 -18.59072) (xy 454.584289 -18.558269)
			(xy 454.54414 -18.51956) (xy 454.510054 -18.475417) (xy 454.482758 -18.426782) (xy 454.462835 -18.374691)
			(xy 454.450709 -18.320254) (xy 454.446638 -18.264632) (xy 449.607432 -18.264632) (xy 449.941188 -18.598388)
			(xy 449.964132 -18.621943) (xy 450.00515 -18.673343) (xy 450.04015 -18.729015) (xy 450.068693 -18.788257)
			(xy 450.090418 -18.850325) (xy 450.105054 -18.914435) (xy 450.112414 -18.979782) (xy 450.112892 -19.012662)
			(xy 450.112892 -19.633184) (xy 454.554334 -19.633184) (xy 454.558405 -19.577562) (xy 454.570531 -19.523125)
			(xy 454.590454 -19.471034) (xy 454.61775 -19.422399) (xy 454.651836 -19.378256) (xy 454.691985 -19.339547)
			(xy 454.737343 -19.307096) (xy 454.786943 -19.281595) (xy 454.839727 -19.263588) (xy 454.89457 -19.253458)
			(xy 454.950304 -19.251421) (xy 455.005741 -19.257521) (xy 455.059698 -19.271627) (xy 455.111027 -19.293439)
			(xy 455.158633 -19.322493) (xy 455.201501 -19.358168) (xy 455.238718 -19.399705) (xy 455.269491 -19.446218)
			(xy 455.293163 -19.496715) (xy 455.309231 -19.550122) (xy 455.317351 -19.605298) (xy 455.31786 -19.633184)
			(xy 455.317351 -19.66107) (xy 455.309231 -19.716246) (xy 455.293163 -19.769653) (xy 455.269491 -19.82015)
			(xy 455.238718 -19.866663) (xy 455.201501 -19.9082) (xy 455.158633 -19.943875) (xy 455.111027 -19.972929)
			(xy 455.059698 -19.994741) (xy 455.005741 -20.008847) (xy 454.950304 -20.014947) (xy 454.89457 -20.01291)
			(xy 454.839727 -20.00278) (xy 454.786943 -19.984773) (xy 454.737343 -19.959272) (xy 454.691985 -19.926821)
			(xy 454.651836 -19.888112) (xy 454.61775 -19.843969) (xy 454.590454 -19.795334) (xy 454.570531 -19.743243)
			(xy 454.558405 -19.688806) (xy 454.554334 -19.633184) (xy 450.112892 -19.633184) (xy 450.112892 -21.475192)
			(xy 450.116555 -21.479729) (xy 450.125537 -21.487161) (xy 450.130672 -21.489924) (xy 450.202554 -21.520404)
			(xy 450.203062 -21.520404) (xy 450.220334 -21.527516) (xy 450.229549 -21.530828) (xy 450.249114 -21.530971)
			(xy 450.267317 -21.523798) (xy 450.27469 -21.517356) (xy 450.583808 -21.208238) (xy 450.823584 -20.968716)
			(xy 450.830864 -20.960142) (xy 450.837839 -20.938789) (xy 450.837046 -20.927568) (xy 450.835014 -20.914868)
			(xy 450.82333 -20.842478) (xy 450.822084 -20.837233) (xy 450.817736 -20.82737) (xy 450.814694 -20.82292)
			(xy 450.809614 -20.816062) (xy 450.804026 -20.813268) (xy 450.7799 -20.801241) (xy 450.734989 -20.771423)
			(xy 450.694705 -20.7356) (xy 450.659843 -20.694482) (xy 450.631092 -20.648881) (xy 450.609021 -20.599698)
			(xy 450.594066 -20.547906) (xy 450.586523 -20.494528) (xy 450.586094 -20.467574) (xy 450.586582 -20.440196)
			(xy 450.594375 -20.385997) (xy 450.609802 -20.333458) (xy 450.632548 -20.28365) (xy 450.662152 -20.237586)
			(xy 450.69801 -20.196204) (xy 450.739392 -20.160346) (xy 450.785456 -20.130742) (xy 450.835264 -20.107996)
			(xy 450.887803 -20.092569) (xy 450.942002 -20.084776) (xy 450.996758 -20.084776) (xy 451.050957 -20.092569)
			(xy 451.103496 -20.107996) (xy 451.153304 -20.130742) (xy 451.199368 -20.160346) (xy 451.24075 -20.196204)
			(xy 451.276608 -20.237586) (xy 451.306212 -20.28365) (xy 451.328958 -20.333458) (xy 451.344385 -20.385997)
			(xy 451.352178 -20.440196) (xy 451.352666 -20.467574) (xy 451.352666 -20.468336) (xy 451.35199 -20.500184)
			(xy 451.34139 -20.562995) (xy 451.331584 -20.593304) (xy 451.328282 -20.602956) (xy 451.328028 -20.604734)
			(xy 451.327696 -20.61316) (xy 451.331836 -20.629496) (xy 451.336156 -20.636738) (xy 451.337426 -20.638516)
			(xy 451.384924 -20.705064) (xy 451.385686 -20.70608) (xy 452.948548 -20.70608) (xy 452.981403 -20.706537)
			(xy 453.0467 -20.713888) (xy 453.110764 -20.728504) (xy 453.172788 -20.7502) (xy 453.18297 -20.755102)
			(xy 454.45883 -20.755102) (xy 454.462901 -20.69948) (xy 454.475027 -20.645043) (xy 454.49495 -20.592952)
			(xy 454.522246 -20.544317) (xy 454.556332 -20.500174) (xy 454.596481 -20.461465) (xy 454.641839 -20.429014)
			(xy 454.691439 -20.403513) (xy 454.744223 -20.385506) (xy 454.799066 -20.375376) (xy 454.8548 -20.373339)
			(xy 454.910237 -20.379439) (xy 454.964194 -20.393545) (xy 455.015523 -20.415357) (xy 455.063129 -20.444411)
			(xy 455.105997 -20.480086) (xy 455.143214 -20.521623) (xy 455.173987 -20.568136) (xy 455.197659 -20.618633)
			(xy 455.213727 -20.67204) (xy 455.221847 -20.727216) (xy 455.222356 -20.755102) (xy 455.221847 -20.782988)
			(xy 455.213727 -20.838164) (xy 455.197659 -20.891571) (xy 455.173987 -20.942068) (xy 455.143214 -20.988581)
			(xy 455.105997 -21.030118) (xy 455.063129 -21.065793) (xy 455.015523 -21.094847) (xy 454.964194 -21.116659)
			(xy 454.910237 -21.130765) (xy 454.8548 -21.136865) (xy 454.799066 -21.134828) (xy 454.744223 -21.124698)
			(xy 454.691439 -21.106691) (xy 454.641839 -21.08119) (xy 454.596481 -21.048739) (xy 454.556332 -21.01003)
			(xy 454.522246 -20.965887) (xy 454.49495 -20.917252) (xy 454.475027 -20.865161) (xy 454.462901 -20.810724)
			(xy 454.45883 -20.755102) (xy 453.18297 -20.755102) (xy 453.231993 -20.778704) (xy 453.287635 -20.813657)
			(xy 453.339014 -20.85462) (xy 453.362568 -20.87753) (xy 453.709024 -21.223986) (xy 453.714522 -21.228975)
			(xy 453.727688 -21.235821) (xy 453.734932 -21.237448) (xy 453.744584 -21.238464) (xy 453.762364 -21.238464)
			(xy 453.796464 -21.238939) (xy 453.864205 -21.246852) (xy 453.930568 -21.262577) (xy 453.994657 -21.2859)
			(xy 454.055605 -21.316506) (xy 454.112587 -21.353981) (xy 454.164834 -21.397818) (xy 454.211638 -21.447424)
			(xy 454.252366 -21.502128) (xy 454.286467 -21.561192) (xy 454.313481 -21.623814) (xy 454.333042 -21.68915)
			(xy 454.344886 -21.756314) (xy 454.348852 -21.8244) (xy 454.344886 -21.892486) (xy 454.333042 -21.95965)
			(xy 454.313481 -22.024986) (xy 454.286467 -22.087608) (xy 454.252366 -22.146672) (xy 454.211638 -22.201376)
			(xy 454.164834 -22.250982) (xy 454.112587 -22.294819) (xy 454.055605 -22.332294) (xy 453.994657 -22.3629)
			(xy 453.930568 -22.386223) (xy 453.864205 -22.401948) (xy 453.796464 -22.409861) (xy 453.762364 -22.41042)
			(xy 453.480678 -22.41042) (xy 453.447801 -22.409942) (xy 453.382462 -22.402551) (xy 453.31836 -22.387896)
			(xy 453.2563 -22.366163) (xy 453.197061 -22.337624) (xy 453.141386 -22.302637) (xy 453.089975 -22.261641)
			(xy 453.066404 -22.238716) (xy 453.03059 -22.202648) (xy 453.021446 -22.202394) (xy 453.015096 -22.207474)
			(xy 452.990712 -22.227794) (xy 452.964442 -22.248857) (xy 452.907929 -22.285471) (xy 452.847589 -22.315359)
			(xy 452.784219 -22.338127) (xy 452.718654 -22.353475) (xy 452.651762 -22.3612) (xy 452.618094 -22.361652)
			(xy 452.460106 -22.361652) (xy 452.450962 -22.370542) (xy 452.43242 -22.393656) (xy 452.3994 -22.43455)
			(xy 452.39686 -22.438614) (xy 452.392288 -22.450552) (xy 452.388986 -22.463252) (xy 452.389494 -22.46503)
			(xy 452.391526 -22.47519) (xy 452.39536 -22.494395) (xy 452.399554 -22.533333) (xy 452.399908 -22.552914)
			(xy 452.399908 -22.553422) (xy 452.399908 -22.559264) (xy 452.399145 -22.586805) (xy 452.390671 -22.641245)
			(xy 452.374456 -22.693899) (xy 452.350838 -22.743675) (xy 452.320308 -22.789538) (xy 452.2835 -22.830533)
			(xy 452.24118 -22.86581) (xy 452.194226 -22.894634) (xy 452.143616 -22.916406) (xy 452.0904 -22.930675)
			(xy 452.063104 -22.934422) (xy 452.04888 -22.935946) (xy 452.0184 -22.937216) (xy 451.990254 -22.936713)
			(xy 451.934571 -22.928446) (xy 451.880707 -22.91209) (xy 451.829829 -22.888001) (xy 451.78304 -22.8567)
			(xy 451.76186 -22.838156) (xy 451.761352 -22.837648) (xy 451.755859 -22.833061) (xy 451.742969 -22.826858)
			(xy 451.735952 -22.825456) (xy 451.72884 -22.82444) (xy 451.721728 -22.825202) (xy 451.718053 -22.825745)
			(xy 451.710908 -22.827779) (xy 451.707504 -22.829266) (xy 451.690232 -22.836886) (xy 451.622414 -22.866858)
			(xy 451.613615 -22.871233) (xy 451.59995 -22.885327) (xy 451.592584 -22.903524) (xy 451.592188 -22.91334)
			(xy 451.592188 -23.965154) (xy 452.3773 -23.965154) (xy 452.381371 -23.909532) (xy 452.393497 -23.855095)
			(xy 452.41342 -23.803004) (xy 452.440716 -23.754369) (xy 452.474802 -23.710226) (xy 452.514951 -23.671517)
			(xy 452.560309 -23.639066) (xy 452.609909 -23.613565) (xy 452.662693 -23.595558) (xy 452.717536 -23.585428)
			(xy 452.77327 -23.583391) (xy 452.828707 -23.589491) (xy 452.882664 -23.603597) (xy 452.933993 -23.625409)
			(xy 452.981599 -23.654463) (xy 453.024467 -23.690138) (xy 453.061684 -23.731675) (xy 453.092457 -23.778188)
			(xy 453.116129 -23.828685) (xy 453.132197 -23.882092) (xy 453.140317 -23.937268) (xy 453.140492 -23.946866)
			(xy 453.380346 -23.946866) (xy 453.384417 -23.891244) (xy 453.396543 -23.836807) (xy 453.416466 -23.784716)
			(xy 453.443762 -23.736081) (xy 453.477848 -23.691938) (xy 453.517997 -23.653229) (xy 453.563355 -23.620778)
			(xy 453.612955 -23.595277) (xy 453.665739 -23.57727) (xy 453.720582 -23.56714) (xy 453.776316 -23.565103)
			(xy 453.831753 -23.571203) (xy 453.88571 -23.585309) (xy 453.937039 -23.607121) (xy 453.984645 -23.636175)
			(xy 454.027513 -23.67185) (xy 454.06473 -23.713387) (xy 454.095503 -23.7599) (xy 454.119175 -23.810397)
			(xy 454.135243 -23.863804) (xy 454.143363 -23.91898) (xy 454.143872 -23.946866) (xy 454.143363 -23.974752)
			(xy 454.135243 -24.029928) (xy 454.130888 -24.044402) (xy 454.372724 -24.044402) (xy 454.376795 -23.98878)
			(xy 454.388921 -23.934343) (xy 454.408844 -23.882252) (xy 454.43614 -23.833617) (xy 454.470226 -23.789474)
			(xy 454.510375 -23.750765) (xy 454.555733 -23.718314) (xy 454.605333 -23.692813) (xy 454.658117 -23.674806)
			(xy 454.71296 -23.664676) (xy 454.768694 -23.662639) (xy 454.824131 -23.668739) (xy 454.878088 -23.682845)
			(xy 454.929417 -23.704657) (xy 454.977023 -23.733711) (xy 455.019891 -23.769386) (xy 455.057108 -23.810923)
			(xy 455.087881 -23.857436) (xy 455.111553 -23.907933) (xy 455.127621 -23.96134) (xy 455.135741 -24.016516)
			(xy 455.13625 -24.044402) (xy 455.135741 -24.072288) (xy 455.127621 -24.127464) (xy 455.111553 -24.180871)
			(xy 455.087881 -24.231368) (xy 455.057108 -24.277881) (xy 455.019891 -24.319418) (xy 454.977023 -24.355093)
			(xy 454.929417 -24.384147) (xy 454.878088 -24.405959) (xy 454.824131 -24.420065) (xy 454.768694 -24.426165)
			(xy 454.71296 -24.424128) (xy 454.658117 -24.413998) (xy 454.605333 -24.395991) (xy 454.555733 -24.37049)
			(xy 454.510375 -24.338039) (xy 454.470226 -24.29933) (xy 454.43614 -24.255187) (xy 454.408844 -24.206552)
			(xy 454.388921 -24.154461) (xy 454.376795 -24.100024) (xy 454.372724 -24.044402) (xy 454.130888 -24.044402)
			(xy 454.119175 -24.083335) (xy 454.095503 -24.133832) (xy 454.06473 -24.180345) (xy 454.027513 -24.221882)
			(xy 453.984645 -24.257557) (xy 453.937039 -24.286611) (xy 453.88571 -24.308423) (xy 453.831753 -24.322529)
			(xy 453.776316 -24.328629) (xy 453.720582 -24.326592) (xy 453.665739 -24.316462) (xy 453.612955 -24.298455)
			(xy 453.563355 -24.272954) (xy 453.517997 -24.240503) (xy 453.477848 -24.201794) (xy 453.443762 -24.157651)
			(xy 453.416466 -24.109016) (xy 453.396543 -24.056925) (xy 453.384417 -24.002488) (xy 453.380346 -23.946866)
			(xy 453.140492 -23.946866) (xy 453.140826 -23.965154) (xy 453.140317 -23.99304) (xy 453.132197 -24.048216)
			(xy 453.116129 -24.101623) (xy 453.092457 -24.15212) (xy 453.061684 -24.198633) (xy 453.024467 -24.24017)
			(xy 452.981599 -24.275845) (xy 452.933993 -24.304899) (xy 452.882664 -24.326711) (xy 452.828707 -24.340817)
			(xy 452.77327 -24.346917) (xy 452.717536 -24.34488) (xy 452.662693 -24.33475) (xy 452.609909 -24.316743)
			(xy 452.560309 -24.291242) (xy 452.514951 -24.258791) (xy 452.474802 -24.220082) (xy 452.440716 -24.175939)
			(xy 452.41342 -24.127304) (xy 452.393497 -24.075213) (xy 452.381371 -24.020776) (xy 452.3773 -23.965154)
			(xy 451.592188 -23.965154) (xy 451.592188 -25.90419) (xy 451.592729 -25.914794) (xy 451.60125 -25.934216)
			(xy 451.608698 -25.941782) (xy 451.61249 -25.945029) (xy 451.621058 -25.950149) (xy 451.625716 -25.951942)
			(xy 451.629018 -25.952958) (xy 451.654807 -25.960836) (xy 451.704033 -25.982846) (xy 451.749673 -26.011564)
			(xy 451.790816 -26.046419) (xy 451.826645 -26.086717) (xy 451.856447 -26.131656) (xy 451.879628 -26.180342)
			(xy 451.888098 -26.205942) (xy 451.888606 -26.206958) (xy 451.88886 -26.207974) (xy 451.89092 -26.213415)
			(xy 451.897077 -26.223284) (xy 451.901052 -26.227532) (xy 452.837296 -27.163776) (xy 452.855328 -27.182547)
			(xy 452.885907 -27.224664) (xy 452.909533 -27.271041) (xy 452.925626 -27.320538) (xy 452.933792 -27.371941)
			(xy 452.934324 -27.397964) (xy 452.934324 -30.184598) (xy 452.933793 -30.21062) (xy 452.925619 -30.262019)
			(xy 452.909518 -30.311511) (xy 452.885886 -30.357881) (xy 452.855303 -30.399992) (xy 452.837296 -30.418786)
			(xy 452.510257 -30.745738) (xy 457.614517 -30.745738) (xy 457.614517 -30.616598) (xy 457.622467 -30.487703)
			(xy 457.638337 -30.359543) (xy 457.662066 -30.232602) (xy 457.693565 -30.107363) (xy 457.732714 -29.9843)
			(xy 457.779365 -29.863881) (xy 457.83334 -29.746562) (xy 457.894435 -29.632788) (xy 457.962418 -29.522991)
			(xy 458.037032 -29.417588) (xy 458.117993 -29.316978) (xy 458.204993 -29.221543) (xy 458.297704 -29.131644)
			(xy 458.395774 -29.047623) (xy 458.498829 -28.969799) (xy 458.60648 -28.898467) (xy 458.718319 -28.833897)
			(xy 458.83392 -28.776335) (xy 458.952845 -28.725998) (xy 459.074644 -28.683078) (xy 459.198854 -28.647737)
			(xy 459.325003 -28.62011) (xy 459.452615 -28.600301) (xy 459.581204 -28.588385) (xy 459.710282 -28.584409)
			(xy 459.83936 -28.588385) (xy 459.967949 -28.600301) (xy 460.095561 -28.62011) (xy 460.22171 -28.647737)
			(xy 460.34592 -28.683078) (xy 460.467719 -28.725998) (xy 460.586644 -28.776335) (xy 460.702245 -28.833897)
			(xy 460.814084 -28.898467) (xy 460.921735 -28.969799) (xy 461.02479 -29.047623) (xy 461.12286 -29.131644)
			(xy 461.215571 -29.221543) (xy 461.302571 -29.316978) (xy 461.383532 -29.417588) (xy 461.458146 -29.522991)
			(xy 461.526129 -29.632788) (xy 461.587224 -29.746562) (xy 461.641199 -29.863881) (xy 461.68785 -29.9843)
			(xy 461.726999 -30.107363) (xy 461.758498 -30.232602) (xy 461.782227 -30.359543) (xy 461.798097 -30.487703)
			(xy 461.806047 -30.616598) (xy 461.806544 -30.681168) (xy 461.806047 -30.745738) (xy 461.798097 -30.874633)
			(xy 461.782227 -31.002793) (xy 461.758498 -31.129734) (xy 461.726999 -31.254973) (xy 461.68785 -31.378036)
			(xy 461.641199 -31.498455) (xy 461.587224 -31.615774) (xy 461.526129 -31.729548) (xy 461.458146 -31.839345)
			(xy 461.383532 -31.944748) (xy 461.302571 -32.045358) (xy 461.215571 -32.140793) (xy 461.12286 -32.230692)
			(xy 461.02479 -32.314713) (xy 460.921735 -32.392537) (xy 460.814084 -32.463869) (xy 460.702245 -32.528439)
			(xy 460.586644 -32.586001) (xy 460.467719 -32.636338) (xy 460.34592 -32.679258) (xy 460.22171 -32.714599)
			(xy 460.095561 -32.742226) (xy 459.967949 -32.762035) (xy 459.83936 -32.773951) (xy 459.710282 -32.777928)
			(xy 459.581204 -32.773951) (xy 459.452615 -32.762035) (xy 459.325003 -32.742226) (xy 459.198854 -32.714599)
			(xy 459.074644 -32.679258) (xy 458.952845 -32.636338) (xy 458.83392 -32.586001) (xy 458.718319 -32.528439)
			(xy 458.60648 -32.463869) (xy 458.498829 -32.392537) (xy 458.395774 -32.314713) (xy 458.297704 -32.230692)
			(xy 458.204993 -32.140793) (xy 458.117993 -32.045358) (xy 458.037032 -31.944748) (xy 457.962418 -31.839345)
			(xy 457.894435 -31.729548) (xy 457.83334 -31.615774) (xy 457.779365 -31.498455) (xy 457.732714 -31.378036)
			(xy 457.693565 -31.254973) (xy 457.662066 -31.129734) (xy 457.638337 -31.002793) (xy 457.622467 -30.874633)
			(xy 457.614517 -30.745738) (xy 452.510257 -30.745738) (xy 451.88378 -31.372048) (xy 451.878498 -31.377765)
			(xy 451.871395 -31.391605) (xy 451.86981 -31.399226) (xy 451.869048 -31.407862) (xy 451.869048 -31.87065)
			(xy 451.869125 -31.87486) (xy 451.870522 -31.883162) (xy 451.871842 -31.88716) (xy 451.873862 -31.892521)
			(xy 451.879886 -31.902262) (xy 451.88378 -31.906464) (xy 457.656946 -37.679376) (xy 457.6732 -37.696219)
			(xy 457.701295 -37.733655) (xy 457.723854 -37.774666) (xy 457.74043 -37.818439) (xy 457.750695 -37.864105)
			(xy 457.752958 -37.887402) (xy 457.75372 -37.896546) (xy 457.757276 -37.90442) (xy 457.759254 -37.908404)
			(xy 457.764358 -37.915688) (xy 457.767436 -37.918898) (xy 457.885038 -38.0365) (xy 457.891891 -38.043895)
			(xy 457.899636 -38.062494) (xy 457.900024 -38.072568) (xy 457.900024 -70.91045) (xy 457.90104 -70.919848)
			(xy 457.90104 -70.920356) (xy 457.902743 -70.927516) (xy 457.909575 -70.940544) (xy 457.914502 -70.94601)
			(xy 459.711298 -72.742806) (xy 459.718144 -72.750205) (xy 459.725876 -72.768803) (xy 459.726284 -72.778874)
			(xy 459.726284 -73.13041) (xy 459.72857 -73.13803) (xy 459.735559 -73.162002) (xy 459.74309 -73.211363)
			(xy 459.743556 -73.236328) (xy 459.743556 -76.38288) (xy 459.743089 -76.407846) (xy 459.735571 -76.457209)
			(xy 459.72857 -76.481178) (xy 459.726284 -76.488798) (xy 459.726284 -77.199998) (xy 459.725789 -77.225289)
			(xy 459.717883 -77.275249) (xy 459.702264 -77.323358) (xy 459.679316 -77.368435) (xy 459.649604 -77.40937)
			(xy 459.63205 -77.427582) (xy 457.877418 -79.182214) (xy 457.870019 -79.189057) (xy 457.85142 -79.196775)
			(xy 457.84135 -79.1972) (xy 439.028078 -79.1972) (xy 439.01801 -79.197627) (xy 438.999411 -79.205347)
			(xy 438.99201 -79.212186) (xy 436.103522 -82.100674) (xy 436.09725 -82.107531) (xy 436.089668 -82.124482)
			(xy 436.088619 -82.143021) (xy 436.091076 -82.151982) (xy 436.118 -82.237834) (xy 436.120318 -82.24447)
			(xy 436.128058 -82.256197) (xy 436.13324 -82.260948) (xy 436.138574 -82.26552) (xy 436.150512 -82.271362)
			(xy 436.157624 -82.272632) (xy 436.191115 -82.279016) (xy 436.256435 -82.298561) (xy 436.319044 -82.325557)
			(xy 436.378096 -82.35964) (xy 436.432791 -82.400349) (xy 436.48239 -82.447132) (xy 436.526222 -82.499357)
			(xy 436.563694 -82.556318) (xy 436.594299 -82.617245) (xy 436.617624 -82.681313) (xy 436.633353 -82.747655)
			(xy 436.641272 -82.815375) (xy 436.641748 -82.849466) (xy 436.641236 -82.884881) (xy 436.632702 -82.955194)
			(xy 436.615755 -83.023966) (xy 436.59064 -83.090194) (xy 436.557726 -83.152911) (xy 436.517491 -83.211203)
			(xy 436.470523 -83.26422) (xy 436.417506 -83.311188) (xy 436.359214 -83.351424) (xy 436.296497 -83.384339)
			(xy 436.23027 -83.409453) (xy 436.161498 -83.426402) (xy 436.091185 -83.434936) (xy 436.05577 -83.435444)
			(xy 435.859174 -83.435444) (xy 435.853163 -83.435608) (xy 435.841477 -83.438424) (xy 435.83606 -83.441032)
			(xy 435.832588 -83.442874) (xy 435.826213 -83.447471) (xy 435.82336 -83.450176) (xy 435.734714 -83.538822)
			(xy 435.734024 -83.544985) (xy 435.735315 -83.557315) (xy 435.737254 -83.563206) (xy 435.752748 -83.606386)
			(xy 435.752748 -83.606894) (xy 435.76875 -83.650836) (xy 435.770007 -83.654142) (xy 435.773322 -83.660388)
			(xy 435.775354 -83.663282) (xy 435.779418 -83.668616) (xy 435.782212 -83.670648) (xy 435.808374 -83.67268)
			(xy 435.841763 -83.675922) (xy 435.907544 -83.68908) (xy 435.971393 -83.709663) (xy 436.032474 -83.737403)
			(xy 436.089988 -83.771936) (xy 436.143183 -83.81281) (xy 436.191362 -83.859491) (xy 436.233896 -83.911368)
			(xy 436.270228 -83.967763) (xy 436.299882 -84.027938) (xy 436.322472 -84.091105) (xy 436.3377 -84.156439)
			(xy 436.345369 -84.223084) (xy 436.345838 -84.256626) (xy 436.345838 -84.263992) (xy 436.34533 -84.275168)
			(xy 436.343633 -84.311945) (xy 436.332137 -84.384666) (xy 436.311612 -84.45537) (xy 436.282382 -84.522943)
			(xy 436.244909 -84.586317) (xy 436.199785 -84.644491) (xy 436.174134 -84.6709) (xy 435.011576 -85.833458)
			(xy 435.008866 -85.836306) (xy 435.004265 -85.842681) (xy 435.002432 -85.846158) (xy 434.999849 -85.851585)
			(xy 434.997027 -85.863265) (xy 434.996844 -85.869272) (xy 434.996844 -86.800944) (xy 434.998622 -86.803484)
			(xy 435.036214 -86.81212) (xy 435.051521 -86.815729) (xy 435.081763 -86.824369) (xy 435.096666 -86.829392)
			(xy 435.098698 -86.8299) (xy 435.101238 -86.830916) (xy 435.10327 -86.831678) (xy 435.108858 -86.83371)
			(xy 435.130956 -86.841838) (xy 435.142386 -86.836504) (xy 435.173882 -86.81466) (xy 435.17439 -86.81466)
			(xy 435.215538 -86.78545) (xy 435.224936 -86.775798) (xy 435.224936 -86.641178) (xy 435.225414 -86.6083)
			(xy 435.232805 -86.542961) (xy 435.247458 -86.478859) (xy 435.26919 -86.416798) (xy 435.297728 -86.357557)
			(xy 435.332713 -86.301881) (xy 435.373707 -86.250467) (xy 435.39664 -86.226904) (xy 435.431692 -86.191852)
			(xy 435.45528 -86.168918) (xy 435.506719 -86.127901) (xy 435.562428 -86.0929) (xy 435.621705 -86.064357)
			(xy 435.683805 -86.04263) (xy 435.747947 -86.027993) (xy 435.813324 -86.020629) (xy 435.84622 -86.020148)
			(xy 435.881628 -86.020663) (xy 435.951928 -86.029203) (xy 436.020686 -86.046157) (xy 436.086897 -86.071276)
			(xy 436.149598 -86.104195) (xy 436.207872 -86.144434) (xy 436.26087 -86.191404) (xy 436.307818 -86.244422)
			(xy 436.348032 -86.302713) (xy 436.380925 -86.365427) (xy 436.406016 -86.43165) (xy 436.422941 -86.500414)
			(xy 436.431452 -86.570717) (xy 436.431944 -86.606126) (xy 436.431523 -86.638781) (xy 436.424321 -86.703692)
			(xy 436.409952 -86.767402) (xy 436.399686 -86.798404) (xy 436.396892 -86.806532) (xy 436.396892 -92.50934)
			(xy 436.40629 -92.518992) (xy 436.410354 -92.52204) (xy 436.47741 -92.570808) (xy 436.481697 -92.57339)
			(xy 436.491037 -92.576978) (xy 436.495952 -92.57792) (xy 436.50789 -92.579698) (xy 436.519828 -92.575888)
			(xy 436.52059 -92.575634) (xy 436.549323 -92.566681) (xy 436.608188 -92.554139) (xy 436.668043 -92.547825)
			(xy 436.698136 -92.54744) (xy 440.876182 -92.54744) (xy 440.908448 -92.547911) (xy 440.972573 -92.555166)
			(xy 441.035485 -92.569542) (xy 441.096396 -92.590859) (xy 441.154543 -92.618851) (xy 441.209197 -92.653165)
			(xy 441.259674 -92.693373) (xy 441.282836 -92.715842) (xy 441.636404 -93.06941) (xy 441.640214 -93.07195)
			(xy 441.66143 -93.087066) (xy 441.701368 -93.120516) (xy 441.71997 -93.138752) (xy 442.830458 -94.24924)
			(xy 443.73622 -94.24924) (xy 443.740291 -94.193618) (xy 443.752417 -94.139181) (xy 443.77234 -94.08709)
			(xy 443.799636 -94.038455) (xy 443.833722 -93.994312) (xy 443.873871 -93.955603) (xy 443.919229 -93.923152)
			(xy 443.968829 -93.897651) (xy 444.021613 -93.879644) (xy 444.076456 -93.869514) (xy 444.13219 -93.867477)
			(xy 444.187627 -93.873577) (xy 444.241584 -93.887683) (xy 444.292913 -93.909495) (xy 444.340519 -93.938549)
			(xy 444.383387 -93.974224) (xy 444.420604 -94.015761) (xy 444.451377 -94.062274) (xy 444.475049 -94.112771)
			(xy 444.491117 -94.166178) (xy 444.499237 -94.221354) (xy 444.499746 -94.24924) (xy 444.499672 -94.253304)
			(xy 444.75222 -94.253304) (xy 444.756291 -94.197682) (xy 444.768417 -94.143245) (xy 444.78834 -94.091154)
			(xy 444.815636 -94.042519) (xy 444.849722 -93.998376) (xy 444.889871 -93.959667) (xy 444.935229 -93.927216)
			(xy 444.984829 -93.901715) (xy 445.037613 -93.883708) (xy 445.092456 -93.873578) (xy 445.14819 -93.871541)
			(xy 445.203627 -93.877641) (xy 445.257584 -93.891747) (xy 445.308913 -93.913559) (xy 445.356519 -93.942613)
			(xy 445.399387 -93.978288) (xy 445.436604 -94.019825) (xy 445.467377 -94.066338) (xy 445.491049 -94.116835)
			(xy 445.507117 -94.170242) (xy 445.515237 -94.225418) (xy 445.515746 -94.253304) (xy 445.515237 -94.28119)
			(xy 445.507117 -94.336366) (xy 445.491049 -94.389773) (xy 445.467377 -94.44027) (xy 445.436604 -94.486783)
			(xy 445.399387 -94.52832) (xy 445.356519 -94.563995) (xy 445.308913 -94.593049) (xy 445.257584 -94.614861)
			(xy 445.203627 -94.628967) (xy 445.14819 -94.635067) (xy 445.092456 -94.63303) (xy 445.037613 -94.6229)
			(xy 444.984829 -94.604893) (xy 444.935229 -94.579392) (xy 444.889871 -94.546941) (xy 444.849722 -94.508232)
			(xy 444.815636 -94.464089) (xy 444.78834 -94.415454) (xy 444.768417 -94.363363) (xy 444.756291 -94.308926)
			(xy 444.75222 -94.253304) (xy 444.499672 -94.253304) (xy 444.499237 -94.277126) (xy 444.491117 -94.332302)
			(xy 444.475049 -94.385709) (xy 444.451377 -94.436206) (xy 444.420604 -94.482719) (xy 444.383387 -94.524256)
			(xy 444.340519 -94.559931) (xy 444.292913 -94.588985) (xy 444.241584 -94.610797) (xy 444.187627 -94.624903)
			(xy 444.13219 -94.631003) (xy 444.076456 -94.628966) (xy 444.021613 -94.618836) (xy 443.968829 -94.600829)
			(xy 443.919229 -94.575328) (xy 443.873871 -94.542877) (xy 443.833722 -94.504168) (xy 443.799636 -94.460025)
			(xy 443.77234 -94.41139) (xy 443.752417 -94.359299) (xy 443.740291 -94.304862) (xy 443.73622 -94.24924)
			(xy 442.830458 -94.24924) (xy 444.081154 -95.499936) (xy 444.104052 -95.5235) (xy 444.145006 -95.574883)
			(xy 444.179955 -95.630526) (xy 444.208459 -95.689729) (xy 444.23016 -95.75175) (xy 444.244786 -95.815809)
			(xy 444.251847 -95.878378) (xy 447.420115 -95.878378) (xy 447.427868 -95.824421) (xy 447.443221 -95.772116)
			(xy 447.465861 -95.722529) (xy 447.495329 -95.676668) (xy 447.531023 -95.635468) (xy 447.572217 -95.599767)
			(xy 447.618072 -95.570292) (xy 447.667656 -95.547643) (xy 447.719958 -95.532281) (xy 447.773914 -95.524519)
			(xy 447.828426 -95.524515) (xy 447.882383 -95.532268) (xy 447.934688 -95.547622) (xy 447.984275 -95.570263)
			(xy 448.030135 -95.599731) (xy 448.071335 -95.635425) (xy 448.107035 -95.67662) (xy 448.13651 -95.722476)
			(xy 448.159158 -95.77206) (xy 448.17452 -95.824362) (xy 448.182281 -95.878318) (xy 448.182746 -95.905574)
			(xy 448.182746 -95.906082) (xy 448.182663 -95.916454) (xy 448.181521 -95.937166) (xy 448.18046 -95.947484)
			(xy 448.179401 -95.96203) (xy 448.184605 -95.990714) (xy 448.197692 -96.016765) (xy 448.217597 -96.038064)
			(xy 448.242703 -96.052882) (xy 448.27097 -96.060014) (xy 448.3001 -96.05888) (xy 448.314064 -96.054672)
			(xy 448.343673 -96.045318) (xy 448.404939 -96.035236) (xy 448.435984 -96.034606) (xy 448.436238 -96.034606)
			(xy 448.463486 -96.035119) (xy 448.517426 -96.04288) (xy 448.569712 -96.058237) (xy 448.619281 -96.08088)
			(xy 448.665123 -96.110346) (xy 448.706305 -96.146036) (xy 448.741989 -96.187224) (xy 448.771448 -96.233071)
			(xy 448.794083 -96.282643) (xy 448.809433 -96.334932) (xy 448.817185 -96.388873) (xy 448.817182 -96.443368)
			(xy 448.809424 -96.497309) (xy 448.794069 -96.549596) (xy 448.771428 -96.599166) (xy 448.741964 -96.645009)
			(xy 448.706276 -96.686193) (xy 448.66509 -96.721879) (xy 448.619245 -96.75134) (xy 448.569673 -96.773977)
			(xy 448.517385 -96.789329) (xy 448.463444 -96.797084) (xy 448.408949 -96.797084) (xy 448.355008 -96.789328)
			(xy 448.30272 -96.773975) (xy 448.253149 -96.751337) (xy 448.207305 -96.721875) (xy 448.166119 -96.686188)
			(xy 448.130432 -96.645004) (xy 448.100968 -96.59916) (xy 448.078329 -96.54959) (xy 448.062974 -96.497302)
			(xy 448.055217 -96.443362) (xy 448.05473 -96.416114) (xy 448.05473 -96.415606) (xy 448.054812 -96.405234)
			(xy 448.055955 -96.384522) (xy 448.057016 -96.374204) (xy 448.058118 -96.359659) (xy 448.052909 -96.330969)
			(xy 448.039816 -96.304914) (xy 448.019904 -96.283612) (xy 447.99479 -96.268795) (xy 447.966515 -96.261666)
			(xy 447.937378 -96.262804) (xy 447.923412 -96.267016) (xy 447.893805 -96.276375) (xy 447.832537 -96.286454)
			(xy 447.801492 -96.287082) (xy 447.801238 -96.287082) (xy 447.773982 -96.286686) (xy 447.720025 -96.278933)
			(xy 447.66772 -96.263581) (xy 447.618132 -96.240941) (xy 447.572271 -96.211474) (xy 447.531071 -96.17578)
			(xy 447.495369 -96.134586) (xy 447.465894 -96.088731) (xy 447.443244 -96.039148) (xy 447.427882 -95.986846)
			(xy 447.420119 -95.93289) (xy 447.420115 -95.878378) (xy 444.251847 -95.878378) (xy 444.252154 -95.881102)
			(xy 444.252604 -95.913956) (xy 444.252604 -95.922846) (xy 444.2531 -95.932847) (xy 444.260768 -95.951323)
			(xy 444.274919 -95.96546) (xy 444.293402 -95.97311) (xy 444.303404 -95.973646) (xy 444.318136 -95.973646)
			(xy 444.330582 -95.965772) (xy 444.35355 -95.951815) (xy 444.402573 -95.929788) (xy 444.454203 -95.914861)
			(xy 444.507418 -95.907329) (xy 444.53429 -95.906844) (xy 444.561547 -95.907306) (xy 444.615506 -95.915063)
			(xy 444.667811 -95.93042) (xy 444.717399 -95.953065) (xy 444.763259 -95.982536) (xy 444.804458 -96.018235)
			(xy 444.840158 -96.059433) (xy 444.86963 -96.105292) (xy 444.892276 -96.154879) (xy 444.907635 -96.207185)
			(xy 444.915393 -96.261143) (xy 444.915393 -96.273112) (xy 445.497964 -96.273112) (xy 445.502035 -96.21749)
			(xy 445.514161 -96.163053) (xy 445.534084 -96.110962) (xy 445.56138 -96.062327) (xy 445.595466 -96.018184)
			(xy 445.635615 -95.979475) (xy 445.680973 -95.947024) (xy 445.730573 -95.921523) (xy 445.783357 -95.903516)
			(xy 445.8382 -95.893386) (xy 445.893934 -95.891349) (xy 445.949371 -95.897449) (xy 446.003328 -95.911555)
			(xy 446.054657 -95.933367) (xy 446.102263 -95.962421) (xy 446.145131 -95.998096) (xy 446.182348 -96.039633)
			(xy 446.213121 -96.086146) (xy 446.236793 -96.136643) (xy 446.252861 -96.19005) (xy 446.260981 -96.245226)
			(xy 446.26149 -96.273112) (xy 446.260981 -96.300998) (xy 446.252861 -96.356174) (xy 446.236793 -96.409581)
			(xy 446.213121 -96.460078) (xy 446.182348 -96.506591) (xy 446.145131 -96.548128) (xy 446.102263 -96.583803)
			(xy 446.054657 -96.612857) (xy 446.003328 -96.634669) (xy 445.949371 -96.648775) (xy 445.893934 -96.654875)
			(xy 445.8382 -96.652838) (xy 445.783357 -96.642708) (xy 445.730573 -96.624701) (xy 445.680973 -96.5992)
			(xy 445.635615 -96.566749) (xy 445.595466 -96.52804) (xy 445.56138 -96.483897) (xy 445.534084 -96.435262)
			(xy 445.514161 -96.383171) (xy 445.502035 -96.328734) (xy 445.497964 -96.273112) (xy 444.915393 -96.273112)
			(xy 444.915393 -96.315657) (xy 444.907635 -96.369615) (xy 444.892276 -96.421921) (xy 444.86963 -96.471508)
			(xy 444.840158 -96.517367) (xy 444.804458 -96.558565) (xy 444.763259 -96.594264) (xy 444.717399 -96.623735)
			(xy 444.667811 -96.64638) (xy 444.615506 -96.661737) (xy 444.561547 -96.669494) (xy 444.53429 -96.66986)
			(xy 444.534036 -96.66986) (xy 444.509779 -96.669482) (xy 444.461656 -96.663325) (xy 444.414705 -96.651107)
			(xy 444.39205 -96.642428) (xy 444.380366 -96.637602) (xy 444.355474 -96.640142) (xy 444.274956 -96.694752)
			(xy 444.264984 -96.702234) (xy 444.253276 -96.724212) (xy 444.252604 -96.736662) (xy 444.252604 -96.882458)
			(xy 444.252146 -96.915313) (xy 444.244794 -96.980609) (xy 444.230177 -97.044672) (xy 444.20848 -97.106695)
			(xy 444.179975 -97.165899) (xy 444.14502 -97.22154) (xy 444.104056 -97.272917) (xy 444.081154 -97.296478)
			(xy 443.435994 -97.941638) (xy 443.412429 -97.964534) (xy 443.361045 -98.005483) (xy 443.305401 -98.040426)
			(xy 443.246198 -98.068923) (xy 443.184177 -98.090618) (xy 443.120119 -98.105237) (xy 443.054827 -98.112597)
			(xy 443.021974 -98.113088) (xy 443.02172 -98.113088) (xy 442.986321 -98.112576) (xy 442.91604 -98.104044)
			(xy 442.847299 -98.087103) (xy 442.781102 -98.061998) (xy 442.718414 -98.029097) (xy 442.660149 -97.98888)
			(xy 442.607157 -97.941932) (xy 442.56021 -97.888938) (xy 442.519994 -97.830672) (xy 442.487095 -97.767983)
			(xy 442.461993 -97.701785) (xy 442.445053 -97.633044) (xy 442.436523 -97.562763) (xy 442.435996 -97.527364)
			(xy 442.435996 -97.52711) (xy 442.436456 -97.494256) (xy 442.443811 -97.428961) (xy 442.458431 -97.364901)
			(xy 442.480131 -97.30288) (xy 442.508638 -97.243678) (xy 442.543594 -97.18804) (xy 442.58456 -97.136666)
			(xy 442.607446 -97.11309) (xy 442.888878 -96.831658) (xy 442.896184 -96.823572) (xy 442.903825 -96.803183)
			(xy 442.90361 -96.792288) (xy 442.897768 -96.704912) (xy 442.887354 -96.685862) (xy 442.878464 -96.679004)
			(xy 442.855432 -96.660841) (xy 442.814694 -96.618643) (xy 442.780891 -96.570709) (xy 442.754818 -96.518168)
			(xy 442.73709 -96.462258) (xy 442.728122 -96.404293) (xy 442.727588 -96.374966) (xy 442.727588 -96.374712)
			(xy 442.728058 -96.347587) (xy 442.735733 -96.293884) (xy 442.750943 -96.241812) (xy 442.773382 -96.192421)
			(xy 442.802597 -96.146711) (xy 442.837996 -96.105603) (xy 442.858144 -96.087438) (xy 442.866272 -96.080326)
			(xy 442.875416 -96.06153) (xy 442.87821 -95.976948) (xy 442.878069 -95.966516) (xy 442.870457 -95.947113)
			(xy 442.863478 -95.939356) (xy 442.843412 -95.91929) (xy 442.836 -95.912606) (xy 442.817567 -95.905009)
			(xy 442.797629 -95.905009) (xy 442.779196 -95.912606) (xy 442.771784 -95.91929) (xy 442.76391 -95.927164)
			(xy 442.7601 -95.937324) (xy 442.749377 -95.964074) (xy 442.721046 -96.01426) (xy 442.685493 -96.059616)
			(xy 442.643525 -96.099111) (xy 442.596097 -96.131848) (xy 442.544285 -96.157082) (xy 442.489269 -96.17424)
			(xy 442.432299 -96.182931) (xy 442.403484 -96.18345) (xy 442.40323 -96.18345) (xy 442.37334 -96.182845)
			(xy 442.314295 -96.173489) (xy 442.257425 -96.155062) (xy 442.23051 -96.142048) (xy 442.230256 -96.142048)
			(xy 442.220519 -96.137588) (xy 442.199152 -96.136459) (xy 442.179197 -96.144181) (xy 442.171328 -96.151446)
			(xy 442.106558 -96.216216) (xy 442.083005 -96.239165) (xy 442.031608 -96.280191) (xy 441.975938 -96.3152)
			(xy 441.916695 -96.343751) (xy 441.854627 -96.365484) (xy 441.790515 -96.380126) (xy 441.725166 -96.387493)
			(xy 441.692284 -96.38792) (xy 441.397644 -96.38792) (xy 441.362234 -96.387409) (xy 441.29193 -96.378875)
			(xy 441.223167 -96.361926) (xy 441.156951 -96.33681) (xy 441.094245 -96.303893) (xy 441.035966 -96.263655)
			(xy 440.982964 -96.216684) (xy 440.936012 -96.163665) (xy 440.895796 -96.105372) (xy 440.862902 -96.042654)
			(xy 440.83781 -95.976428) (xy 440.820887 -95.90766) (xy 440.812378 -95.837352) (xy 440.81192 -95.801942)
			(xy 440.812358 -95.76892) (xy 440.819758 -95.703292) (xy 440.834492 -95.638912) (xy 440.856371 -95.576597)
			(xy 440.87034 -95.546672) (xy 440.87034 -95.546418) (xy 440.873714 -95.53859) (xy 440.875583 -95.521657)
			(xy 440.871778 -95.505051) (xy 440.867546 -95.49765) (xy 440.82208 -95.424752) (xy 440.817245 -95.417608)
			(xy 440.803796 -95.406823) (xy 440.787521 -95.40114) (xy 440.7789 -95.400876) (xy 439.735722 -95.400876)
			(xy 439.726198 -95.401268) (xy 439.708464 -95.40822) (xy 439.694497 -95.421172) (xy 439.690002 -95.429578)
			(xy 439.650124 -95.511874) (xy 439.64642 -95.520565) (xy 439.644917 -95.539379) (xy 439.650298 -95.557471)
			(xy 439.655712 -95.565214) (xy 439.655966 -95.565468) (xy 439.671486 -95.585735) (xy 439.697543 -95.62963)
			(xy 439.71751 -95.676609) (xy 439.73103 -95.725832) (xy 439.737862 -95.776419) (xy 439.738262 -95.801942)
			(xy 439.737796 -95.829192) (xy 439.730034 -95.883136) (xy 439.714674 -95.935426) (xy 439.692028 -95.984998)
			(xy 439.662558 -96.030842) (xy 439.626864 -96.072026) (xy 439.585672 -96.107711) (xy 439.53982 -96.13717)
			(xy 439.490243 -96.159804) (xy 439.43795 -96.175152) (xy 439.384004 -96.182902) (xy 439.356754 -96.18345)
			(xy 439.329855 -96.182986) (xy 439.27659 -96.175422) (xy 439.224916 -96.160452) (xy 439.175858 -96.138371)
			(xy 439.130387 -96.109617) (xy 439.089407 -96.074762) (xy 439.053729 -96.034495) (xy 439.024061 -95.989616)
			(xy 439.000991 -95.941015) (xy 438.992518 -95.91548) (xy 438.992518 -95.914972) (xy 438.990473 -95.909309)
			(xy 438.984188 -95.899045) (xy 438.980072 -95.894652) (xy 438.707022 -95.621602) (xy 438.699619 -95.614768)
			(xy 438.681021 -95.607062) (xy 438.670954 -95.606616) (xy 437.797194 -95.606616) (xy 437.785957 -95.607203)
			(xy 437.765654 -95.616837) (xy 437.758078 -95.625158) (xy 437.708294 -95.68561) (xy 437.701613 -95.694643)
			(xy 437.696078 -95.716391) (xy 437.697626 -95.72752) (xy 437.697626 -95.727774) (xy 437.701063 -95.746123)
			(xy 437.704748 -95.783275) (xy 437.704992 -95.801942) (xy 437.704506 -95.829193) (xy 437.69675 -95.883141)
			(xy 437.681395 -95.935436) (xy 437.658753 -95.985013) (xy 437.629287 -96.030863) (xy 437.593596 -96.072054)
			(xy 437.552405 -96.107745) (xy 437.506555 -96.137211) (xy 437.456978 -96.159853) (xy 437.404683 -96.175208)
			(xy 437.350735 -96.182964) (xy 437.296233 -96.182964) (xy 437.242285 -96.175208) (xy 437.18999 -96.159853)
			(xy 437.140413 -96.137211) (xy 437.094563 -96.107745) (xy 437.053372 -96.072054) (xy 437.017681 -96.030863)
			(xy 436.988215 -95.985013) (xy 436.965573 -95.935436) (xy 436.950218 -95.883141) (xy 436.942462 -95.829193)
			(xy 436.941976 -95.801942) (xy 436.942239 -95.78334) (xy 436.945931 -95.746317) (xy 436.949342 -95.728028)
			(xy 436.949342 -95.72752) (xy 436.950893 -95.716393) (xy 436.945346 -95.694651) (xy 436.938674 -95.68561)
			(xy 436.88889 -95.625158) (xy 436.881293 -95.616864) (xy 436.861003 -95.60722) (xy 436.849774 -95.606616)
			(xy 436.776368 -95.606616) (xy 436.766301 -95.607045) (xy 436.747706 -95.61477) (xy 436.7403 -95.621602)
			(xy 434.408219 -97.953576) (xy 436.643016 -97.953576) (xy 436.647087 -97.897954) (xy 436.659213 -97.843517)
			(xy 436.679136 -97.791426) (xy 436.706432 -97.742791) (xy 436.740518 -97.698648) (xy 436.780667 -97.659939)
			(xy 436.826025 -97.627488) (xy 436.875625 -97.601987) (xy 436.928409 -97.58398) (xy 436.983252 -97.57385)
			(xy 437.038986 -97.571813) (xy 437.094423 -97.577913) (xy 437.14838 -97.592019) (xy 437.199709 -97.613831)
			(xy 437.247315 -97.642885) (xy 437.290183 -97.67856) (xy 437.3274 -97.720097) (xy 437.358173 -97.76661)
			(xy 437.381845 -97.817107) (xy 437.383089 -97.821242) (xy 437.957466 -97.821242) (xy 437.961537 -97.76562)
			(xy 437.973663 -97.711183) (xy 437.993586 -97.659092) (xy 438.020882 -97.610457) (xy 438.054968 -97.566314)
			(xy 438.095117 -97.527605) (xy 438.140475 -97.495154) (xy 438.190075 -97.469653) (xy 438.242859 -97.451646)
			(xy 438.297702 -97.441516) (xy 438.353436 -97.439479) (xy 438.408873 -97.445579) (xy 438.46283 -97.459685)
			(xy 438.514159 -97.481497) (xy 438.561765 -97.510551) (xy 438.604633 -97.546226) (xy 438.64185 -97.587763)
			(xy 438.672623 -97.634276) (xy 438.696295 -97.684773) (xy 438.712363 -97.73818) (xy 438.720483 -97.793356)
			(xy 438.720992 -97.821242) (xy 438.720495 -97.848447) (xy 439.22852 -97.848447) (xy 439.22852 -97.793953)
			(xy 439.236275 -97.740012) (xy 439.251628 -97.687725) (xy 439.274265 -97.638154) (xy 439.303727 -97.592309)
			(xy 439.339413 -97.551124) (xy 439.380597 -97.515437) (xy 439.42644 -97.485973) (xy 439.47601 -97.463334)
			(xy 439.528297 -97.447979) (xy 439.582237 -97.440221) (xy 439.609484 -97.439734) (xy 439.638401 -97.440251)
			(xy 439.695573 -97.448978) (xy 439.750772 -97.466236) (xy 439.802734 -97.491628) (xy 439.850268 -97.524572)
			(xy 439.892284 -97.564314) (xy 439.910474 -97.5868) (xy 439.918102 -97.595585) (xy 439.938987 -97.605781)
			(xy 439.950606 -97.606358) (xy 440.030362 -97.606358) (xy 440.041999 -97.605855) (xy 440.062909 -97.595642)
			(xy 440.070494 -97.5868) (xy 440.088688 -97.564319) (xy 440.130707 -97.524584) (xy 440.178242 -97.491645)
			(xy 440.230202 -97.466256) (xy 440.285399 -97.448999) (xy 440.342568 -97.440269) (xy 440.371484 -97.439734)
			(xy 440.398741 -97.440112) (xy 440.452699 -97.447868) (xy 440.505005 -97.463224) (xy 440.554593 -97.485868)
			(xy 440.600453 -97.515339) (xy 440.641652 -97.551037) (xy 440.677351 -97.592234) (xy 440.706824 -97.638093)
			(xy 440.72947 -97.68768) (xy 440.744829 -97.739985) (xy 440.752587 -97.793943) (xy 440.752587 -97.821242)
			(xy 441.005466 -97.821242) (xy 441.009537 -97.76562) (xy 441.021663 -97.711183) (xy 441.041586 -97.659092)
			(xy 441.068882 -97.610457) (xy 441.102968 -97.566314) (xy 441.143117 -97.527605) (xy 441.188475 -97.495154)
			(xy 441.238075 -97.469653) (xy 441.290859 -97.451646) (xy 441.345702 -97.441516) (xy 441.401436 -97.439479)
			(xy 441.456873 -97.445579) (xy 441.51083 -97.459685) (xy 441.562159 -97.481497) (xy 441.609765 -97.510551)
			(xy 441.652633 -97.546226) (xy 441.68985 -97.587763) (xy 441.720623 -97.634276) (xy 441.744295 -97.684773)
			(xy 441.760363 -97.73818) (xy 441.768483 -97.793356) (xy 441.768992 -97.821242) (xy 441.768483 -97.849128)
			(xy 441.760363 -97.904304) (xy 441.744295 -97.957711) (xy 441.720623 -98.008208) (xy 441.68985 -98.054721)
			(xy 441.652633 -98.096258) (xy 441.609765 -98.131933) (xy 441.562159 -98.160987) (xy 441.51083 -98.182799)
			(xy 441.456873 -98.196905) (xy 441.401436 -98.203005) (xy 441.345702 -98.200968) (xy 441.290859 -98.190838)
			(xy 441.238075 -98.172831) (xy 441.188475 -98.14733) (xy 441.143117 -98.114879) (xy 441.102968 -98.07617)
			(xy 441.068882 -98.032027) (xy 441.041586 -97.983392) (xy 441.021663 -97.931301) (xy 441.009537 -97.876864)
			(xy 441.005466 -97.821242) (xy 440.752587 -97.821242) (xy 440.752587 -97.848457) (xy 440.744829 -97.902415)
			(xy 440.72947 -97.95472) (xy 440.706824 -98.004307) (xy 440.677351 -98.050166) (xy 440.641652 -98.091363)
			(xy 440.600453 -98.127061) (xy 440.554593 -98.156532) (xy 440.505005 -98.179176) (xy 440.452699 -98.194532)
			(xy 440.398741 -98.202288) (xy 440.371484 -98.20275) (xy 440.342568 -98.20219) (xy 440.285398 -98.193472)
			(xy 440.2302 -98.176224) (xy 440.178237 -98.15084) (xy 440.130702 -98.117903) (xy 440.088685 -98.078167)
			(xy 440.070494 -98.055684) (xy 440.062883 -98.046881) (xy 440.041985 -98.036696) (xy 440.030362 -98.036126)
			(xy 439.950606 -98.036126) (xy 439.938975 -98.036674) (xy 439.918065 -98.046856) (xy 439.910474 -98.055684)
			(xy 439.892294 -98.078177) (xy 439.850272 -98.117912) (xy 439.802735 -98.15085) (xy 439.750772 -98.176237)
			(xy 439.695572 -98.193491) (xy 439.638401 -98.202217) (xy 439.609484 -98.20275) (xy 439.582237 -98.202179)
			(xy 439.528297 -98.194421) (xy 439.47601 -98.179066) (xy 439.42644 -98.156427) (xy 439.380597 -98.126963)
			(xy 439.339413 -98.091276) (xy 439.303727 -98.050091) (xy 439.274265 -98.004246) (xy 439.251628 -97.954675)
			(xy 439.236275 -97.902388) (xy 439.22852 -97.848447) (xy 438.720495 -97.848447) (xy 438.720483 -97.849128)
			(xy 438.712363 -97.904304) (xy 438.696295 -97.957711) (xy 438.672623 -98.008208) (xy 438.64185 -98.054721)
			(xy 438.604633 -98.096258) (xy 438.561765 -98.131933) (xy 438.514159 -98.160987) (xy 438.46283 -98.182799)
			(xy 438.408873 -98.196905) (xy 438.353436 -98.203005) (xy 438.297702 -98.200968) (xy 438.242859 -98.190838)
			(xy 438.190075 -98.172831) (xy 438.140475 -98.14733) (xy 438.095117 -98.114879) (xy 438.054968 -98.07617)
			(xy 438.020882 -98.032027) (xy 437.993586 -97.983392) (xy 437.973663 -97.931301) (xy 437.961537 -97.876864)
			(xy 437.957466 -97.821242) (xy 437.383089 -97.821242) (xy 437.397913 -97.870514) (xy 437.406033 -97.92569)
			(xy 437.406542 -97.953576) (xy 437.406033 -97.981462) (xy 437.397913 -98.036638) (xy 437.381845 -98.090045)
			(xy 437.358173 -98.140542) (xy 437.3274 -98.187055) (xy 437.290183 -98.228592) (xy 437.247315 -98.264267)
			(xy 437.199709 -98.293321) (xy 437.14838 -98.315133) (xy 437.094423 -98.329239) (xy 437.038986 -98.335339)
			(xy 436.983252 -98.333302) (xy 436.928409 -98.323172) (xy 436.875625 -98.305165) (xy 436.826025 -98.279664)
			(xy 436.780667 -98.247213) (xy 436.740518 -98.208504) (xy 436.706432 -98.164361) (xy 436.679136 -98.115726)
			(xy 436.659213 -98.063635) (xy 436.647087 -98.009198) (xy 436.643016 -97.953576) (xy 434.408219 -97.953576)
			(xy 433.818404 -98.543364) (xy 435.285894 -98.543364) (xy 435.289965 -98.487742) (xy 435.302091 -98.433305)
			(xy 435.322014 -98.381214) (xy 435.34931 -98.332579) (xy 435.383396 -98.288436) (xy 435.423545 -98.249727)
			(xy 435.468903 -98.217276) (xy 435.518503 -98.191775) (xy 435.571287 -98.173768) (xy 435.62613 -98.163638)
			(xy 435.681864 -98.161601) (xy 435.737301 -98.167701) (xy 435.791258 -98.181807) (xy 435.842587 -98.203619)
			(xy 435.890193 -98.232673) (xy 435.933061 -98.268348) (xy 435.970278 -98.309885) (xy 436.001051 -98.356398)
			(xy 436.024723 -98.406895) (xy 436.040791 -98.460302) (xy 436.048911 -98.515478) (xy 436.04942 -98.543364)
			(xy 436.048911 -98.57125) (xy 436.040791 -98.626426) (xy 436.024723 -98.679833) (xy 436.001051 -98.73033)
			(xy 435.98174 -98.759518) (xy 447.471292 -98.759518) (xy 447.471771 -98.732148) (xy 447.479586 -98.67797)
			(xy 447.495072 -98.625467) (xy 447.517911 -98.57572) (xy 447.547632 -98.529752) (xy 447.565272 -98.50882)
			(xy 447.565526 -98.508566) (xy 447.571094 -98.501467) (xy 447.577351 -98.48456) (xy 447.577718 -98.475546)
			(xy 447.577718 -98.40849) (xy 447.577362 -98.399473) (xy 447.571113 -98.382556) (xy 447.565526 -98.37547)
			(xy 447.565272 -98.37547) (xy 447.565272 -98.375216) (xy 447.547647 -98.35427) (xy 447.517918 -98.308306)
			(xy 447.495069 -98.258562) (xy 447.479569 -98.206061) (xy 447.471738 -98.151884) (xy 447.471736 -98.097143)
			(xy 447.479564 -98.042965) (xy 447.495059 -97.990464) (xy 447.517905 -97.940718) (xy 447.547631 -97.894752)
			(xy 447.565272 -97.87382) (xy 447.565526 -97.873566) (xy 447.571094 -97.866467) (xy 447.577351 -97.84956)
			(xy 447.577718 -97.840546) (xy 447.577718 -97.77349) (xy 447.577362 -97.764473) (xy 447.571113 -97.747556)
			(xy 447.565526 -97.74047) (xy 447.565272 -97.74047) (xy 447.565272 -97.740216) (xy 447.547623 -97.719292)
			(xy 447.517913 -97.673317) (xy 447.49508 -97.623567) (xy 447.479591 -97.571065) (xy 447.471765 -97.516888)
			(xy 447.471292 -97.489518) (xy 447.471778 -97.462267) (xy 447.479534 -97.408319) (xy 447.494889 -97.356024)
			(xy 447.517531 -97.306447) (xy 447.546997 -97.260597) (xy 447.582688 -97.219406) (xy 447.623879 -97.183715)
			(xy 447.669729 -97.154249) (xy 447.719306 -97.131607) (xy 447.771601 -97.116252) (xy 447.825549 -97.108496)
			(xy 447.880051 -97.108496) (xy 447.933999 -97.116252) (xy 447.986294 -97.131607) (xy 448.035871 -97.154249)
			(xy 448.081721 -97.183715) (xy 448.122912 -97.219406) (xy 448.158603 -97.260597) (xy 448.188069 -97.306447)
			(xy 448.210711 -97.356024) (xy 448.226066 -97.408319) (xy 448.233822 -97.462267) (xy 448.234308 -97.489518)
			(xy 448.233851 -97.516889) (xy 448.22603 -97.571068) (xy 448.210539 -97.623571) (xy 448.187696 -97.673318)
			(xy 448.15797 -97.719284) (xy 448.140328 -97.740216) (xy 448.140074 -97.74047) (xy 448.134491 -97.747559)
			(xy 448.128243 -97.764474) (xy 448.127882 -97.77349) (xy 448.127882 -97.840546) (xy 448.128269 -97.84956)
			(xy 448.134496 -97.866477) (xy 448.140074 -97.873566) (xy 448.140328 -97.873566) (xy 448.140328 -97.87382)
			(xy 448.157988 -97.894738) (xy 448.187716 -97.940707) (xy 448.210563 -97.990455) (xy 448.22606 -98.04296)
			(xy 448.233887 -98.097142) (xy 448.233886 -98.151886) (xy 448.226054 -98.206066) (xy 448.210553 -98.25857)
			(xy 448.187703 -98.308317) (xy 448.157972 -98.354284) (xy 448.140328 -98.375216) (xy 448.140074 -98.37547)
			(xy 448.134491 -98.382559) (xy 448.128243 -98.399474) (xy 448.127882 -98.40849) (xy 448.127882 -98.475546)
			(xy 448.128269 -98.48456) (xy 448.134496 -98.501477) (xy 448.136129 -98.503552) (xy 449.126063 -98.503552)
			(xy 449.126063 -98.449048) (xy 449.13382 -98.395098) (xy 449.149176 -98.342801) (xy 449.171818 -98.293222)
			(xy 449.201286 -98.247369) (xy 449.236979 -98.206177) (xy 449.278171 -98.170485) (xy 449.324023 -98.141017)
			(xy 449.373603 -98.118375) (xy 449.4259 -98.10302) (xy 449.47985 -98.095263) (xy 449.507102 -98.0948)
			(xy 449.533416 -98.095266) (xy 449.585545 -98.102501) (xy 449.636187 -98.116821) (xy 449.684386 -98.137953)
			(xy 449.72923 -98.1655) (xy 449.769869 -98.198938) (xy 449.788026 -98.21799) (xy 449.795537 -98.225404)
			(xy 449.814825 -98.233921) (xy 449.825364 -98.2345) (xy 449.90004 -98.2345) (xy 449.910588 -98.233952)
			(xy 449.929883 -98.22543) (xy 449.937378 -98.21799) (xy 449.955549 -98.19895) (xy 449.996176 -98.165492)
			(xy 450.041013 -98.137931) (xy 450.089211 -98.11679) (xy 450.139855 -98.102469) (xy 450.191987 -98.095241)
			(xy 450.218302 -98.0948) (xy 450.245554 -98.09527) (xy 450.299502 -98.103027) (xy 450.351798 -98.118382)
			(xy 450.401376 -98.141024) (xy 450.447227 -98.170491) (xy 450.488418 -98.206183) (xy 450.52411 -98.247374)
			(xy 450.553577 -98.293226) (xy 450.573272 -98.336354) (xy 451.149466 -98.336354) (xy 451.149948 -98.308984)
			(xy 451.157759 -98.254805) (xy 451.173244 -98.202302) (xy 451.196082 -98.152554) (xy 451.225805 -98.106587)
			(xy 451.243446 -98.085656) (xy 451.2437 -98.085402) (xy 451.249292 -98.078319) (xy 451.255535 -98.0614)
			(xy 451.255892 -98.052382) (xy 451.255892 -97.985326) (xy 451.255524 -97.97631) (xy 451.249284 -97.959393)
			(xy 451.2437 -97.952306) (xy 451.243446 -97.952306) (xy 451.243446 -97.952052) (xy 451.225759 -97.931156)
			(xy 451.196035 -97.885182) (xy 451.173191 -97.83543) (xy 451.157698 -97.782922) (xy 451.149873 -97.728738)
			(xy 451.149878 -97.673992) (xy 451.157713 -97.61981) (xy 451.173216 -97.567305) (xy 451.196068 -97.517557)
			(xy 451.225801 -97.471588) (xy 451.243446 -97.450656) (xy 451.2437 -97.450402) (xy 451.249292 -97.443319)
			(xy 451.255535 -97.4264) (xy 451.255892 -97.417382) (xy 451.255892 -97.350326) (xy 451.255524 -97.34131)
			(xy 451.249284 -97.324393) (xy 451.2437 -97.317306) (xy 451.243446 -97.317306) (xy 451.243446 -97.317052)
			(xy 451.225825 -97.296105) (xy 451.196109 -97.250137) (xy 451.173269 -97.200394) (xy 451.157774 -97.147896)
			(xy 451.149942 -97.093722) (xy 451.149466 -97.066354) (xy 451.149952 -97.039103) (xy 451.157708 -96.985155)
			(xy 451.173063 -96.93286) (xy 451.195705 -96.883283) (xy 451.225171 -96.837433) (xy 451.260862 -96.796242)
			(xy 451.302053 -96.760551) (xy 451.347903 -96.731085) (xy 451.39748 -96.708443) (xy 451.449775 -96.693088)
			(xy 451.503723 -96.685332) (xy 451.558225 -96.685332) (xy 451.612173 -96.693088) (xy 451.664468 -96.708443)
			(xy 451.714045 -96.731085) (xy 451.759895 -96.760551) (xy 451.801086 -96.796242) (xy 451.836777 -96.837433)
			(xy 451.866243 -96.883283) (xy 451.888885 -96.93286) (xy 451.90424 -96.985155) (xy 451.911996 -97.039103)
			(xy 451.912482 -97.066354) (xy 451.911993 -97.093723) (xy 451.904182 -97.147902) (xy 451.888698 -97.200405)
			(xy 451.865861 -97.250152) (xy 451.836141 -97.29612) (xy 451.818502 -97.317052) (xy 451.818248 -97.317306)
			(xy 451.812647 -97.324382) (xy 451.80641 -97.341307) (xy 451.806056 -97.350326) (xy 451.806056 -97.417382)
			(xy 451.80641 -97.426399) (xy 451.812658 -97.443317) (xy 451.818248 -97.450402) (xy 451.818502 -97.450402)
			(xy 451.818502 -97.450656) (xy 451.836096 -97.471626) (xy 451.865821 -97.517588) (xy 451.888667 -97.567328)
			(xy 451.904166 -97.619824) (xy 451.911998 -97.673997) (xy 451.912003 -97.728733) (xy 451.904181 -97.782908)
			(xy 451.888692 -97.835407) (xy 451.865854 -97.885151) (xy 451.836138 -97.931119) (xy 451.818502 -97.952052)
			(xy 451.818248 -97.952306) (xy 451.812647 -97.959382) (xy 451.80641 -97.976307) (xy 451.806056 -97.985326)
			(xy 451.806056 -98.052382) (xy 451.80641 -98.061399) (xy 451.812658 -98.078317) (xy 451.818248 -98.085402)
			(xy 451.818502 -98.085402) (xy 451.818502 -98.085656) (xy 451.836134 -98.106594) (xy 451.865847 -98.152565)
			(xy 451.888684 -98.202311) (xy 451.904177 -98.25481) (xy 451.912007 -98.308985) (xy 451.912482 -98.336354)
			(xy 451.911996 -98.363605) (xy 451.90424 -98.417553) (xy 451.888885 -98.469848) (xy 451.866243 -98.519425)
			(xy 451.836777 -98.565275) (xy 451.801086 -98.606466) (xy 451.759895 -98.642157) (xy 451.714045 -98.671623)
			(xy 451.664468 -98.694265) (xy 451.612173 -98.70962) (xy 451.558225 -98.717376) (xy 451.503723 -98.717376)
			(xy 451.449775 -98.70962) (xy 451.39748 -98.694265) (xy 451.347903 -98.671623) (xy 451.302053 -98.642157)
			(xy 451.260862 -98.606466) (xy 451.225171 -98.565275) (xy 451.195705 -98.519425) (xy 451.173063 -98.469848)
			(xy 451.157708 -98.417553) (xy 451.149952 -98.363605) (xy 451.149466 -98.336354) (xy 450.573272 -98.336354)
			(xy 450.576218 -98.342804) (xy 450.591574 -98.3951) (xy 450.59933 -98.449048) (xy 450.59933 -98.503552)
			(xy 450.591574 -98.5575) (xy 450.576218 -98.609796) (xy 450.553577 -98.659374) (xy 450.52411 -98.705226)
			(xy 450.488418 -98.746417) (xy 450.447227 -98.782109) (xy 450.401376 -98.811576) (xy 450.351798 -98.834218)
			(xy 450.299502 -98.849573) (xy 450.245554 -98.85733) (xy 450.218302 -98.857816) (xy 450.191988 -98.857342)
			(xy 450.13986 -98.850108) (xy 450.089218 -98.83579) (xy 450.041019 -98.814658) (xy 449.996175 -98.787114)
			(xy 449.955535 -98.753677) (xy 449.937378 -98.734626) (xy 449.929863 -98.727216) (xy 449.910578 -98.718696)
			(xy 449.90004 -98.718116) (xy 449.825364 -98.718116) (xy 449.814816 -98.718662) (xy 449.79552 -98.727185)
			(xy 449.788026 -98.734626) (xy 449.769856 -98.753667) (xy 449.729229 -98.787124) (xy 449.684391 -98.814685)
			(xy 449.636194 -98.835826) (xy 449.585549 -98.850146) (xy 449.533417 -98.857375) (xy 449.507102 -98.857816)
			(xy 449.47985 -98.857337) (xy 449.4259 -98.84958) (xy 449.373603 -98.834225) (xy 449.324023 -98.811583)
			(xy 449.278171 -98.782115) (xy 449.236979 -98.746423) (xy 449.201286 -98.705231) (xy 449.171818 -98.659378)
			(xy 449.149176 -98.609799) (xy 449.13382 -98.557502) (xy 449.126063 -98.503552) (xy 448.136129 -98.503552)
			(xy 448.140074 -98.508566) (xy 448.140328 -98.509074) (xy 448.151273 -98.521808) (xy 448.171114 -98.548899)
			(xy 448.179952 -98.563176) (xy 448.185286 -98.572066) (xy 448.202304 -98.584258) (xy 448.295522 -98.604578)
			(xy 448.316096 -98.60026) (xy 448.324732 -98.594418) (xy 448.348787 -98.578404) (xy 448.400722 -98.553064)
			(xy 448.455882 -98.535842) (xy 448.513009 -98.527132) (xy 448.541902 -98.5266) (xy 448.569154 -98.52707)
			(xy 448.623102 -98.534827) (xy 448.675398 -98.550182) (xy 448.724976 -98.572824) (xy 448.770827 -98.602291)
			(xy 448.812018 -98.637983) (xy 448.84771 -98.679174) (xy 448.877177 -98.725026) (xy 448.899818 -98.774604)
			(xy 448.915174 -98.8269) (xy 448.92293 -98.880848) (xy 448.92293 -98.935352) (xy 448.915174 -98.9893)
			(xy 448.899818 -99.041596) (xy 448.877177 -99.091174) (xy 448.84771 -99.137026) (xy 448.812018 -99.178217)
			(xy 448.770827 -99.213909) (xy 448.724976 -99.243376) (xy 448.675398 -99.266018) (xy 448.623102 -99.281373)
			(xy 448.569154 -99.28913) (xy 448.541902 -99.289616) (xy 448.51381 -99.28912) (xy 448.458233 -99.280893)
			(xy 448.404464 -99.264602) (xy 448.353667 -99.2406) (xy 448.30694 -99.209405) (xy 448.265295 -99.171693)
			(xy 448.229633 -99.12828) (xy 448.21475 -99.10445) (xy 448.209416 -99.09556) (xy 448.192398 -99.083368)
			(xy 448.09918 -99.063048) (xy 448.078606 -99.067366) (xy 448.06997 -99.073208) (xy 448.045916 -99.089224)
			(xy 447.993981 -99.114563) (xy 447.93882 -99.131784) (xy 447.881693 -99.140494) (xy 447.8528 -99.141026)
			(xy 447.82555 -99.140522) (xy 447.771603 -99.132766) (xy 447.71931 -99.117412) (xy 447.669734 -99.094772)
			(xy 447.623885 -99.065308) (xy 447.582695 -99.029618) (xy 447.547003 -98.98843) (xy 447.517536 -98.942582)
			(xy 447.494894 -98.893007) (xy 447.479538 -98.840714) (xy 447.471779 -98.786768) (xy 447.471292 -98.759518)
			(xy 435.98174 -98.759518) (xy 435.970278 -98.776843) (xy 435.933061 -98.81838) (xy 435.890193 -98.854055)
			(xy 435.842587 -98.883109) (xy 435.791258 -98.904921) (xy 435.737301 -98.919027) (xy 435.681864 -98.925127)
			(xy 435.62613 -98.92309) (xy 435.571287 -98.91296) (xy 435.518503 -98.894953) (xy 435.468903 -98.869452)
			(xy 435.423545 -98.837001) (xy 435.383396 -98.798292) (xy 435.34931 -98.754149) (xy 435.322014 -98.705514)
			(xy 435.302091 -98.653423) (xy 435.289965 -98.598986) (xy 435.285894 -98.543364) (xy 433.818404 -98.543364)
			(xy 432.912345 -99.449382) (xy 436.206136 -99.449382) (xy 436.210207 -99.39376) (xy 436.222333 -99.339323)
			(xy 436.242256 -99.287232) (xy 436.269552 -99.238597) (xy 436.303638 -99.194454) (xy 436.343787 -99.155745)
			(xy 436.389145 -99.123294) (xy 436.438745 -99.097793) (xy 436.491529 -99.079786) (xy 436.546372 -99.069656)
			(xy 436.602106 -99.067619) (xy 436.657543 -99.073719) (xy 436.7115 -99.087825) (xy 436.762829 -99.109637)
			(xy 436.810435 -99.138691) (xy 436.853303 -99.174366) (xy 436.89052 -99.215903) (xy 436.921293 -99.262416)
			(xy 436.944965 -99.312913) (xy 436.961033 -99.36632) (xy 436.969153 -99.421496) (xy 436.969662 -99.449382)
			(xy 436.969495 -99.458526) (xy 441.938662 -99.458526) (xy 441.942733 -99.402904) (xy 441.954859 -99.348467)
			(xy 441.974782 -99.296376) (xy 442.002078 -99.247741) (xy 442.036164 -99.203598) (xy 442.076313 -99.164889)
			(xy 442.121671 -99.132438) (xy 442.171271 -99.106937) (xy 442.224055 -99.08893) (xy 442.278898 -99.0788)
			(xy 442.334632 -99.076763) (xy 442.390069 -99.082863) (xy 442.444026 -99.096969) (xy 442.495355 -99.118781)
			(xy 442.542961 -99.147835) (xy 442.585829 -99.18351) (xy 442.623046 -99.225047) (xy 442.653819 -99.27156)
			(xy 442.677491 -99.322057) (xy 442.693559 -99.375464) (xy 442.701679 -99.43064) (xy 442.702188 -99.458526)
			(xy 442.701679 -99.486412) (xy 442.693559 -99.541588) (xy 442.677491 -99.594995) (xy 442.653819 -99.645492)
			(xy 442.623046 -99.692005) (xy 442.585829 -99.733542) (xy 442.542961 -99.769217) (xy 442.495355 -99.798271)
			(xy 442.444026 -99.820083) (xy 442.390069 -99.834189) (xy 442.334632 -99.840289) (xy 442.278898 -99.838252)
			(xy 442.224055 -99.828122) (xy 442.171271 -99.810115) (xy 442.121671 -99.784614) (xy 442.076313 -99.752163)
			(xy 442.036164 -99.713454) (xy 442.002078 -99.669311) (xy 441.974782 -99.620676) (xy 441.954859 -99.568585)
			(xy 441.942733 -99.514148) (xy 441.938662 -99.458526) (xy 436.969495 -99.458526) (xy 436.969153 -99.477268)
			(xy 436.961033 -99.532444) (xy 436.944965 -99.585851) (xy 436.921293 -99.636348) (xy 436.89052 -99.682861)
			(xy 436.853303 -99.724398) (xy 436.810435 -99.760073) (xy 436.762829 -99.789127) (xy 436.7115 -99.810939)
			(xy 436.657543 -99.825045) (xy 436.602106 -99.831145) (xy 436.546372 -99.829108) (xy 436.491529 -99.818978)
			(xy 436.438745 -99.800971) (xy 436.389145 -99.77547) (xy 436.343787 -99.743019) (xy 436.303638 -99.70431)
			(xy 436.269552 -99.660167) (xy 436.242256 -99.611532) (xy 436.222333 -99.559441) (xy 436.210207 -99.505004)
			(xy 436.206136 -99.449382) (xy 432.912345 -99.449382) (xy 431.182018 -101.17963) (xy 431.175174 -101.187029)
			(xy 431.174002 -101.18985) (xy 445.29349 -101.18985) (xy 445.29349 -101.13535) (xy 445.301246 -101.081404)
			(xy 445.316601 -101.029111) (xy 445.339241 -100.979536) (xy 445.368706 -100.933687) (xy 445.404396 -100.892499)
			(xy 445.445584 -100.856808) (xy 445.491433 -100.827343) (xy 445.541008 -100.804702) (xy 445.5933 -100.789347)
			(xy 445.647246 -100.781591) (xy 445.674496 -100.781104) (xy 445.701866 -100.781571) (xy 445.756045 -100.789389)
			(xy 445.808548 -100.804877) (xy 445.858295 -100.827719) (xy 445.904262 -100.857443) (xy 445.925194 -100.875084)
			(xy 445.925448 -100.875338) (xy 445.932542 -100.880913) (xy 445.949453 -100.887166) (xy 445.958468 -100.88753)
			(xy 446.025524 -100.88753) (xy 446.034541 -100.887178) (xy 446.051458 -100.880926) (xy 446.058544 -100.875338)
			(xy 446.058544 -100.875084) (xy 446.058798 -100.875084) (xy 446.079718 -100.85743) (xy 446.125694 -100.827721)
			(xy 446.175445 -100.804888) (xy 446.227948 -100.7894) (xy 446.282126 -100.781576) (xy 446.309496 -100.781104)
			(xy 446.33675 -100.781543) (xy 446.390703 -100.789299) (xy 446.443003 -100.804656) (xy 446.492585 -100.827299)
			(xy 446.53844 -100.856767) (xy 446.579635 -100.892462) (xy 446.61533 -100.933656) (xy 446.6448 -100.979511)
			(xy 446.667443 -101.029093) (xy 446.6828 -101.081393) (xy 446.690557 -101.135346) (xy 446.690557 -101.189854)
			(xy 446.6828 -101.243807) (xy 446.667443 -101.296107) (xy 446.6448 -101.345689) (xy 446.61533 -101.391544)
			(xy 446.579635 -101.432738) (xy 446.53844 -101.468433) (xy 446.492585 -101.497901) (xy 446.443003 -101.520544)
			(xy 446.390703 -101.535901) (xy 446.33675 -101.543657) (xy 446.309496 -101.54412) (xy 446.282125 -101.543676)
			(xy 446.227944 -101.535856) (xy 446.17544 -101.520363) (xy 446.125693 -101.497515) (xy 446.079728 -101.467785)
			(xy 446.058798 -101.45014) (xy 446.058544 -101.449886) (xy 446.05145 -101.44431) (xy 446.034539 -101.438057)
			(xy 446.025524 -101.437694) (xy 445.958468 -101.437694) (xy 445.94945 -101.438037) (xy 445.932533 -101.444295)
			(xy 445.925448 -101.449886) (xy 445.925448 -101.45014) (xy 445.925194 -101.45014) (xy 445.90428 -101.467802)
			(xy 445.858302 -101.497509) (xy 445.80855 -101.52034) (xy 445.756045 -101.535826) (xy 445.701866 -101.543649)
			(xy 445.674496 -101.54412) (xy 445.647246 -101.543609) (xy 445.5933 -101.535853) (xy 445.541008 -101.520498)
			(xy 445.491433 -101.497857) (xy 445.445584 -101.468392) (xy 445.404396 -101.432701) (xy 445.368706 -101.391513)
			(xy 445.339241 -101.345664) (xy 445.316601 -101.296089) (xy 445.301246 -101.243796) (xy 445.29349 -101.18985)
			(xy 431.174002 -101.18985) (xy 431.167448 -101.205628) (xy 431.167032 -101.215698) (xy 431.167032 -101.579172)
			(xy 436.070754 -101.579172) (xy 436.074825 -101.52355) (xy 436.086951 -101.469113) (xy 436.106874 -101.417022)
			(xy 436.13417 -101.368387) (xy 436.168256 -101.324244) (xy 436.208405 -101.285535) (xy 436.253763 -101.253084)
			(xy 436.303363 -101.227583) (xy 436.356147 -101.209576) (xy 436.41099 -101.199446) (xy 436.466724 -101.197409)
			(xy 436.522161 -101.203509) (xy 436.576118 -101.217615) (xy 436.627447 -101.239427) (xy 436.675053 -101.268481)
			(xy 436.717921 -101.304156) (xy 436.755138 -101.345693) (xy 436.785911 -101.392206) (xy 436.809583 -101.442703)
			(xy 436.825651 -101.49611) (xy 436.833771 -101.551286) (xy 436.83428 -101.579172) (xy 436.833771 -101.607058)
			(xy 436.825651 -101.662234) (xy 436.809583 -101.715641) (xy 436.785911 -101.766138) (xy 436.755138 -101.812651)
			(xy 436.717921 -101.854188) (xy 436.698003 -101.870764) (xy 441.53912 -101.870764) (xy 441.543191 -101.815142)
			(xy 441.555317 -101.760705) (xy 441.57524 -101.708614) (xy 441.602536 -101.659979) (xy 441.636622 -101.615836)
			(xy 441.676771 -101.577127) (xy 441.722129 -101.544676) (xy 441.771729 -101.519175) (xy 441.824513 -101.501168)
			(xy 441.879356 -101.491038) (xy 441.93509 -101.489001) (xy 441.990527 -101.495101) (xy 442.044484 -101.509207)
			(xy 442.095813 -101.531019) (xy 442.143419 -101.560073) (xy 442.186287 -101.595748) (xy 442.223504 -101.637285)
			(xy 442.254277 -101.683798) (xy 442.277949 -101.734295) (xy 442.294017 -101.787702) (xy 442.302137 -101.842878)
			(xy 442.302646 -101.870764) (xy 442.302137 -101.89865) (xy 442.294017 -101.953826) (xy 442.277949 -102.007233)
			(xy 442.254277 -102.05773) (xy 442.223504 -102.104243) (xy 442.200022 -102.130451) (xy 444.843152 -102.130451)
			(xy 444.843152 -102.075949) (xy 444.850908 -102.022002) (xy 444.866261 -101.969707) (xy 444.888901 -101.920129)
			(xy 444.918365 -101.874278) (xy 444.954054 -101.833086) (xy 444.995241 -101.797392) (xy 445.041089 -101.767923)
			(xy 445.090664 -101.745277) (xy 445.142957 -101.729917) (xy 445.196903 -101.722155) (xy 445.224154 -101.721666)
			(xy 445.251524 -101.722143) (xy 445.305703 -101.729956) (xy 445.358207 -101.745441) (xy 445.407954 -101.768281)
			(xy 445.453921 -101.798005) (xy 445.474852 -101.815646) (xy 445.475106 -101.8159) (xy 445.482187 -101.821495)
			(xy 445.499108 -101.827737) (xy 445.508126 -101.828092) (xy 445.575182 -101.828092) (xy 445.584198 -101.827728)
			(xy 445.601115 -101.821486) (xy 445.608202 -101.8159) (xy 445.608202 -101.815646) (xy 445.608456 -101.815646)
			(xy 445.6294 -101.798021) (xy 445.675369 -101.768306) (xy 445.725113 -101.745466) (xy 445.777611 -101.729972)
			(xy 445.831786 -101.722141) (xy 445.859154 -101.721666) (xy 445.886407 -101.722178) (xy 445.940359 -101.729929)
			(xy 445.992659 -101.74528) (xy 446.042242 -101.767919) (xy 446.088097 -101.797383) (xy 446.129293 -101.833075)
			(xy 446.164989 -101.874266) (xy 446.194459 -101.920118) (xy 446.217104 -101.969698) (xy 446.232461 -102.021996)
			(xy 446.240219 -102.075947) (xy 446.240219 -102.130453) (xy 446.232461 -102.184404) (xy 446.217104 -102.236702)
			(xy 446.194459 -102.286282) (xy 446.164989 -102.332134) (xy 446.129293 -102.373325) (xy 446.088097 -102.409017)
			(xy 446.042242 -102.438481) (xy 445.992659 -102.46112) (xy 445.940359 -102.476471) (xy 445.886407 -102.484222)
			(xy 445.859154 -102.484682) (xy 445.831785 -102.484189) (xy 445.777607 -102.476378) (xy 445.725104 -102.460896)
			(xy 445.675356 -102.43806) (xy 445.629388 -102.408341) (xy 445.608456 -102.390702) (xy 445.608202 -102.390448)
			(xy 445.601124 -102.38485) (xy 445.5842 -102.378611) (xy 445.575182 -102.378256) (xy 445.508126 -102.378256)
			(xy 445.499109 -102.378613) (xy 445.482191 -102.384859) (xy 445.475106 -102.390448) (xy 445.475106 -102.390702)
			(xy 445.474852 -102.390702) (xy 445.453911 -102.40833) (xy 445.407941 -102.438044) (xy 445.358196 -102.460882)
			(xy 445.305697 -102.476375) (xy 445.251523 -102.484206) (xy 445.224154 -102.484682) (xy 445.196903 -102.484245)
			(xy 445.142957 -102.476483) (xy 445.090664 -102.461123) (xy 445.041089 -102.438477) (xy 444.995241 -102.409008)
			(xy 444.954054 -102.373314) (xy 444.918365 -102.332122) (xy 444.888901 -102.286271) (xy 444.866261 -102.236693)
			(xy 444.850908 -102.184398) (xy 444.843152 -102.130451) (xy 442.200022 -102.130451) (xy 442.186287 -102.14578)
			(xy 442.143419 -102.181455) (xy 442.095813 -102.210509) (xy 442.044484 -102.232321) (xy 441.990527 -102.246427)
			(xy 441.93509 -102.252527) (xy 441.879356 -102.25049) (xy 441.824513 -102.24036) (xy 441.771729 -102.222353)
			(xy 441.722129 -102.196852) (xy 441.676771 -102.164401) (xy 441.636622 -102.125692) (xy 441.602536 -102.081549)
			(xy 441.57524 -102.032914) (xy 441.555317 -101.980823) (xy 441.543191 -101.926386) (xy 441.53912 -101.870764)
			(xy 436.698003 -101.870764) (xy 436.675053 -101.889863) (xy 436.627447 -101.918917) (xy 436.576118 -101.940729)
			(xy 436.522161 -101.954835) (xy 436.466724 -101.960935) (xy 436.41099 -101.958898) (xy 436.356147 -101.948768)
			(xy 436.303363 -101.930761) (xy 436.253763 -101.90526) (xy 436.208405 -101.872809) (xy 436.168256 -101.8341)
			(xy 436.13417 -101.789957) (xy 436.106874 -101.741322) (xy 436.086951 -101.689231) (xy 436.074825 -101.634794)
			(xy 436.070754 -101.579172) (xy 431.167032 -101.579172) (xy 431.167032 -103.13924) (xy 437.807098 -103.13924)
			(xy 437.811169 -103.083618) (xy 437.823295 -103.029181) (xy 437.843218 -102.97709) (xy 437.870514 -102.928455)
			(xy 437.9046 -102.884312) (xy 437.944749 -102.845603) (xy 437.990107 -102.813152) (xy 438.039707 -102.787651)
			(xy 438.092491 -102.769644) (xy 438.147334 -102.759514) (xy 438.203068 -102.757477) (xy 438.258505 -102.763577)
			(xy 438.312462 -102.777683) (xy 438.363791 -102.799495) (xy 438.411397 -102.828549) (xy 438.454265 -102.864224)
			(xy 438.491482 -102.905761) (xy 438.522255 -102.952274) (xy 438.545927 -103.002771) (xy 438.561995 -103.056178)
			(xy 438.570115 -103.111354) (xy 438.570624 -103.13924) (xy 438.570115 -103.167126) (xy 438.561995 -103.222302)
			(xy 438.545927 -103.275709) (xy 438.522255 -103.326206) (xy 438.491482 -103.372719) (xy 438.454265 -103.414256)
			(xy 438.411397 -103.449931) (xy 438.363791 -103.478985) (xy 438.312462 -103.500797) (xy 438.258505 -103.514903)
			(xy 438.203068 -103.521003) (xy 438.147334 -103.518966) (xy 438.092491 -103.508836) (xy 438.039707 -103.490829)
			(xy 437.990107 -103.465328) (xy 437.944749 -103.432877) (xy 437.9046 -103.394168) (xy 437.870514 -103.350025)
			(xy 437.843218 -103.30139) (xy 437.823295 -103.249299) (xy 437.811169 -103.194862) (xy 437.807098 -103.13924)
			(xy 431.167032 -103.13924) (xy 431.167032 -104.674924) (xy 436.859424 -104.674924) (xy 436.863495 -104.619302)
			(xy 436.875621 -104.564865) (xy 436.895544 -104.512774) (xy 436.92284 -104.464139) (xy 436.956926 -104.419996)
			(xy 436.997075 -104.381287) (xy 437.042433 -104.348836) (xy 437.092033 -104.323335) (xy 437.144817 -104.305328)
			(xy 437.19966 -104.295198) (xy 437.255394 -104.293161) (xy 437.310831 -104.299261) (xy 437.364788 -104.313367)
			(xy 437.416117 -104.335179) (xy 437.463723 -104.364233) (xy 437.506591 -104.399908) (xy 437.543808 -104.441445)
			(xy 437.574581 -104.487958) (xy 437.598253 -104.538455) (xy 437.614321 -104.591862) (xy 437.622441 -104.647038)
			(xy 437.62295 -104.674924) (xy 437.622441 -104.70281) (xy 437.614321 -104.757986) (xy 437.598253 -104.811393)
			(xy 437.574581 -104.86189) (xy 437.543808 -104.908403) (xy 437.506591 -104.94994) (xy 437.463723 -104.985615)
			(xy 437.416117 -105.014669) (xy 437.364788 -105.036481) (xy 437.310831 -105.050587) (xy 437.255394 -105.056687)
			(xy 437.19966 -105.05465) (xy 437.144817 -105.04452) (xy 437.092033 -105.026513) (xy 437.042433 -105.001012)
			(xy 436.997075 -104.968561) (xy 436.956926 -104.929852) (xy 436.92284 -104.885709) (xy 436.895544 -104.837074)
			(xy 436.875621 -104.784983) (xy 436.863495 -104.730546) (xy 436.859424 -104.674924) (xy 431.167032 -104.674924)
			(xy 431.167032 -107.058206) (xy 437.873902 -107.058206) (xy 437.874429 -107.029467) (xy 437.883051 -106.97264)
			(xy 437.9001 -106.917749) (xy 437.925191 -106.866037) (xy 437.957755 -106.818675) (xy 437.977026 -106.797348)
			(xy 437.98363 -106.79049) (xy 437.990742 -106.772456) (xy 437.990742 -106.683556) (xy 437.98363 -106.665522)
			(xy 437.977026 -106.658664) (xy 437.957761 -106.637332) (xy 437.925195 -106.589971) (xy 437.900103 -106.53826)
			(xy 437.883053 -106.48337) (xy 437.87443 -106.426543) (xy 437.874429 -106.369066) (xy 437.883051 -106.312239)
			(xy 437.9001 -106.257349) (xy 437.925191 -106.205637) (xy 437.957756 -106.158275) (xy 437.977026 -106.136948)
			(xy 437.98363 -106.13009) (xy 437.990742 -106.112056) (xy 437.990742 -106.023156) (xy 437.98363 -106.005122)
			(xy 437.977026 -105.998264) (xy 437.957756 -105.976936) (xy 437.92519 -105.929574) (xy 437.900098 -105.877863)
			(xy 437.883047 -105.822972) (xy 437.874423 -105.766145) (xy 437.873902 -105.737406) (xy 437.874388 -105.710155)
			(xy 437.882144 -105.656207) (xy 437.897499 -105.603912) (xy 437.920141 -105.554335) (xy 437.949607 -105.508485)
			(xy 437.985298 -105.467294) (xy 438.026489 -105.431603) (xy 438.072339 -105.402137) (xy 438.121916 -105.379495)
			(xy 438.174211 -105.36414) (xy 438.228159 -105.356384) (xy 438.282661 -105.356384) (xy 438.336609 -105.36414)
			(xy 438.388904 -105.379495) (xy 438.438481 -105.402137) (xy 438.484331 -105.431603) (xy 438.525522 -105.467294)
			(xy 438.561213 -105.508485) (xy 438.590679 -105.554335) (xy 438.613321 -105.603912) (xy 438.628676 -105.656207)
			(xy 438.636432 -105.710155) (xy 438.636918 -105.737406) (xy 438.636393 -105.766145) (xy 438.62777 -105.822972)
			(xy 438.61072 -105.877862) (xy 438.585629 -105.929574) (xy 438.553064 -105.976937) (xy 438.533794 -105.998264)
			(xy 438.52719 -106.005122) (xy 438.520078 -106.023156) (xy 438.520078 -106.112056) (xy 438.52719 -106.13009)
			(xy 438.533794 -106.136948) (xy 438.55307 -106.15827) (xy 438.585633 -106.205634) (xy 438.610724 -106.257346)
			(xy 438.627772 -106.312238) (xy 438.636394 -106.369065) (xy 438.636393 -106.426543) (xy 438.62777 -106.483371)
			(xy 438.61072 -106.538262) (xy 438.585629 -106.589974) (xy 438.553064 -106.637337) (xy 438.533794 -106.658664)
			(xy 438.52719 -106.665522) (xy 438.520078 -106.683556) (xy 438.520078 -106.772456) (xy 438.52719 -106.79049)
			(xy 438.533794 -106.797348) (xy 438.553056 -106.818683) (xy 438.585626 -106.866042) (xy 438.610721 -106.917751)
			(xy 438.627773 -106.972641) (xy 438.636397 -107.029467) (xy 438.636918 -107.058206) (xy 438.636432 -107.085457)
			(xy 438.628676 -107.139405) (xy 438.613321 -107.1917) (xy 438.590679 -107.241277) (xy 438.561213 -107.287127)
			(xy 438.525522 -107.328318) (xy 438.484331 -107.364009) (xy 438.438481 -107.393475) (xy 438.388904 -107.416117)
			(xy 438.336609 -107.431472) (xy 438.282661 -107.439228) (xy 438.228159 -107.439228) (xy 438.174211 -107.431472)
			(xy 438.121916 -107.416117) (xy 438.072339 -107.393475) (xy 438.026489 -107.364009) (xy 437.985298 -107.328318)
			(xy 437.949607 -107.287127) (xy 437.920141 -107.241277) (xy 437.897499 -107.1917) (xy 437.882144 -107.139405)
			(xy 437.874388 -107.085457) (xy 437.873902 -107.058206) (xy 431.167032 -107.058206) (xy 431.167032 -107.506516)
			(xy 431.167459 -107.516584) (xy 431.175181 -107.535182) (xy 431.182018 -107.542584) (xy 432.01844 -108.379006)
			(xy 438.762902 -108.379006) (xy 438.763429 -108.350267) (xy 438.772051 -108.29344) (xy 438.7891 -108.238549)
			(xy 438.814191 -108.186837) (xy 438.846755 -108.139475) (xy 438.866026 -108.118148) (xy 438.87263 -108.11129)
			(xy 438.879742 -108.093256) (xy 438.879742 -108.004356) (xy 438.87263 -107.986322) (xy 438.866026 -107.979464)
			(xy 438.846761 -107.958132) (xy 438.814195 -107.910771) (xy 438.789103 -107.85906) (xy 438.772053 -107.80417)
			(xy 438.76343 -107.747343) (xy 438.763429 -107.689866) (xy 438.772051 -107.633039) (xy 438.7891 -107.578149)
			(xy 438.814191 -107.526437) (xy 438.846756 -107.479075) (xy 438.866026 -107.457748) (xy 438.87263 -107.45089)
			(xy 438.879742 -107.432856) (xy 438.879742 -107.343956) (xy 438.87263 -107.325922) (xy 438.866026 -107.319064)
			(xy 438.846761 -107.297732) (xy 438.814195 -107.250371) (xy 438.789103 -107.19866) (xy 438.772053 -107.14377)
			(xy 438.76343 -107.086943) (xy 438.763429 -107.029466) (xy 438.772051 -106.972639) (xy 438.7891 -106.917749)
			(xy 438.814191 -106.866037) (xy 438.846756 -106.818675) (xy 438.866026 -106.797348) (xy 438.87263 -106.79049)
			(xy 438.879742 -106.772456) (xy 438.879742 -106.683556) (xy 438.87263 -106.665522) (xy 438.866026 -106.658664)
			(xy 438.846761 -106.637332) (xy 438.814195 -106.589971) (xy 438.789103 -106.53826) (xy 438.772053 -106.48337)
			(xy 438.76343 -106.426543) (xy 438.763429 -106.369066) (xy 438.772051 -106.312239) (xy 438.7891 -106.257349)
			(xy 438.814191 -106.205637) (xy 438.846756 -106.158275) (xy 438.866026 -106.136948) (xy 438.87263 -106.13009)
			(xy 438.879742 -106.112056) (xy 438.879742 -106.023156) (xy 438.87263 -106.005122) (xy 438.866026 -105.998264)
			(xy 438.846761 -105.976932) (xy 438.814195 -105.929571) (xy 438.789103 -105.87786) (xy 438.772053 -105.82297)
			(xy 438.76343 -105.766143) (xy 438.763429 -105.708666) (xy 438.772051 -105.651839) (xy 438.7891 -105.596949)
			(xy 438.814191 -105.545237) (xy 438.846756 -105.497875) (xy 438.866026 -105.476548) (xy 438.87263 -105.46969)
			(xy 438.879742 -105.451656) (xy 438.879742 -105.362756) (xy 438.87263 -105.344722) (xy 438.866026 -105.337864)
			(xy 438.846761 -105.316532) (xy 438.814195 -105.269171) (xy 438.789103 -105.21746) (xy 438.772053 -105.16257)
			(xy 438.76343 -105.105743) (xy 438.763429 -105.048266) (xy 438.772051 -104.991439) (xy 438.7891 -104.936549)
			(xy 438.814191 -104.884837) (xy 438.846756 -104.837475) (xy 438.866026 -104.816148) (xy 438.87263 -104.80929)
			(xy 438.879742 -104.791256) (xy 438.879742 -104.702356) (xy 438.87263 -104.684322) (xy 438.866026 -104.677464)
			(xy 438.846761 -104.656132) (xy 438.814195 -104.608771) (xy 438.789103 -104.55706) (xy 438.772053 -104.50217)
			(xy 438.76343 -104.445343) (xy 438.763429 -104.387866) (xy 438.772051 -104.331039) (xy 438.7891 -104.276149)
			(xy 438.814191 -104.224437) (xy 438.846756 -104.177075) (xy 438.866026 -104.155748) (xy 438.87263 -104.14889)
			(xy 438.879742 -104.130856) (xy 438.879742 -104.041956) (xy 438.87263 -104.023922) (xy 438.866026 -104.017064)
			(xy 438.846761 -103.995732) (xy 438.814195 -103.948371) (xy 438.789103 -103.89666) (xy 438.772053 -103.84177)
			(xy 438.76343 -103.784943) (xy 438.763429 -103.727466) (xy 438.772051 -103.670639) (xy 438.7891 -103.615749)
			(xy 438.814191 -103.564037) (xy 438.846756 -103.516675) (xy 438.866026 -103.495348) (xy 438.87263 -103.48849)
			(xy 438.879742 -103.470456) (xy 438.879742 -103.381556) (xy 438.87263 -103.363522) (xy 438.866026 -103.356664)
			(xy 438.846756 -103.335336) (xy 438.81419 -103.287974) (xy 438.789098 -103.236263) (xy 438.772047 -103.181372)
			(xy 438.763423 -103.124545) (xy 438.762902 -103.095806) (xy 438.763344 -103.068599) (xy 438.771069 -103.014735)
			(xy 438.786375 -102.962517) (xy 438.808953 -102.913008) (xy 438.838342 -102.867212) (xy 438.873946 -102.826063)
			(xy 438.915041 -102.790395) (xy 438.937654 -102.775258) (xy 438.946036 -102.769924) (xy 438.957212 -102.753668)
			(xy 438.9755 -102.674674) (xy 438.977308 -102.665045) (xy 438.974311 -102.645703) (xy 438.969658 -102.637082)
			(xy 438.969404 -102.637082) (xy 438.969404 -102.636574) (xy 438.956199 -102.614063) (xy 438.935343 -102.566221)
			(xy 438.921193 -102.515987) (xy 438.914009 -102.464294) (xy 438.913524 -102.4382) (xy 438.91401 -102.410949)
			(xy 438.921766 -102.357001) (xy 438.937121 -102.304706) (xy 438.959763 -102.255129) (xy 438.989229 -102.209279)
			(xy 439.02492 -102.168088) (xy 439.066111 -102.132397) (xy 439.111961 -102.102931) (xy 439.161538 -102.080289)
			(xy 439.213833 -102.064934) (xy 439.267781 -102.057178) (xy 439.322283 -102.057178) (xy 439.376231 -102.064934)
			(xy 439.428526 -102.080289) (xy 439.478103 -102.102931) (xy 439.523953 -102.132397) (xy 439.565144 -102.168088)
			(xy 439.600835 -102.209279) (xy 439.630301 -102.255129) (xy 439.652943 -102.304706) (xy 439.668298 -102.357001)
			(xy 439.676054 -102.410949) (xy 439.67654 -102.4382) (xy 439.676083 -102.465407) (xy 439.668359 -102.519269)
			(xy 439.653054 -102.571485) (xy 439.630478 -102.620994) (xy 439.601091 -102.666789) (xy 439.56549 -102.70794)
			(xy 439.524399 -102.743609) (xy 439.501788 -102.758748) (xy 439.493406 -102.764082) (xy 439.48223 -102.780338)
			(xy 439.463942 -102.859332) (xy 439.462138 -102.868962) (xy 439.465134 -102.888302) (xy 439.469784 -102.896924)
			(xy 439.470038 -102.896924) (xy 439.470038 -102.897432) (xy 439.48325 -102.919939) (xy 439.504103 -102.967783)
			(xy 439.518251 -103.018018) (xy 439.525433 -103.069712) (xy 439.525918 -103.095806) (xy 439.525393 -103.124545)
			(xy 439.51677 -103.181372) (xy 439.49972 -103.236262) (xy 439.474629 -103.287974) (xy 439.442064 -103.335337)
			(xy 439.422794 -103.356664) (xy 439.41619 -103.363522) (xy 439.409078 -103.381556) (xy 439.409078 -103.470456)
			(xy 439.41619 -103.48849) (xy 439.422794 -103.495348) (xy 439.44207 -103.51667) (xy 439.474633 -103.564034)
			(xy 439.499724 -103.615746) (xy 439.516772 -103.670638) (xy 439.525394 -103.727465) (xy 439.525393 -103.784943)
			(xy 439.51677 -103.841771) (xy 439.49972 -103.896662) (xy 439.474629 -103.948374) (xy 439.442064 -103.995737)
			(xy 439.422794 -104.017064) (xy 439.417168 -104.022906) (xy 444.16599 -104.022906) (xy 444.166465 -103.996592)
			(xy 444.173698 -103.944464) (xy 444.188016 -103.893822) (xy 444.209147 -103.845623) (xy 444.236692 -103.800779)
			(xy 444.270129 -103.760139) (xy 444.28918 -103.741982) (xy 444.296589 -103.734466) (xy 444.30511 -103.715182)
			(xy 444.30569 -103.704644) (xy 444.30569 -103.629968) (xy 444.30514 -103.619421) (xy 444.29662 -103.600125)
			(xy 444.28918 -103.59263) (xy 444.270142 -103.574457) (xy 444.236684 -103.53383) (xy 444.209123 -103.488994)
			(xy 444.187982 -103.440796) (xy 444.173661 -103.390152) (xy 444.166431 -103.338021) (xy 444.16599 -103.311706)
			(xy 444.166461 -103.284453) (xy 444.174217 -103.230503) (xy 444.189572 -103.178205) (xy 444.212214 -103.128625)
			(xy 444.241681 -103.082772) (xy 444.277374 -103.04158) (xy 444.318566 -103.005886) (xy 444.364418 -102.976418)
			(xy 444.413998 -102.953775) (xy 444.466295 -102.938419) (xy 444.520245 -102.930661) (xy 444.547498 -102.930198)
			(xy 444.575163 -102.930713) (xy 444.629912 -102.938712) (xy 444.682933 -102.954528) (xy 444.733117 -102.977831)
			(xy 444.779413 -103.008132) (xy 444.820851 -103.044796) (xy 444.856564 -103.087057) (xy 444.871602 -103.110284)
			(xy 444.878229 -103.119969) (xy 444.898098 -103.132408) (xy 444.909702 -103.13416) (xy 444.989712 -103.142034)
			(xy 445.001351 -103.14267) (xy 445.023189 -103.134588) (xy 445.031622 -103.12654) (xy 445.031876 -103.126286)
			(xy 445.049936 -103.107683) (xy 445.090272 -103.075107) (xy 445.134651 -103.048297) (xy 445.182254 -103.027749)
			(xy 445.232202 -103.01384) (xy 445.283574 -103.006827) (xy 445.309498 -103.006398) (xy 445.336751 -103.006857)
			(xy 445.390702 -103.014614) (xy 445.443001 -103.02997) (xy 445.492581 -103.052613) (xy 445.538435 -103.082081)
			(xy 445.579628 -103.117775) (xy 445.615321 -103.158969) (xy 445.644789 -103.204822) (xy 445.667431 -103.254403)
			(xy 445.682787 -103.306701) (xy 445.690543 -103.360653) (xy 445.691006 -103.387906) (xy 445.690542 -103.415276)
			(xy 445.682723 -103.469455) (xy 445.667234 -103.521958) (xy 445.644392 -103.571705) (xy 445.614667 -103.617672)
			(xy 445.597026 -103.638604) (xy 445.596772 -103.638858) (xy 445.591194 -103.64595) (xy 445.584943 -103.662863)
			(xy 445.58458 -103.671878) (xy 445.58458 -103.685653) (xy 456.792771 -103.685653) (xy 456.792771 -103.631147)
			(xy 456.800529 -103.577195) (xy 456.815886 -103.524896) (xy 456.838531 -103.475315) (xy 456.868001 -103.429462)
			(xy 456.903697 -103.38827) (xy 456.944893 -103.352578) (xy 456.990749 -103.323112) (xy 457.040332 -103.300473)
			(xy 457.092632 -103.285121) (xy 457.146585 -103.277369) (xy 457.173838 -103.276908) (xy 457.200153 -103.277348)
			(xy 457.252283 -103.284588) (xy 457.302926 -103.298912) (xy 457.351125 -103.32005) (xy 457.395968 -103.347601)
			(xy 457.436606 -103.381044) (xy 457.454762 -103.400098) (xy 457.462296 -103.407484) (xy 457.481567 -103.416017)
			(xy 457.4921 -103.416608) (xy 457.566776 -103.416608) (xy 457.577325 -103.416077) (xy 457.596621 -103.407543)
			(xy 457.604114 -103.400098) (xy 457.623934 -103.37931) (xy 457.668706 -103.343335) (xy 457.718364 -103.314475)
			(xy 457.771786 -103.293382) (xy 457.827765 -103.280533) (xy 457.885038 -103.276218) (xy 457.942311 -103.280533)
			(xy 457.99829 -103.293382) (xy 458.051712 -103.314475) (xy 458.10137 -103.343335) (xy 458.146142 -103.37931)
			(xy 458.165962 -103.400098) (xy 458.173496 -103.407484) (xy 458.192767 -103.416017) (xy 458.2033 -103.416608)
			(xy 458.277976 -103.416608) (xy 458.288525 -103.416077) (xy 458.307821 -103.407543) (xy 458.315314 -103.400098)
			(xy 458.333469 -103.381042) (xy 458.374099 -103.347585) (xy 458.418939 -103.320026) (xy 458.46714 -103.298888)
			(xy 458.517788 -103.284571) (xy 458.569922 -103.277346) (xy 458.596238 -103.276908) (xy 458.623489 -103.277364)
			(xy 458.677434 -103.285126) (xy 458.729727 -103.300485) (xy 458.779301 -103.323129) (xy 458.825149 -103.352598)
			(xy 458.866336 -103.388291) (xy 458.902025 -103.429482) (xy 458.931489 -103.475332) (xy 458.954129 -103.524909)
			(xy 458.969482 -103.577203) (xy 458.977238 -103.631149) (xy 458.977238 -103.685651) (xy 458.969482 -103.739597)
			(xy 458.954129 -103.791891) (xy 458.931489 -103.841468) (xy 458.902025 -103.887319) (xy 458.866336 -103.928509)
			(xy 458.825149 -103.964202) (xy 458.779301 -103.993671) (xy 458.729727 -104.016315) (xy 458.677434 -104.031674)
			(xy 458.623489 -104.039436) (xy 458.596238 -104.039924) (xy 458.569923 -104.03949) (xy 458.517793 -104.032247)
			(xy 458.46715 -104.017921) (xy 458.418952 -103.996782) (xy 458.374109 -103.969231) (xy 458.33347 -103.935788)
			(xy 458.315314 -103.916734) (xy 458.307785 -103.909341) (xy 458.288511 -103.900811) (xy 458.277976 -103.900224)
			(xy 458.2033 -103.900224) (xy 458.192748 -103.900733) (xy 458.173452 -103.909281) (xy 458.165962 -103.916734)
			(xy 458.146142 -103.937522) (xy 458.10137 -103.973497) (xy 458.051712 -104.002357) (xy 457.99829 -104.02345)
			(xy 457.942311 -104.036299) (xy 457.885038 -104.040614) (xy 457.827765 -104.036299) (xy 457.771786 -104.02345)
			(xy 457.718364 -104.002357) (xy 457.668706 -103.973497) (xy 457.623934 -103.937522) (xy 457.604114 -103.916734)
			(xy 457.596585 -103.909341) (xy 457.577311 -103.900811) (xy 457.566776 -103.900224) (xy 457.4921 -103.900224)
			(xy 457.481548 -103.900733) (xy 457.462252 -103.909281) (xy 457.454762 -103.916734) (xy 457.436625 -103.935807)
			(xy 457.39599 -103.969262) (xy 457.351146 -103.996817) (xy 457.302942 -104.017953) (xy 457.252291 -104.032266)
			(xy 457.200155 -104.039487) (xy 457.173838 -104.039924) (xy 457.146585 -104.039431) (xy 457.092632 -104.031679)
			(xy 457.040332 -104.016327) (xy 456.990749 -103.993688) (xy 456.944893 -103.964222) (xy 456.903697 -103.92853)
			(xy 456.868001 -103.887338) (xy 456.838531 -103.841485) (xy 456.815886 -103.791904) (xy 456.800529 -103.739605)
			(xy 456.792771 -103.685653) (xy 445.58458 -103.685653) (xy 445.58458 -103.738934) (xy 445.584925 -103.747952)
			(xy 445.591181 -103.764869) (xy 445.596772 -103.771954) (xy 445.597026 -103.771954) (xy 445.597026 -103.772208)
			(xy 445.614686 -103.793123) (xy 445.644394 -103.839101) (xy 445.667226 -103.888853) (xy 445.682712 -103.941357)
			(xy 445.690535 -103.995536) (xy 445.691006 -104.022906) (xy 445.690528 -104.050157) (xy 445.68277 -104.104106)
			(xy 445.667414 -104.156401) (xy 445.644772 -104.205978) (xy 445.615305 -104.251828) (xy 445.579613 -104.293019)
			(xy 445.538422 -104.32871) (xy 445.492571 -104.358176) (xy 445.442993 -104.380817) (xy 445.390698 -104.396172)
			(xy 445.336749 -104.403928) (xy 445.309498 -104.404414) (xy 445.280579 -104.40393) (xy 445.223405 -104.395198)
			(xy 445.168204 -104.377936) (xy 445.116242 -104.352538) (xy 445.068709 -104.319587) (xy 445.026696 -104.279838)
			(xy 445.008508 -104.257348) (xy 445.000897 -104.248546) (xy 444.979999 -104.238361) (xy 444.968376 -104.23779)
			(xy 444.88862 -104.23779) (xy 444.876992 -104.238359) (xy 444.856082 -104.248527) (xy 444.848488 -104.257348)
			(xy 444.830316 -104.279847) (xy 444.788291 -104.319579) (xy 444.740751 -104.352515) (xy 444.688787 -104.3779)
			(xy 444.633587 -104.395154) (xy 444.576415 -104.40388) (xy 444.547498 -104.404414) (xy 444.520247 -104.403924)
			(xy 444.4663 -104.396167) (xy 444.414005 -104.380812) (xy 444.364429 -104.358171) (xy 444.318578 -104.328706)
			(xy 444.277388 -104.293014) (xy 444.241697 -104.251825) (xy 444.21223 -104.205975) (xy 444.189589 -104.156398)
			(xy 444.174233 -104.104104) (xy 444.166476 -104.050157) (xy 444.16599 -104.022906) (xy 439.417168 -104.022906)
			(xy 439.41619 -104.023922) (xy 439.409078 -104.041956) (xy 439.409078 -104.130856) (xy 439.41619 -104.14889)
			(xy 439.422794 -104.155748) (xy 439.44207 -104.17707) (xy 439.474633 -104.224434) (xy 439.499724 -104.276146)
			(xy 439.516772 -104.331038) (xy 439.525394 -104.387865) (xy 439.525393 -104.445343) (xy 439.51677 -104.502171)
			(xy 439.49972 -104.557062) (xy 439.474629 -104.608774) (xy 439.442064 -104.656137) (xy 439.422794 -104.677464)
			(xy 439.41619 -104.684322) (xy 439.409078 -104.702356) (xy 439.409078 -104.791256) (xy 439.41619 -104.80929)
			(xy 439.422794 -104.816148) (xy 439.44207 -104.83747) (xy 439.474633 -104.884834) (xy 439.499724 -104.936546)
			(xy 439.516772 -104.991438) (xy 439.525394 -105.048265) (xy 439.525393 -105.08445) (xy 444.044072 -105.08445)
			(xy 444.044072 -105.02995) (xy 444.051828 -104.976004) (xy 444.067181 -104.923711) (xy 444.089821 -104.874135)
			(xy 444.119285 -104.828285) (xy 444.154974 -104.787095) (xy 444.196161 -104.751403) (xy 444.242008 -104.721935)
			(xy 444.291582 -104.699292) (xy 444.343874 -104.683934) (xy 444.39782 -104.676174) (xy 444.42507 -104.675686)
			(xy 444.452439 -104.676173) (xy 444.506617 -104.683986) (xy 444.55912 -104.699471) (xy 444.608867 -104.722308)
			(xy 444.654835 -104.752027) (xy 444.675768 -104.769666) (xy 444.676022 -104.76992) (xy 444.683096 -104.775524)
			(xy 444.700023 -104.78176) (xy 444.709042 -104.782112) (xy 444.776098 -104.782112) (xy 444.785114 -104.781751)
			(xy 444.802031 -104.775506) (xy 444.809118 -104.76992) (xy 444.809118 -104.769666) (xy 444.809372 -104.769666)
			(xy 444.830305 -104.752025) (xy 444.876273 -104.722301) (xy 444.926019 -104.699455) (xy 444.978521 -104.683959)
			(xy 445.032699 -104.67613) (xy 445.087441 -104.67613) (xy 445.141619 -104.683959) (xy 445.194121 -104.699455)
			(xy 445.243867 -104.722301) (xy 445.289835 -104.752025) (xy 445.310768 -104.769666) (xy 445.311022 -104.76992)
			(xy 445.318096 -104.775524) (xy 445.335023 -104.78176) (xy 445.344042 -104.782112) (xy 445.411098 -104.782112)
			(xy 445.420114 -104.781751) (xy 445.437031 -104.775506) (xy 445.444118 -104.76992) (xy 445.444118 -104.769666)
			(xy 445.444372 -104.769666) (xy 445.465305 -104.752025) (xy 445.511273 -104.722301) (xy 445.561019 -104.699455)
			(xy 445.613521 -104.683959) (xy 445.667699 -104.67613) (xy 445.722441 -104.67613) (xy 445.776619 -104.683959)
			(xy 445.829121 -104.699455) (xy 445.878867 -104.722301) (xy 445.924835 -104.752025) (xy 445.945768 -104.769666)
			(xy 445.946022 -104.76992) (xy 445.953096 -104.775524) (xy 445.970023 -104.78176) (xy 445.979042 -104.782112)
			(xy 446.046098 -104.782112) (xy 446.055114 -104.781751) (xy 446.072031 -104.775506) (xy 446.079118 -104.76992)
			(xy 446.079118 -104.769666) (xy 446.079372 -104.769666) (xy 446.100299 -104.752021) (xy 446.146274 -104.722311)
			(xy 446.196023 -104.699477) (xy 446.248524 -104.683987) (xy 446.302701 -104.67616) (xy 446.33007 -104.675686)
			(xy 446.357324 -104.676159) (xy 446.411277 -104.683913) (xy 446.463578 -104.699266) (xy 446.513161 -104.721906)
			(xy 446.559017 -104.751373) (xy 446.600213 -104.787066) (xy 446.635909 -104.828259) (xy 446.665379 -104.874113)
			(xy 446.688024 -104.923694) (xy 446.703381 -104.975994) (xy 446.711139 -105.029946) (xy 446.711139 -105.084454)
			(xy 446.703381 -105.138406) (xy 446.688024 -105.190706) (xy 446.665379 -105.240287) (xy 446.635909 -105.286141)
			(xy 446.600213 -105.327334) (xy 446.559017 -105.363027) (xy 446.513161 -105.392494) (xy 446.463578 -105.415134)
			(xy 446.411277 -105.430487) (xy 446.357324 -105.438241) (xy 446.33007 -105.438702) (xy 446.302699 -105.438253)
			(xy 446.248519 -105.430431) (xy 446.196016 -105.414938) (xy 446.14627 -105.392092) (xy 446.100303 -105.362365)
			(xy 446.079372 -105.344722) (xy 446.079118 -105.344468) (xy 446.072033 -105.338879) (xy 446.055115 -105.332635)
			(xy 446.046098 -105.332276) (xy 445.979042 -105.332276) (xy 445.970028 -105.332658) (xy 445.953111 -105.338889)
			(xy 445.946022 -105.344468) (xy 445.945768 -105.344722) (xy 445.924835 -105.362363) (xy 445.878867 -105.392087)
			(xy 445.829121 -105.414933) (xy 445.776619 -105.430429) (xy 445.722441 -105.438258) (xy 445.667699 -105.438258)
			(xy 445.613521 -105.430429) (xy 445.561019 -105.414933) (xy 445.511273 -105.392087) (xy 445.465305 -105.362363)
			(xy 445.444372 -105.344722) (xy 445.444118 -105.344468) (xy 445.437033 -105.338879) (xy 445.420115 -105.332635)
			(xy 445.411098 -105.332276) (xy 445.344042 -105.332276) (xy 445.335028 -105.332658) (xy 445.318111 -105.338889)
			(xy 445.311022 -105.344468) (xy 445.311022 -105.344722) (xy 445.310768 -105.344722) (xy 445.289835 -105.362363)
			(xy 445.243867 -105.392087) (xy 445.194121 -105.414933) (xy 445.141619 -105.430429) (xy 445.087441 -105.438258)
			(xy 445.032699 -105.438258) (xy 444.978521 -105.430429) (xy 444.926019 -105.414933) (xy 444.876273 -105.392087)
			(xy 444.830305 -105.362363) (xy 444.809372 -105.344722) (xy 444.809118 -105.344468) (xy 444.802033 -105.338879)
			(xy 444.785115 -105.332635) (xy 444.776098 -105.332276) (xy 444.709042 -105.332276) (xy 444.700028 -105.332658)
			(xy 444.683111 -105.338889) (xy 444.676022 -105.344468) (xy 444.676022 -105.344722) (xy 444.675768 -105.344722)
			(xy 444.654824 -105.362346) (xy 444.608854 -105.392059) (xy 444.55911 -105.414898) (xy 444.506612 -105.430393)
			(xy 444.452438 -105.438225) (xy 444.42507 -105.438702) (xy 444.39782 -105.438226) (xy 444.343874 -105.430466)
			(xy 444.291582 -105.415108) (xy 444.242008 -105.392465) (xy 444.196161 -105.362997) (xy 444.154974 -105.327305)
			(xy 444.119285 -105.286115) (xy 444.089821 -105.240265) (xy 444.067181 -105.190689) (xy 444.051828 -105.138396)
			(xy 444.044072 -105.08445) (xy 439.525393 -105.08445) (xy 439.525393 -105.105743) (xy 439.51677 -105.162571)
			(xy 439.49972 -105.217462) (xy 439.474629 -105.269174) (xy 439.442064 -105.316537) (xy 439.422794 -105.337864)
			(xy 439.41619 -105.344722) (xy 439.409078 -105.362756) (xy 439.409078 -105.451656) (xy 439.41619 -105.46969)
			(xy 439.422794 -105.476548) (xy 439.44207 -105.49787) (xy 439.474633 -105.545234) (xy 439.499724 -105.596946)
			(xy 439.516772 -105.651838) (xy 439.525394 -105.708665) (xy 439.525393 -105.766143) (xy 439.51677 -105.822971)
			(xy 439.49972 -105.877862) (xy 439.474629 -105.929574) (xy 439.442064 -105.976937) (xy 439.422794 -105.998264)
			(xy 439.41619 -106.005122) (xy 439.409078 -106.023156) (xy 439.409078 -106.112056) (xy 439.41619 -106.13009)
			(xy 439.422794 -106.136948) (xy 439.44207 -106.15827) (xy 439.474633 -106.205634) (xy 439.499724 -106.257346)
			(xy 439.516772 -106.312238) (xy 439.525394 -106.369065) (xy 439.525393 -106.426543) (xy 439.51677 -106.483371)
			(xy 439.49972 -106.538262) (xy 439.474629 -106.589974) (xy 439.442064 -106.637337) (xy 439.422794 -106.658664)
			(xy 439.41619 -106.665522) (xy 439.409078 -106.683556) (xy 439.409078 -106.772456) (xy 439.41619 -106.79049)
			(xy 439.422794 -106.797348) (xy 439.427403 -106.802446) (xy 456.721028 -106.802446) (xy 456.721028 -106.747954)
			(xy 456.728782 -106.694018) (xy 456.744133 -106.641733) (xy 456.766768 -106.592166) (xy 456.796226 -106.546323)
			(xy 456.831909 -106.50514) (xy 456.873088 -106.469453) (xy 456.918927 -106.439989) (xy 456.968492 -106.417349)
			(xy 457.020775 -106.401992) (xy 457.07471 -106.394231) (xy 457.101956 -106.393742) (xy 457.128272 -106.394159)
			(xy 457.180403 -106.401402) (xy 457.231047 -106.41573) (xy 457.279246 -106.436872) (xy 457.324089 -106.464428)
			(xy 457.364725 -106.497876) (xy 457.38288 -106.516932) (xy 457.390416 -106.524317) (xy 457.409685 -106.532853)
			(xy 457.420218 -106.533442) (xy 457.494894 -106.533442) (xy 457.505443 -106.532911) (xy 457.524738 -106.524376)
			(xy 457.532232 -106.516932) (xy 457.552052 -106.496144) (xy 457.596824 -106.460169) (xy 457.646482 -106.431309)
			(xy 457.699904 -106.410216) (xy 457.755883 -106.397367) (xy 457.813156 -106.393052) (xy 457.870429 -106.397367)
			(xy 457.926408 -106.410216) (xy 457.97983 -106.431309) (xy 458.029488 -106.460169) (xy 458.07426 -106.496144)
			(xy 458.09408 -106.516932) (xy 458.101616 -106.524317) (xy 458.120885 -106.532853) (xy 458.131418 -106.533442)
			(xy 458.206094 -106.533442) (xy 458.216643 -106.532911) (xy 458.235938 -106.524376) (xy 458.243432 -106.516932)
			(xy 458.261585 -106.497874) (xy 458.302215 -106.464416) (xy 458.347055 -106.436856) (xy 458.395257 -106.415718)
			(xy 458.445905 -106.401402) (xy 458.49804 -106.394179) (xy 458.524356 -106.393742) (xy 458.551614 -106.394102)
			(xy 458.605577 -106.401855) (xy 458.657887 -106.417209) (xy 458.70748 -106.439852) (xy 458.753344 -106.469323)
			(xy 458.794548 -106.505021) (xy 458.830251 -106.54622) (xy 458.859727 -106.592082) (xy 458.882375 -106.641671)
			(xy 458.897736 -106.69398) (xy 458.905495 -106.747942) (xy 458.905495 -106.802458) (xy 458.897736 -106.85642)
			(xy 458.882375 -106.908729) (xy 458.859727 -106.958318) (xy 458.830251 -107.00418) (xy 458.794548 -107.045379)
			(xy 458.753344 -107.081077) (xy 458.70748 -107.110548) (xy 458.657887 -107.133191) (xy 458.605577 -107.148545)
			(xy 458.551615 -107.156298) (xy 458.524356 -107.156758) (xy 458.49804 -107.156333) (xy 458.44591 -107.149092)
			(xy 458.395265 -107.134765) (xy 458.347066 -107.113625) (xy 458.302224 -107.08607) (xy 458.261587 -107.052624)
			(xy 458.243432 -107.033568) (xy 458.235891 -107.026188) (xy 458.216626 -107.017649) (xy 458.206094 -107.017058)
			(xy 458.131418 -107.017058) (xy 458.12087 -107.017596) (xy 458.101575 -107.026126) (xy 458.09408 -107.033568)
			(xy 458.07426 -107.054356) (xy 458.029488 -107.090331) (xy 457.97983 -107.119191) (xy 457.926408 -107.140284)
			(xy 457.870429 -107.153133) (xy 457.813156 -107.157448) (xy 457.755883 -107.153133) (xy 457.699904 -107.140284)
			(xy 457.646482 -107.119191) (xy 457.596824 -107.090331) (xy 457.552052 -107.054356) (xy 457.532232 -107.033568)
			(xy 457.524691 -107.026188) (xy 457.505426 -107.017649) (xy 457.494894 -107.017058) (xy 457.420218 -107.017058)
			(xy 457.40967 -107.017596) (xy 457.390375 -107.026126) (xy 457.38288 -107.033568) (xy 457.364721 -107.05262)
			(xy 457.324093 -107.086079) (xy 457.279253 -107.113639) (xy 457.231053 -107.134778) (xy 457.180406 -107.149096)
			(xy 457.128272 -107.15632) (xy 457.101956 -107.156758) (xy 457.07471 -107.156169) (xy 457.020775 -107.148408)
			(xy 456.968492 -107.133051) (xy 456.918927 -107.110411) (xy 456.873088 -107.080947) (xy 456.831909 -107.04526)
			(xy 456.796226 -107.004077) (xy 456.766768 -106.958234) (xy 456.744133 -106.908667) (xy 456.728782 -106.856382)
			(xy 456.721028 -106.802446) (xy 439.427403 -106.802446) (xy 439.44207 -106.81867) (xy 439.474633 -106.866034)
			(xy 439.499724 -106.917746) (xy 439.516772 -106.972638) (xy 439.525394 -107.029465) (xy 439.525393 -107.086943)
			(xy 439.51677 -107.143771) (xy 439.49972 -107.198662) (xy 439.474629 -107.250374) (xy 439.442064 -107.297737)
			(xy 439.422794 -107.319064) (xy 439.41619 -107.325922) (xy 439.409078 -107.343956) (xy 439.409078 -107.432856)
			(xy 439.41619 -107.45089) (xy 439.422794 -107.457748) (xy 439.44207 -107.47907) (xy 439.474633 -107.526434)
			(xy 439.499724 -107.578146) (xy 439.516772 -107.633038) (xy 439.525394 -107.689865) (xy 439.525393 -107.740249)
			(xy 443.984396 -107.740249) (xy 443.984396 -107.685751) (xy 443.992152 -107.631808) (xy 444.007505 -107.579517)
			(xy 444.030144 -107.529944) (xy 444.059607 -107.484096) (xy 444.095294 -107.442909) (xy 444.13648 -107.407219)
			(xy 444.182326 -107.377753) (xy 444.231898 -107.355112) (xy 444.284188 -107.339756) (xy 444.338131 -107.331998)
			(xy 444.36538 -107.33151) (xy 444.39275 -107.331985) (xy 444.446929 -107.339801) (xy 444.499432 -107.355287)
			(xy 444.549179 -107.378127) (xy 444.595146 -107.40785) (xy 444.616078 -107.42549) (xy 444.616332 -107.425744)
			(xy 444.62343 -107.431314) (xy 444.640338 -107.437569) (xy 444.649352 -107.437936) (xy 444.716408 -107.437936)
			(xy 444.725424 -107.437575) (xy 444.742341 -107.43133) (xy 444.749428 -107.425744) (xy 444.749428 -107.42549)
			(xy 444.749682 -107.42549) (xy 444.770615 -107.407849) (xy 444.816583 -107.378125) (xy 444.866329 -107.355279)
			(xy 444.918831 -107.339783) (xy 444.973009 -107.331954) (xy 445.027751 -107.331954) (xy 445.081929 -107.339783)
			(xy 445.134431 -107.355279) (xy 445.184177 -107.378125) (xy 445.230145 -107.407849) (xy 445.251078 -107.42549)
			(xy 445.251332 -107.425744) (xy 445.25843 -107.431314) (xy 445.275338 -107.437569) (xy 445.284352 -107.437936)
			(xy 445.351408 -107.437936) (xy 445.360424 -107.437575) (xy 445.377341 -107.43133) (xy 445.384428 -107.425744)
			(xy 445.384428 -107.42549) (xy 445.384682 -107.42549) (xy 445.405615 -107.407849) (xy 445.451583 -107.378125)
			(xy 445.501329 -107.355279) (xy 445.553831 -107.339783) (xy 445.608009 -107.331954) (xy 445.662751 -107.331954)
			(xy 445.716929 -107.339783) (xy 445.769431 -107.355279) (xy 445.819177 -107.378125) (xy 445.865145 -107.407849)
			(xy 445.886078 -107.42549) (xy 445.886332 -107.425744) (xy 445.89343 -107.431314) (xy 445.910338 -107.437569)
			(xy 445.919352 -107.437936) (xy 445.986408 -107.437936) (xy 445.995424 -107.437575) (xy 446.012341 -107.43133)
			(xy 446.019428 -107.425744) (xy 446.019428 -107.42549) (xy 446.019682 -107.42549) (xy 446.040609 -107.407844)
			(xy 446.086583 -107.378134) (xy 446.136332 -107.355299) (xy 446.188834 -107.33981) (xy 446.24301 -107.331983)
			(xy 446.27038 -107.33151) (xy 446.297635 -107.331936) (xy 446.351591 -107.339691) (xy 446.403894 -107.355046)
			(xy 446.453479 -107.377688) (xy 446.499336 -107.407157) (xy 446.540534 -107.442852) (xy 446.576231 -107.484047)
			(xy 446.605702 -107.529904) (xy 446.628347 -107.579488) (xy 446.643705 -107.63179) (xy 446.651463 -107.685745)
			(xy 446.651463 -107.740255) (xy 446.643705 -107.79421) (xy 446.628347 -107.846512) (xy 446.605702 -107.896096)
			(xy 446.576231 -107.941953) (xy 446.540534 -107.983148) (xy 446.499336 -108.018843) (xy 446.453479 -108.048312)
			(xy 446.403894 -108.070954) (xy 446.351591 -108.086309) (xy 446.297635 -108.094064) (xy 446.27038 -108.094526)
			(xy 446.243008 -108.09409) (xy 446.188827 -108.086267) (xy 446.136323 -108.070772) (xy 446.086577 -108.047924)
			(xy 446.040612 -108.018191) (xy 446.019682 -108.000546) (xy 446.019428 -108.000292) (xy 446.012338 -107.99471)
			(xy 445.995424 -107.988461) (xy 445.986408 -107.9881) (xy 445.919352 -107.9881) (xy 445.910338 -107.988482)
			(xy 445.893421 -107.994712) (xy 445.886332 -108.000292) (xy 445.886078 -108.000546) (xy 445.865145 -108.018187)
			(xy 445.819177 -108.047911) (xy 445.769431 -108.070757) (xy 445.716929 -108.086253) (xy 445.662751 -108.094082)
			(xy 445.608009 -108.094082) (xy 445.553831 -108.086253) (xy 445.501329 -108.070757) (xy 445.451583 -108.047911)
			(xy 445.405615 -108.018187) (xy 445.384682 -108.000546) (xy 445.384428 -108.000292) (xy 445.377338 -107.99471)
			(xy 445.360424 -107.988461) (xy 445.351408 -107.9881) (xy 445.284352 -107.9881) (xy 445.275338 -107.988482)
			(xy 445.258421 -107.994712) (xy 445.251332 -108.000292) (xy 445.251332 -108.000546) (xy 445.251078 -108.000546)
			(xy 445.230145 -108.018187) (xy 445.184177 -108.047911) (xy 445.134431 -108.070757) (xy 445.081929 -108.086253)
			(xy 445.027751 -108.094082) (xy 444.973009 -108.094082) (xy 444.918831 -108.086253) (xy 444.866329 -108.070757)
			(xy 444.816583 -108.047911) (xy 444.770615 -108.018187) (xy 444.749682 -108.000546) (xy 444.749428 -108.000292)
			(xy 444.742338 -107.99471) (xy 444.725424 -107.988461) (xy 444.716408 -107.9881) (xy 444.649352 -107.9881)
			(xy 444.640338 -107.988482) (xy 444.623421 -107.994712) (xy 444.616332 -108.000292) (xy 444.616332 -108.000546)
			(xy 444.616078 -108.000546) (xy 444.59512 -108.018154) (xy 444.549155 -108.047872) (xy 444.499415 -108.070715)
			(xy 444.446919 -108.086213) (xy 444.392748 -108.094048) (xy 444.36538 -108.094526) (xy 444.338131 -108.094002)
			(xy 444.284188 -108.086244) (xy 444.231898 -108.070888) (xy 444.182326 -108.048247) (xy 444.13648 -108.018781)
			(xy 444.095294 -107.983091) (xy 444.059607 -107.941904) (xy 444.030144 -107.896056) (xy 444.007505 -107.846483)
			(xy 443.992152 -107.794192) (xy 443.984396 -107.740249) (xy 439.525393 -107.740249) (xy 439.525393 -107.747343)
			(xy 439.51677 -107.804171) (xy 439.49972 -107.859062) (xy 439.474629 -107.910774) (xy 439.442064 -107.958137)
			(xy 439.422794 -107.979464) (xy 439.41619 -107.986322) (xy 439.409078 -108.004356) (xy 439.409078 -108.093256)
			(xy 439.41619 -108.11129) (xy 439.422794 -108.118148) (xy 439.442056 -108.139483) (xy 439.474626 -108.186842)
			(xy 439.499721 -108.238551) (xy 439.516773 -108.293441) (xy 439.525397 -108.350267) (xy 439.525918 -108.379006)
			(xy 439.525432 -108.406257) (xy 439.517676 -108.460205) (xy 439.502321 -108.5125) (xy 439.479679 -108.562077)
			(xy 439.474905 -108.569506) (xy 455.161142 -108.569506) (xy 455.161601 -108.542135) (xy 455.169419 -108.487956)
			(xy 455.184909 -108.435452) (xy 455.207753 -108.385705) (xy 455.23748 -108.339739) (xy 455.255122 -108.318808)
			(xy 455.255376 -108.318554) (xy 455.260955 -108.311463) (xy 455.267204 -108.294549) (xy 455.267568 -108.285534)
			(xy 455.267568 -108.218478) (xy 455.267229 -108.209459) (xy 455.26097 -108.192542) (xy 455.255376 -108.185458)
			(xy 455.255122 -108.185458) (xy 455.255122 -108.185204) (xy 455.237475 -108.164278) (xy 455.207763 -108.118304)
			(xy 455.184929 -108.068555) (xy 455.16944 -108.016053) (xy 455.161614 -107.961876) (xy 455.161142 -107.934506)
			(xy 455.161628 -107.907255) (xy 455.169384 -107.853307) (xy 455.184739 -107.801012) (xy 455.207381 -107.751435)
			(xy 455.236847 -107.705585) (xy 455.272538 -107.664394) (xy 455.313729 -107.628703) (xy 455.359579 -107.599237)
			(xy 455.409156 -107.576595) (xy 455.461451 -107.56124) (xy 455.515399 -107.553484) (xy 455.569901 -107.553484)
			(xy 455.623849 -107.56124) (xy 455.676144 -107.576595) (xy 455.725721 -107.599237) (xy 455.771571 -107.628703)
			(xy 455.812762 -107.664394) (xy 455.848453 -107.705585) (xy 455.877919 -107.751435) (xy 455.900561 -107.801012)
			(xy 455.915916 -107.853307) (xy 455.923672 -107.907255) (xy 455.924158 -107.934506) (xy 455.923706 -107.961877)
			(xy 455.915886 -108.016057) (xy 455.900394 -108.068561) (xy 455.877549 -108.118307) (xy 455.847821 -108.164273)
			(xy 455.830178 -108.185204) (xy 455.829924 -108.185458) (xy 455.82434 -108.192546) (xy 455.818094 -108.209462)
			(xy 455.817732 -108.218478) (xy 455.817732 -108.285534) (xy 455.818066 -108.294553) (xy 455.824329 -108.311471)
			(xy 455.829924 -108.318554) (xy 455.830178 -108.318554) (xy 455.830178 -108.318808) (xy 455.847831 -108.339729)
			(xy 455.877541 -108.385705) (xy 455.900375 -108.435455) (xy 455.915863 -108.487958) (xy 455.923687 -108.542136)
			(xy 455.924158 -108.569506) (xy 455.923672 -108.596757) (xy 455.915916 -108.650705) (xy 455.900561 -108.703)
			(xy 455.877919 -108.752577) (xy 455.848453 -108.798427) (xy 455.812762 -108.839618) (xy 455.771571 -108.875309)
			(xy 455.725721 -108.904775) (xy 455.676144 -108.927417) (xy 455.623849 -108.942772) (xy 455.569901 -108.950528)
			(xy 455.515399 -108.950528) (xy 455.461451 -108.942772) (xy 455.409156 -108.927417) (xy 455.359579 -108.904775)
			(xy 455.313729 -108.875309) (xy 455.272538 -108.839618) (xy 455.236847 -108.798427) (xy 455.207381 -108.752577)
			(xy 455.184739 -108.703) (xy 455.169384 -108.650705) (xy 455.161628 -108.596757) (xy 455.161142 -108.569506)
			(xy 439.474905 -108.569506) (xy 439.450213 -108.607927) (xy 439.414522 -108.649118) (xy 439.373331 -108.684809)
			(xy 439.327481 -108.714275) (xy 439.277904 -108.736917) (xy 439.225609 -108.752272) (xy 439.171661 -108.760028)
			(xy 439.117159 -108.760028) (xy 439.063211 -108.752272) (xy 439.010916 -108.736917) (xy 438.961339 -108.714275)
			(xy 438.915489 -108.684809) (xy 438.874298 -108.649118) (xy 438.838607 -108.607927) (xy 438.809141 -108.562077)
			(xy 438.786499 -108.5125) (xy 438.771144 -108.460205) (xy 438.763388 -108.406257) (xy 438.762902 -108.379006)
			(xy 432.01844 -108.379006) (xy 433.141882 -109.502448) (xy 457.714602 -109.502448) (xy 457.718673 -109.446826)
			(xy 457.730799 -109.392389) (xy 457.750722 -109.340298) (xy 457.778018 -109.291663) (xy 457.812104 -109.24752)
			(xy 457.852253 -109.208811) (xy 457.897611 -109.17636) (xy 457.947211 -109.150859) (xy 457.999995 -109.132852)
			(xy 458.054838 -109.122722) (xy 458.110572 -109.120685) (xy 458.166009 -109.126785) (xy 458.219966 -109.140891)
			(xy 458.271295 -109.162703) (xy 458.318901 -109.191757) (xy 458.361769 -109.227432) (xy 458.398986 -109.268969)
			(xy 458.429759 -109.315482) (xy 458.453431 -109.365979) (xy 458.469499 -109.419386) (xy 458.477619 -109.474562)
			(xy 458.478128 -109.502448) (xy 458.477619 -109.530334) (xy 458.469499 -109.58551) (xy 458.453431 -109.638917)
			(xy 458.429759 -109.689414) (xy 458.398986 -109.735927) (xy 458.361769 -109.777464) (xy 458.318901 -109.813139)
			(xy 458.271295 -109.842193) (xy 458.219966 -109.864005) (xy 458.166009 -109.878111) (xy 458.110572 -109.884211)
			(xy 458.054838 -109.882174) (xy 457.999995 -109.872044) (xy 457.947211 -109.854037) (xy 457.897611 -109.828536)
			(xy 457.852253 -109.796085) (xy 457.812104 -109.757376) (xy 457.778018 -109.713233) (xy 457.750722 -109.664598)
			(xy 457.730799 -109.612507) (xy 457.718673 -109.55807) (xy 457.714602 -109.502448) (xy 433.141882 -109.502448)
			(xy 434.261006 -110.621572) (xy 438.8612 -110.621572) (xy 438.861649 -110.595257) (xy 438.868887 -110.543128)
			(xy 438.88321 -110.492485) (xy 438.904346 -110.444286) (xy 438.931895 -110.399443) (xy 438.965337 -110.358804)
			(xy 438.98439 -110.340648) (xy 438.991815 -110.333146) (xy 439.000326 -110.313851) (xy 439.0009 -110.30331)
			(xy 439.0009 -110.228634) (xy 439.000366 -110.218085) (xy 438.991834 -110.198789) (xy 438.98439 -110.191296)
			(xy 438.965338 -110.173137) (xy 438.931881 -110.132508) (xy 438.904321 -110.087668) (xy 438.883182 -110.039468)
			(xy 438.868864 -109.988821) (xy 438.861639 -109.936688) (xy 438.8612 -109.910372) (xy 438.861686 -109.883121)
			(xy 438.869442 -109.829173) (xy 438.884797 -109.776878) (xy 438.907439 -109.727301) (xy 438.936905 -109.681451)
			(xy 438.972596 -109.64026) (xy 439.013787 -109.604569) (xy 439.059637 -109.575103) (xy 439.109214 -109.552461)
			(xy 439.161509 -109.537106) (xy 439.215457 -109.52935) (xy 439.269959 -109.52935) (xy 439.323907 -109.537106)
			(xy 439.376202 -109.552461) (xy 439.425779 -109.575103) (xy 439.471629 -109.604569) (xy 439.51282 -109.64026)
			(xy 439.548511 -109.681451) (xy 439.577977 -109.727301) (xy 439.600619 -109.776878) (xy 439.615974 -109.829173)
			(xy 439.62373 -109.883121) (xy 439.624216 -109.910372) (xy 439.623791 -109.936687) (xy 439.616547 -109.988818)
			(xy 439.602219 -110.039461) (xy 439.581079 -110.08766) (xy 439.553525 -110.132502) (xy 439.52008 -110.17314)
			(xy 439.501026 -110.191296) (xy 439.493628 -110.198821) (xy 439.485101 -110.218098) (xy 439.484516 -110.228634)
			(xy 439.484516 -110.30331) (xy 439.485022 -110.313863) (xy 439.493573 -110.333158) (xy 439.501026 -110.340648)
			(xy 439.520103 -110.358782) (xy 439.553557 -110.399417) (xy 439.581113 -110.444262) (xy 439.602247 -110.492467)
			(xy 439.61656 -110.543118) (xy 439.62378 -110.595255) (xy 439.624216 -110.621572) (xy 439.62373 -110.648823)
			(xy 439.615974 -110.702771) (xy 439.600619 -110.755066) (xy 439.577977 -110.804643) (xy 439.548511 -110.850493)
			(xy 439.51282 -110.891684) (xy 439.471629 -110.927375) (xy 439.425779 -110.956841) (xy 439.376202 -110.979483)
			(xy 439.323907 -110.994838) (xy 439.269959 -111.002594) (xy 439.215457 -111.002594) (xy 439.161509 -110.994838)
			(xy 439.109214 -110.979483) (xy 439.059637 -110.956841) (xy 439.013787 -110.927375) (xy 438.972596 -110.891684)
			(xy 438.936905 -110.850493) (xy 438.907439 -110.804643) (xy 438.884797 -110.755066) (xy 438.869442 -110.702771)
			(xy 438.861686 -110.648823) (xy 438.8612 -110.621572) (xy 434.261006 -110.621572) (xy 434.986684 -111.34725)
			(xy 434.993524 -111.35465) (xy 435.001243 -111.373249) (xy 435.00167 -111.383318) (xy 435.00167 -111.665004)
			(xy 435.003194 -111.670846) (xy 435.007404 -111.689934) (xy 435.011862 -111.72877) (xy 435.012084 -111.748316)
			(xy 435.012084 -112.297972) (xy 441.369958 -112.297972) (xy 441.370388 -112.271657) (xy 441.377628 -112.219526)
			(xy 441.391953 -112.168882) (xy 441.413093 -112.120682) (xy 441.440646 -112.07584) (xy 441.474093 -112.035203)
			(xy 441.493148 -112.017048) (xy 441.500567 -112.009541) (xy 441.509083 -111.99025) (xy 441.509658 -111.97971)
			(xy 441.509658 -111.905034) (xy 441.509136 -111.894483) (xy 441.500597 -111.875187) (xy 441.493148 -111.867696)
			(xy 441.474088 -111.849546) (xy 441.440633 -111.808914) (xy 441.413076 -111.764072) (xy 441.391939 -111.71587)
			(xy 441.377622 -111.665222) (xy 441.370397 -111.613088) (xy 441.369958 -111.586772) (xy 441.370444 -111.559521)
			(xy 441.3782 -111.505573) (xy 441.393555 -111.453278) (xy 441.416197 -111.403701) (xy 441.445663 -111.357851)
			(xy 441.481354 -111.31666) (xy 441.522545 -111.280969) (xy 441.568395 -111.251503) (xy 441.617972 -111.228861)
			(xy 441.670267 -111.213506) (xy 441.724215 -111.20575) (xy 441.778717 -111.20575) (xy 441.832665 -111.213506)
			(xy 441.88496 -111.228861) (xy 441.934537 -111.251503) (xy 441.980387 -111.280969) (xy 442.021578 -111.31666)
			(xy 442.057269 -111.357851) (xy 442.086735 -111.403701) (xy 442.109377 -111.453278) (xy 442.124732 -111.505573)
			(xy 442.132488 -111.559521) (xy 442.132974 -111.586772) (xy 442.132563 -111.613088) (xy 442.125318 -111.665219)
			(xy 442.110988 -111.715863) (xy 442.089845 -111.764062) (xy 442.062289 -111.808904) (xy 442.02884 -111.849541)
			(xy 442.009784 -111.867696) (xy 442.00238 -111.875215) (xy 441.993857 -111.894497) (xy 441.993274 -111.905034)
			(xy 441.993274 -111.97971) (xy 441.993792 -111.990261) (xy 442.002336 -112.009556) (xy 442.009784 -112.017048)
			(xy 442.028853 -112.03519) (xy 442.062309 -112.075823) (xy 442.089867 -112.120665) (xy 442.111003 -112.168869)
			(xy 442.125317 -112.219519) (xy 442.132538 -112.271655) (xy 442.132974 -112.297972) (xy 443.401958 -112.297972)
			(xy 443.402388 -112.271657) (xy 443.409628 -112.219526) (xy 443.423953 -112.168882) (xy 443.445093 -112.120682)
			(xy 443.472646 -112.07584) (xy 443.506093 -112.035203) (xy 443.525148 -112.017048) (xy 443.532567 -112.009541)
			(xy 443.541083 -111.99025) (xy 443.541658 -111.97971) (xy 443.541658 -111.905034) (xy 443.541136 -111.894483)
			(xy 443.532597 -111.875187) (xy 443.525148 -111.867696) (xy 443.506088 -111.849546) (xy 443.472633 -111.808914)
			(xy 443.445076 -111.764072) (xy 443.423939 -111.71587) (xy 443.409622 -111.665222) (xy 443.402397 -111.613088)
			(xy 443.401958 -111.586772) (xy 443.402444 -111.559521) (xy 443.4102 -111.505573) (xy 443.425555 -111.453278)
			(xy 443.448197 -111.403701) (xy 443.477663 -111.357851) (xy 443.513354 -111.31666) (xy 443.554545 -111.280969)
			(xy 443.600395 -111.251503) (xy 443.649972 -111.228861) (xy 443.702267 -111.213506) (xy 443.756215 -111.20575)
			(xy 443.810717 -111.20575) (xy 443.864665 -111.213506) (xy 443.91696 -111.228861) (xy 443.966537 -111.251503)
			(xy 444.012387 -111.280969) (xy 444.053578 -111.31666) (xy 444.089269 -111.357851) (xy 444.118735 -111.403701)
			(xy 444.141377 -111.453278) (xy 444.156732 -111.505573) (xy 444.164488 -111.559521) (xy 444.164974 -111.586772)
			(xy 444.164563 -111.613088) (xy 444.157318 -111.665219) (xy 444.142988 -111.715863) (xy 444.121845 -111.764062)
			(xy 444.094289 -111.808904) (xy 444.06084 -111.849541) (xy 444.041784 -111.867696) (xy 444.03438 -111.875215)
			(xy 444.025857 -111.894497) (xy 444.025274 -111.905034) (xy 444.025274 -111.97971) (xy 444.025792 -111.990261)
			(xy 444.034336 -112.009556) (xy 444.041784 -112.017048) (xy 444.060853 -112.03519) (xy 444.06285 -112.037615)
			(xy 445.856202 -112.037615) (xy 445.860515 -111.980345) (xy 445.87336 -111.924368) (xy 445.894448 -111.870948)
			(xy 445.923303 -111.821291) (xy 445.959273 -111.776519) (xy 445.980058 -111.756698) (xy 445.987456 -111.749173)
			(xy 445.995984 -111.729896) (xy 445.996568 -111.71936) (xy 445.996568 -111.644684) (xy 445.99607 -111.63413)
			(xy 445.987514 -111.614835) (xy 445.980058 -111.607346) (xy 445.960975 -111.589218) (xy 445.927522 -111.548581)
			(xy 445.899968 -111.503735) (xy 445.878834 -111.455529) (xy 445.864523 -111.404877) (xy 445.857304 -111.35274)
			(xy 445.856868 -111.326422) (xy 445.857354 -111.299171) (xy 445.86511 -111.245223) (xy 445.880465 -111.192928)
			(xy 445.903107 -111.143351) (xy 445.932573 -111.097501) (xy 445.968264 -111.05631) (xy 446.009455 -111.020619)
			(xy 446.055305 -110.991153) (xy 446.104882 -110.968511) (xy 446.157177 -110.953156) (xy 446.211125 -110.9454)
			(xy 446.265627 -110.9454) (xy 446.319575 -110.953156) (xy 446.37187 -110.968511) (xy 446.421447 -110.991153)
			(xy 446.467297 -111.020619) (xy 446.508488 -111.05631) (xy 446.544179 -111.097501) (xy 446.573645 -111.143351)
			(xy 446.596287 -111.192928) (xy 446.611642 -111.245223) (xy 446.619398 -111.299171) (xy 446.619884 -111.326422)
			(xy 446.619436 -111.352737) (xy 446.612198 -111.404866) (xy 446.597876 -111.45551) (xy 446.576739 -111.503709)
			(xy 446.54919 -111.548552) (xy 446.515747 -111.58919) (xy 446.496694 -111.607346) (xy 446.489269 -111.614848)
			(xy 446.480759 -111.634143) (xy 446.480184 -111.644684) (xy 446.480184 -111.71936) (xy 446.480726 -111.729908)
			(xy 446.489253 -111.749203) (xy 446.496694 -111.756698) (xy 446.517505 -111.776495) (xy 446.553482 -111.82127)
			(xy 446.582343 -111.870931) (xy 446.603436 -111.924356) (xy 446.616284 -111.980339) (xy 446.620598 -112.037615)
			(xy 448.394417 -112.037615) (xy 448.39873 -111.980345) (xy 448.411576 -111.924367) (xy 448.432666 -111.870947)
			(xy 448.461522 -111.82129) (xy 448.497494 -111.776518) (xy 448.51828 -111.756698) (xy 448.525682 -111.749176)
			(xy 448.534207 -111.729896) (xy 448.53479 -111.71936) (xy 448.53479 -111.644684) (xy 448.534286 -111.634131)
			(xy 448.525734 -111.614836) (xy 448.51828 -111.607346) (xy 448.499201 -111.589214) (xy 448.465747 -111.548578)
			(xy 448.438192 -111.503733) (xy 448.417057 -111.455528) (xy 448.402745 -111.404877) (xy 448.395526 -111.352739)
			(xy 448.39509 -111.326422) (xy 448.395576 -111.299171) (xy 448.403332 -111.245223) (xy 448.418687 -111.192928)
			(xy 448.441329 -111.143351) (xy 448.470795 -111.097501) (xy 448.506486 -111.05631) (xy 448.547677 -111.020619)
			(xy 448.593527 -110.991153) (xy 448.643104 -110.968511) (xy 448.695399 -110.953156) (xy 448.749347 -110.9454)
			(xy 448.803849 -110.9454) (xy 448.857797 -110.953156) (xy 448.910092 -110.968511) (xy 448.959669 -110.991153)
			(xy 449.005519 -111.020619) (xy 449.04671 -111.05631) (xy 449.082401 -111.097501) (xy 449.111867 -111.143351)
			(xy 449.134509 -111.192928) (xy 449.149864 -111.245223) (xy 449.15762 -111.299171) (xy 449.158106 -111.326422)
			(xy 449.157651 -111.352736) (xy 449.150414 -111.404865) (xy 449.136092 -111.455508) (xy 449.114957 -111.503707)
			(xy 449.087409 -111.54855) (xy 449.053968 -111.58919) (xy 449.034916 -111.607346) (xy 449.027494 -111.614851)
			(xy 449.018981 -111.634143) (xy 449.018406 -111.644684) (xy 449.018406 -111.71936) (xy 449.018941 -111.729909)
			(xy 449.027472 -111.749205) (xy 449.034916 -111.756698) (xy 449.055726 -111.776496) (xy 449.091701 -111.821271)
			(xy 449.12056 -111.870932) (xy 449.141652 -111.924357) (xy 449.154499 -111.98034) (xy 449.155522 -111.993923)
			(xy 452.597351 -111.993923) (xy 452.601664 -111.936653) (xy 452.61451 -111.880675) (xy 452.6356 -111.827255)
			(xy 452.664458 -111.777599) (xy 452.700431 -111.732829) (xy 452.721218 -111.71301) (xy 452.72862 -111.705489)
			(xy 452.737144 -111.686208) (xy 452.737728 -111.675672) (xy 452.737728 -111.600996) (xy 452.737206 -111.590446)
			(xy 452.728665 -111.571151) (xy 452.721218 -111.563658) (xy 452.700462 -111.543805) (xy 452.664484 -111.499039)
			(xy 452.63562 -111.449386) (xy 452.614523 -111.395969) (xy 452.60167 -111.339993) (xy 452.597351 -111.282723)
			(xy 452.601664 -111.225453) (xy 452.61451 -111.169475) (xy 452.6356 -111.116055) (xy 452.664458 -111.066399)
			(xy 452.700431 -111.021629) (xy 452.721218 -111.00181) (xy 452.72862 -110.994289) (xy 452.737144 -110.975008)
			(xy 452.737728 -110.964472) (xy 452.737728 -110.889796) (xy 452.737206 -110.879246) (xy 452.728665 -110.859951)
			(xy 452.721218 -110.852458) (xy 452.702153 -110.834312) (xy 452.668696 -110.793681) (xy 452.641137 -110.748839)
			(xy 452.620001 -110.700636) (xy 452.605686 -110.649986) (xy 452.598464 -110.597851) (xy 452.598028 -110.571534)
			(xy 452.598487 -110.54428) (xy 452.60624 -110.490327) (xy 452.621594 -110.438027) (xy 452.644235 -110.388445)
			(xy 452.673703 -110.34259) (xy 452.709397 -110.301396) (xy 452.750591 -110.265702) (xy 452.796447 -110.236234)
			(xy 452.846029 -110.213593) (xy 452.898329 -110.19824) (xy 452.952282 -110.190487) (xy 452.979536 -110.190026)
			(xy 453.005851 -110.190461) (xy 453.057981 -110.197701) (xy 453.108625 -110.212026) (xy 453.156824 -110.233165)
			(xy 453.201667 -110.260717) (xy 453.242305 -110.294162) (xy 453.26046 -110.313216) (xy 453.267992 -110.320604)
			(xy 453.287264 -110.329136) (xy 453.297798 -110.329726) (xy 453.372474 -110.329726) (xy 453.383022 -110.329188)
			(xy 453.402317 -110.320658) (xy 453.409812 -110.313216) (xy 453.427972 -110.294165) (xy 453.4686 -110.260707)
			(xy 453.51344 -110.233147) (xy 453.56164 -110.212007) (xy 453.612286 -110.197689) (xy 453.66442 -110.190464)
			(xy 453.690736 -110.190026) (xy 453.71799 -110.190444) (xy 453.771942 -110.198207) (xy 453.82424 -110.213568)
			(xy 453.873819 -110.236216) (xy 453.913439 -110.261683) (xy 455.214548 -110.261683) (xy 455.214548 -110.209717)
			(xy 455.222677 -110.158392) (xy 455.238734 -110.10897) (xy 455.262325 -110.062668) (xy 455.292869 -110.020627)
			(xy 455.329613 -109.983881) (xy 455.371653 -109.953335) (xy 455.417953 -109.929741) (xy 455.467374 -109.913681)
			(xy 455.518699 -109.905549) (xy 455.544682 -109.905038) (xy 455.571328 -109.905497) (xy 455.623931 -109.914033)
			(xy 455.674482 -109.930904) (xy 455.721668 -109.955672) (xy 455.764266 -109.987694) (xy 455.80117 -110.026139)
			(xy 455.816716 -110.047786) (xy 455.82508 -110.059072) (xy 455.846753 -110.076927) (xy 455.872467 -110.08821)
			(xy 455.900282 -110.092068) (xy 455.928097 -110.08821) (xy 455.953811 -110.076927) (xy 455.975484 -110.059072)
			(xy 455.983848 -110.047786) (xy 455.999412 -110.026159) (xy 456.036331 -109.987743) (xy 456.078931 -109.955744)
			(xy 456.126112 -109.930989) (xy 456.176652 -109.914121) (xy 456.229242 -109.905575) (xy 456.255882 -109.905038)
			(xy 456.281876 -109.905428) (xy 456.333224 -109.913558) (xy 456.382667 -109.929621) (xy 456.42899 -109.953221)
			(xy 456.471049 -109.983777) (xy 456.507811 -110.020537) (xy 456.53837 -110.062595) (xy 456.561972 -110.108916)
			(xy 456.578038 -110.158359) (xy 456.586171 -110.209706) (xy 456.586171 -110.261694) (xy 456.578038 -110.313041)
			(xy 456.561972 -110.362484) (xy 456.53837 -110.408805) (xy 456.507811 -110.450863) (xy 456.471049 -110.487623)
			(xy 456.432466 -110.515654) (xy 459.128112 -110.515654) (xy 459.132183 -110.460032) (xy 459.144309 -110.405595)
			(xy 459.164232 -110.353504) (xy 459.191528 -110.304869) (xy 459.225614 -110.260726) (xy 459.265763 -110.222017)
			(xy 459.311121 -110.189566) (xy 459.360721 -110.164065) (xy 459.413505 -110.146058) (xy 459.468348 -110.135928)
			(xy 459.524082 -110.133891) (xy 459.579519 -110.139991) (xy 459.633476 -110.154097) (xy 459.684805 -110.175909)
			(xy 459.732411 -110.204963) (xy 459.775279 -110.240638) (xy 459.812496 -110.282175) (xy 459.843269 -110.328688)
			(xy 459.866941 -110.379185) (xy 459.883009 -110.432592) (xy 459.891129 -110.487768) (xy 459.891638 -110.515654)
			(xy 459.891129 -110.54354) (xy 459.883009 -110.598716) (xy 459.866941 -110.652123) (xy 459.843269 -110.70262)
			(xy 459.812496 -110.749133) (xy 459.775279 -110.79067) (xy 459.732411 -110.826345) (xy 459.684805 -110.855399)
			(xy 459.633476 -110.877211) (xy 459.579519 -110.891317) (xy 459.524082 -110.897417) (xy 459.468348 -110.89538)
			(xy 459.413505 -110.88525) (xy 459.360721 -110.867243) (xy 459.311121 -110.841742) (xy 459.265763 -110.809291)
			(xy 459.225614 -110.770582) (xy 459.191528 -110.726439) (xy 459.164232 -110.677804) (xy 459.144309 -110.625713)
			(xy 459.132183 -110.571276) (xy 459.128112 -110.515654) (xy 456.432466 -110.515654) (xy 456.42899 -110.518179)
			(xy 456.382667 -110.541779) (xy 456.333224 -110.557842) (xy 456.281876 -110.565972) (xy 456.255882 -110.566454)
			(xy 456.229238 -110.565951) (xy 456.176636 -110.557424) (xy 456.126087 -110.540563) (xy 456.0789 -110.515803)
			(xy 456.036301 -110.483789) (xy 455.999395 -110.44535) (xy 455.983848 -110.423706) (xy 455.975484 -110.41242)
			(xy 455.953811 -110.394565) (xy 455.928097 -110.383282) (xy 455.900282 -110.379424) (xy 455.872467 -110.383282)
			(xy 455.846753 -110.394565) (xy 455.82508 -110.41242) (xy 455.816716 -110.423706) (xy 455.80111 -110.445301)
			(xy 455.7642 -110.483719) (xy 455.721608 -110.515722) (xy 455.674436 -110.540482) (xy 455.623904 -110.557357)
			(xy 455.57132 -110.565912) (xy 455.544682 -110.566454) (xy 455.518699 -110.565851) (xy 455.467374 -110.557719)
			(xy 455.417953 -110.541659) (xy 455.371653 -110.518065) (xy 455.329613 -110.487519) (xy 455.292869 -110.450773)
			(xy 455.262325 -110.408732) (xy 455.238734 -110.36243) (xy 455.222677 -110.313008) (xy 455.214548 -110.261683)
			(xy 453.913439 -110.261683) (xy 453.919671 -110.265689) (xy 453.960862 -110.301388) (xy 453.996553 -110.342585)
			(xy 454.026018 -110.388442) (xy 454.048656 -110.438026) (xy 454.064008 -110.490327) (xy 454.071761 -110.54428)
			(xy 454.072244 -110.571534) (xy 454.071817 -110.59785) (xy 454.064577 -110.649981) (xy 454.050251 -110.700625)
			(xy 454.029111 -110.748824) (xy 454.001557 -110.793666) (xy 453.96811 -110.834303) (xy 453.949054 -110.852458)
			(xy 453.941677 -110.860001) (xy 453.933137 -110.879264) (xy 453.932544 -110.889796) (xy 453.932544 -110.964472)
			(xy 453.933062 -110.975023) (xy 453.941604 -110.994319) (xy 453.949054 -111.00181) (xy 453.969874 -111.021597)
			(xy 454.005846 -111.066375) (xy 454.034702 -111.116038) (xy 454.052798 -111.161885) (xy 455.214523 -111.161885)
			(xy 455.214523 -111.109915) (xy 455.222653 -111.058586) (xy 455.238712 -111.00916) (xy 455.262304 -110.962855)
			(xy 455.29285 -110.920811) (xy 455.329597 -110.884062) (xy 455.37164 -110.853514) (xy 455.417944 -110.829919)
			(xy 455.467369 -110.813857) (xy 455.518697 -110.805725) (xy 455.544682 -110.805214) (xy 455.571327 -110.805683)
			(xy 455.62393 -110.814219) (xy 455.674479 -110.831089) (xy 455.721665 -110.855854) (xy 455.764264 -110.887874)
			(xy 455.801169 -110.926316) (xy 455.816716 -110.947962) (xy 455.82508 -110.959248) (xy 455.846753 -110.977103)
			(xy 455.872467 -110.988386) (xy 455.900282 -110.992244) (xy 455.928097 -110.988386) (xy 455.953811 -110.977103)
			(xy 455.975484 -110.959248) (xy 455.983848 -110.947962) (xy 455.999405 -110.92633) (xy 456.036326 -110.887915)
			(xy 456.078928 -110.855917) (xy 456.12611 -110.831164) (xy 456.176651 -110.814296) (xy 456.229242 -110.805751)
			(xy 456.255882 -110.805214) (xy 456.281874 -110.805652) (xy 456.333218 -110.813781) (xy 456.382658 -110.829843)
			(xy 456.428977 -110.853441) (xy 456.471034 -110.883995) (xy 456.507793 -110.920752) (xy 456.538349 -110.962808)
			(xy 456.56195 -111.009125) (xy 456.578014 -111.058564) (xy 456.586147 -111.109908) (xy 456.586147 -111.161892)
			(xy 456.578014 -111.213236) (xy 456.56195 -111.262675) (xy 456.538349 -111.308992) (xy 456.507793 -111.351048)
			(xy 456.471034 -111.387805) (xy 456.428977 -111.418359) (xy 456.382658 -111.441957) (xy 456.333218 -111.458019)
			(xy 456.281874 -111.466148) (xy 456.255882 -111.46663) (xy 456.229237 -111.466138) (xy 456.176635 -111.45761)
			(xy 456.126084 -111.440747) (xy 456.078897 -111.415985) (xy 456.036299 -111.383969) (xy 455.999394 -111.345527)
			(xy 455.983848 -111.323882) (xy 455.975484 -111.312596) (xy 455.953811 -111.294741) (xy 455.928097 -111.283458)
			(xy 455.900282 -111.2796) (xy 455.872467 -111.283458) (xy 455.846753 -111.294741) (xy 455.82508 -111.312596)
			(xy 455.816716 -111.323882) (xy 455.801133 -111.345494) (xy 455.764215 -111.383907) (xy 455.721618 -111.415906)
			(xy 455.674441 -111.440662) (xy 455.623907 -111.457535) (xy 455.571321 -111.466089) (xy 455.544682 -111.46663)
			(xy 455.518697 -111.466075) (xy 455.467369 -111.457943) (xy 455.417944 -111.441881) (xy 455.37164 -111.418286)
			(xy 455.329597 -111.387738) (xy 455.29285 -111.350989) (xy 455.262304 -111.308945) (xy 455.238712 -111.26264)
			(xy 455.222653 -111.213214) (xy 455.214523 -111.161885) (xy 454.052798 -111.161885) (xy 454.05579 -111.169465)
			(xy 454.068636 -111.225447) (xy 454.072947 -111.282723) (xy 454.068629 -111.339998) (xy 454.055777 -111.395979)
			(xy 454.034681 -111.449403) (xy 454.00582 -111.499063) (xy 453.969843 -111.543837) (xy 453.949054 -111.563658)
			(xy 453.941677 -111.571201) (xy 453.933137 -111.590464) (xy 453.932544 -111.600996) (xy 453.932544 -111.675672)
			(xy 453.933062 -111.686223) (xy 453.941604 -111.705519) (xy 453.949054 -111.71301) (xy 453.969874 -111.732797)
			(xy 454.005846 -111.777575) (xy 454.034702 -111.827238) (xy 454.05579 -111.880665) (xy 454.068636 -111.936647)
			(xy 454.072947 -111.993923) (xy 454.068629 -112.051198) (xy 454.066199 -112.061783) (xy 455.214546 -112.061783)
			(xy 455.214546 -112.009817) (xy 455.222675 -111.958491) (xy 455.238732 -111.909069) (xy 455.262324 -111.862767)
			(xy 455.292867 -111.820725) (xy 455.329612 -111.783979) (xy 455.371652 -111.753433) (xy 455.417952 -111.729839)
			(xy 455.467374 -111.713779) (xy 455.518699 -111.705647) (xy 455.544682 -111.705136) (xy 455.571328 -111.705595)
			(xy 455.623931 -111.714132) (xy 455.674481 -111.731003) (xy 455.721668 -111.755771) (xy 455.764266 -111.787792)
			(xy 455.80117 -111.826237) (xy 455.816716 -111.847884) (xy 455.82508 -111.85917) (xy 455.846753 -111.877025)
			(xy 455.872467 -111.888308) (xy 455.900282 -111.892166) (xy 455.928097 -111.888308) (xy 455.953811 -111.877025)
			(xy 455.975484 -111.85917) (xy 455.983848 -111.847884) (xy 455.999411 -111.826257) (xy 456.03633 -111.787841)
			(xy 456.078931 -111.755841) (xy 456.126112 -111.731087) (xy 456.176651 -111.714219) (xy 456.229242 -111.705673)
			(xy 456.255882 -111.705136) (xy 456.281876 -111.70553) (xy 456.333223 -111.71366) (xy 456.382667 -111.729723)
			(xy 456.428989 -111.753323) (xy 456.471048 -111.783879) (xy 456.472823 -111.785654) (xy 457.757782 -111.785654)
			(xy 457.761853 -111.730032) (xy 457.773979 -111.675595) (xy 457.793902 -111.623504) (xy 457.821198 -111.574869)
			(xy 457.855284 -111.530726) (xy 457.895433 -111.492017) (xy 457.940791 -111.459566) (xy 457.990391 -111.434065)
			(xy 458.043175 -111.416058) (xy 458.098018 -111.405928) (xy 458.153752 -111.403891) (xy 458.209189 -111.409991)
			(xy 458.263146 -111.424097) (xy 458.314475 -111.445909) (xy 458.362081 -111.474963) (xy 458.404949 -111.510638)
			(xy 458.442166 -111.552175) (xy 458.472939 -111.598688) (xy 458.496611 -111.649185) (xy 458.512679 -111.702592)
			(xy 458.520799 -111.757768) (xy 458.521308 -111.785654) (xy 458.520799 -111.81354) (xy 458.512679 -111.868716)
			(xy 458.496611 -111.922123) (xy 458.472939 -111.97262) (xy 458.442166 -112.019133) (xy 458.404949 -112.06067)
			(xy 458.362081 -112.096345) (xy 458.314475 -112.125399) (xy 458.263146 -112.147211) (xy 458.209189 -112.161317)
			(xy 458.153752 -112.167417) (xy 458.098018 -112.16538) (xy 458.043175 -112.15525) (xy 457.990391 -112.137243)
			(xy 457.940791 -112.111742) (xy 457.895433 -112.079291) (xy 457.855284 -112.040582) (xy 457.821198 -111.996439)
			(xy 457.793902 -111.947804) (xy 457.773979 -111.895713) (xy 457.761853 -111.841276) (xy 457.757782 -111.785654)
			(xy 456.472823 -111.785654) (xy 456.50781 -111.820638) (xy 456.538368 -111.862696) (xy 456.56197 -111.909017)
			(xy 456.578036 -111.958459) (xy 456.586169 -112.009806) (xy 456.586169 -112.061794) (xy 456.578036 -112.113141)
			(xy 456.56197 -112.162583) (xy 456.538368 -112.208904) (xy 456.50781 -112.250962) (xy 456.471048 -112.287721)
			(xy 456.458336 -112.296956) (xy 459.194914 -112.296956) (xy 459.198985 -112.241334) (xy 459.211111 -112.186897)
			(xy 459.231034 -112.134806) (xy 459.25833 -112.086171) (xy 459.292416 -112.042028) (xy 459.332565 -112.003319)
			(xy 459.377923 -111.970868) (xy 459.427523 -111.945367) (xy 459.480307 -111.92736) (xy 459.53515 -111.91723)
			(xy 459.590884 -111.915193) (xy 459.646321 -111.921293) (xy 459.700278 -111.935399) (xy 459.751607 -111.957211)
			(xy 459.799213 -111.986265) (xy 459.842081 -112.02194) (xy 459.879298 -112.063477) (xy 459.910071 -112.10999)
			(xy 459.933743 -112.160487) (xy 459.949811 -112.213894) (xy 459.957931 -112.26907) (xy 459.95844 -112.296956)
			(xy 459.957931 -112.324842) (xy 459.949811 -112.380018) (xy 459.933743 -112.433425) (xy 459.910071 -112.483922)
			(xy 459.879298 -112.530435) (xy 459.842081 -112.571972) (xy 459.799213 -112.607647) (xy 459.751607 -112.636701)
			(xy 459.700278 -112.658513) (xy 459.646321 -112.672619) (xy 459.590884 -112.678719) (xy 459.53515 -112.676682)
			(xy 459.480307 -112.666552) (xy 459.427523 -112.648545) (xy 459.377923 -112.623044) (xy 459.332565 -112.590593)
			(xy 459.292416 -112.551884) (xy 459.25833 -112.507741) (xy 459.231034 -112.459106) (xy 459.211111 -112.407015)
			(xy 459.198985 -112.352578) (xy 459.194914 -112.296956) (xy 456.458336 -112.296956) (xy 456.428989 -112.318277)
			(xy 456.382667 -112.341877) (xy 456.333223 -112.35794) (xy 456.281876 -112.36607) (xy 456.255882 -112.366552)
			(xy 456.229238 -112.36605) (xy 456.176636 -112.357523) (xy 456.126086 -112.340661) (xy 456.0789 -112.315902)
			(xy 456.036301 -112.283887) (xy 455.999395 -112.245448) (xy 455.983848 -112.223804) (xy 455.975484 -112.212518)
			(xy 455.953811 -112.194663) (xy 455.928097 -112.18338) (xy 455.900282 -112.179522) (xy 455.872467 -112.18338)
			(xy 455.846753 -112.194663) (xy 455.82508 -112.212518) (xy 455.816716 -112.223804) (xy 455.801109 -112.245399)
			(xy 455.7642 -112.283817) (xy 455.721608 -112.31582) (xy 455.674436 -112.340579) (xy 455.623904 -112.357455)
			(xy 455.57132 -112.36601) (xy 455.544682 -112.366552) (xy 455.518699 -112.365953) (xy 455.467374 -112.357821)
			(xy 455.417952 -112.341761) (xy 455.371652 -112.318167) (xy 455.329612 -112.287621) (xy 455.292867 -112.250875)
			(xy 455.262324 -112.208833) (xy 455.238732 -112.162531) (xy 455.222675 -112.113109) (xy 455.214546 -112.061783)
			(xy 454.066199 -112.061783) (xy 454.055777 -112.107179) (xy 454.034681 -112.160603) (xy 454.00582 -112.210263)
			(xy 453.969843 -112.255037) (xy 453.949054 -112.274858) (xy 453.941677 -112.282401) (xy 453.933137 -112.301664)
			(xy 453.932544 -112.312196) (xy 453.932544 -112.386872) (xy 453.933062 -112.397423) (xy 453.941604 -112.416719)
			(xy 453.949054 -112.42421) (xy 453.968118 -112.442357) (xy 454.001572 -112.48299) (xy 454.029129 -112.527832)
			(xy 454.050265 -112.576034) (xy 454.064581 -112.626683) (xy 454.071806 -112.678818) (xy 454.072244 -112.705134)
			(xy 454.071754 -112.732384) (xy 454.063994 -112.78633) (xy 454.048636 -112.838623) (xy 454.025994 -112.888198)
			(xy 453.996527 -112.934046) (xy 453.972487 -112.961789) (xy 455.214468 -112.961789) (xy 455.214468 -112.909811)
			(xy 455.222598 -112.858473) (xy 455.23866 -112.809039) (xy 455.262257 -112.762726) (xy 455.292808 -112.720674)
			(xy 455.329561 -112.683919) (xy 455.371611 -112.653366) (xy 455.417922 -112.629767) (xy 455.467356 -112.613703)
			(xy 455.518693 -112.605569) (xy 455.544682 -112.605058) (xy 455.571328 -112.605508) (xy 455.623932 -112.614045)
			(xy 455.674484 -112.630917) (xy 455.72167 -112.655687) (xy 455.764268 -112.687711) (xy 455.801171 -112.726158)
			(xy 455.816716 -112.747806) (xy 455.82508 -112.759092) (xy 455.846753 -112.776947) (xy 455.872467 -112.78823)
			(xy 455.900282 -112.792088) (xy 455.928097 -112.78823) (xy 455.953811 -112.776947) (xy 455.975484 -112.759092)
			(xy 455.983848 -112.747806) (xy 455.999388 -112.726162) (xy 456.036315 -112.68775) (xy 456.078921 -112.655755)
			(xy 456.126106 -112.631005) (xy 456.176648 -112.614139) (xy 456.229241 -112.605594) (xy 456.255882 -112.605058)
			(xy 456.28187 -112.605608) (xy 456.333205 -112.613736) (xy 456.382637 -112.629795) (xy 456.428948 -112.653389)
			(xy 456.470997 -112.683938) (xy 456.50775 -112.720689) (xy 456.538301 -112.762737) (xy 456.561898 -112.809046)
			(xy 456.57796 -112.858477) (xy 456.586091 -112.909813) (xy 456.586091 -112.961787) (xy 456.57796 -113.013123)
			(xy 456.561898 -113.062554) (xy 456.538301 -113.108863) (xy 456.50775 -113.150911) (xy 456.470997 -113.187662)
			(xy 456.428948 -113.218211) (xy 456.382637 -113.241805) (xy 456.333205 -113.257864) (xy 456.28187 -113.265992)
			(xy 456.255882 -113.266474) (xy 456.229238 -113.265963) (xy 456.176638 -113.257436) (xy 456.126088 -113.240576)
			(xy 456.078902 -113.215818) (xy 456.036303 -113.183805) (xy 455.999395 -113.145369) (xy 455.983848 -113.123726)
			(xy 455.975484 -113.11244) (xy 455.953811 -113.094585) (xy 455.928097 -113.083302) (xy 455.900282 -113.079444)
			(xy 455.872467 -113.083302) (xy 455.846753 -113.094585) (xy 455.82508 -113.11244) (xy 455.816716 -113.123726)
			(xy 455.801116 -113.145325) (xy 455.764204 -113.183742) (xy 455.721611 -113.215744) (xy 455.674437 -113.240503)
			(xy 455.623904 -113.257378) (xy 455.57132 -113.265932) (xy 455.544682 -113.266474) (xy 455.518693 -113.266031)
			(xy 455.467356 -113.257897) (xy 455.417922 -113.241833) (xy 455.371611 -113.218234) (xy 455.329561 -113.187681)
			(xy 455.292808 -113.150926) (xy 455.262257 -113.108874) (xy 455.23866 -113.062561) (xy 455.222598 -113.013127)
			(xy 455.214468 -112.961789) (xy 453.972487 -112.961789) (xy 453.960836 -112.975235) (xy 453.919648 -113.010926)
			(xy 453.873799 -113.040393) (xy 453.824224 -113.063035) (xy 453.771932 -113.078393) (xy 453.717986 -113.086154)
			(xy 453.690736 -113.086642) (xy 453.66442 -113.086236) (xy 453.612288 -113.078991) (xy 453.561643 -113.064661)
			(xy 453.513444 -113.043517) (xy 453.468602 -113.01596) (xy 453.427966 -112.982509) (xy 453.409812 -112.963452)
			(xy 453.402281 -112.956061) (xy 453.383008 -112.947529) (xy 453.372474 -112.946942) (xy 453.297798 -112.946942)
			(xy 453.287245 -112.947444) (xy 453.267949 -112.955997) (xy 453.26046 -112.963452) (xy 453.242327 -112.98253)
			(xy 453.201691 -113.015983) (xy 453.156846 -113.043538) (xy 453.108641 -113.064672) (xy 453.05799 -113.078985)
			(xy 453.005853 -113.086206) (xy 452.979536 -113.086642) (xy 452.952286 -113.086111) (xy 452.898339 -113.07836)
			(xy 452.846044 -113.06301) (xy 452.796467 -113.040375) (xy 452.750615 -113.010913) (xy 452.709423 -112.975227)
			(xy 452.673729 -112.934041) (xy 452.644259 -112.888195) (xy 452.621614 -112.838621) (xy 452.606255 -112.78633)
			(xy 452.598494 -112.732384) (xy 452.598028 -112.705134) (xy 452.598442 -112.678818) (xy 452.605687 -112.626687)
			(xy 452.620016 -112.576043) (xy 452.641158 -112.527844) (xy 452.668714 -112.483002) (xy 452.702162 -112.442365)
			(xy 452.721218 -112.42421) (xy 452.72862 -112.416689) (xy 452.737144 -112.397408) (xy 452.737728 -112.386872)
			(xy 452.737728 -112.312196) (xy 452.737206 -112.301646) (xy 452.728665 -112.282351) (xy 452.721218 -112.274858)
			(xy 452.700462 -112.255005) (xy 452.664484 -112.210239) (xy 452.63562 -112.160586) (xy 452.614523 -112.107169)
			(xy 452.60167 -112.051193) (xy 452.597351 -111.993923) (xy 449.155522 -111.993923) (xy 449.158813 -112.037615)
			(xy 449.154495 -112.09489) (xy 449.141643 -112.150871) (xy 449.120547 -112.204294) (xy 449.091684 -112.253953)
			(xy 449.055706 -112.298726) (xy 449.034916 -112.318546) (xy 449.027494 -112.326051) (xy 449.018981 -112.345343)
			(xy 449.018406 -112.355884) (xy 449.018406 -112.43056) (xy 449.018941 -112.441109) (xy 449.027472 -112.460405)
			(xy 449.034916 -112.467898) (xy 449.053967 -112.486058) (xy 449.087424 -112.526687) (xy 449.114983 -112.571527)
			(xy 449.136122 -112.619727) (xy 449.15044 -112.670373) (xy 449.157667 -112.722506) (xy 449.158106 -112.748822)
			(xy 449.15762 -112.776073) (xy 449.149864 -112.830021) (xy 449.134509 -112.882316) (xy 449.111867 -112.931893)
			(xy 449.082401 -112.977743) (xy 449.04671 -113.018934) (xy 449.005519 -113.054625) (xy 448.959669 -113.084091)
			(xy 448.910092 -113.106733) (xy 448.857797 -113.122088) (xy 448.803849 -113.129844) (xy 448.749347 -113.129844)
			(xy 448.695399 -113.122088) (xy 448.643104 -113.106733) (xy 448.593527 -113.084091) (xy 448.547677 -113.054625)
			(xy 448.506486 -113.018934) (xy 448.470795 -112.977743) (xy 448.441329 -112.931893) (xy 448.418687 -112.882316)
			(xy 448.403332 -112.830021) (xy 448.395576 -112.776073) (xy 448.39509 -112.748822) (xy 448.395575 -112.722509)
			(xy 448.402807 -112.670381) (xy 448.417123 -112.619739) (xy 448.438252 -112.57154) (xy 448.465795 -112.526696)
			(xy 448.49923 -112.486055) (xy 448.51828 -112.467898) (xy 448.525682 -112.460376) (xy 448.534207 -112.441096)
			(xy 448.53479 -112.43056) (xy 448.53479 -112.355884) (xy 448.534286 -112.345331) (xy 448.525734 -112.326036)
			(xy 448.51828 -112.318546) (xy 448.497514 -112.298704) (xy 448.461539 -112.253935) (xy 448.432679 -112.20428)
			(xy 448.411585 -112.150861) (xy 448.398734 -112.094885) (xy 448.394417 -112.037615) (xy 446.620598 -112.037615)
			(xy 446.61628 -112.094891) (xy 446.603427 -112.150872) (xy 446.58233 -112.204296) (xy 446.553465 -112.253954)
			(xy 446.517485 -112.298727) (xy 446.496694 -112.318546) (xy 446.489269 -112.326048) (xy 446.480759 -112.345343)
			(xy 446.480184 -112.355884) (xy 446.480184 -112.43056) (xy 446.480726 -112.441108) (xy 446.489253 -112.460403)
			(xy 446.496694 -112.467898) (xy 446.51574 -112.486063) (xy 446.549199 -112.52669) (xy 446.576759 -112.571529)
			(xy 446.597899 -112.619728) (xy 446.612218 -112.670374) (xy 446.619445 -112.722506) (xy 446.619884 -112.748822)
			(xy 446.619398 -112.776073) (xy 446.611642 -112.830021) (xy 446.596287 -112.882316) (xy 446.573645 -112.931893)
			(xy 446.544179 -112.977743) (xy 446.508488 -113.018934) (xy 446.467297 -113.054625) (xy 446.421447 -113.084091)
			(xy 446.37187 -113.106733) (xy 446.319575 -113.122088) (xy 446.265627 -113.129844) (xy 446.211125 -113.129844)
			(xy 446.157177 -113.122088) (xy 446.104882 -113.106733) (xy 446.055305 -113.084091) (xy 446.009455 -113.054625)
			(xy 445.968264 -113.018934) (xy 445.932573 -112.977743) (xy 445.903107 -112.931893) (xy 445.880465 -112.882316)
			(xy 445.86511 -112.830021) (xy 445.857354 -112.776073) (xy 445.856868 -112.748822) (xy 445.85736 -112.722509)
			(xy 445.864592 -112.670382) (xy 445.878906 -112.61974) (xy 445.900034 -112.571541) (xy 445.927575 -112.526697)
			(xy 445.961009 -112.486056) (xy 445.980058 -112.467898) (xy 445.987456 -112.460373) (xy 445.995984 -112.441096)
			(xy 445.996568 -112.43056) (xy 445.996568 -112.355884) (xy 445.99607 -112.34533) (xy 445.987514 -112.326035)
			(xy 445.980058 -112.318546) (xy 445.959293 -112.298703) (xy 445.92332 -112.253933) (xy 445.894462 -112.204279)
			(xy 445.873369 -112.15086) (xy 445.860519 -112.094884) (xy 445.856202 -112.037615) (xy 444.06285 -112.037615)
			(xy 444.094309 -112.075823) (xy 444.121867 -112.120665) (xy 444.143003 -112.168869) (xy 444.157317 -112.219519)
			(xy 444.164538 -112.271655) (xy 444.164974 -112.297972) (xy 444.164488 -112.325223) (xy 444.156732 -112.379171)
			(xy 444.141377 -112.431466) (xy 444.118735 -112.481043) (xy 444.089269 -112.526893) (xy 444.053578 -112.568084)
			(xy 444.012387 -112.603775) (xy 443.966537 -112.633241) (xy 443.91696 -112.655883) (xy 443.864665 -112.671238)
			(xy 443.810717 -112.678994) (xy 443.756215 -112.678994) (xy 443.702267 -112.671238) (xy 443.649972 -112.655883)
			(xy 443.600395 -112.633241) (xy 443.554545 -112.603775) (xy 443.513354 -112.568084) (xy 443.477663 -112.526893)
			(xy 443.448197 -112.481043) (xy 443.425555 -112.431466) (xy 443.4102 -112.379171) (xy 443.402444 -112.325223)
			(xy 443.401958 -112.297972) (xy 442.132974 -112.297972) (xy 442.132488 -112.325223) (xy 442.124732 -112.379171)
			(xy 442.109377 -112.431466) (xy 442.086735 -112.481043) (xy 442.057269 -112.526893) (xy 442.021578 -112.568084)
			(xy 441.980387 -112.603775) (xy 441.934537 -112.633241) (xy 441.88496 -112.655883) (xy 441.832665 -112.671238)
			(xy 441.778717 -112.678994) (xy 441.724215 -112.678994) (xy 441.670267 -112.671238) (xy 441.617972 -112.655883)
			(xy 441.568395 -112.633241) (xy 441.522545 -112.603775) (xy 441.481354 -112.568084) (xy 441.445663 -112.526893)
			(xy 441.416197 -112.481043) (xy 441.393555 -112.431466) (xy 441.3782 -112.379171) (xy 441.370444 -112.325223)
			(xy 441.369958 -112.297972) (xy 435.012084 -112.297972) (xy 435.012084 -114.084613) (xy 437.749383 -114.084613)
			(xy 437.749388 -114.030111) (xy 437.75715 -113.976165) (xy 437.77251 -113.923872) (xy 437.795156 -113.874298)
			(xy 437.824627 -113.828451) (xy 437.860322 -113.787265) (xy 437.901515 -113.751579) (xy 437.947368 -113.722118)
			(xy 437.996947 -113.699482) (xy 438.049243 -113.684133) (xy 438.103191 -113.676382) (xy 438.130442 -113.675922)
			(xy 438.130696 -113.675922) (xy 438.160133 -113.676472) (xy 438.218307 -113.685537) (xy 438.24652 -113.693956)
			(xy 438.258458 -113.697766) (xy 438.282334 -113.693956) (xy 438.358534 -113.637568) (xy 438.367806 -113.629826)
			(xy 438.37855 -113.608231) (xy 438.379108 -113.596166) (xy 438.379108 -113.591086) (xy 438.379542 -113.563832)
			(xy 438.387301 -113.509879) (xy 438.40266 -113.45758) (xy 438.425305 -113.407998) (xy 438.454776 -113.362145)
			(xy 438.490473 -113.320952) (xy 438.531669 -113.285258) (xy 438.577525 -113.255791) (xy 438.627108 -113.233149)
			(xy 438.679409 -113.217795) (xy 438.733362 -113.21004) (xy 438.760616 -113.209578) (xy 438.789532 -113.210127)
			(xy 438.846703 -113.218846) (xy 438.901903 -113.236096) (xy 438.953865 -113.261481) (xy 439.0014 -113.294421)
			(xy 439.043416 -113.33416) (xy 439.061606 -113.356644) (xy 439.069213 -113.365451) (xy 439.090114 -113.375633)
			(xy 439.101738 -113.376202) (xy 439.181494 -113.376202) (xy 439.193124 -113.375645) (xy 439.214033 -113.365469)
			(xy 439.221626 -113.356644) (xy 439.239813 -113.334157) (xy 439.281833 -113.29442) (xy 439.329368 -113.26148)
			(xy 439.38133 -113.236092) (xy 439.436529 -113.218837) (xy 439.4937 -113.210111) (xy 439.522616 -113.209578)
			(xy 439.549867 -113.210063) (xy 439.603814 -113.217821) (xy 439.656108 -113.233178) (xy 439.705684 -113.25582)
			(xy 439.751534 -113.285286) (xy 439.792724 -113.320978) (xy 439.828415 -113.362168) (xy 439.857881 -113.408017)
			(xy 439.880523 -113.457594) (xy 439.895879 -113.509888) (xy 439.903637 -113.563835) (xy 439.903725 -113.568734)
			(xy 459.189834 -113.568734) (xy 459.193905 -113.513112) (xy 459.206031 -113.458675) (xy 459.225954 -113.406584)
			(xy 459.25325 -113.357949) (xy 459.287336 -113.313806) (xy 459.327485 -113.275097) (xy 459.372843 -113.242646)
			(xy 459.422443 -113.217145) (xy 459.475227 -113.199138) (xy 459.53007 -113.189008) (xy 459.585804 -113.186971)
			(xy 459.641241 -113.193071) (xy 459.695198 -113.207177) (xy 459.746527 -113.228989) (xy 459.794133 -113.258043)
			(xy 459.837001 -113.293718) (xy 459.874218 -113.335255) (xy 459.904991 -113.381768) (xy 459.928663 -113.432265)
			(xy 459.944731 -113.485672) (xy 459.952851 -113.540848) (xy 459.95336 -113.568734) (xy 459.952851 -113.59662)
			(xy 459.944731 -113.651796) (xy 459.928663 -113.705203) (xy 459.904991 -113.7557) (xy 459.874218 -113.802213)
			(xy 459.837001 -113.84375) (xy 459.794133 -113.879425) (xy 459.746527 -113.908479) (xy 459.695198 -113.930291)
			(xy 459.641241 -113.944397) (xy 459.585804 -113.950497) (xy 459.53007 -113.94846) (xy 459.475227 -113.93833)
			(xy 459.422443 -113.920323) (xy 459.372843 -113.894822) (xy 459.327485 -113.862371) (xy 459.287336 -113.823662)
			(xy 459.25325 -113.779519) (xy 459.225954 -113.730884) (xy 459.206031 -113.678793) (xy 459.193905 -113.624356)
			(xy 459.189834 -113.568734) (xy 439.903725 -113.568734) (xy 439.904124 -113.591086) (xy 439.903696 -113.618491)
			(xy 439.895842 -113.672735) (xy 439.880307 -113.725297) (xy 439.857412 -113.775095) (xy 439.827627 -113.821106)
			(xy 439.791566 -113.862381) (xy 439.74997 -113.898072) (xy 439.727086 -113.913158) (xy 439.718067 -113.919608)
			(xy 439.706213 -113.938317) (xy 439.704226 -113.949226) (xy 439.692034 -114.037364) (xy 439.698638 -114.0587)
			(xy 439.706258 -114.067082) (xy 439.724546 -114.088672) (xy 439.73208 -114.097462) (xy 439.75286 -114.107627)
			(xy 439.764424 -114.10823) (xy 439.844434 -114.10823) (xy 439.85607 -114.107721) (xy 439.876981 -114.097513)
			(xy 439.884566 -114.088672) (xy 439.902769 -114.066199) (xy 439.944787 -114.026464) (xy 439.99232 -113.993525)
			(xy 440.044279 -113.968135) (xy 440.099474 -113.950876) (xy 440.156641 -113.942143) (xy 440.185556 -113.941606)
			(xy 440.212812 -113.942038) (xy 440.26677 -113.94979) (xy 440.319075 -113.965143) (xy 440.368662 -113.987784)
			(xy 440.414523 -114.017252) (xy 440.427475 -114.028474) (xy 453.305162 -114.028474) (xy 453.309233 -113.972852)
			(xy 453.321359 -113.918415) (xy 453.341282 -113.866324) (xy 453.368578 -113.817689) (xy 453.402664 -113.773546)
			(xy 453.442813 -113.734837) (xy 453.488171 -113.702386) (xy 453.537771 -113.676885) (xy 453.590555 -113.658878)
			(xy 453.645398 -113.648748) (xy 453.701132 -113.646711) (xy 453.756569 -113.652811) (xy 453.810526 -113.666917)
			(xy 453.861855 -113.688729) (xy 453.909461 -113.717783) (xy 453.952329 -113.753458) (xy 453.989546 -113.794995)
			(xy 454.020319 -113.841508) (xy 454.043991 -113.892005) (xy 454.060059 -113.945412) (xy 454.068179 -114.000588)
			(xy 454.068688 -114.028474) (xy 454.068179 -114.05636) (xy 454.060059 -114.111536) (xy 454.043991 -114.164943)
			(xy 454.020319 -114.21544) (xy 453.989546 -114.261953) (xy 453.952329 -114.30349) (xy 453.909461 -114.339165)
			(xy 453.861855 -114.368219) (xy 453.810526 -114.390031) (xy 453.756569 -114.404137) (xy 453.701132 -114.410237)
			(xy 453.645398 -114.4082) (xy 453.590555 -114.39807) (xy 453.537771 -114.380063) (xy 453.488171 -114.354562)
			(xy 453.442813 -114.322111) (xy 453.402664 -114.283402) (xy 453.368578 -114.239259) (xy 453.341282 -114.190624)
			(xy 453.321359 -114.138533) (xy 453.309233 -114.084096) (xy 453.305162 -114.028474) (xy 440.427475 -114.028474)
			(xy 440.455722 -114.052947) (xy 440.491422 -114.094142) (xy 440.520895 -114.139999) (xy 440.543542 -114.189584)
			(xy 440.558901 -114.241887) (xy 440.566659 -114.295844) (xy 440.566659 -114.350356) (xy 440.558901 -114.404313)
			(xy 440.543542 -114.456616) (xy 440.520895 -114.506201) (xy 440.491422 -114.552058) (xy 440.455722 -114.593253)
			(xy 440.414523 -114.628948) (xy 440.368662 -114.658416) (xy 440.319075 -114.681057) (xy 440.26677 -114.69641)
			(xy 440.212812 -114.704162) (xy 440.185556 -114.704622) (xy 440.156639 -114.704093) (xy 440.099467 -114.69537)
			(xy 440.044267 -114.678116) (xy 439.992305 -114.652727) (xy 439.944771 -114.619784) (xy 439.902755 -114.580042)
			(xy 439.884566 -114.557556) (xy 439.876971 -114.548736) (xy 439.856061 -114.538561) (xy 439.844434 -114.537998)
			(xy 439.764678 -114.537998) (xy 439.753046 -114.53854) (xy 439.732137 -114.548727) (xy 439.724546 -114.557556)
			(xy 439.706318 -114.580008) (xy 439.664307 -114.619747) (xy 439.61678 -114.652691) (xy 439.564826 -114.678086)
			(xy 439.509635 -114.695348) (xy 439.45247 -114.704084) (xy 439.423556 -114.704622) (xy 439.396304 -114.704163)
			(xy 439.342356 -114.696401) (xy 439.290062 -114.681041) (xy 439.240486 -114.658396) (xy 439.194636 -114.628926)
			(xy 439.153447 -114.593232) (xy 439.117756 -114.55204) (xy 439.08829 -114.506188) (xy 439.065648 -114.45661)
			(xy 439.050293 -114.404314) (xy 439.042535 -114.350366) (xy 439.042048 -114.323114) (xy 439.042489 -114.29571)
			(xy 439.050342 -114.241467) (xy 439.065876 -114.188906) (xy 439.088769 -114.139108) (xy 439.118552 -114.093098)
			(xy 439.154611 -114.051822) (xy 439.196204 -114.016129) (xy 439.219086 -114.001042) (xy 439.228118 -113.994609)
			(xy 439.239962 -113.975886) (xy 439.241946 -113.964974) (xy 439.254138 -113.876836) (xy 439.247534 -113.8555)
			(xy 439.239914 -113.847118) (xy 439.221626 -113.825528) (xy 439.214061 -113.81677) (xy 439.193304 -113.806588)
			(xy 439.181748 -113.80597) (xy 439.101738 -113.80597) (xy 439.0901 -113.806463) (xy 439.069189 -113.816682)
			(xy 439.061606 -113.825528) (xy 439.043419 -113.848014) (xy 439.001397 -113.887748) (xy 438.953861 -113.920686)
			(xy 438.9019 -113.946074) (xy 438.846702 -113.96333) (xy 438.789532 -113.972059) (xy 438.760616 -113.972594)
			(xy 438.760362 -113.972594) (xy 438.730925 -113.97203) (xy 438.672752 -113.962975) (xy 438.644538 -113.95456)
			(xy 438.6326 -113.95075) (xy 438.608724 -113.95456) (xy 438.532524 -114.010948) (xy 438.523238 -114.018675)
			(xy 438.512503 -114.040282) (xy 438.51195 -114.05235) (xy 438.51195 -114.05743) (xy 438.511413 -114.084681)
			(xy 438.503652 -114.138627) (xy 438.488293 -114.19092) (xy 438.465648 -114.240495) (xy 438.436178 -114.286342)
			(xy 438.400484 -114.327529) (xy 438.359291 -114.363217) (xy 438.313439 -114.392679) (xy 438.26386 -114.415315)
			(xy 438.211565 -114.430665) (xy 438.157617 -114.438417) (xy 438.103115 -114.438412) (xy 438.049169 -114.430651)
			(xy 437.996876 -114.415291) (xy 437.947302 -114.392646) (xy 437.901455 -114.363176) (xy 437.860268 -114.327481)
			(xy 437.824581 -114.286288) (xy 437.79512 -114.240435) (xy 437.772483 -114.190856) (xy 437.757134 -114.138561)
			(xy 437.749383 -114.084613) (xy 435.012084 -114.084613) (xy 435.012084 -116.432076) (xy 435.01252 -116.44214)
			(xy 435.020252 -116.460726) (xy 435.02707 -116.468144) (xy 436.338726 -117.779546) (xy 436.346125 -117.786231)
			(xy 436.364538 -117.793833) (xy 436.384458 -117.793833) (xy 436.393844 -117.790468) (xy 436.408322 -117.784626)
			(xy 436.42534 -117.758972) (xy 436.42534 -116.373656) (xy 436.424907 -116.363591) (xy 436.417175 -116.345004)
			(xy 436.410354 -116.337588) (xy 435.85003 -115.777518) (xy 435.845678 -115.773349) (xy 435.835401 -115.767056)
			(xy 435.82971 -115.765072) (xy 435.829456 -115.765072) (xy 435.803896 -115.756638) (xy 435.755259 -115.733588)
			(xy 435.710343 -115.703932) (xy 435.670039 -115.668259) (xy 435.635149 -115.627277) (xy 435.606363 -115.581798)
			(xy 435.584254 -115.532726) (xy 435.569259 -115.481034) (xy 435.561677 -115.427747) (xy 435.561232 -115.400836)
			(xy 435.561693 -115.373583) (xy 435.569446 -115.31963) (xy 435.584799 -115.26733) (xy 435.60744 -115.217748)
			(xy 435.636908 -115.171893) (xy 435.672602 -115.130699) (xy 435.713796 -115.095006) (xy 435.759651 -115.065538)
			(xy 435.809234 -115.042898) (xy 435.861534 -115.027545) (xy 435.915487 -115.019793) (xy 435.94274 -115.019328)
			(xy 435.96964 -115.019791) (xy 436.022906 -115.027354) (xy 436.074581 -115.042324) (xy 436.123642 -115.064404)
			(xy 436.169114 -115.093156) (xy 436.210097 -115.128011) (xy 436.245778 -115.168277) (xy 436.275448 -115.213156)
			(xy 436.298521 -115.261757) (xy 436.306976 -115.287298) (xy 436.306976 -115.287806) (xy 436.309018 -115.29347)
			(xy 436.3153 -115.303738) (xy 436.319422 -115.308126) (xy 436.381652 -115.370356) (xy 437.661302 -115.370356)
			(xy 437.665373 -115.314734) (xy 437.677499 -115.260297) (xy 437.697422 -115.208206) (xy 437.724718 -115.159571)
			(xy 437.758804 -115.115428) (xy 437.798953 -115.076719) (xy 437.844311 -115.044268) (xy 437.893911 -115.018767)
			(xy 437.946695 -115.00076) (xy 438.001538 -114.99063) (xy 438.057272 -114.988593) (xy 438.112709 -114.994693)
			(xy 438.166666 -115.008799) (xy 438.171718 -115.010946) (xy 454.91984 -115.010946) (xy 454.923911 -114.955324)
			(xy 454.936037 -114.900887) (xy 454.95596 -114.848796) (xy 454.983256 -114.800161) (xy 455.017342 -114.756018)
			(xy 455.057491 -114.717309) (xy 455.102849 -114.684858) (xy 455.152449 -114.659357) (xy 455.205233 -114.64135)
			(xy 455.260076 -114.63122) (xy 455.31581 -114.629183) (xy 455.371247 -114.635283) (xy 455.425204 -114.649389)
			(xy 455.476533 -114.671201) (xy 455.524139 -114.700255) (xy 455.567007 -114.73593) (xy 455.604224 -114.777467)
			(xy 455.634997 -114.82398) (xy 455.658669 -114.874477) (xy 455.674737 -114.927884) (xy 455.682857 -114.98306)
			(xy 455.683366 -115.010946) (xy 455.682857 -115.038832) (xy 455.679933 -115.058698) (xy 456.28636 -115.058698)
			(xy 456.290431 -115.003076) (xy 456.302557 -114.948639) (xy 456.32248 -114.896548) (xy 456.349776 -114.847913)
			(xy 456.383862 -114.80377) (xy 456.424011 -114.765061) (xy 456.469369 -114.73261) (xy 456.518969 -114.707109)
			(xy 456.571753 -114.689102) (xy 456.626596 -114.678972) (xy 456.68233 -114.676935) (xy 456.737767 -114.683035)
			(xy 456.791724 -114.697141) (xy 456.843053 -114.718953) (xy 456.890659 -114.748007) (xy 456.933527 -114.783682)
			(xy 456.970744 -114.825219) (xy 457.001517 -114.871732) (xy 457.025189 -114.922229) (xy 457.041257 -114.975636)
			(xy 457.043426 -114.990372) (xy 457.665072 -114.990372) (xy 457.669143 -114.93475) (xy 457.681269 -114.880313)
			(xy 457.701192 -114.828222) (xy 457.728488 -114.779587) (xy 457.762574 -114.735444) (xy 457.802723 -114.696735)
			(xy 457.848081 -114.664284) (xy 457.897681 -114.638783) (xy 457.950465 -114.620776) (xy 458.005308 -114.610646)
			(xy 458.061042 -114.608609) (xy 458.116479 -114.614709) (xy 458.170436 -114.628815) (xy 458.221765 -114.650627)
			(xy 458.269371 -114.679681) (xy 458.312239 -114.715356) (xy 458.349456 -114.756893) (xy 458.380229 -114.803406)
			(xy 458.403901 -114.853903) (xy 458.419969 -114.90731) (xy 458.427819 -114.960654) (xy 459.191866 -114.960654)
			(xy 459.195937 -114.905032) (xy 459.208063 -114.850595) (xy 459.227986 -114.798504) (xy 459.255282 -114.749869)
			(xy 459.289368 -114.705726) (xy 459.329517 -114.667017) (xy 459.374875 -114.634566) (xy 459.424475 -114.609065)
			(xy 459.477259 -114.591058) (xy 459.532102 -114.580928) (xy 459.587836 -114.578891) (xy 459.643273 -114.584991)
			(xy 459.69723 -114.599097) (xy 459.748559 -114.620909) (xy 459.796165 -114.649963) (xy 459.839033 -114.685638)
			(xy 459.87625 -114.727175) (xy 459.907023 -114.773688) (xy 459.930695 -114.824185) (xy 459.946763 -114.877592)
			(xy 459.954883 -114.932768) (xy 459.955392 -114.960654) (xy 459.954883 -114.98854) (xy 459.946763 -115.043716)
			(xy 459.930695 -115.097123) (xy 459.907023 -115.14762) (xy 459.87625 -115.194133) (xy 459.839033 -115.23567)
			(xy 459.796165 -115.271345) (xy 459.748559 -115.300399) (xy 459.69723 -115.322211) (xy 459.643273 -115.336317)
			(xy 459.587836 -115.342417) (xy 459.532102 -115.34038) (xy 459.477259 -115.33025) (xy 459.424475 -115.312243)
			(xy 459.374875 -115.286742) (xy 459.329517 -115.254291) (xy 459.289368 -115.215582) (xy 459.255282 -115.171439)
			(xy 459.227986 -115.122804) (xy 459.208063 -115.070713) (xy 459.195937 -115.016276) (xy 459.191866 -114.960654)
			(xy 458.427819 -114.960654) (xy 458.428089 -114.962486) (xy 458.428598 -114.990372) (xy 458.428089 -115.018258)
			(xy 458.419969 -115.073434) (xy 458.403901 -115.126841) (xy 458.380229 -115.177338) (xy 458.349456 -115.223851)
			(xy 458.312239 -115.265388) (xy 458.269371 -115.301063) (xy 458.221765 -115.330117) (xy 458.170436 -115.351929)
			(xy 458.116479 -115.366035) (xy 458.061042 -115.372135) (xy 458.005308 -115.370098) (xy 457.950465 -115.359968)
			(xy 457.897681 -115.341961) (xy 457.848081 -115.31646) (xy 457.802723 -115.284009) (xy 457.762574 -115.2453)
			(xy 457.728488 -115.201157) (xy 457.701192 -115.152522) (xy 457.681269 -115.100431) (xy 457.669143 -115.045994)
			(xy 457.665072 -114.990372) (xy 457.043426 -114.990372) (xy 457.049377 -115.030812) (xy 457.049886 -115.058698)
			(xy 457.049377 -115.086584) (xy 457.041257 -115.14176) (xy 457.025189 -115.195167) (xy 457.001517 -115.245664)
			(xy 456.970744 -115.292177) (xy 456.933527 -115.333714) (xy 456.890659 -115.369389) (xy 456.843053 -115.398443)
			(xy 456.791724 -115.420255) (xy 456.737767 -115.434361) (xy 456.68233 -115.440461) (xy 456.626596 -115.438424)
			(xy 456.571753 -115.428294) (xy 456.518969 -115.410287) (xy 456.469369 -115.384786) (xy 456.424011 -115.352335)
			(xy 456.383862 -115.313626) (xy 456.349776 -115.269483) (xy 456.32248 -115.220848) (xy 456.302557 -115.168757)
			(xy 456.290431 -115.11432) (xy 456.28636 -115.058698) (xy 455.679933 -115.058698) (xy 455.674737 -115.094008)
			(xy 455.658669 -115.147415) (xy 455.634997 -115.197912) (xy 455.604224 -115.244425) (xy 455.567007 -115.285962)
			(xy 455.524139 -115.321637) (xy 455.476533 -115.350691) (xy 455.425204 -115.372503) (xy 455.371247 -115.386609)
			(xy 455.31581 -115.392709) (xy 455.260076 -115.390672) (xy 455.205233 -115.380542) (xy 455.152449 -115.362535)
			(xy 455.102849 -115.337034) (xy 455.057491 -115.304583) (xy 455.017342 -115.265874) (xy 454.983256 -115.221731)
			(xy 454.95596 -115.173096) (xy 454.936037 -115.121005) (xy 454.923911 -115.066568) (xy 454.91984 -115.010946)
			(xy 438.171718 -115.010946) (xy 438.217995 -115.030611) (xy 438.265601 -115.059665) (xy 438.308469 -115.09534)
			(xy 438.345686 -115.136877) (xy 438.376459 -115.18339) (xy 438.400131 -115.233887) (xy 438.416199 -115.287294)
			(xy 438.424319 -115.34247) (xy 438.424828 -115.370356) (xy 438.424319 -115.398242) (xy 438.416199 -115.453418)
			(xy 438.400131 -115.506825) (xy 438.376459 -115.557322) (xy 438.345686 -115.603835) (xy 438.308469 -115.645372)
			(xy 438.265601 -115.681047) (xy 438.217995 -115.710101) (xy 438.166666 -115.731913) (xy 438.112709 -115.746019)
			(xy 438.057272 -115.752119) (xy 438.001538 -115.750082) (xy 437.946695 -115.739952) (xy 437.893911 -115.721945)
			(xy 437.844311 -115.696444) (xy 437.798953 -115.663993) (xy 437.758804 -115.625284) (xy 437.724718 -115.581141)
			(xy 437.697422 -115.532506) (xy 437.677499 -115.480415) (xy 437.665373 -115.425978) (xy 437.661302 -115.370356)
			(xy 436.381652 -115.370356) (xy 436.843932 -115.832636) (xy 441.279278 -115.832636) (xy 441.283349 -115.777014)
			(xy 441.295475 -115.722577) (xy 441.315398 -115.670486) (xy 441.342694 -115.621851) (xy 441.37678 -115.577708)
			(xy 441.416929 -115.538999) (xy 441.462287 -115.506548) (xy 441.511887 -115.481047) (xy 441.564671 -115.46304)
			(xy 441.619514 -115.45291) (xy 441.675248 -115.450873) (xy 441.730685 -115.456973) (xy 441.784642 -115.471079)
			(xy 441.835971 -115.492891) (xy 441.883577 -115.521945) (xy 441.926445 -115.55762) (xy 441.963662 -115.599157)
			(xy 441.994435 -115.64567) (xy 442.018107 -115.696167) (xy 442.034175 -115.749574) (xy 442.042295 -115.80475)
			(xy 442.042804 -115.832636) (xy 442.042295 -115.860522) (xy 442.034175 -115.915698) (xy 442.018107 -115.969105)
			(xy 441.994435 -116.019602) (xy 441.963662 -116.066115) (xy 441.926445 -116.107652) (xy 441.883577 -116.143327)
			(xy 441.835971 -116.172381) (xy 441.784642 -116.194193) (xy 441.730685 -116.208299) (xy 441.675248 -116.214399)
			(xy 441.619514 -116.212362) (xy 441.564671 -116.202232) (xy 441.511887 -116.184225) (xy 441.462287 -116.158724)
			(xy 441.416929 -116.126273) (xy 441.37678 -116.087564) (xy 441.342694 -116.043421) (xy 441.315398 -115.994786)
			(xy 441.295475 -115.942695) (xy 441.283349 -115.888258) (xy 441.279278 -115.832636) (xy 436.843932 -115.832636)
			(xy 436.99176 -115.980464) (xy 437.009794 -115.999234) (xy 437.040378 -116.04135) (xy 437.064009 -116.087726)
			(xy 437.080105 -116.137223) (xy 437.088274 -116.188628) (xy 437.088788 -116.214652) (xy 437.088788 -116.66982)
			(xy 437.67324 -116.66982) (xy 437.677311 -116.614198) (xy 437.689437 -116.559761) (xy 437.70936 -116.50767)
			(xy 437.736656 -116.459035) (xy 437.770742 -116.414892) (xy 437.810891 -116.376183) (xy 437.856249 -116.343732)
			(xy 437.905849 -116.318231) (xy 437.958633 -116.300224) (xy 438.013476 -116.290094) (xy 438.06921 -116.288057)
			(xy 438.124647 -116.294157) (xy 438.178604 -116.308263) (xy 438.229933 -116.330075) (xy 438.277539 -116.359129)
			(xy 438.320407 -116.394804) (xy 438.357624 -116.436341) (xy 438.388397 -116.482854) (xy 438.412069 -116.533351)
			(xy 438.428137 -116.586758) (xy 438.43438 -116.62918) (xy 453.438004 -116.62918) (xy 453.442075 -116.573558)
			(xy 453.454201 -116.519121) (xy 453.474124 -116.46703) (xy 453.50142 -116.418395) (xy 453.535506 -116.374252)
			(xy 453.575655 -116.335543) (xy 453.621013 -116.303092) (xy 453.670613 -116.277591) (xy 453.723397 -116.259584)
			(xy 453.77824 -116.249454) (xy 453.833974 -116.247417) (xy 453.889411 -116.253517) (xy 453.943368 -116.267623)
			(xy 453.994697 -116.289435) (xy 454.042303 -116.318489) (xy 454.085171 -116.354164) (xy 454.122388 -116.395701)
			(xy 454.153161 -116.442214) (xy 454.176833 -116.492711) (xy 454.192901 -116.546118) (xy 454.201021 -116.601294)
			(xy 454.20153 -116.62918) (xy 454.201021 -116.657066) (xy 454.192901 -116.712242) (xy 454.176833 -116.765649)
			(xy 454.153161 -116.816146) (xy 454.122388 -116.862659) (xy 454.085171 -116.904196) (xy 454.042303 -116.939871)
			(xy 453.994697 -116.968925) (xy 453.943368 -116.990737) (xy 453.889411 -117.004843) (xy 453.833974 -117.010943)
			(xy 453.77824 -117.008906) (xy 453.723397 -116.998776) (xy 453.670613 -116.980769) (xy 453.621013 -116.955268)
			(xy 453.575655 -116.922817) (xy 453.535506 -116.884108) (xy 453.50142 -116.839965) (xy 453.474124 -116.79133)
			(xy 453.454201 -116.739239) (xy 453.442075 -116.684802) (xy 453.438004 -116.62918) (xy 438.43438 -116.62918)
			(xy 438.436257 -116.641934) (xy 438.436766 -116.66982) (xy 438.436257 -116.697706) (xy 438.428137 -116.752882)
			(xy 438.412069 -116.806289) (xy 438.388397 -116.856786) (xy 438.357624 -116.903299) (xy 438.320407 -116.944836)
			(xy 438.277539 -116.980511) (xy 438.229933 -117.009565) (xy 438.178604 -117.031377) (xy 438.124647 -117.045483)
			(xy 438.06921 -117.051583) (xy 438.013476 -117.049546) (xy 437.958633 -117.039416) (xy 437.905849 -117.021409)
			(xy 437.856249 -116.995908) (xy 437.810891 -116.963457) (xy 437.770742 -116.924748) (xy 437.736656 -116.880605)
			(xy 437.70936 -116.83197) (xy 437.689437 -116.779879) (xy 437.677311 -116.725442) (xy 437.67324 -116.66982)
			(xy 437.088788 -116.66982) (xy 437.088788 -117.390446) (xy 439.042618 -117.390446) (xy 439.042618 -117.335954)
			(xy 439.050373 -117.282015) (xy 439.065724 -117.22973) (xy 439.088359 -117.180161) (xy 439.117818 -117.134317)
			(xy 439.153501 -117.093133) (xy 439.194682 -117.057445) (xy 439.240522 -117.027981) (xy 439.290089 -117.005339)
			(xy 439.342372 -116.989982) (xy 439.39631 -116.982221) (xy 439.423556 -116.981732) (xy 439.452472 -116.98227)
			(xy 439.509643 -116.990993) (xy 439.564842 -117.008246) (xy 439.616804 -117.033634) (xy 439.664339 -117.066575)
			(xy 439.706356 -117.106314) (xy 439.724546 -117.128798) (xy 439.732143 -117.137616) (xy 439.753051 -117.147794)
			(xy 439.764678 -117.148356) (xy 439.844434 -117.148356) (xy 439.856069 -117.147838) (xy 439.876979 -117.137636)
			(xy 439.884566 -117.128798) (xy 439.902776 -117.10633) (xy 439.944792 -117.066594) (xy 439.992323 -117.033653)
			(xy 440.04428 -117.008262) (xy 440.099474 -116.991003) (xy 440.156641 -116.982269) (xy 440.185556 -116.981732)
			(xy 440.212814 -116.982112) (xy 440.266775 -116.989865) (xy 440.319084 -117.005218) (xy 440.368675 -117.027861)
			(xy 440.414538 -117.057331) (xy 440.455741 -117.093028) (xy 440.464067 -117.102636) (xy 441.279278 -117.102636)
			(xy 441.283349 -117.047014) (xy 441.295475 -116.992577) (xy 441.315398 -116.940486) (xy 441.342694 -116.891851)
			(xy 441.37678 -116.847708) (xy 441.416929 -116.808999) (xy 441.462287 -116.776548) (xy 441.511887 -116.751047)
			(xy 441.564671 -116.73304) (xy 441.619514 -116.72291) (xy 441.675248 -116.720873) (xy 441.730685 -116.726973)
			(xy 441.784642 -116.741079) (xy 441.835971 -116.762891) (xy 441.883577 -116.791945) (xy 441.926445 -116.82762)
			(xy 441.963662 -116.869157) (xy 441.994435 -116.91567) (xy 442.018107 -116.966167) (xy 442.034175 -117.019574)
			(xy 442.042295 -117.07475) (xy 442.042804 -117.102636) (xy 442.042295 -117.130522) (xy 442.034175 -117.185698)
			(xy 442.018107 -117.239105) (xy 442.013854 -117.248178) (xy 456.038964 -117.248178) (xy 456.043035 -117.192556)
			(xy 456.055161 -117.138119) (xy 456.075084 -117.086028) (xy 456.10238 -117.037393) (xy 456.136466 -116.99325)
			(xy 456.176615 -116.954541) (xy 456.221973 -116.92209) (xy 456.271573 -116.896589) (xy 456.324357 -116.878582)
			(xy 456.3792 -116.868452) (xy 456.434934 -116.866415) (xy 456.490371 -116.872515) (xy 456.544328 -116.886621)
			(xy 456.595657 -116.908433) (xy 456.643263 -116.937487) (xy 456.686131 -116.973162) (xy 456.723348 -117.014699)
			(xy 456.754121 -117.061212) (xy 456.777793 -117.111709) (xy 456.793861 -117.165116) (xy 456.801981 -117.220292)
			(xy 456.80249 -117.248178) (xy 457.054964 -117.248178) (xy 457.059035 -117.192556) (xy 457.071161 -117.138119)
			(xy 457.091084 -117.086028) (xy 457.11838 -117.037393) (xy 457.152466 -116.99325) (xy 457.192615 -116.954541)
			(xy 457.237973 -116.92209) (xy 457.287573 -116.896589) (xy 457.340357 -116.878582) (xy 457.3952 -116.868452)
			(xy 457.450934 -116.866415) (xy 457.506371 -116.872515) (xy 457.560328 -116.886621) (xy 457.611657 -116.908433)
			(xy 457.659263 -116.937487) (xy 457.702131 -116.973162) (xy 457.739348 -117.014699) (xy 457.770121 -117.061212)
			(xy 457.793793 -117.111709) (xy 457.809861 -117.165116) (xy 457.817981 -117.220292) (xy 457.81849 -117.248178)
			(xy 458.070964 -117.248178) (xy 458.075035 -117.192556) (xy 458.087161 -117.138119) (xy 458.107084 -117.086028)
			(xy 458.13438 -117.037393) (xy 458.168466 -116.99325) (xy 458.208615 -116.954541) (xy 458.253973 -116.92209)
			(xy 458.303573 -116.896589) (xy 458.356357 -116.878582) (xy 458.4112 -116.868452) (xy 458.466934 -116.866415)
			(xy 458.522371 -116.872515) (xy 458.576328 -116.886621) (xy 458.627657 -116.908433) (xy 458.675263 -116.937487)
			(xy 458.718131 -116.973162) (xy 458.755348 -117.014699) (xy 458.786121 -117.061212) (xy 458.809793 -117.111709)
			(xy 458.825861 -117.165116) (xy 458.833981 -117.220292) (xy 458.83449 -117.248178) (xy 458.833981 -117.276064)
			(xy 458.825861 -117.33124) (xy 458.809793 -117.384647) (xy 458.786121 -117.435144) (xy 458.755348 -117.481657)
			(xy 458.718131 -117.523194) (xy 458.675263 -117.558869) (xy 458.627657 -117.587923) (xy 458.576328 -117.609735)
			(xy 458.522371 -117.623841) (xy 458.466934 -117.629941) (xy 458.4112 -117.627904) (xy 458.356357 -117.617774)
			(xy 458.303573 -117.599767) (xy 458.253973 -117.574266) (xy 458.208615 -117.541815) (xy 458.168466 -117.503106)
			(xy 458.13438 -117.458963) (xy 458.107084 -117.410328) (xy 458.087161 -117.358237) (xy 458.075035 -117.3038)
			(xy 458.070964 -117.248178) (xy 457.81849 -117.248178) (xy 457.817981 -117.276064) (xy 457.809861 -117.33124)
			(xy 457.793793 -117.384647) (xy 457.770121 -117.435144) (xy 457.739348 -117.481657) (xy 457.702131 -117.523194)
			(xy 457.659263 -117.558869) (xy 457.611657 -117.587923) (xy 457.560328 -117.609735) (xy 457.506371 -117.623841)
			(xy 457.450934 -117.629941) (xy 457.3952 -117.627904) (xy 457.340357 -117.617774) (xy 457.287573 -117.599767)
			(xy 457.237973 -117.574266) (xy 457.192615 -117.541815) (xy 457.152466 -117.503106) (xy 457.11838 -117.458963)
			(xy 457.091084 -117.410328) (xy 457.071161 -117.358237) (xy 457.059035 -117.3038) (xy 457.054964 -117.248178)
			(xy 456.80249 -117.248178) (xy 456.801981 -117.276064) (xy 456.793861 -117.33124) (xy 456.777793 -117.384647)
			(xy 456.754121 -117.435144) (xy 456.723348 -117.481657) (xy 456.686131 -117.523194) (xy 456.643263 -117.558869)
			(xy 456.595657 -117.587923) (xy 456.544328 -117.609735) (xy 456.490371 -117.623841) (xy 456.434934 -117.629941)
			(xy 456.3792 -117.627904) (xy 456.324357 -117.617774) (xy 456.271573 -117.599767) (xy 456.221973 -117.574266)
			(xy 456.176615 -117.541815) (xy 456.136466 -117.503106) (xy 456.10238 -117.458963) (xy 456.075084 -117.410328)
			(xy 456.055161 -117.358237) (xy 456.043035 -117.3038) (xy 456.038964 -117.248178) (xy 442.013854 -117.248178)
			(xy 441.994435 -117.289602) (xy 441.963662 -117.336115) (xy 441.926445 -117.377652) (xy 441.883577 -117.413327)
			(xy 441.835971 -117.442381) (xy 441.784642 -117.464193) (xy 441.730685 -117.478299) (xy 441.675248 -117.484399)
			(xy 441.619514 -117.482362) (xy 441.564671 -117.472232) (xy 441.511887 -117.454225) (xy 441.462287 -117.428724)
			(xy 441.416929 -117.396273) (xy 441.37678 -117.357564) (xy 441.342694 -117.313421) (xy 441.315398 -117.264786)
			(xy 441.295475 -117.212695) (xy 441.283349 -117.158258) (xy 441.279278 -117.102636) (xy 440.464067 -117.102636)
			(xy 440.491443 -117.134226) (xy 440.520918 -117.180087) (xy 440.543566 -117.229675) (xy 440.558926 -117.281982)
			(xy 440.566685 -117.335942) (xy 440.566685 -117.390458) (xy 440.558926 -117.444418) (xy 440.543566 -117.496725)
			(xy 440.520918 -117.546313) (xy 440.491443 -117.592174) (xy 440.455741 -117.633372) (xy 440.414538 -117.669069)
			(xy 440.368675 -117.698539) (xy 440.319084 -117.721182) (xy 440.266775 -117.736535) (xy 440.212814 -117.744288)
			(xy 440.185556 -117.744748) (xy 440.15664 -117.744209) (xy 440.099468 -117.735487) (xy 440.044269 -117.718235)
			(xy 439.992307 -117.692847) (xy 439.944773 -117.659906) (xy 439.902756 -117.620167) (xy 439.884566 -117.597682)
			(xy 439.876967 -117.588866) (xy 439.85606 -117.578688) (xy 439.844434 -117.578124) (xy 439.764678 -117.578124)
			(xy 439.753045 -117.578656) (xy 439.732135 -117.588849) (xy 439.724546 -117.597682) (xy 439.706324 -117.62014)
			(xy 439.664312 -117.659877) (xy 439.616783 -117.69282) (xy 439.564828 -117.718213) (xy 439.509635 -117.735475)
			(xy 439.45247 -117.74421) (xy 439.423556 -117.744748) (xy 439.39631 -117.744179) (xy 439.342372 -117.736418)
			(xy 439.290089 -117.721061) (xy 439.240522 -117.698419) (xy 439.194682 -117.668955) (xy 439.153501 -117.633267)
			(xy 439.117818 -117.592083) (xy 439.088359 -117.546239) (xy 439.065724 -117.49667) (xy 439.050373 -117.444385)
			(xy 439.042618 -117.390446) (xy 437.088788 -117.390446) (xy 437.088788 -117.661182) (xy 437.089226 -117.671246)
			(xy 437.09696 -117.68983) (xy 437.103774 -117.69725) (xy 437.874494 -118.467886) (xy 445.782444 -118.467886)
			(xy 445.786515 -118.412264) (xy 445.798641 -118.357827) (xy 445.818564 -118.305736) (xy 445.84586 -118.257101)
			(xy 445.879946 -118.212958) (xy 445.920095 -118.174249) (xy 445.965453 -118.141798) (xy 446.015053 -118.116297)
			(xy 446.067837 -118.09829) (xy 446.12268 -118.08816) (xy 446.178414 -118.086123) (xy 446.233851 -118.092223)
			(xy 446.287808 -118.106329) (xy 446.339137 -118.128141) (xy 446.386743 -118.157195) (xy 446.429611 -118.19287)
			(xy 446.466828 -118.234407) (xy 446.497601 -118.28092) (xy 446.521273 -118.331417) (xy 446.537341 -118.384824)
			(xy 446.545461 -118.44) (xy 446.54597 -118.467886) (xy 446.545461 -118.495772) (xy 446.537341 -118.550948)
			(xy 446.521273 -118.604355) (xy 446.497601 -118.654852) (xy 446.466828 -118.701365) (xy 446.429611 -118.742902)
			(xy 446.408777 -118.76024) (xy 448.838826 -118.76024) (xy 448.842897 -118.704618) (xy 448.855023 -118.650181)
			(xy 448.874946 -118.59809) (xy 448.902242 -118.549455) (xy 448.936328 -118.505312) (xy 448.976477 -118.466603)
			(xy 449.021835 -118.434152) (xy 449.071435 -118.408651) (xy 449.124219 -118.390644) (xy 449.179062 -118.380514)
			(xy 449.234796 -118.378477) (xy 449.290233 -118.384577) (xy 449.34419 -118.398683) (xy 449.395519 -118.420495)
			(xy 449.443125 -118.449549) (xy 449.485993 -118.485224) (xy 449.52321 -118.526761) (xy 449.553983 -118.573274)
			(xy 449.577655 -118.623771) (xy 449.593723 -118.677178) (xy 449.601843 -118.732354) (xy 449.602352 -118.76024)
			(xy 450.864476 -118.76024) (xy 450.868547 -118.704618) (xy 450.880673 -118.650181) (xy 450.900596 -118.59809)
			(xy 450.927892 -118.549455) (xy 450.961978 -118.505312) (xy 451.002127 -118.466603) (xy 451.047485 -118.434152)
			(xy 451.097085 -118.408651) (xy 451.149869 -118.390644) (xy 451.204712 -118.380514) (xy 451.260446 -118.378477)
			(xy 451.315883 -118.384577) (xy 451.36984 -118.398683) (xy 451.421169 -118.420495) (xy 451.468775 -118.449549)
			(xy 451.511643 -118.485224) (xy 451.54886 -118.526761) (xy 451.579633 -118.573274) (xy 451.603305 -118.623771)
			(xy 451.619373 -118.677178) (xy 451.627493 -118.732354) (xy 451.628002 -118.76024) (xy 451.627493 -118.788126)
			(xy 451.619373 -118.843302) (xy 451.603305 -118.896709) (xy 451.579633 -118.947206) (xy 451.54886 -118.993719)
			(xy 451.511643 -119.035256) (xy 451.468775 -119.070931) (xy 451.421169 -119.099985) (xy 451.36984 -119.121797)
			(xy 451.315883 -119.135903) (xy 451.260446 -119.142003) (xy 451.204712 -119.139966) (xy 451.149869 -119.129836)
			(xy 451.097085 -119.111829) (xy 451.047485 -119.086328) (xy 451.002127 -119.053877) (xy 450.961978 -119.015168)
			(xy 450.927892 -118.971025) (xy 450.900596 -118.92239) (xy 450.880673 -118.870299) (xy 450.868547 -118.815862)
			(xy 450.864476 -118.76024) (xy 449.602352 -118.76024) (xy 449.601843 -118.788126) (xy 449.593723 -118.843302)
			(xy 449.577655 -118.896709) (xy 449.553983 -118.947206) (xy 449.52321 -118.993719) (xy 449.485993 -119.035256)
			(xy 449.443125 -119.070931) (xy 449.395519 -119.099985) (xy 449.34419 -119.121797) (xy 449.290233 -119.135903)
			(xy 449.234796 -119.142003) (xy 449.179062 -119.139966) (xy 449.124219 -119.129836) (xy 449.071435 -119.111829)
			(xy 449.021835 -119.086328) (xy 448.976477 -119.053877) (xy 448.936328 -119.015168) (xy 448.902242 -118.971025)
			(xy 448.874946 -118.92239) (xy 448.855023 -118.870299) (xy 448.842897 -118.815862) (xy 448.838826 -118.76024)
			(xy 446.408777 -118.76024) (xy 446.386743 -118.778577) (xy 446.339137 -118.807631) (xy 446.287808 -118.829443)
			(xy 446.233851 -118.843549) (xy 446.178414 -118.849649) (xy 446.12268 -118.847612) (xy 446.067837 -118.837482)
			(xy 446.015053 -118.819475) (xy 445.965453 -118.793974) (xy 445.920095 -118.761523) (xy 445.879946 -118.722814)
			(xy 445.84586 -118.678671) (xy 445.818564 -118.630036) (xy 445.798641 -118.577945) (xy 445.786515 -118.523508)
			(xy 445.782444 -118.467886) (xy 437.874494 -118.467886) (xy 438.814267 -119.407557) (xy 442.799609 -119.407557)
			(xy 442.799609 -119.353043) (xy 442.807368 -119.299083) (xy 442.822727 -119.246777) (xy 442.845374 -119.197189)
			(xy 442.874848 -119.151329) (xy 442.910548 -119.110131) (xy 442.951749 -119.074433) (xy 442.99761 -119.044962)
			(xy 443.0472 -119.022318) (xy 443.099507 -119.006962) (xy 443.153467 -118.999207) (xy 443.180724 -118.998746)
			(xy 443.208095 -118.999187) (xy 443.262276 -119.007009) (xy 443.31478 -119.022503) (xy 443.364526 -119.045351)
			(xy 443.410492 -119.075082) (xy 443.431422 -119.092726) (xy 443.431676 -119.09298) (xy 443.438758 -119.098572)
			(xy 443.455679 -119.104813) (xy 443.464696 -119.105172) (xy 443.531752 -119.105172) (xy 443.540767 -119.104798)
			(xy 443.557685 -119.098563) (xy 443.564772 -119.09298) (xy 443.564772 -119.092726) (xy 443.565026 -119.092726)
			(xy 443.585979 -119.075112) (xy 443.631945 -119.045396) (xy 443.681688 -119.022554) (xy 443.734184 -119.007058)
			(xy 443.788356 -118.999223) (xy 443.815724 -118.998746) (xy 443.842971 -118.999326) (xy 443.896909 -119.007084)
			(xy 443.949195 -119.022439) (xy 443.998763 -119.045079) (xy 444.044605 -119.074543) (xy 444.085787 -119.11023)
			(xy 444.121472 -119.151414) (xy 444.150932 -119.197258) (xy 444.173569 -119.246828) (xy 444.188921 -119.299114)
			(xy 444.196676 -119.353053) (xy 444.196676 -119.407547) (xy 444.188921 -119.461486) (xy 444.184358 -119.477028)
			(xy 447.903344 -119.477028) (xy 447.907415 -119.421406) (xy 447.919541 -119.366969) (xy 447.939464 -119.314878)
			(xy 447.96676 -119.266243) (xy 448.000846 -119.2221) (xy 448.040995 -119.183391) (xy 448.086353 -119.15094)
			(xy 448.135953 -119.125439) (xy 448.188737 -119.107432) (xy 448.24358 -119.097302) (xy 448.299314 -119.095265)
			(xy 448.354751 -119.101365) (xy 448.408708 -119.115471) (xy 448.460037 -119.137283) (xy 448.507643 -119.166337)
			(xy 448.550511 -119.202012) (xy 448.587728 -119.243549) (xy 448.618501 -119.290062) (xy 448.642173 -119.340559)
			(xy 448.658241 -119.393966) (xy 448.666361 -119.449142) (xy 448.66687 -119.477028) (xy 448.666361 -119.504914)
			(xy 448.658241 -119.56009) (xy 448.642173 -119.613497) (xy 448.618501 -119.663994) (xy 448.587728 -119.710507)
			(xy 448.580265 -119.718836) (xy 455.836526 -119.718836) (xy 455.840597 -119.663214) (xy 455.852723 -119.608777)
			(xy 455.872646 -119.556686) (xy 455.899942 -119.508051) (xy 455.934028 -119.463908) (xy 455.974177 -119.425199)
			(xy 456.019535 -119.392748) (xy 456.069135 -119.367247) (xy 456.121919 -119.34924) (xy 456.176762 -119.33911)
			(xy 456.232496 -119.337073) (xy 456.287933 -119.343173) (xy 456.34189 -119.357279) (xy 456.393219 -119.379091)
			(xy 456.440825 -119.408145) (xy 456.483693 -119.44382) (xy 456.52091 -119.485357) (xy 456.551683 -119.53187)
			(xy 456.575355 -119.582367) (xy 456.591423 -119.635774) (xy 456.599543 -119.69095) (xy 456.600052 -119.718836)
			(xy 456.599543 -119.746722) (xy 456.591423 -119.801898) (xy 456.575355 -119.855305) (xy 456.551683 -119.905802)
			(xy 456.52091 -119.952315) (xy 456.483693 -119.993852) (xy 456.440825 -120.029527) (xy 456.393219 -120.058581)
			(xy 456.34189 -120.080393) (xy 456.287933 -120.094499) (xy 456.232496 -120.100599) (xy 456.176762 -120.098562)
			(xy 456.121919 -120.088432) (xy 456.069135 -120.070425) (xy 456.019535 -120.044924) (xy 455.974177 -120.012473)
			(xy 455.934028 -119.973764) (xy 455.899942 -119.929621) (xy 455.872646 -119.880986) (xy 455.852723 -119.828895)
			(xy 455.840597 -119.774458) (xy 455.836526 -119.718836) (xy 448.580265 -119.718836) (xy 448.550511 -119.752044)
			(xy 448.507643 -119.787719) (xy 448.460037 -119.816773) (xy 448.408708 -119.838585) (xy 448.354751 -119.852691)
			(xy 448.299314 -119.858791) (xy 448.24358 -119.856754) (xy 448.188737 -119.846624) (xy 448.135953 -119.828617)
			(xy 448.086353 -119.803116) (xy 448.040995 -119.770665) (xy 448.000846 -119.731956) (xy 447.96676 -119.687813)
			(xy 447.939464 -119.639178) (xy 447.919541 -119.587087) (xy 447.907415 -119.53265) (xy 447.903344 -119.477028)
			(xy 444.184358 -119.477028) (xy 444.173569 -119.513772) (xy 444.150932 -119.563342) (xy 444.121472 -119.609186)
			(xy 444.085787 -119.65037) (xy 444.044605 -119.686057) (xy 443.998763 -119.715521) (xy 443.949195 -119.738161)
			(xy 443.896909 -119.753516) (xy 443.842971 -119.761274) (xy 443.815724 -119.761762) (xy 443.788354 -119.761291)
			(xy 443.734175 -119.753476) (xy 443.681671 -119.737988) (xy 443.631924 -119.715148) (xy 443.585957 -119.685423)
			(xy 443.565026 -119.667782) (xy 443.564772 -119.667528) (xy 443.557675 -119.661957) (xy 443.540766 -119.655703)
			(xy 443.531752 -119.655336) (xy 443.464696 -119.655336) (xy 443.455678 -119.655683) (xy 443.438761 -119.661937)
			(xy 443.431676 -119.667528) (xy 443.431676 -119.667782) (xy 443.431422 -119.667782) (xy 443.41049 -119.685421)
			(xy 443.364518 -119.715134) (xy 443.31477 -119.73797) (xy 443.262269 -119.753461) (xy 443.208093 -119.761288)
			(xy 443.180724 -119.761762) (xy 443.153467 -119.761393) (xy 443.099507 -119.753638) (xy 443.0472 -119.738282)
			(xy 442.99761 -119.715638) (xy 442.951749 -119.686167) (xy 442.910548 -119.650469) (xy 442.874848 -119.609271)
			(xy 442.845374 -119.563411) (xy 442.822727 -119.513823) (xy 442.807368 -119.461517) (xy 442.799609 -119.407557)
			(xy 438.814267 -119.407557) (xy 439.299843 -119.89308) (xy 445.869058 -119.89308) (xy 445.873129 -119.837458)
			(xy 445.885255 -119.783021) (xy 445.905178 -119.73093) (xy 445.932474 -119.682295) (xy 445.96656 -119.638152)
			(xy 446.006709 -119.599443) (xy 446.052067 -119.566992) (xy 446.101667 -119.541491) (xy 446.154451 -119.523484)
			(xy 446.209294 -119.513354) (xy 446.265028 -119.511317) (xy 446.320465 -119.517417) (xy 446.374422 -119.531523)
			(xy 446.425751 -119.553335) (xy 446.473357 -119.582389) (xy 446.516225 -119.618064) (xy 446.553442 -119.659601)
			(xy 446.584215 -119.706114) (xy 446.607887 -119.756611) (xy 446.623955 -119.810018) (xy 446.632075 -119.865194)
			(xy 446.632584 -119.89308) (xy 446.632075 -119.920966) (xy 446.623955 -119.976142) (xy 446.607887 -120.029549)
			(xy 446.584215 -120.080046) (xy 446.553442 -120.126559) (xy 446.516225 -120.168096) (xy 446.473357 -120.203771)
			(xy 446.425751 -120.232825) (xy 446.374422 -120.254637) (xy 446.320465 -120.268743) (xy 446.265028 -120.274843)
			(xy 446.209294 -120.272806) (xy 446.154451 -120.262676) (xy 446.101667 -120.244669) (xy 446.052067 -120.219168)
			(xy 446.006709 -120.186717) (xy 445.96656 -120.148008) (xy 445.932474 -120.103865) (xy 445.905178 -120.05523)
			(xy 445.885255 -120.003139) (xy 445.873129 -119.948702) (xy 445.869058 -119.89308) (xy 439.299843 -119.89308)
			(xy 439.434732 -120.027954) (xy 439.44213 -120.0348) (xy 439.460729 -120.04253) (xy 439.4708 -120.04294)
			(xy 440.972702 -120.04294) (xy 440.998789 -120.043426) (xy 441.050321 -120.051593) (xy 441.099938 -120.067725)
			(xy 441.14642 -120.091425) (xy 441.188618 -120.122109) (xy 441.207398 -120.140222) (xy 441.265818 -120.198642)
			(xy 441.273215 -120.205492) (xy 441.291813 -120.213229) (xy 441.301886 -120.213628) (xy 442.873892 -120.213628)
			(xy 442.89998 -120.214113) (xy 442.951512 -120.222279) (xy 443.001131 -120.23841) (xy 443.047614 -120.262108)
			(xy 443.089814 -120.29279) (xy 443.108588 -120.31091) (xy 443.290706 -120.493028) (xy 447.904106 -120.493028)
			(xy 447.908177 -120.437406) (xy 447.920303 -120.382969) (xy 447.940226 -120.330878) (xy 447.967522 -120.282243)
			(xy 448.001608 -120.2381) (xy 448.041757 -120.199391) (xy 448.087115 -120.16694) (xy 448.136715 -120.141439)
			(xy 448.189499 -120.123432) (xy 448.244342 -120.113302) (xy 448.300076 -120.111265) (xy 448.355513 -120.117365)
			(xy 448.40947 -120.131471) (xy 448.460799 -120.153283) (xy 448.508405 -120.182337) (xy 448.551273 -120.218012)
			(xy 448.58849 -120.259549) (xy 448.619263 -120.306062) (xy 448.642935 -120.356559) (xy 448.659003 -120.409966)
			(xy 448.667123 -120.465142) (xy 448.667632 -120.493028) (xy 448.667123 -120.520914) (xy 448.659003 -120.57609)
			(xy 448.642935 -120.629497) (xy 448.619263 -120.679994) (xy 448.58849 -120.726507) (xy 448.551273 -120.768044)
			(xy 448.522198 -120.79224) (xy 448.836032 -120.79224) (xy 448.840103 -120.736618) (xy 448.852229 -120.682181)
			(xy 448.872152 -120.63009) (xy 448.899448 -120.581455) (xy 448.933534 -120.537312) (xy 448.973683 -120.498603)
			(xy 449.019041 -120.466152) (xy 449.068641 -120.440651) (xy 449.121425 -120.422644) (xy 449.176268 -120.412514)
			(xy 449.232002 -120.410477) (xy 449.287439 -120.416577) (xy 449.341396 -120.430683) (xy 449.392725 -120.452495)
			(xy 449.440331 -120.481549) (xy 449.483199 -120.517224) (xy 449.520416 -120.558761) (xy 449.551189 -120.605274)
			(xy 449.574861 -120.655771) (xy 449.590929 -120.709178) (xy 449.599049 -120.764354) (xy 449.599558 -120.79224)
			(xy 450.991476 -120.79224) (xy 450.995547 -120.736618) (xy 451.007673 -120.682181) (xy 451.027596 -120.63009)
			(xy 451.054892 -120.581455) (xy 451.088978 -120.537312) (xy 451.129127 -120.498603) (xy 451.174485 -120.466152)
			(xy 451.224085 -120.440651) (xy 451.276869 -120.422644) (xy 451.331712 -120.412514) (xy 451.387446 -120.410477)
			(xy 451.442883 -120.416577) (xy 451.49684 -120.430683) (xy 451.548169 -120.452495) (xy 451.595775 -120.481549)
			(xy 451.638643 -120.517224) (xy 451.646777 -120.526302) (xy 454.293476 -120.526302) (xy 454.297547 -120.47068)
			(xy 454.309673 -120.416243) (xy 454.329596 -120.364152) (xy 454.356892 -120.315517) (xy 454.390978 -120.271374)
			(xy 454.431127 -120.232665) (xy 454.476485 -120.200214) (xy 454.526085 -120.174713) (xy 454.578869 -120.156706)
			(xy 454.633712 -120.146576) (xy 454.689446 -120.144539) (xy 454.744883 -120.150639) (xy 454.79884 -120.164745)
			(xy 454.850169 -120.186557) (xy 454.897775 -120.215611) (xy 454.940643 -120.251286) (xy 454.97786 -120.292823)
			(xy 455.008633 -120.339336) (xy 455.032305 -120.389833) (xy 455.048373 -120.44324) (xy 455.056493 -120.498416)
			(xy 455.057002 -120.526302) (xy 455.056493 -120.554188) (xy 455.048373 -120.609364) (xy 455.032305 -120.662771)
			(xy 455.008633 -120.713268) (xy 454.97786 -120.759781) (xy 454.940643 -120.801318) (xy 454.897775 -120.836993)
			(xy 454.850169 -120.866047) (xy 454.79884 -120.887859) (xy 454.744883 -120.901965) (xy 454.689446 -120.908065)
			(xy 454.633712 -120.906028) (xy 454.578869 -120.895898) (xy 454.526085 -120.877891) (xy 454.476485 -120.85239)
			(xy 454.431127 -120.819939) (xy 454.390978 -120.78123) (xy 454.356892 -120.737087) (xy 454.329596 -120.688452)
			(xy 454.309673 -120.636361) (xy 454.297547 -120.581924) (xy 454.293476 -120.526302) (xy 451.646777 -120.526302)
			(xy 451.67586 -120.558761) (xy 451.706633 -120.605274) (xy 451.730305 -120.655771) (xy 451.746373 -120.709178)
			(xy 451.754493 -120.764354) (xy 451.755002 -120.79224) (xy 451.754493 -120.820126) (xy 451.746373 -120.875302)
			(xy 451.730305 -120.928709) (xy 451.706633 -120.979206) (xy 451.67586 -121.025719) (xy 451.638643 -121.067256)
			(xy 451.595775 -121.102931) (xy 451.548169 -121.131985) (xy 451.49684 -121.153797) (xy 451.442883 -121.167903)
			(xy 451.387446 -121.174003) (xy 451.331712 -121.171966) (xy 451.276869 -121.161836) (xy 451.224085 -121.143829)
			(xy 451.174485 -121.118328) (xy 451.129127 -121.085877) (xy 451.088978 -121.047168) (xy 451.054892 -121.003025)
			(xy 451.027596 -120.95439) (xy 451.007673 -120.902299) (xy 450.995547 -120.847862) (xy 450.991476 -120.79224)
			(xy 449.599558 -120.79224) (xy 449.599049 -120.820126) (xy 449.590929 -120.875302) (xy 449.574861 -120.928709)
			(xy 449.551189 -120.979206) (xy 449.520416 -121.025719) (xy 449.483199 -121.067256) (xy 449.440331 -121.102931)
			(xy 449.392725 -121.131985) (xy 449.341396 -121.153797) (xy 449.287439 -121.167903) (xy 449.232002 -121.174003)
			(xy 449.176268 -121.171966) (xy 449.121425 -121.161836) (xy 449.068641 -121.143829) (xy 449.019041 -121.118328)
			(xy 448.973683 -121.085877) (xy 448.933534 -121.047168) (xy 448.899448 -121.003025) (xy 448.872152 -120.95439)
			(xy 448.852229 -120.902299) (xy 448.840103 -120.847862) (xy 448.836032 -120.79224) (xy 448.522198 -120.79224)
			(xy 448.508405 -120.803719) (xy 448.460799 -120.832773) (xy 448.40947 -120.854585) (xy 448.355513 -120.868691)
			(xy 448.300076 -120.874791) (xy 448.244342 -120.872754) (xy 448.189499 -120.862624) (xy 448.136715 -120.844617)
			(xy 448.087115 -120.819116) (xy 448.041757 -120.786665) (xy 448.001608 -120.747956) (xy 447.967522 -120.703813)
			(xy 447.940226 -120.655178) (xy 447.920303 -120.603087) (xy 447.908177 -120.54865) (xy 447.904106 -120.493028)
			(xy 443.290706 -120.493028) (xy 444.03645 -121.238772) (xy 445.884298 -121.238772) (xy 445.888369 -121.18315)
			(xy 445.900495 -121.128713) (xy 445.920418 -121.076622) (xy 445.947714 -121.027987) (xy 445.9818 -120.983844)
			(xy 446.021949 -120.945135) (xy 446.067307 -120.912684) (xy 446.116907 -120.887183) (xy 446.169691 -120.869176)
			(xy 446.224534 -120.859046) (xy 446.280268 -120.857009) (xy 446.335705 -120.863109) (xy 446.389662 -120.877215)
			(xy 446.440991 -120.899027) (xy 446.488597 -120.928081) (xy 446.531465 -120.963756) (xy 446.568682 -121.005293)
			(xy 446.599455 -121.051806) (xy 446.623127 -121.102303) (xy 446.639195 -121.15571) (xy 446.647315 -121.210886)
			(xy 446.647824 -121.238772) (xy 446.647315 -121.266658) (xy 446.639195 -121.321834) (xy 446.623127 -121.375241)
			(xy 446.599455 -121.425738) (xy 446.568682 -121.472251) (xy 446.531465 -121.513788) (xy 446.488597 -121.549463)
			(xy 446.440991 -121.578517) (xy 446.389662 -121.600329) (xy 446.335705 -121.614435) (xy 446.280268 -121.620535)
			(xy 446.224534 -121.618498) (xy 446.169691 -121.608368) (xy 446.116907 -121.590361) (xy 446.067307 -121.56486)
			(xy 446.021949 -121.532409) (xy 445.9818 -121.4937) (xy 445.947714 -121.449557) (xy 445.920418 -121.400922)
			(xy 445.900495 -121.348831) (xy 445.888369 -121.294394) (xy 445.884298 -121.238772) (xy 444.03645 -121.238772)
			(xy 446.216024 -123.418346) (xy 446.220377 -123.422515) (xy 446.230653 -123.428808) (xy 446.236344 -123.430792)
			(xy 446.236598 -123.430792) (xy 446.245488 -123.433586) (xy 446.253108 -123.435618) (xy 446.265808 -123.43765)
			(xy 446.275818 -123.437161) (xy 446.294316 -123.429502) (xy 446.308478 -123.415351) (xy 446.316153 -123.39686)
			(xy 446.316608 -123.38685) (xy 446.310766 -123.366784) (xy 446.305686 -123.354846) (xy 446.293016 -123.332675)
			(xy 446.273065 -123.28567) (xy 446.259564 -123.236422) (xy 446.252754 -123.185814) (xy 446.252346 -123.160282)
			(xy 446.252346 -123.160028) (xy 446.252807 -123.132771) (xy 446.260562 -123.07881) (xy 446.275917 -123.026503)
			(xy 446.29856 -122.976914) (xy 446.328031 -122.931052) (xy 446.363729 -122.889851) (xy 446.404927 -122.85415)
			(xy 446.450786 -122.824675) (xy 446.500374 -122.802028) (xy 446.55268 -122.786668) (xy 446.606639 -122.778909)
			(xy 446.661154 -122.778909) (xy 446.715114 -122.786667) (xy 446.76742 -122.802026) (xy 446.817008 -122.824672)
			(xy 446.862868 -122.854146) (xy 446.904067 -122.889846) (xy 446.939765 -122.931046) (xy 446.969236 -122.976908)
			(xy 446.991881 -123.026497) (xy 447.007237 -123.078804) (xy 447.014992 -123.132764) (xy 447.014989 -123.187279)
			(xy 447.007228 -123.241238) (xy 446.991866 -123.293543) (xy 446.969216 -123.34313) (xy 446.93974 -123.388988)
			(xy 446.904037 -123.430184) (xy 446.862834 -123.46588) (xy 446.81697 -123.495348) (xy 446.76738 -123.517989)
			(xy 446.715072 -123.533342) (xy 446.661111 -123.541094) (xy 446.633854 -123.541536) (xy 446.633346 -123.541536)
			(xy 446.622974 -123.541459) (xy 446.602262 -123.540313) (xy 446.591944 -123.53925) (xy 446.57899 -123.537726)
			(xy 446.555114 -123.547632) (xy 446.493138 -123.624848) (xy 446.48807 -123.631679) (xy 446.482393 -123.647702)
			(xy 446.482326 -123.664701) (xy 446.484756 -123.672854) (xy 446.494121 -123.70246) (xy 446.504204 -123.763728)
			(xy 446.504822 -123.794774) (xy 446.504822 -123.795028) (xy 446.504334 -123.822278) (xy 446.496575 -123.876224)
			(xy 446.481217 -123.928516) (xy 446.458575 -123.978091) (xy 446.429108 -124.023938) (xy 446.393417 -124.065126)
			(xy 446.352227 -124.100816) (xy 446.306378 -124.130281) (xy 446.256803 -124.152922) (xy 446.20451 -124.168278)
			(xy 446.150564 -124.176035) (xy 446.123314 -124.176536) (xy 446.096412 -124.176076) (xy 446.043143 -124.168519)
			(xy 445.991463 -124.153554) (xy 445.942398 -124.131477) (xy 445.896922 -124.102725) (xy 445.855935 -124.06787)
			(xy 445.820252 -124.027603) (xy 445.79058 -123.982721) (xy 445.767507 -123.934117) (xy 445.759078 -123.908566)
			(xy 445.759078 -123.908058) (xy 445.757035 -123.902395) (xy 445.750753 -123.892127) (xy 445.746632 -123.887738)
			(xy 442.751464 -120.89257) (xy 442.744067 -120.885722) (xy 442.725468 -120.877989) (xy 442.715396 -120.877584)
			(xy 441.785248 -120.877584) (xy 441.776452 -120.877945) (xy 441.759893 -120.883882) (xy 441.746321 -120.895073)
			(xy 441.74156 -120.902476) (xy 441.69711 -120.97766) (xy 441.692924 -120.985413) (xy 441.689602 -121.002702)
			(xy 441.692379 -121.020087) (xy 441.696348 -121.027952) (xy 441.711181 -121.056266) (xy 441.73222 -121.11662)
			(xy 441.742907 -121.179636) (xy 441.743592 -121.211594) (xy 441.743592 -121.212102) (xy 441.74312 -121.239472)
			(xy 441.735296 -121.29365) (xy 441.719808 -121.346153) (xy 441.696976 -121.395904) (xy 441.667266 -121.44188)
			(xy 441.649612 -121.4628) (xy 441.649612 -121.463054) (xy 441.649358 -121.463054) (xy 441.64377 -121.47014)
			(xy 441.637518 -121.487057) (xy 441.637166 -121.496074) (xy 441.637166 -121.56313) (xy 441.63753 -121.572145)
			(xy 441.643781 -121.589057) (xy 441.649358 -121.59615) (xy 441.649612 -121.596404) (xy 441.667253 -121.617336)
			(xy 441.696978 -121.663302) (xy 441.71982 -121.713049) (xy 441.735309 -121.765553) (xy 441.743127 -121.819732)
			(xy 441.743592 -121.847102) (xy 441.743129 -121.874354) (xy 441.735371 -121.928304) (xy 441.720015 -121.980601)
			(xy 441.697372 -122.03018) (xy 441.667904 -122.076031) (xy 441.63221 -122.117223) (xy 441.591017 -122.152915)
			(xy 441.545164 -122.182381) (xy 441.495584 -122.205021) (xy 441.443287 -122.220375) (xy 441.389336 -122.22813)
			(xy 441.362084 -122.22861) (xy 441.335207 -122.228149) (xy 441.281987 -122.220597) (xy 441.230355 -122.205646)
			(xy 441.181334 -122.183592) (xy 441.135896 -122.154873) (xy 441.094942 -122.120056) (xy 441.059284 -122.079833)
			(xy 441.044076 -122.057668) (xy 441.037974 -122.049404) (xy 441.02081 -122.038146) (xy 441.010802 -122.035824)
			(xy 440.928506 -122.020584) (xy 440.90844 -122.025156) (xy 440.900058 -122.031252) (xy 440.875607 -122.048066)
			(xy 440.822597 -122.074727) (xy 440.7661 -122.092867) (xy 440.707477 -122.102047) (xy 440.677808 -122.102626)
			(xy 440.650556 -122.102141) (xy 440.596606 -122.094385) (xy 440.54431 -122.079031) (xy 440.49473 -122.056391)
			(xy 440.448878 -122.026925) (xy 440.407685 -121.991234) (xy 440.371991 -121.950043) (xy 440.342522 -121.904193)
			(xy 440.319878 -121.854615) (xy 440.30452 -121.802319) (xy 440.296761 -121.74837) (xy 440.2963 -121.721118)
			(xy 440.296777 -121.69375) (xy 440.304612 -121.639577) (xy 440.320108 -121.587081) (xy 440.342948 -121.537337)
			(xy 440.372662 -121.491369) (xy 440.39028 -121.47042) (xy 440.39028 -121.470166) (xy 440.390534 -121.470166)
			(xy 440.396111 -121.463077) (xy 440.402338 -121.44616) (xy 440.402726 -121.437146) (xy 440.402726 -121.37009)
			(xy 440.402365 -121.361074) (xy 440.396118 -121.344158) (xy 440.390534 -121.33707) (xy 440.39028 -121.336816)
			(xy 440.372638 -121.315885) (xy 440.342911 -121.269918) (xy 440.320067 -121.220171) (xy 440.304576 -121.167668)
			(xy 440.296756 -121.113489) (xy 440.2963 -121.086118) (xy 440.2963 -121.085864) (xy 440.296886 -121.056661)
			(xy 440.305834 -120.998943) (xy 440.323455 -120.943257) (xy 440.349339 -120.890898) (xy 440.365642 -120.866662)
			(xy 440.37377 -120.854978) (xy 440.375802 -120.826784) (xy 440.327542 -120.734328) (xy 440.322936 -120.726288)
			(xy 440.309137 -120.713945) (xy 440.291841 -120.707342) (xy 440.282584 -120.706896) (xy 440.120024 -120.706896)
			(xy 440.10972 -120.707374) (xy 440.090779 -120.715495) (xy 440.076578 -120.730429) (xy 440.072526 -120.739916)
			(xy 440.033664 -120.843548) (xy 440.041284 -120.874282) (xy 440.053222 -120.884696) (xy 440.073231 -120.902904)
			(xy 440.108423 -120.943992) (xy 440.137465 -120.989635) (xy 440.159776 -121.038919) (xy 440.174909 -121.090858)
			(xy 440.182562 -121.144413) (xy 440.183016 -121.171462) (xy 440.182555 -121.198717) (xy 440.174803 -121.252672)
			(xy 440.15945 -121.304975) (xy 440.13681 -121.354561) (xy 440.107343 -121.400419) (xy 440.071649 -121.441617)
			(xy 440.030456 -121.477315) (xy 439.984601 -121.506788) (xy 439.935018 -121.529434) (xy 439.882717 -121.544793)
			(xy 439.828763 -121.552552) (xy 439.801508 -121.55297) (xy 439.774138 -121.552499) (xy 439.71996 -121.544675)
			(xy 439.667456 -121.529188) (xy 439.617705 -121.506355) (xy 439.571729 -121.476646) (xy 439.55081 -121.45899)
			(xy 439.550556 -121.45899) (xy 439.550556 -121.458736) (xy 439.543473 -121.453139) (xy 439.526556 -121.446874)
			(xy 439.517536 -121.446544) (xy 439.45048 -121.446544) (xy 439.441464 -121.446906) (xy 439.424548 -121.453152)
			(xy 439.41746 -121.458736) (xy 439.417206 -121.45899) (xy 439.396275 -121.476633) (xy 439.350309 -121.50636)
			(xy 439.300562 -121.529205) (xy 439.248059 -121.544696) (xy 439.193879 -121.552516) (xy 439.166508 -121.55297)
			(xy 439.139256 -121.552507) (xy 439.085306 -121.544751) (xy 439.033009 -121.529395) (xy 438.983431 -121.506753)
			(xy 438.937579 -121.477284) (xy 438.896389 -121.44159) (xy 438.860698 -121.400397) (xy 438.831233 -121.354543)
			(xy 438.808594 -121.304962) (xy 438.793243 -121.252665) (xy 438.785491 -121.198714) (xy 438.785 -121.171462)
			(xy 438.78547 -121.14406) (xy 438.793305 -121.089819) (xy 438.808823 -121.037257) (xy 438.831705 -120.987459)
			(xy 438.861479 -120.941447) (xy 438.897531 -120.900172) (xy 438.939121 -120.864481) (xy 438.98539 -120.83511)
			(xy 439.035387 -120.812665) (xy 439.061606 -120.804686) (xy 439.070352 -120.801759) (xy 439.085134 -120.790754)
			(xy 439.09511 -120.77526) (xy 439.09742 -120.766332) (xy 439.11901 -120.664732) (xy 439.109866 -120.638316)
			(xy 439.098944 -120.629172) (xy 439.077608 -120.609614) (xy 438.68721 -120.218962) (xy 438.679889 -120.212148)
			(xy 438.661464 -120.204407) (xy 438.641479 -120.204339) (xy 438.632092 -120.207786) (xy 438.531 -120.249442)
			(xy 438.513728 -120.274588) (xy 438.513728 -120.290082) (xy 438.513042 -120.317142) (xy 438.504965 -120.370664)
			(xy 438.489397 -120.422506) (xy 438.466651 -120.471623) (xy 438.437185 -120.517028) (xy 438.419748 -120.537732)
			(xy 438.419748 -120.537986) (xy 438.419494 -120.537986) (xy 438.413907 -120.545072) (xy 438.407661 -120.561989)
			(xy 438.407302 -120.571006) (xy 438.407302 -120.638062) (xy 438.407655 -120.647081) (xy 438.413893 -120.664005)
			(xy 438.419494 -120.671082) (xy 438.419748 -120.671336) (xy 438.437387 -120.692268) (xy 438.467109 -120.738235)
			(xy 438.489951 -120.78798) (xy 438.505444 -120.84048) (xy 438.513269 -120.894656) (xy 438.513266 -120.949395)
			(xy 438.505433 -121.00357) (xy 438.489933 -121.056068) (xy 438.467084 -121.10581) (xy 438.437356 -121.151773)
			(xy 438.419748 -121.172732) (xy 438.419748 -121.172986) (xy 438.419494 -121.172986) (xy 438.413907 -121.180072)
			(xy 438.407661 -121.196989) (xy 438.407302 -121.206006) (xy 438.407302 -121.273062) (xy 438.407655 -121.282081)
			(xy 438.413893 -121.299005) (xy 438.419494 -121.306082) (xy 438.419748 -121.306336) (xy 438.437387 -121.327268)
			(xy 438.467109 -121.373235) (xy 438.489951 -121.42298) (xy 438.505444 -121.47548) (xy 438.513269 -121.529656)
			(xy 438.513266 -121.584395) (xy 438.505433 -121.63857) (xy 438.489933 -121.691068) (xy 438.467084 -121.74081)
			(xy 438.437356 -121.786773) (xy 438.419748 -121.807732) (xy 438.419748 -121.807986) (xy 438.419494 -121.807986)
			(xy 438.413907 -121.815072) (xy 438.407661 -121.831989) (xy 438.407302 -121.841006) (xy 438.407302 -121.908062)
			(xy 438.407655 -121.917081) (xy 438.413893 -121.934005) (xy 438.419494 -121.941082) (xy 438.419748 -121.941336)
			(xy 438.43739 -121.962267) (xy 438.467116 -122.008233) (xy 438.489957 -122.05798) (xy 438.505445 -122.110484)
			(xy 438.51326 -122.164664) (xy 438.513728 -122.192034) (xy 438.51324 -122.219284) (xy 438.50548 -122.273229)
			(xy 438.490122 -122.325521) (xy 438.467479 -122.375095) (xy 438.438012 -122.420943) (xy 438.402321 -122.462131)
			(xy 438.361132 -122.49782) (xy 438.315283 -122.527286) (xy 438.265708 -122.549927) (xy 438.213416 -122.565283)
			(xy 438.15947 -122.573041) (xy 438.13222 -122.573542) (xy 438.104931 -122.573078) (xy 438.050909 -122.565306)
			(xy 437.998545 -122.549918) (xy 437.948908 -122.527228) (xy 437.925718 -122.512836) (xy 437.914034 -122.505216)
			(xy 437.886094 -122.5042) (xy 437.795416 -122.553476) (xy 437.787581 -122.558162) (xy 437.775632 -122.571947)
			(xy 437.769303 -122.589057) (xy 437.769 -122.59818) (xy 437.769 -123.364548) (xy 442.364398 -123.364548)
			(xy 442.364398 -123.310052) (xy 442.372153 -123.25611) (xy 442.387506 -123.20382) (xy 442.410144 -123.154248)
			(xy 442.439605 -123.108401) (xy 442.475292 -123.067214) (xy 442.516476 -123.031525) (xy 442.56232 -123.002059)
			(xy 442.61189 -122.979417) (xy 442.664178 -122.96406) (xy 442.71812 -122.9563) (xy 442.745368 -122.955812)
			(xy 442.772738 -122.956294) (xy 442.826916 -122.964107) (xy 442.879419 -122.979593) (xy 442.929166 -123.002431)
			(xy 442.975134 -123.032152) (xy 442.996066 -123.049792) (xy 442.99632 -123.050046) (xy 443.003393 -123.055653)
			(xy 443.02032 -123.061886) (xy 443.02934 -123.062238) (xy 443.096396 -123.062238) (xy 443.105412 -123.061871)
			(xy 443.122328 -123.055629) (xy 443.129416 -123.050046) (xy 443.129416 -123.049792) (xy 443.12967 -123.049792)
			(xy 443.150603 -123.032151) (xy 443.196571 -123.002427) (xy 443.246317 -122.979581) (xy 443.298819 -122.964085)
			(xy 443.352997 -122.956256) (xy 443.407739 -122.956256) (xy 443.461917 -122.964085) (xy 443.514419 -122.979581)
			(xy 443.564165 -123.002427) (xy 443.610133 -123.032151) (xy 443.631066 -123.049792) (xy 443.63132 -123.050046)
			(xy 443.638393 -123.055653) (xy 443.65532 -123.061886) (xy 443.66434 -123.062238) (xy 443.731396 -123.062238)
			(xy 443.740412 -123.061871) (xy 443.757328 -123.055629) (xy 443.764416 -123.050046) (xy 443.764416 -123.049792)
			(xy 443.76467 -123.049792) (xy 443.785602 -123.032152) (xy 443.831575 -123.002441) (xy 443.881322 -122.979605)
			(xy 443.933823 -122.964114) (xy 443.987999 -122.956286) (xy 444.015368 -122.955812) (xy 444.042624 -122.956233)
			(xy 444.096581 -122.963986) (xy 444.148886 -122.97934) (xy 444.198472 -123.001982) (xy 444.244332 -123.031451)
			(xy 444.285531 -123.067147) (xy 444.32123 -123.108342) (xy 444.350702 -123.154199) (xy 444.373348 -123.203784)
			(xy 444.388707 -123.256088) (xy 444.396465 -123.310044) (xy 444.396465 -123.364556) (xy 444.388707 -123.418512)
			(xy 444.373348 -123.470816) (xy 444.350702 -123.520401) (xy 444.32123 -123.566258) (xy 444.285531 -123.607453)
			(xy 444.244332 -123.643149) (xy 444.198472 -123.672618) (xy 444.148886 -123.69526) (xy 444.096581 -123.710614)
			(xy 444.042624 -123.718367) (xy 444.015368 -123.718828) (xy 443.987996 -123.718398) (xy 443.933815 -123.710574)
			(xy 443.881311 -123.695078) (xy 443.831564 -123.672227) (xy 443.7856 -123.642494) (xy 443.76467 -123.624848)
			(xy 443.764416 -123.624594) (xy 443.75733 -123.619007) (xy 443.740413 -123.612761) (xy 443.731396 -123.612402)
			(xy 443.66434 -123.612402) (xy 443.655325 -123.612778) (xy 443.638408 -123.619012) (xy 443.63132 -123.624594)
			(xy 443.631066 -123.624848) (xy 443.610133 -123.642489) (xy 443.564165 -123.672213) (xy 443.514419 -123.695059)
			(xy 443.461917 -123.710555) (xy 443.407739 -123.718384) (xy 443.352997 -123.718384) (xy 443.298819 -123.710555)
			(xy 443.246317 -123.695059) (xy 443.196571 -123.672213) (xy 443.150603 -123.642489) (xy 443.12967 -123.624848)
			(xy 443.129416 -123.624594) (xy 443.12233 -123.619007) (xy 443.105413 -123.612761) (xy 443.096396 -123.612402)
			(xy 443.02934 -123.612402) (xy 443.020325 -123.612778) (xy 443.003408 -123.619012) (xy 442.99632 -123.624594)
			(xy 442.99632 -123.624848) (xy 442.996066 -123.624848) (xy 442.975113 -123.642462) (xy 442.929147 -123.672179)
			(xy 442.879405 -123.695021) (xy 442.826908 -123.710518) (xy 442.772736 -123.718351) (xy 442.745368 -123.718828)
			(xy 442.71812 -123.7183) (xy 442.664178 -123.71054) (xy 442.61189 -123.695183) (xy 442.56232 -123.672541)
			(xy 442.516476 -123.643075) (xy 442.475292 -123.607386) (xy 442.439605 -123.566199) (xy 442.410144 -123.520352)
			(xy 442.387506 -123.47078) (xy 442.372153 -123.41849) (xy 442.364398 -123.364548) (xy 437.769 -123.364548)
			(xy 437.769 -124.215144) (xy 442.906656 -124.215144) (xy 442.910727 -124.159522) (xy 442.922853 -124.105085)
			(xy 442.942776 -124.052994) (xy 442.970072 -124.004359) (xy 443.004158 -123.960216) (xy 443.044307 -123.921507)
			(xy 443.089665 -123.889056) (xy 443.139265 -123.863555) (xy 443.192049 -123.845548) (xy 443.246892 -123.835418)
			(xy 443.302626 -123.833381) (xy 443.358063 -123.839481) (xy 443.41202 -123.853587) (xy 443.463349 -123.875399)
			(xy 443.510955 -123.904453) (xy 443.553823 -123.940128) (xy 443.59104 -123.981665) (xy 443.621813 -124.028178)
			(xy 443.645485 -124.078675) (xy 443.661553 -124.132082) (xy 443.669673 -124.187258) (xy 443.670182 -124.215144)
			(xy 443.669673 -124.24303) (xy 443.661553 -124.298206) (xy 443.645485 -124.351613) (xy 443.621813 -124.40211)
			(xy 443.59104 -124.448623) (xy 443.553823 -124.49016) (xy 443.510955 -124.525835) (xy 443.463349 -124.554889)
			(xy 443.41202 -124.576701) (xy 443.358063 -124.590807) (xy 443.302626 -124.596907) (xy 443.246892 -124.59487)
			(xy 443.192049 -124.58474) (xy 443.139265 -124.566733) (xy 443.089665 -124.541232) (xy 443.044307 -124.508781)
			(xy 443.004158 -124.470072) (xy 442.970072 -124.425929) (xy 442.942776 -124.377294) (xy 442.922853 -124.325203)
			(xy 442.910727 -124.270766) (xy 442.906656 -124.215144) (xy 437.769 -124.215144) (xy 437.769 -124.640594)
			(xy 449.232272 -124.640594) (xy 449.236343 -124.584972) (xy 449.248469 -124.530535) (xy 449.268392 -124.478444)
			(xy 449.295688 -124.429809) (xy 449.329774 -124.385666) (xy 449.369923 -124.346957) (xy 449.415281 -124.314506)
			(xy 449.464881 -124.289005) (xy 449.517665 -124.270998) (xy 449.572508 -124.260868) (xy 449.628242 -124.258831)
			(xy 449.683679 -124.264931) (xy 449.737636 -124.279037) (xy 449.788965 -124.300849) (xy 449.836571 -124.329903)
			(xy 449.879439 -124.365578) (xy 449.916656 -124.407115) (xy 449.947429 -124.453628) (xy 449.971101 -124.504125)
			(xy 449.987169 -124.557532) (xy 449.995289 -124.612708) (xy 449.995798 -124.640594) (xy 449.995289 -124.66848)
			(xy 449.987169 -124.723656) (xy 449.971101 -124.777063) (xy 449.947429 -124.82756) (xy 449.916656 -124.874073)
			(xy 449.879439 -124.91561) (xy 449.836571 -124.951285) (xy 449.788965 -124.980339) (xy 449.737636 -125.002151)
			(xy 449.683679 -125.016257) (xy 449.628242 -125.022357) (xy 449.572508 -125.02032) (xy 449.517665 -125.01019)
			(xy 449.464881 -124.992183) (xy 449.415281 -124.966682) (xy 449.369923 -124.934231) (xy 449.329774 -124.895522)
			(xy 449.295688 -124.851379) (xy 449.268392 -124.802744) (xy 449.248469 -124.750653) (xy 449.236343 -124.696216)
			(xy 449.232272 -124.640594) (xy 437.769 -124.640594) (xy 437.769 -125.891544) (xy 443.47511 -125.891544)
			(xy 443.475537 -125.865229) (xy 443.48278 -125.813098) (xy 443.497106 -125.762455) (xy 443.518246 -125.714256)
			(xy 443.5458 -125.669413) (xy 443.579245 -125.628775) (xy 443.5983 -125.61062) (xy 443.605695 -125.603093)
			(xy 443.614223 -125.583817) (xy 443.61481 -125.573282) (xy 443.61481 -125.498606) (xy 443.614288 -125.488056)
			(xy 443.605748 -125.46876) (xy 443.5983 -125.461268) (xy 443.579236 -125.443121) (xy 443.54578 -125.402489)
			(xy 443.518222 -125.357647) (xy 443.497085 -125.309445) (xy 443.482769 -125.258796) (xy 443.475547 -125.206661)
			(xy 443.47511 -125.180344) (xy 443.475596 -125.153093) (xy 443.483352 -125.099145) (xy 443.498707 -125.04685)
			(xy 443.521349 -124.997273) (xy 443.550815 -124.951423) (xy 443.586506 -124.910232) (xy 443.627697 -124.874541)
			(xy 443.673547 -124.845075) (xy 443.723124 -124.822433) (xy 443.775419 -124.807078) (xy 443.829367 -124.799322)
			(xy 443.883869 -124.799322) (xy 443.937817 -124.807078) (xy 443.990112 -124.822433) (xy 444.039689 -124.845075)
			(xy 444.085539 -124.874541) (xy 444.12673 -124.910232) (xy 444.162421 -124.951423) (xy 444.191887 -124.997273)
			(xy 444.214529 -125.04685) (xy 444.229884 -125.099145) (xy 444.23764 -125.153093) (xy 444.238126 -125.180344)
			(xy 444.23768 -125.206659) (xy 444.230439 -125.258788) (xy 444.216115 -125.30943) (xy 444.194979 -125.357629)
			(xy 444.16743 -125.402472) (xy 444.133989 -125.443111) (xy 444.114936 -125.461268) (xy 444.107552 -125.468804)
			(xy 444.099016 -125.488073) (xy 444.098426 -125.498606) (xy 444.098426 -125.573282) (xy 444.098944 -125.583833)
			(xy 444.107486 -125.603129) (xy 444.114936 -125.61062) (xy 444.134001 -125.628766) (xy 444.167456 -125.669398)
			(xy 444.195013 -125.714241) (xy 444.216149 -125.762444) (xy 444.230465 -125.813092) (xy 444.237688 -125.865227)
			(xy 444.238126 -125.891544) (xy 444.23764 -125.918795) (xy 444.229884 -125.972743) (xy 444.214529 -126.025038)
			(xy 444.191887 -126.074615) (xy 444.162421 -126.120465) (xy 444.12673 -126.161656) (xy 444.085539 -126.197347)
			(xy 444.039689 -126.226813) (xy 443.990112 -126.249455) (xy 443.937817 -126.26481) (xy 443.883869 -126.272566)
			(xy 443.829367 -126.272566) (xy 443.775419 -126.26481) (xy 443.723124 -126.249455) (xy 443.673547 -126.226813)
			(xy 443.627697 -126.197347) (xy 443.586506 -126.161656) (xy 443.550815 -126.120465) (xy 443.521349 -126.074615)
			(xy 443.498707 -126.025038) (xy 443.483352 -125.972743) (xy 443.475596 -125.918795) (xy 443.47511 -125.891544)
			(xy 437.769 -125.891544) (xy 437.769 -128.77546) (xy 437.769093 -128.780479) (xy 437.771015 -128.79033)
			(xy 437.77281 -128.795018) (xy 437.938926 -129.19456) (xy 437.940933 -129.199124) (xy 437.946432 -129.207439)
			(xy 437.949848 -129.21107) (xy 442.937392 -134.198614) (xy 442.936376 -134.199376) (xy 444.612014 -135.875014)
			(xy 444.619409 -135.881868) (xy 444.638008 -135.88961) (xy 444.648082 -135.89) (xy 445.875918 -135.89)
			(xy 445.885987 -135.890427) (xy 445.904586 -135.898146) (xy 445.911986 -135.904986) (xy 447.152014 -137.145014)
			(xy 447.158868 -137.152409) (xy 447.16661 -137.171008) (xy 447.167 -137.181082) (xy 447.167 -138.154918)
			(xy 447.166573 -138.164987) (xy 447.158854 -138.183586) (xy 447.152014 -138.190986) (xy 447.054986 -138.288014)
			(xy 447.047591 -138.294868) (xy 447.028992 -138.30261) (xy 447.018918 -138.303) (xy 446.860422 -138.303)
			(xy 446.855342 -138.304016) (xy 446.83552 -138.308041) (xy 446.795303 -138.312373) (xy 446.775078 -138.312652)
			(xy 446.754854 -138.312361) (xy 446.714636 -138.308039) (xy 446.694814 -138.304016) (xy 446.689734 -138.303)
			(xy 446.503044 -138.303) (xy 446.49282 -138.303405) (xy 446.473946 -138.311258) (xy 446.466468 -138.31824)
			(xy 446.442805 -138.341882) (xy 446.391003 -138.384203) (xy 446.334715 -138.420346) (xy 446.274676 -138.449839)
			(xy 446.211667 -138.472299) (xy 446.14651 -138.487434) (xy 446.080052 -138.495045) (xy 446.046606 -138.495532)
			(xy 446.01316 -138.495056) (xy 445.946703 -138.487437) (xy 445.881546 -138.472298) (xy 445.818537 -138.449836)
			(xy 445.758497 -138.420344) (xy 445.702208 -138.384204) (xy 445.650401 -138.341888) (xy 445.626744 -138.31824)
			(xy 445.619269 -138.311246) (xy 445.600397 -138.303365) (xy 445.590168 -138.303) (xy 442.856366 -138.303)
			(xy 442.846299 -138.303429) (xy 442.827703 -138.311153) (xy 442.820298 -138.317986) (xy 442.59627 -138.542014)
			(xy 442.589418 -138.54941) (xy 442.581678 -138.568009) (xy 442.581284 -138.578082) (xy 442.581284 -207.97393)
			(xy 454.542396 -207.97393) (xy 454.546467 -207.918308) (xy 454.558593 -207.863871) (xy 454.578516 -207.81178)
			(xy 454.605812 -207.763145) (xy 454.639898 -207.719002) (xy 454.680047 -207.680293) (xy 454.725405 -207.647842)
			(xy 454.775005 -207.622341) (xy 454.827789 -207.604334) (xy 454.882632 -207.594204) (xy 454.938366 -207.592167)
			(xy 454.993803 -207.598267) (xy 455.04776 -207.612373) (xy 455.099089 -207.634185) (xy 455.146695 -207.663239)
			(xy 455.189563 -207.698914) (xy 455.22678 -207.740451) (xy 455.257553 -207.786964) (xy 455.281225 -207.837461)
			(xy 455.297293 -207.890868) (xy 455.305413 -207.946044) (xy 455.305922 -207.97393) (xy 455.305413 -208.001816)
			(xy 455.297293 -208.056992) (xy 455.281225 -208.110399) (xy 455.257553 -208.160896) (xy 455.22678 -208.207409)
			(xy 455.189563 -208.248946) (xy 455.146695 -208.284621) (xy 455.099089 -208.313675) (xy 455.04776 -208.335487)
			(xy 454.993803 -208.349593) (xy 454.938366 -208.355693) (xy 454.882632 -208.353656) (xy 454.827789 -208.343526)
			(xy 454.775005 -208.325519) (xy 454.725405 -208.300018) (xy 454.680047 -208.267567) (xy 454.639898 -208.228858)
			(xy 454.605812 -208.184715) (xy 454.578516 -208.13608) (xy 454.558593 -208.083989) (xy 454.546467 -208.029552)
			(xy 454.542396 -207.97393) (xy 442.581284 -207.97393) (xy 442.581284 -209.380836) (xy 445.288416 -209.380836)
			(xy 445.288416 -208.517236) (xy 445.288906 -208.487268) (xy 445.296729 -208.427846) (xy 445.312242 -208.369953)
			(xy 445.335178 -208.31458) (xy 445.365145 -208.262674) (xy 445.401632 -208.215124) (xy 445.444012 -208.172744)
			(xy 445.491562 -208.136257) (xy 445.543468 -208.10629) (xy 445.598841 -208.083354) (xy 445.656734 -208.067841)
			(xy 445.716156 -208.060018) (xy 445.776092 -208.060018) (xy 445.835514 -208.067841) (xy 445.893407 -208.083354)
			(xy 445.94878 -208.10629) (xy 446.000686 -208.136257) (xy 446.048236 -208.172744) (xy 446.090616 -208.215124)
			(xy 446.127103 -208.262674) (xy 446.15707 -208.31458) (xy 446.180006 -208.369953) (xy 446.195519 -208.427846)
			(xy 446.203342 -208.487268) (xy 446.203832 -208.517236) (xy 446.203832 -209.380836) (xy 446.203342 -209.410804)
			(xy 446.195519 -209.470226) (xy 446.180006 -209.528119) (xy 446.15707 -209.583492) (xy 446.127103 -209.635398)
			(xy 446.090616 -209.682948) (xy 446.048236 -209.725328) (xy 446.000686 -209.761815) (xy 445.94878 -209.791782)
			(xy 445.893407 -209.814718) (xy 445.835514 -209.830231) (xy 445.776092 -209.838054) (xy 445.716156 -209.838054)
			(xy 445.656734 -209.830231) (xy 445.598841 -209.814718) (xy 445.543468 -209.791782) (xy 445.491562 -209.761815)
			(xy 445.444012 -209.725328) (xy 445.401632 -209.682948) (xy 445.365145 -209.635398) (xy 445.335178 -209.583492)
			(xy 445.312242 -209.528119) (xy 445.296729 -209.470226) (xy 445.288906 -209.410804) (xy 445.288416 -209.380836)
			(xy 442.581284 -209.380836) (xy 442.581284 -209.94878) (xy 451.586598 -209.94878) (xy 451.590669 -209.893158)
			(xy 451.602795 -209.838721) (xy 451.622718 -209.78663) (xy 451.650014 -209.737995) (xy 451.6841 -209.693852)
			(xy 451.724249 -209.655143) (xy 451.769607 -209.622692) (xy 451.819207 -209.597191) (xy 451.871991 -209.579184)
			(xy 451.926834 -209.569054) (xy 451.982568 -209.567017) (xy 452.038005 -209.573117) (xy 452.091962 -209.587223)
			(xy 452.143291 -209.609035) (xy 452.190897 -209.638089) (xy 452.233765 -209.673764) (xy 452.270982 -209.715301)
			(xy 452.301755 -209.761814) (xy 452.325427 -209.812311) (xy 452.341495 -209.865718) (xy 452.349615 -209.920894)
			(xy 452.350124 -209.94878) (xy 452.349615 -209.976666) (xy 452.341495 -210.031842) (xy 452.325427 -210.085249)
			(xy 452.301755 -210.135746) (xy 452.270982 -210.182259) (xy 452.233765 -210.223796) (xy 452.190897 -210.259471)
			(xy 452.143291 -210.288525) (xy 452.091962 -210.310337) (xy 452.038005 -210.324443) (xy 451.982568 -210.330543)
			(xy 451.926834 -210.328506) (xy 451.871991 -210.318376) (xy 451.819207 -210.300369) (xy 451.769607 -210.274868)
			(xy 451.724249 -210.242417) (xy 451.6841 -210.203708) (xy 451.650014 -210.159565) (xy 451.622718 -210.11093)
			(xy 451.602795 -210.058839) (xy 451.590669 -210.004402) (xy 451.586598 -209.94878) (xy 442.581284 -209.94878)
			(xy 442.581284 -222.0976) (xy 451.742046 -222.0976) (xy 451.746117 -222.041978) (xy 451.758243 -221.987541)
			(xy 451.778166 -221.93545) (xy 451.805462 -221.886815) (xy 451.839548 -221.842672) (xy 451.879697 -221.803963)
			(xy 451.925055 -221.771512) (xy 451.974655 -221.746011) (xy 452.027439 -221.728004) (xy 452.082282 -221.717874)
			(xy 452.138016 -221.715837) (xy 452.193453 -221.721937) (xy 452.24741 -221.736043) (xy 452.298739 -221.757855)
			(xy 452.346345 -221.786909) (xy 452.389213 -221.822584) (xy 452.42643 -221.864121) (xy 452.457203 -221.910634)
			(xy 452.480875 -221.961131) (xy 452.496943 -222.014538) (xy 452.505063 -222.069714) (xy 452.505572 -222.0976)
			(xy 452.505063 -222.125486) (xy 452.496943 -222.180662) (xy 452.480875 -222.234069) (xy 452.457203 -222.284566)
			(xy 452.42643 -222.331079) (xy 452.389213 -222.372616) (xy 452.346345 -222.408291) (xy 452.298739 -222.437345)
			(xy 452.24741 -222.459157) (xy 452.193453 -222.473263) (xy 452.138016 -222.479363) (xy 452.082282 -222.477326)
			(xy 452.027439 -222.467196) (xy 451.974655 -222.449189) (xy 451.925055 -222.423688) (xy 451.879697 -222.391237)
			(xy 451.839548 -222.352528) (xy 451.805462 -222.308385) (xy 451.778166 -222.25975) (xy 451.758243 -222.207659)
			(xy 451.746117 -222.153222) (xy 451.742046 -222.0976) (xy 442.581284 -222.0976) (xy 442.581284 -223.316546)
			(xy 443.32982 -223.316546) (xy 443.333891 -223.260924) (xy 443.346017 -223.206487) (xy 443.36594 -223.154396)
			(xy 443.393236 -223.105761) (xy 443.427322 -223.061618) (xy 443.467471 -223.022909) (xy 443.512829 -222.990458)
			(xy 443.562429 -222.964957) (xy 443.615213 -222.94695) (xy 443.670056 -222.93682) (xy 443.72579 -222.934783)
			(xy 443.781227 -222.940883) (xy 443.835184 -222.954989) (xy 443.886513 -222.976801) (xy 443.934119 -223.005855)
			(xy 443.976987 -223.04153) (xy 444.014204 -223.083067) (xy 444.044977 -223.12958) (xy 444.068649 -223.180077)
			(xy 444.084717 -223.233484) (xy 444.092837 -223.28866) (xy 444.093346 -223.316546) (xy 444.092837 -223.344432)
			(xy 444.084717 -223.399608) (xy 444.068649 -223.453015) (xy 444.044977 -223.503512) (xy 444.014204 -223.550025)
			(xy 443.976987 -223.591562) (xy 443.934119 -223.627237) (xy 443.886513 -223.656291) (xy 443.835184 -223.678103)
			(xy 443.781227 -223.692209) (xy 443.72579 -223.698309) (xy 443.670056 -223.696272) (xy 443.615213 -223.686142)
			(xy 443.562429 -223.668135) (xy 443.512829 -223.642634) (xy 443.467471 -223.610183) (xy 443.427322 -223.571474)
			(xy 443.393236 -223.527331) (xy 443.36594 -223.478696) (xy 443.346017 -223.426605) (xy 443.333891 -223.372168)
			(xy 443.32982 -223.316546) (xy 442.581284 -223.316546) (xy 442.581284 -224.700846) (xy 443.326518 -224.700846)
			(xy 443.330589 -224.645224) (xy 443.342715 -224.590787) (xy 443.362638 -224.538696) (xy 443.389934 -224.490061)
			(xy 443.42402 -224.445918) (xy 443.464169 -224.407209) (xy 443.509527 -224.374758) (xy 443.559127 -224.349257)
			(xy 443.611911 -224.33125) (xy 443.666754 -224.32112) (xy 443.722488 -224.319083) (xy 443.777925 -224.325183)
			(xy 443.831882 -224.339289) (xy 443.883211 -224.361101) (xy 443.930817 -224.390155) (xy 443.973685 -224.42583)
			(xy 444.010902 -224.467367) (xy 444.041675 -224.51388) (xy 444.065347 -224.564377) (xy 444.081415 -224.617784)
			(xy 444.089535 -224.67296) (xy 444.090044 -224.700846) (xy 444.089535 -224.728732) (xy 444.081415 -224.783908)
			(xy 444.065347 -224.837315) (xy 444.041675 -224.887812) (xy 444.010902 -224.934325) (xy 443.973685 -224.975862)
			(xy 443.930817 -225.011537) (xy 443.883211 -225.040591) (xy 443.831882 -225.062403) (xy 443.777925 -225.076509)
			(xy 443.722488 -225.082609) (xy 443.666754 -225.080572) (xy 443.611911 -225.070442) (xy 443.559127 -225.052435)
			(xy 443.509527 -225.026934) (xy 443.464169 -224.994483) (xy 443.42402 -224.955774) (xy 443.389934 -224.911631)
			(xy 443.362638 -224.862996) (xy 443.342715 -224.810905) (xy 443.330589 -224.756468) (xy 443.326518 -224.700846)
			(xy 442.581284 -224.700846) (xy 442.581284 -226.681538) (xy 457.325982 -226.681538) (xy 457.330053 -226.625916)
			(xy 457.342179 -226.571479) (xy 457.362102 -226.519388) (xy 457.389398 -226.470753) (xy 457.423484 -226.42661)
			(xy 457.463633 -226.387901) (xy 457.508991 -226.35545) (xy 457.558591 -226.329949) (xy 457.611375 -226.311942)
			(xy 457.666218 -226.301812) (xy 457.721952 -226.299775) (xy 457.777389 -226.305875) (xy 457.831346 -226.319981)
			(xy 457.882675 -226.341793) (xy 457.930281 -226.370847) (xy 457.973149 -226.406522) (xy 458.010366 -226.448059)
			(xy 458.041139 -226.494572) (xy 458.064811 -226.545069) (xy 458.080879 -226.598476) (xy 458.088999 -226.653652)
			(xy 458.089508 -226.681538) (xy 458.088999 -226.709424) (xy 458.080879 -226.7646) (xy 458.064811 -226.818007)
			(xy 458.041139 -226.868504) (xy 458.010366 -226.915017) (xy 457.973149 -226.956554) (xy 457.930281 -226.992229)
			(xy 457.882675 -227.021283) (xy 457.831346 -227.043095) (xy 457.777389 -227.057201) (xy 457.721952 -227.063301)
			(xy 457.666218 -227.061264) (xy 457.611375 -227.051134) (xy 457.558591 -227.033127) (xy 457.508991 -227.007626)
			(xy 457.463633 -226.975175) (xy 457.423484 -226.936466) (xy 457.389398 -226.892323) (xy 457.362102 -226.843688)
			(xy 457.342179 -226.791597) (xy 457.330053 -226.73716) (xy 457.325982 -226.681538) (xy 442.581284 -226.681538)
			(xy 442.581284 -228.667848) (xy 442.823618 -228.667848) (xy 442.823618 -228.613352) (xy 442.831374 -228.55941)
			(xy 442.846727 -228.50712) (xy 442.869366 -228.457548) (xy 442.898829 -228.411703) (xy 442.934517 -228.370517)
			(xy 442.975703 -228.334829) (xy 443.021548 -228.305366) (xy 443.07112 -228.282727) (xy 443.12341 -228.267374)
			(xy 443.177352 -228.259618) (xy 443.2046 -228.259132) (xy 443.233517 -228.259638) (xy 443.29069 -228.268368)
			(xy 443.345889 -228.285628) (xy 443.397851 -228.311022) (xy 443.445385 -228.343968) (xy 443.487401 -228.383711)
			(xy 443.50559 -228.406198) (xy 443.513212 -228.41499) (xy 443.534101 -228.425182) (xy 443.545722 -228.425756)
			(xy 443.625478 -228.425756) (xy 443.637109 -228.425205) (xy 443.658019 -228.415026) (xy 443.66561 -228.406198)
			(xy 443.683795 -228.383709) (xy 443.725816 -228.343975) (xy 443.773352 -228.311036) (xy 443.825315 -228.285649)
			(xy 443.880513 -228.268394) (xy 443.937684 -228.259666) (xy 443.9666 -228.259132) (xy 443.993854 -228.259538)
			(xy 444.047807 -228.267295) (xy 444.100108 -228.282652) (xy 444.14969 -228.305295) (xy 444.195545 -228.334765)
			(xy 444.23674 -228.37046) (xy 444.272435 -228.411655) (xy 444.301905 -228.45751) (xy 444.324548 -228.507092)
			(xy 444.339905 -228.559393) (xy 444.347662 -228.613346) (xy 444.347662 -228.667854) (xy 444.339905 -228.721807)
			(xy 444.324548 -228.774108) (xy 444.301905 -228.82369) (xy 444.272435 -228.869545) (xy 444.23674 -228.91074)
			(xy 444.195545 -228.946435) (xy 444.14969 -228.975905) (xy 444.100108 -228.998548) (xy 444.047807 -229.013905)
			(xy 443.993854 -229.021662) (xy 443.9666 -229.022148) (xy 443.937682 -229.021649) (xy 443.880509 -229.012919)
			(xy 443.825309 -228.995658) (xy 443.773347 -228.970263) (xy 443.725814 -228.937315) (xy 443.683799 -228.89757)
			(xy 443.66561 -228.875082) (xy 443.657992 -228.866286) (xy 443.637099 -228.856097) (xy 443.625478 -228.855524)
			(xy 443.545722 -228.855524) (xy 443.534092 -228.856082) (xy 443.513182 -228.866256) (xy 443.50559 -228.875082)
			(xy 443.4874 -228.897567) (xy 443.445381 -228.937302) (xy 443.397846 -228.970242) (xy 443.345884 -228.99563)
			(xy 443.290686 -229.012886) (xy 443.233516 -229.021614) (xy 443.2046 -229.022148) (xy 443.177352 -229.021582)
			(xy 443.12341 -229.013826) (xy 443.07112 -228.998473) (xy 443.021548 -228.975834) (xy 442.975703 -228.946371)
			(xy 442.934517 -228.910683) (xy 442.898829 -228.869497) (xy 442.869366 -228.823652) (xy 442.846727 -228.77408)
			(xy 442.831374 -228.72179) (xy 442.823618 -228.667848) (xy 442.581284 -228.667848) (xy 442.581284 -229.12197)
			(xy 444.350392 -229.12197) (xy 444.354463 -229.066348) (xy 444.366589 -229.011911) (xy 444.386512 -228.95982)
			(xy 444.413808 -228.911185) (xy 444.447894 -228.867042) (xy 444.488043 -228.828333) (xy 444.533401 -228.795882)
			(xy 444.583001 -228.770381) (xy 444.635785 -228.752374) (xy 444.690628 -228.742244) (xy 444.746362 -228.740207)
			(xy 444.801799 -228.746307) (xy 444.855756 -228.760413) (xy 444.907085 -228.782225) (xy 444.954691 -228.811279)
			(xy 444.997559 -228.846954) (xy 445.034776 -228.888491) (xy 445.065549 -228.935004) (xy 445.089221 -228.985501)
			(xy 445.105289 -229.038908) (xy 445.113409 -229.094084) (xy 445.113918 -229.12197) (xy 445.113409 -229.149856)
			(xy 445.105289 -229.205032) (xy 445.089221 -229.258439) (xy 445.065549 -229.308936) (xy 445.034776 -229.355449)
			(xy 444.997559 -229.396986) (xy 444.954691 -229.432661) (xy 444.907085 -229.461715) (xy 444.855756 -229.483527)
			(xy 444.801799 -229.497633) (xy 444.746362 -229.503733) (xy 444.690628 -229.501696) (xy 444.635785 -229.491566)
			(xy 444.583001 -229.473559) (xy 444.533401 -229.448058) (xy 444.488043 -229.415607) (xy 444.447894 -229.376898)
			(xy 444.413808 -229.332755) (xy 444.386512 -229.28412) (xy 444.366589 -229.232029) (xy 444.354463 -229.177592)
			(xy 444.350392 -229.12197) (xy 442.581284 -229.12197) (xy 442.581284 -230.3526) (xy 461.872582 -230.3526)
			(xy 461.876653 -230.296978) (xy 461.888779 -230.242541) (xy 461.908702 -230.19045) (xy 461.935998 -230.141815)
			(xy 461.970084 -230.097672) (xy 462.010233 -230.058963) (xy 462.055591 -230.026512) (xy 462.105191 -230.001011)
			(xy 462.157975 -229.983004) (xy 462.212818 -229.972874) (xy 462.268552 -229.970837) (xy 462.323989 -229.976937)
			(xy 462.377946 -229.991043) (xy 462.429275 -230.012855) (xy 462.476881 -230.041909) (xy 462.519749 -230.077584)
			(xy 462.556966 -230.119121) (xy 462.587739 -230.165634) (xy 462.611411 -230.216131) (xy 462.627479 -230.269538)
			(xy 462.635599 -230.324714) (xy 462.636108 -230.3526) (xy 462.635599 -230.380486) (xy 462.627479 -230.435662)
			(xy 462.611411 -230.489069) (xy 462.587739 -230.539566) (xy 462.556966 -230.586079) (xy 462.519749 -230.627616)
			(xy 462.476881 -230.663291) (xy 462.429275 -230.692345) (xy 462.377946 -230.714157) (xy 462.323989 -230.728263)
			(xy 462.268552 -230.734363) (xy 462.212818 -230.732326) (xy 462.157975 -230.722196) (xy 462.105191 -230.704189)
			(xy 462.055591 -230.678688) (xy 462.010233 -230.646237) (xy 461.970084 -230.607528) (xy 461.935998 -230.563385)
			(xy 461.908702 -230.51475) (xy 461.888779 -230.462659) (xy 461.876653 -230.408222) (xy 461.872582 -230.3526)
			(xy 442.581284 -230.3526) (xy 442.581284 -232.69448) (xy 451.24192 -232.69448) (xy 451.245991 -232.638858)
			(xy 451.258117 -232.584421) (xy 451.27804 -232.53233) (xy 451.305336 -232.483695) (xy 451.339422 -232.439552)
			(xy 451.379571 -232.400843) (xy 451.424929 -232.368392) (xy 451.474529 -232.342891) (xy 451.527313 -232.324884)
			(xy 451.582156 -232.314754) (xy 451.63789 -232.312717) (xy 451.693327 -232.318817) (xy 451.747284 -232.332923)
			(xy 451.798613 -232.354735) (xy 451.846219 -232.383789) (xy 451.889087 -232.419464) (xy 451.926304 -232.461001)
			(xy 451.957077 -232.507514) (xy 451.980749 -232.558011) (xy 451.996817 -232.611418) (xy 452.004937 -232.666594)
			(xy 452.005446 -232.69448) (xy 452.004937 -232.722366) (xy 451.996817 -232.777542) (xy 451.980749 -232.830949)
			(xy 451.957077 -232.881446) (xy 451.926304 -232.927959) (xy 451.889087 -232.969496) (xy 451.846219 -233.005171)
			(xy 451.798613 -233.034225) (xy 451.747284 -233.056037) (xy 451.693327 -233.070143) (xy 451.63789 -233.076243)
			(xy 451.582156 -233.074206) (xy 451.527313 -233.064076) (xy 451.474529 -233.046069) (xy 451.424929 -233.020568)
			(xy 451.379571 -232.988117) (xy 451.339422 -232.949408) (xy 451.305336 -232.905265) (xy 451.27804 -232.85663)
			(xy 451.258117 -232.804539) (xy 451.245991 -232.750102) (xy 451.24192 -232.69448) (xy 442.581284 -232.69448)
			(xy 442.581284 -232.771442) (xy 442.581634 -232.780396) (xy 442.587786 -232.797215) (xy 442.599329 -232.810907)
			(xy 442.606938 -232.815638) (xy 442.629898 -232.829318) (xy 442.672101 -232.862112) (xy 442.709313 -232.900474)
			(xy 442.740807 -232.943655) (xy 442.765966 -232.99081) (xy 442.784296 -233.041014) (xy 442.79544 -233.093285)
			(xy 442.799179 -233.1466) (xy 442.79544 -233.199915) (xy 442.784296 -233.252186) (xy 442.775272 -233.276902)
			(xy 443.9318 -233.276902) (xy 443.935871 -233.22128) (xy 443.947997 -233.166843) (xy 443.96792 -233.114752)
			(xy 443.995216 -233.066117) (xy 444.029302 -233.021974) (xy 444.069451 -232.983265) (xy 444.114809 -232.950814)
			(xy 444.164409 -232.925313) (xy 444.217193 -232.907306) (xy 444.272036 -232.897176) (xy 444.32777 -232.895139)
			(xy 444.383207 -232.901239) (xy 444.437164 -232.915345) (xy 444.488493 -232.937157) (xy 444.536099 -232.966211)
			(xy 444.578967 -233.001886) (xy 444.616184 -233.043423) (xy 444.646957 -233.089936) (xy 444.670629 -233.140433)
			(xy 444.686697 -233.19384) (xy 444.694817 -233.249016) (xy 444.695326 -233.276902) (xy 444.694817 -233.304788)
			(xy 444.686697 -233.359964) (xy 444.670629 -233.413371) (xy 444.646957 -233.463868) (xy 444.616184 -233.510381)
			(xy 444.578967 -233.551918) (xy 444.536099 -233.587593) (xy 444.488493 -233.616647) (xy 444.437164 -233.638459)
			(xy 444.383207 -233.652565) (xy 444.32777 -233.658665) (xy 444.272036 -233.656628) (xy 444.217193 -233.646498)
			(xy 444.164409 -233.628491) (xy 444.114809 -233.60299) (xy 444.069451 -233.570539) (xy 444.029302 -233.53183)
			(xy 443.995216 -233.487687) (xy 443.96792 -233.439052) (xy 443.947997 -233.386961) (xy 443.935871 -233.332524)
			(xy 443.9318 -233.276902) (xy 442.775272 -233.276902) (xy 442.765966 -233.30239) (xy 442.740807 -233.349545)
			(xy 442.709313 -233.392726) (xy 442.672101 -233.431088) (xy 442.629898 -233.463882) (xy 442.606938 -233.477562)
			(xy 442.59933 -233.482296) (xy 442.587778 -233.495977) (xy 442.581654 -233.512804) (xy 442.581284 -233.521758)
			(xy 442.581284 -234.655869) (xy 448.021157 -234.655869) (xy 448.021157 -234.595931) (xy 448.028981 -234.536505)
			(xy 448.044494 -234.478608) (xy 448.067432 -234.423232) (xy 448.097401 -234.371324) (xy 448.13389 -234.323771)
			(xy 448.176273 -234.281388) (xy 448.223825 -234.2449) (xy 448.275734 -234.214931) (xy 448.33111 -234.191993)
			(xy 448.389007 -234.17648) (xy 448.448433 -234.168657) (xy 448.478402 -234.168188) (xy 449.342002 -234.168188)
			(xy 449.371969 -234.168686) (xy 449.431391 -234.176509) (xy 449.489283 -234.192022) (xy 449.544656 -234.214958)
			(xy 449.596561 -234.244925) (xy 449.64411 -234.281411) (xy 449.68649 -234.323792) (xy 449.722976 -234.371341)
			(xy 449.752943 -234.423246) (xy 449.775879 -234.478618) (xy 449.791391 -234.536511) (xy 449.799214 -234.595933)
			(xy 449.799214 -234.655867) (xy 449.791391 -234.715289) (xy 449.775879 -234.773182) (xy 449.752943 -234.828554)
			(xy 449.749404 -234.834684) (xy 450.697598 -234.834684) (xy 450.701669 -234.779062) (xy 450.713795 -234.724625)
			(xy 450.733718 -234.672534) (xy 450.761014 -234.623899) (xy 450.7951 -234.579756) (xy 450.835249 -234.541047)
			(xy 450.880607 -234.508596) (xy 450.930207 -234.483095) (xy 450.982991 -234.465088) (xy 451.037834 -234.454958)
			(xy 451.093568 -234.452921) (xy 451.149005 -234.459021) (xy 451.202962 -234.473127) (xy 451.254291 -234.494939)
			(xy 451.301897 -234.523993) (xy 451.344765 -234.559668) (xy 451.381982 -234.601205) (xy 451.412755 -234.647718)
			(xy 451.436427 -234.698215) (xy 451.452495 -234.751622) (xy 451.460615 -234.806798) (xy 451.461124 -234.834684)
			(xy 451.460615 -234.86257) (xy 451.452495 -234.917746) (xy 451.436427 -234.971153) (xy 451.412755 -235.02165)
			(xy 451.381982 -235.068163) (xy 451.344765 -235.1097) (xy 451.301897 -235.145375) (xy 451.254291 -235.174429)
			(xy 451.202962 -235.196241) (xy 451.149005 -235.210347) (xy 451.093568 -235.216447) (xy 451.037834 -235.21441)
			(xy 450.982991 -235.20428) (xy 450.930207 -235.186273) (xy 450.880607 -235.160772) (xy 450.835249 -235.128321)
			(xy 450.7951 -235.089612) (xy 450.761014 -235.045469) (xy 450.733718 -234.996834) (xy 450.713795 -234.944743)
			(xy 450.701669 -234.890306) (xy 450.697598 -234.834684) (xy 449.749404 -234.834684) (xy 449.722976 -234.880459)
			(xy 449.68649 -234.928008) (xy 449.64411 -234.970389) (xy 449.596561 -235.006875) (xy 449.544656 -235.036842)
			(xy 449.489283 -235.059778) (xy 449.431391 -235.075291) (xy 449.371969 -235.083114) (xy 449.342002 -235.083604)
			(xy 448.478402 -235.083604) (xy 448.448433 -235.083143) (xy 448.389007 -235.07532) (xy 448.33111 -235.059807)
			(xy 448.275734 -235.036869) (xy 448.223825 -235.0069) (xy 448.176273 -234.970412) (xy 448.13389 -234.928029)
			(xy 448.097401 -234.880476) (xy 448.067432 -234.828568) (xy 448.044494 -234.773192) (xy 448.028981 -234.715295)
			(xy 448.021157 -234.655869) (xy 442.581284 -234.655869) (xy 442.581284 -236.4994) (xy 444.422782 -236.4994)
			(xy 444.426853 -236.443778) (xy 444.438979 -236.389341) (xy 444.458902 -236.33725) (xy 444.486198 -236.288615)
			(xy 444.520284 -236.244472) (xy 444.560433 -236.205763) (xy 444.605791 -236.173312) (xy 444.655391 -236.147811)
			(xy 444.708175 -236.129804) (xy 444.763018 -236.119674) (xy 444.818752 -236.117637) (xy 444.874189 -236.123737)
			(xy 444.928146 -236.137843) (xy 444.979475 -236.159655) (xy 445.027081 -236.188709) (xy 445.069949 -236.224384)
			(xy 445.107166 -236.265921) (xy 445.137939 -236.312434) (xy 445.161611 -236.362931) (xy 445.169274 -236.388402)
			(xy 450.160898 -236.388402) (xy 450.161419 -236.359485) (xy 450.170147 -236.302314) (xy 450.187405 -236.247115)
			(xy 450.212796 -236.195154) (xy 450.245739 -236.14762) (xy 450.285479 -236.105603) (xy 450.307964 -236.087412)
			(xy 450.316766 -236.079801) (xy 450.32695 -236.058903) (xy 450.327522 -236.04728) (xy 450.327522 -235.967524)
			(xy 450.326947 -235.955897) (xy 450.316783 -235.934987) (xy 450.307964 -235.927392) (xy 450.285469 -235.909215)
			(xy 450.245736 -235.867191) (xy 450.2128 -235.819653) (xy 450.187414 -235.767689) (xy 450.170159 -235.71249)
			(xy 450.161432 -235.655319) (xy 450.160898 -235.626402) (xy 450.161384 -235.599151) (xy 450.16914 -235.545203)
			(xy 450.184495 -235.492908) (xy 450.207137 -235.443331) (xy 450.236603 -235.397481) (xy 450.272294 -235.35629)
			(xy 450.313485 -235.320599) (xy 450.359335 -235.291133) (xy 450.408912 -235.268491) (xy 450.461207 -235.253136)
			(xy 450.515155 -235.24538) (xy 450.569657 -235.24538) (xy 450.623605 -235.253136) (xy 450.6759 -235.268491)
			(xy 450.725477 -235.291133) (xy 450.771327 -235.320599) (xy 450.812518 -235.35629) (xy 450.848209 -235.397481)
			(xy 450.877675 -235.443331) (xy 450.900317 -235.492908) (xy 450.915672 -235.545203) (xy 450.923428 -235.599151)
			(xy 450.923914 -235.626402) (xy 450.92343 -235.655321) (xy 450.914698 -235.712495) (xy 450.897436 -235.767696)
			(xy 450.872038 -235.819658) (xy 450.839087 -235.867191) (xy 450.799338 -235.909204) (xy 450.776848 -235.927392)
			(xy 450.768046 -235.935003) (xy 450.757861 -235.955901) (xy 450.75729 -235.967524) (xy 450.75729 -236.04728)
			(xy 450.757859 -236.058908) (xy 450.768027 -236.079818) (xy 450.776848 -236.087412) (xy 450.799347 -236.105584)
			(xy 450.839079 -236.147609) (xy 450.872015 -236.195149) (xy 450.8974 -236.247113) (xy 450.914654 -236.302313)
			(xy 450.921397 -236.346492) (xy 454.16038 -236.346492) (xy 454.164451 -236.29087) (xy 454.176577 -236.236433)
			(xy 454.1965 -236.184342) (xy 454.223796 -236.135707) (xy 454.257882 -236.091564) (xy 454.298031 -236.052855)
			(xy 454.343389 -236.020404) (xy 454.392989 -235.994903) (xy 454.445773 -235.976896) (xy 454.500616 -235.966766)
			(xy 454.55635 -235.964729) (xy 454.611787 -235.970829) (xy 454.665744 -235.984935) (xy 454.717073 -236.006747)
			(xy 454.764679 -236.035801) (xy 454.807547 -236.071476) (xy 454.844764 -236.113013) (xy 454.875537 -236.159526)
			(xy 454.899209 -236.210023) (xy 454.915277 -236.26343) (xy 454.922866 -236.314996) (xy 455.160378 -236.314996)
			(xy 455.164449 -236.259374) (xy 455.176575 -236.204937) (xy 455.196498 -236.152846) (xy 455.223794 -236.104211)
			(xy 455.25788 -236.060068) (xy 455.298029 -236.021359) (xy 455.343387 -235.988908) (xy 455.392987 -235.963407)
			(xy 455.445771 -235.9454) (xy 455.500614 -235.93527) (xy 455.556348 -235.933233) (xy 455.611785 -235.939333)
			(xy 455.665742 -235.953439) (xy 455.717071 -235.975251) (xy 455.764677 -236.004305) (xy 455.807545 -236.03998)
			(xy 455.844762 -236.081517) (xy 455.875535 -236.12803) (xy 455.899207 -236.178527) (xy 455.915275 -236.231934)
			(xy 455.923395 -236.28711) (xy 455.923904 -236.314996) (xy 455.923395 -236.342882) (xy 455.915275 -236.398058)
			(xy 455.910691 -236.413294) (xy 456.148692 -236.413294) (xy 456.152763 -236.357672) (xy 456.164889 -236.303235)
			(xy 456.184812 -236.251144) (xy 456.212108 -236.202509) (xy 456.246194 -236.158366) (xy 456.286343 -236.119657)
			(xy 456.331701 -236.087206) (xy 456.381301 -236.061705) (xy 456.434085 -236.043698) (xy 456.488928 -236.033568)
			(xy 456.544662 -236.031531) (xy 456.600099 -236.037631) (xy 456.654056 -236.051737) (xy 456.705385 -236.073549)
			(xy 456.752991 -236.102603) (xy 456.795859 -236.138278) (xy 456.833076 -236.179815) (xy 456.863849 -236.226328)
			(xy 456.887521 -236.276825) (xy 456.903589 -236.330232) (xy 456.911709 -236.385408) (xy 456.912218 -236.413294)
			(xy 456.911709 -236.44118) (xy 456.903589 -236.496356) (xy 456.887521 -236.549763) (xy 456.863849 -236.60026)
			(xy 456.833076 -236.646773) (xy 456.795859 -236.68831) (xy 456.752991 -236.723985) (xy 456.705385 -236.753039)
			(xy 456.654056 -236.774851) (xy 456.600099 -236.788957) (xy 456.544662 -236.795057) (xy 456.488928 -236.79302)
			(xy 456.434085 -236.78289) (xy 456.381301 -236.764883) (xy 456.331701 -236.739382) (xy 456.286343 -236.706931)
			(xy 456.246194 -236.668222) (xy 456.212108 -236.624079) (xy 456.184812 -236.575444) (xy 456.164889 -236.523353)
			(xy 456.152763 -236.468916) (xy 456.148692 -236.413294) (xy 455.910691 -236.413294) (xy 455.899207 -236.451465)
			(xy 455.875535 -236.501962) (xy 455.844762 -236.548475) (xy 455.807545 -236.590012) (xy 455.764677 -236.625687)
			(xy 455.717071 -236.654741) (xy 455.665742 -236.676553) (xy 455.611785 -236.690659) (xy 455.556348 -236.696759)
			(xy 455.500614 -236.694722) (xy 455.445771 -236.684592) (xy 455.392987 -236.666585) (xy 455.343387 -236.641084)
			(xy 455.298029 -236.608633) (xy 455.25788 -236.569924) (xy 455.223794 -236.525781) (xy 455.196498 -236.477146)
			(xy 455.176575 -236.425055) (xy 455.164449 -236.370618) (xy 455.160378 -236.314996) (xy 454.922866 -236.314996)
			(xy 454.923397 -236.318606) (xy 454.923906 -236.346492) (xy 454.923397 -236.374378) (xy 454.915277 -236.429554)
			(xy 454.899209 -236.482961) (xy 454.875537 -236.533458) (xy 454.844764 -236.579971) (xy 454.807547 -236.621508)
			(xy 454.764679 -236.657183) (xy 454.717073 -236.686237) (xy 454.665744 -236.708049) (xy 454.611787 -236.722155)
			(xy 454.55635 -236.728255) (xy 454.500616 -236.726218) (xy 454.445773 -236.716088) (xy 454.392989 -236.698081)
			(xy 454.343389 -236.67258) (xy 454.298031 -236.640129) (xy 454.257882 -236.60142) (xy 454.223796 -236.557277)
			(xy 454.1965 -236.508642) (xy 454.176577 -236.456551) (xy 454.164451 -236.402114) (xy 454.16038 -236.346492)
			(xy 450.921397 -236.346492) (xy 450.92338 -236.359485) (xy 450.923914 -236.388402) (xy 450.923428 -236.415653)
			(xy 450.915672 -236.469601) (xy 450.900317 -236.521896) (xy 450.877675 -236.571473) (xy 450.848209 -236.617323)
			(xy 450.812518 -236.658514) (xy 450.771327 -236.694205) (xy 450.725477 -236.723671) (xy 450.6759 -236.746313)
			(xy 450.623605 -236.761668) (xy 450.569657 -236.769424) (xy 450.515155 -236.769424) (xy 450.461207 -236.761668)
			(xy 450.408912 -236.746313) (xy 450.359335 -236.723671) (xy 450.313485 -236.694205) (xy 450.272294 -236.658514)
			(xy 450.236603 -236.617323) (xy 450.207137 -236.571473) (xy 450.184495 -236.521896) (xy 450.16914 -236.469601)
			(xy 450.161384 -236.415653) (xy 450.160898 -236.388402) (xy 445.169274 -236.388402) (xy 445.177679 -236.416338)
			(xy 445.185799 -236.471514) (xy 445.186308 -236.4994) (xy 445.185799 -236.527286) (xy 445.177679 -236.582462)
			(xy 445.161611 -236.635869) (xy 445.137939 -236.686366) (xy 445.107166 -236.732879) (xy 445.069949 -236.774416)
			(xy 445.027081 -236.810091) (xy 444.979475 -236.839145) (xy 444.928146 -236.860957) (xy 444.874189 -236.875063)
			(xy 444.818752 -236.881163) (xy 444.763018 -236.879126) (xy 444.708175 -236.868996) (xy 444.655391 -236.850989)
			(xy 444.605791 -236.825488) (xy 444.560433 -236.793037) (xy 444.520284 -236.754328) (xy 444.486198 -236.710185)
			(xy 444.458902 -236.66155) (xy 444.438979 -236.609459) (xy 444.426853 -236.555022) (xy 444.422782 -236.4994)
			(xy 442.581284 -236.4994) (xy 442.581284 -237.5154) (xy 443.254382 -237.5154) (xy 443.258453 -237.459778)
			(xy 443.270579 -237.405341) (xy 443.290502 -237.35325) (xy 443.317798 -237.304615) (xy 443.351884 -237.260472)
			(xy 443.392033 -237.221763) (xy 443.437391 -237.189312) (xy 443.486991 -237.163811) (xy 443.539775 -237.145804)
			(xy 443.594618 -237.135674) (xy 443.650352 -237.133637) (xy 443.705789 -237.139737) (xy 443.759746 -237.153843)
			(xy 443.811075 -237.175655) (xy 443.858681 -237.204709) (xy 443.901549 -237.240384) (xy 443.938766 -237.281921)
			(xy 443.969539 -237.328434) (xy 443.993211 -237.378931) (xy 444.009279 -237.432338) (xy 444.017399 -237.487514)
			(xy 444.017908 -237.5154) (xy 444.017399 -237.543286) (xy 444.009279 -237.598462) (xy 443.993211 -237.651869)
			(xy 443.969539 -237.702366) (xy 443.938766 -237.748879) (xy 443.901549 -237.790416) (xy 443.858681 -237.826091)
			(xy 443.811075 -237.855145) (xy 443.759746 -237.876957) (xy 443.705789 -237.891063) (xy 443.650352 -237.897163)
			(xy 443.594618 -237.895126) (xy 443.539775 -237.884996) (xy 443.486991 -237.866989) (xy 443.437391 -237.841488)
			(xy 443.392033 -237.809037) (xy 443.351884 -237.770328) (xy 443.317798 -237.726185) (xy 443.290502 -237.67755)
			(xy 443.270579 -237.625459) (xy 443.258453 -237.571022) (xy 443.254382 -237.5154) (xy 442.581284 -237.5154)
			(xy 442.581284 -237.821216) (xy 442.581709 -237.831285) (xy 442.589426 -237.849887) (xy 442.59627 -237.857284)
			(xy 447.587116 -242.84813) (xy 451.778624 -242.84813) (xy 451.779037 -242.821814) (xy 451.786282 -242.769683)
			(xy 451.800611 -242.719039) (xy 451.821754 -242.67084) (xy 451.84931 -242.625998) (xy 451.882758 -242.585361)
			(xy 451.901814 -242.567206) (xy 451.909217 -242.559686) (xy 451.91774 -242.540405) (xy 451.918324 -242.529868)
			(xy 451.918324 -242.455192) (xy 451.917806 -242.444641) (xy 451.909262 -242.425346) (xy 451.901814 -242.417854)
			(xy 451.882746 -242.399711) (xy 451.849289 -242.359079) (xy 451.821732 -242.314236) (xy 451.800595 -242.266033)
			(xy 451.786281 -242.215383) (xy 451.77906 -242.163247) (xy 451.778624 -242.13693) (xy 451.779083 -242.109676)
			(xy 451.786837 -242.055724) (xy 451.802191 -242.003424) (xy 451.824832 -241.953842) (xy 451.8543 -241.907987)
			(xy 451.889994 -241.866793) (xy 451.931188 -241.831099) (xy 451.977043 -241.801631) (xy 452.026626 -241.77899)
			(xy 452.078926 -241.763637) (xy 452.132878 -241.755883) (xy 452.160132 -241.755422) (xy 452.186447 -241.755861)
			(xy 452.238577 -241.763101) (xy 452.289221 -241.777425) (xy 452.33742 -241.798563) (xy 452.382262 -241.826114)
			(xy 452.4229 -241.859558) (xy 452.441056 -241.878612) (xy 452.44859 -241.885998) (xy 452.467861 -241.894531)
			(xy 452.478394 -241.895122) (xy 452.55307 -241.895122) (xy 452.563618 -241.894583) (xy 452.582913 -241.886054)
			(xy 452.590408 -241.878612) (xy 452.610228 -241.857824) (xy 452.655 -241.821849) (xy 452.704658 -241.792989)
			(xy 452.75808 -241.771896) (xy 452.814059 -241.759047) (xy 452.871332 -241.754732) (xy 452.928605 -241.759047)
			(xy 452.984584 -241.771896) (xy 453.038006 -241.792989) (xy 453.087664 -241.821849) (xy 453.132436 -241.857824)
			(xy 453.152256 -241.878612) (xy 453.15979 -241.885998) (xy 453.179061 -241.894531) (xy 453.189594 -241.895122)
			(xy 453.26427 -241.895122) (xy 453.274818 -241.894583) (xy 453.294113 -241.886054) (xy 453.301608 -241.878612)
			(xy 453.319769 -241.859562) (xy 453.360397 -241.826104) (xy 453.405236 -241.798544) (xy 453.453436 -241.777404)
			(xy 453.504083 -241.763086) (xy 453.556216 -241.755861) (xy 453.582532 -241.755422) (xy 453.609785 -241.755848)
			(xy 453.663737 -241.76361) (xy 453.716035 -241.77897) (xy 453.765614 -241.801618) (xy 453.811466 -241.83109)
			(xy 453.852656 -241.866788) (xy 453.888347 -241.907984) (xy 453.917812 -241.953841) (xy 453.940451 -242.003424)
			(xy 453.955803 -242.055724) (xy 453.963556 -242.109677) (xy 453.96404 -242.13693) (xy 453.963612 -242.163246)
			(xy 453.956372 -242.215376) (xy 453.942046 -242.266021) (xy 453.920906 -242.31422) (xy 453.893352 -242.359062)
			(xy 453.859906 -242.399699) (xy 453.84085 -242.417854) (xy 453.83343 -242.42536) (xy 453.824915 -242.444652)
			(xy 453.82434 -242.455192) (xy 453.82434 -242.529868) (xy 453.824861 -242.540419) (xy 453.833401 -242.559715)
			(xy 453.84085 -242.567206) (xy 453.859911 -242.585356) (xy 453.893366 -242.625988) (xy 453.920923 -242.67083)
			(xy 453.94206 -242.719031) (xy 453.956377 -242.769679) (xy 453.963601 -242.821814) (xy 453.96404 -242.84813)
			(xy 453.96355 -242.875381) (xy 453.95579 -242.929326) (xy 453.940433 -242.981619) (xy 453.917791 -243.031194)
			(xy 453.888324 -243.077043) (xy 453.852634 -243.118232) (xy 453.811445 -243.153923) (xy 453.765596 -243.18339)
			(xy 453.716021 -243.206032) (xy 453.663728 -243.22139) (xy 453.609783 -243.22915) (xy 453.582532 -243.229638)
			(xy 453.556216 -243.229236) (xy 453.504083 -243.22199) (xy 453.453439 -243.20766) (xy 453.40524 -243.186515)
			(xy 453.360398 -243.158957) (xy 453.319762 -243.125506) (xy 453.301608 -243.106448) (xy 453.294079 -243.099055)
			(xy 453.274805 -243.090524) (xy 453.26427 -243.089938) (xy 453.189594 -243.089938) (xy 453.179041 -243.090439)
			(xy 453.159745 -243.098993) (xy 453.152256 -243.106448) (xy 453.132436 -243.127236) (xy 453.087664 -243.163211)
			(xy 453.038006 -243.192071) (xy 452.984584 -243.213164) (xy 452.928605 -243.226013) (xy 452.871332 -243.230328)
			(xy 452.814059 -243.226013) (xy 452.75808 -243.213164) (xy 452.704658 -243.192071) (xy 452.655 -243.163211)
			(xy 452.610228 -243.127236) (xy 452.590408 -243.106448) (xy 452.582879 -243.099055) (xy 452.563605 -243.090524)
			(xy 452.55307 -243.089938) (xy 452.478394 -243.089938) (xy 452.467841 -243.090439) (xy 452.448545 -243.098993)
			(xy 452.441056 -243.106448) (xy 452.422924 -243.125527) (xy 452.382288 -243.15898) (xy 452.337443 -243.186535)
			(xy 452.289237 -243.207669) (xy 452.238586 -243.221982) (xy 452.186449 -243.229202) (xy 452.160132 -243.229638)
			(xy 452.132881 -243.229115) (xy 452.078934 -243.221363) (xy 452.026639 -243.206013) (xy 451.977061 -243.183376)
			(xy 451.931209 -243.153914) (xy 451.890017 -243.118227) (xy 451.854323 -243.07704) (xy 451.824854 -243.031193)
			(xy 451.802209 -242.981619) (xy 451.78685 -242.929327) (xy 451.779089 -242.875381) (xy 451.778624 -242.84813)
			(xy 447.587116 -242.84813) (xy 450.270626 -245.53164) (xy 458.764894 -245.53164) (xy 458.765323 -245.505325)
			(xy 458.772566 -245.453195) (xy 458.786893 -245.402551) (xy 458.808033 -245.354353) (xy 458.835585 -245.30951)
			(xy 458.86903 -245.268872) (xy 458.888084 -245.250716) (xy 458.895478 -245.243188) (xy 458.904007 -245.223913)
			(xy 458.904594 -245.213378) (xy 458.904594 -245.138702) (xy 458.904079 -245.128151) (xy 458.895534 -245.108855)
			(xy 458.888084 -245.101364) (xy 458.869015 -245.083222) (xy 458.83556 -245.042589) (xy 458.808003 -244.997746)
			(xy 458.786867 -244.949542) (xy 458.772552 -244.898893) (xy 458.765331 -244.846757) (xy 458.764894 -244.82044)
			(xy 458.76538 -244.793189) (xy 458.773136 -244.739241) (xy 458.788491 -244.686946) (xy 458.811133 -244.637369)
			(xy 458.840599 -244.591519) (xy 458.87629 -244.550328) (xy 458.917481 -244.514637) (xy 458.963331 -244.485171)
			(xy 459.012908 -244.462529) (xy 459.065203 -244.447174) (xy 459.119151 -244.439418) (xy 459.173653 -244.439418)
			(xy 459.227601 -244.447174) (xy 459.279896 -244.462529) (xy 459.329473 -244.485171) (xy 459.375323 -244.514637)
			(xy 459.416514 -244.550328) (xy 459.452205 -244.591519) (xy 459.481671 -244.637369) (xy 459.504313 -244.686946)
			(xy 459.519668 -244.739241) (xy 459.527424 -244.793189) (xy 459.52791 -244.82044) (xy 459.527466 -244.846755)
			(xy 459.520226 -244.898884) (xy 459.505902 -244.949527) (xy 459.484765 -244.997726) (xy 459.457215 -245.042569)
			(xy 459.423773 -245.083208) (xy 459.40472 -245.101364) (xy 459.397335 -245.1089) (xy 459.3888 -245.128169)
			(xy 459.38821 -245.138702) (xy 459.38821 -245.213378) (xy 459.388735 -245.223928) (xy 459.397273 -245.243224)
			(xy 459.40472 -245.250716) (xy 459.42378 -245.268867) (xy 459.457236 -245.309498) (xy 459.484794 -245.354339)
			(xy 459.505932 -245.402541) (xy 459.520248 -245.453189) (xy 459.527472 -245.505324) (xy 459.52791 -245.53164)
			(xy 459.527424 -245.558891) (xy 459.519668 -245.612839) (xy 459.504313 -245.665134) (xy 459.481671 -245.714711)
			(xy 459.452205 -245.760561) (xy 459.416514 -245.801752) (xy 459.375323 -245.837443) (xy 459.329473 -245.866909)
			(xy 459.279896 -245.889551) (xy 459.227601 -245.904906) (xy 459.173653 -245.912662) (xy 459.119151 -245.912662)
			(xy 459.065203 -245.904906) (xy 459.012908 -245.889551) (xy 458.963331 -245.866909) (xy 458.917481 -245.837443)
			(xy 458.87629 -245.801752) (xy 458.840599 -245.760561) (xy 458.811133 -245.714711) (xy 458.788491 -245.665134)
			(xy 458.773136 -245.612839) (xy 458.76538 -245.558891) (xy 458.764894 -245.53164) (xy 450.270626 -245.53164)
			(xy 450.905626 -246.16664) (xy 454.116184 -246.16664) (xy 454.120255 -246.111018) (xy 454.132381 -246.056581)
			(xy 454.152304 -246.00449) (xy 454.1796 -245.955855) (xy 454.213686 -245.911712) (xy 454.253835 -245.873003)
			(xy 454.299193 -245.840552) (xy 454.348793 -245.815051) (xy 454.401577 -245.797044) (xy 454.45642 -245.786914)
			(xy 454.512154 -245.784877) (xy 454.567591 -245.790977) (xy 454.621548 -245.805083) (xy 454.672877 -245.826895)
			(xy 454.720483 -245.855949) (xy 454.763351 -245.891624) (xy 454.800568 -245.933161) (xy 454.831341 -245.979674)
			(xy 454.855013 -246.030171) (xy 454.871081 -246.083578) (xy 454.879201 -246.138754) (xy 454.87971 -246.16664)
			(xy 457.316584 -246.16664) (xy 457.320655 -246.111018) (xy 457.332781 -246.056581) (xy 457.352704 -246.00449)
			(xy 457.38 -245.955855) (xy 457.414086 -245.911712) (xy 457.454235 -245.873003) (xy 457.499593 -245.840552)
			(xy 457.549193 -245.815051) (xy 457.601977 -245.797044) (xy 457.65682 -245.786914) (xy 457.712554 -245.784877)
			(xy 457.767991 -245.790977) (xy 457.821948 -245.805083) (xy 457.873277 -245.826895) (xy 457.920883 -245.855949)
			(xy 457.963751 -245.891624) (xy 458.000968 -245.933161) (xy 458.031741 -245.979674) (xy 458.055413 -246.030171)
			(xy 458.071481 -246.083578) (xy 458.079601 -246.138754) (xy 458.08011 -246.16664) (xy 458.079646 -246.19204)
			(xy 458.205584 -246.19204) (xy 458.209655 -246.136418) (xy 458.221781 -246.081981) (xy 458.241704 -246.02989)
			(xy 458.269 -245.981255) (xy 458.303086 -245.937112) (xy 458.343235 -245.898403) (xy 458.388593 -245.865952)
			(xy 458.438193 -245.840451) (xy 458.490977 -245.822444) (xy 458.54582 -245.812314) (xy 458.601554 -245.810277)
			(xy 458.656991 -245.816377) (xy 458.710948 -245.830483) (xy 458.762277 -245.852295) (xy 458.809883 -245.881349)
			(xy 458.852751 -245.917024) (xy 458.889968 -245.958561) (xy 458.920741 -246.005074) (xy 458.944413 -246.055571)
			(xy 458.960481 -246.108978) (xy 458.968601 -246.164154) (xy 458.96911 -246.19204) (xy 458.968601 -246.219926)
			(xy 458.960481 -246.275102) (xy 458.944413 -246.328509) (xy 458.920741 -246.379006) (xy 458.889968 -246.425519)
			(xy 458.852751 -246.467056) (xy 458.809883 -246.502731) (xy 458.762277 -246.531785) (xy 458.710948 -246.553597)
			(xy 458.656991 -246.567703) (xy 458.601554 -246.573803) (xy 458.54582 -246.571766) (xy 458.490977 -246.561636)
			(xy 458.438193 -246.543629) (xy 458.388593 -246.518128) (xy 458.343235 -246.485677) (xy 458.303086 -246.446968)
			(xy 458.269 -246.402825) (xy 458.241704 -246.35419) (xy 458.221781 -246.302099) (xy 458.209655 -246.247662)
			(xy 458.205584 -246.19204) (xy 458.079646 -246.19204) (xy 458.079601 -246.194526) (xy 458.071481 -246.249702)
			(xy 458.055413 -246.303109) (xy 458.031741 -246.353606) (xy 458.000968 -246.400119) (xy 457.963751 -246.441656)
			(xy 457.920883 -246.477331) (xy 457.873277 -246.506385) (xy 457.821948 -246.528197) (xy 457.767991 -246.542303)
			(xy 457.712554 -246.548403) (xy 457.65682 -246.546366) (xy 457.601977 -246.536236) (xy 457.549193 -246.518229)
			(xy 457.499593 -246.492728) (xy 457.454235 -246.460277) (xy 457.414086 -246.421568) (xy 457.38 -246.377425)
			(xy 457.352704 -246.32879) (xy 457.332781 -246.276699) (xy 457.320655 -246.222262) (xy 457.316584 -246.16664)
			(xy 454.87971 -246.16664) (xy 454.879201 -246.194526) (xy 454.871081 -246.249702) (xy 454.855013 -246.303109)
			(xy 454.831341 -246.353606) (xy 454.800568 -246.400119) (xy 454.763351 -246.441656) (xy 454.720483 -246.477331)
			(xy 454.672877 -246.506385) (xy 454.621548 -246.528197) (xy 454.567591 -246.542303) (xy 454.512154 -246.548403)
			(xy 454.45642 -246.546366) (xy 454.401577 -246.536236) (xy 454.348793 -246.518229) (xy 454.299193 -246.492728)
			(xy 454.253835 -246.460277) (xy 454.213686 -246.421568) (xy 454.1796 -246.377425) (xy 454.152304 -246.32879)
			(xy 454.132381 -246.276699) (xy 454.120255 -246.222262) (xy 454.116184 -246.16664) (xy 450.905626 -246.16664)
			(xy 453.262746 -248.52376) (xy 453.269446 -248.529975) (xy 453.286039 -248.537605) (xy 453.304253 -248.538929)
			(xy 453.321774 -248.533779) (xy 453.329294 -248.528586) (xy 453.354241 -248.51062) (xy 453.408677 -248.482061)
			(xy 453.466988 -248.4626) (xy 453.527666 -248.452743) (xy 453.558402 -248.452132) (xy 453.585654 -248.452596)
			(xy 453.639602 -248.460353) (xy 453.691898 -248.47571) (xy 453.741475 -248.498353) (xy 453.787325 -248.527821)
			(xy 453.828514 -248.563516) (xy 453.864204 -248.604709) (xy 453.893667 -248.650562) (xy 453.916305 -248.700142)
			(xy 453.931656 -248.752439) (xy 453.939407 -248.806388) (xy 453.93991 -248.83364) (xy 453.939749 -248.849592)
			(xy 453.937078 -248.881384) (xy 453.934576 -248.89714) (xy 453.932798 -248.908316) (xy 453.93864 -248.929652)
			(xy 453.996044 -248.99747) (xy 454.003636 -249.005601) (xy 454.023795 -249.014947) (xy 454.034906 -249.015504)
			(xy 458.299312 -249.015504) (xy 458.32522 -248.99747) (xy 458.330808 -248.98223) (xy 458.340652 -248.956643)
			(xy 458.366627 -248.908364) (xy 458.399244 -248.8643) (xy 458.437833 -248.825358) (xy 458.481598 -248.792341)
			(xy 458.529639 -248.765928) (xy 458.580965 -248.746663) (xy 458.63452 -248.734943) (xy 458.689202 -248.731009)
			(xy 458.743884 -248.734943) (xy 458.797439 -248.746663) (xy 458.848765 -248.765928) (xy 458.896806 -248.792341)
			(xy 458.940571 -248.825358) (xy 458.97916 -248.8643) (xy 459.011777 -248.908364) (xy 459.037752 -248.956643)
			(xy 459.047596 -248.98223) (xy 459.053184 -248.99747) (xy 459.079092 -249.015504) (xy 466.769958 -249.015504)
			(xy 466.780024 -249.01507) (xy 466.798613 -249.007341) (xy 466.806026 -249.000518) (xy 467.043008 -248.763536)
			(xy 467.049844 -248.756134) (xy 467.057553 -248.737536) (xy 467.057994 -248.727468) (xy 467.057994 -247.000014)
			(xy 467.057555 -246.989951) (xy 467.049818 -246.97137) (xy 467.043008 -246.963946) (xy 466.851746 -246.772684)
			(xy 466.844897 -246.765287) (xy 466.837161 -246.746688) (xy 466.83676 -246.736616) (xy 466.83676 -245.796562)
			(xy 466.836329 -245.786496) (xy 466.8286 -245.767905) (xy 466.821774 -245.760494) (xy 463.303366 -242.242086)
			(xy 463.296515 -242.23469) (xy 463.288775 -242.216091) (xy 463.28838 -242.206018) (xy 463.28838 -95.39986)
			(xy 463.287949 -95.389793) (xy 463.280222 -95.371201) (xy 463.273394 -95.363792) (xy 463.266028 -95.356426)
			(xy 463.266028 -86.535006) (xy 463.266451 -86.524936) (xy 463.274167 -86.506332) (xy 463.281014 -86.498938)
			(xy 466.80755 -82.972402) (xy 466.812532 -82.966972) (xy 466.819384 -82.953934) (xy 466.821012 -82.946748)
			(xy 466.821012 -82.94624) (xy 466.822028 -82.936842) (xy 466.822028 -82.704686) (xy 466.822454 -82.694618)
			(xy 466.830175 -82.676019) (xy 466.837014 -82.668618) (xy 467.036658 -82.468974) (xy 467.041637 -82.463543)
			(xy 467.04848 -82.450503) (xy 467.05012 -82.44332) (xy 467.05012 -82.442812) (xy 467.051136 -82.433414)
			(xy 467.051136 -2.382266) (xy 467.051071 -2.378661) (xy 467.050047 -2.371523) (xy 467.049104 -2.368042)
			(xy 467.04758 -2.36347) (xy 467.04377 -2.354326) (xy 466.87613 -2.186686) (xy 466.869283 -2.179288)
			(xy 466.861548 -2.16069) (xy 466.861144 -2.150618) (xy 466.861144 -1.411478) (xy 466.86108 -1.407872)
			(xy 466.860058 -1.400734) (xy 466.859112 -1.397254) (xy 466.857588 -1.392682) (xy 466.853778 -1.383538)
			(xy 466.130132 -0.659892) (xy 466.127281 -0.657186) (xy 466.120902 -0.652593) (xy 466.117432 -0.650748)
			(xy 466.112005 -0.648165) (xy 466.100325 -0.645345) (xy 466.094318 -0.64516) (xy 446.466722 -0.64516)
			(xy 446.456659 -0.645599) (xy 446.438081 -0.65334) (xy 446.430654 -0.660146) (xy 446.066672 -1.024128)
			(xy 446.059822 -1.031525) (xy 446.052087 -1.050123) (xy 446.051686 -1.060196) (xy 446.051686 -2.72542)
			(xy 446.048983 -2.728273) (xy 446.044396 -2.734655) (xy 446.042542 -2.73812) (xy 446.039954 -2.743546)
			(xy 446.037123 -2.755226) (xy 446.036954 -2.761234) (xy 446.036954 -13.330682) (xy 446.036515 -13.340745)
			(xy 446.028774 -13.359323) (xy 446.021968 -13.36675) (xy 445.822832 -13.565886) (xy 445.817386 -13.571664)
			(xy 445.810134 -13.58578) (xy 445.808608 -13.593572) (xy 445.808608 -13.605764) (xy 445.80937 -13.614146)
			(xy 445.814958 -13.648182) (xy 445.822832 -13.694918) (xy 445.827658 -13.707364) (xy 445.831214 -13.712952)
			(xy 445.834932 -13.717908) (xy 445.844314 -13.725993) (xy 445.849756 -13.728954) (xy 445.850772 -13.729462)
			(xy 445.851026 -13.729716) (xy 445.91052 -13.759123) (xy 446.026128 -13.82432) (xy 446.137461 -13.896578)
			(xy 446.244087 -13.975615) (xy 446.345594 -14.061127) (xy 446.386624 -14.100302) (xy 451.54291 -14.100302)
			(xy 451.546981 -14.04468) (xy 451.559107 -13.990243) (xy 451.57903 -13.938152) (xy 451.606326 -13.889517)
			(xy 451.640412 -13.845374) (xy 451.680561 -13.806665) (xy 451.725919 -13.774214) (xy 451.775519 -13.748713)
			(xy 451.828303 -13.730706) (xy 451.883146 -13.720576) (xy 451.93888 -13.718539) (xy 451.994317 -13.724639)
			(xy 452.048274 -13.738745) (xy 452.099603 -13.760557) (xy 452.147209 -13.789611) (xy 452.190077 -13.825286)
			(xy 452.227294 -13.866823) (xy 452.258067 -13.913336) (xy 452.281739 -13.963833) (xy 452.297807 -14.01724)
			(xy 452.305927 -14.072416) (xy 452.306436 -14.100302) (xy 452.305927 -14.128188) (xy 452.297807 -14.183364)
			(xy 452.281739 -14.236771) (xy 452.258067 -14.287268) (xy 452.227294 -14.333781) (xy 452.190077 -14.375318)
			(xy 452.147209 -14.410993) (xy 452.099603 -14.440047) (xy 452.048274 -14.461859) (xy 451.994317 -14.475965)
			(xy 451.93888 -14.482065) (xy 451.883146 -14.480028) (xy 451.828303 -14.469898) (xy 451.775519 -14.451891)
			(xy 451.725919 -14.42639) (xy 451.680561 -14.393939) (xy 451.640412 -14.35523) (xy 451.606326 -14.311087)
			(xy 451.57903 -14.262452) (xy 451.559107 -14.210361) (xy 451.546981 -14.155924) (xy 451.54291 -14.100302)
			(xy 446.386624 -14.100302) (xy 446.44159 -14.152783) (xy 446.531703 -14.250229) (xy 446.615585 -14.353087)
			(xy 446.692912 -14.46096) (xy 446.763384 -14.573431) (xy 446.826729 -14.690065) (xy 446.882703 -14.81041)
			(xy 446.931088 -14.934002) (xy 446.971697 -15.060362) (xy 447.004374 -15.189002) (xy 447.028992 -15.319424)
			(xy 447.035352 -15.370302) (xy 452.20331 -15.370302) (xy 452.207381 -15.31468) (xy 452.219507 -15.260243)
			(xy 452.23943 -15.208152) (xy 452.266726 -15.159517) (xy 452.300812 -15.115374) (xy 452.340961 -15.076665)
			(xy 452.386319 -15.044214) (xy 452.435919 -15.018713) (xy 452.488703 -15.000706) (xy 452.543546 -14.990576)
			(xy 452.59928 -14.988539) (xy 452.654717 -14.994639) (xy 452.708674 -15.008745) (xy 452.760003 -15.030557)
			(xy 452.807609 -15.059611) (xy 452.850477 -15.095286) (xy 452.887694 -15.136823) (xy 452.918467 -15.183336)
			(xy 452.942139 -15.233833) (xy 452.958207 -15.28724) (xy 452.966327 -15.342416) (xy 452.966836 -15.370302)
			(xy 452.966327 -15.398188) (xy 452.964936 -15.40764) (xy 453.070466 -15.40764) (xy 453.074537 -15.352018)
			(xy 453.086663 -15.297581) (xy 453.106586 -15.24549) (xy 453.133882 -15.196855) (xy 453.167968 -15.152712)
			(xy 453.208117 -15.114003) (xy 453.253475 -15.081552) (xy 453.303075 -15.056051) (xy 453.355859 -15.038044)
			(xy 453.410702 -15.027914) (xy 453.466436 -15.025877) (xy 453.521873 -15.031977) (xy 453.57583 -15.046083)
			(xy 453.627159 -15.067895) (xy 453.674765 -15.096949) (xy 453.717633 -15.132624) (xy 453.75485 -15.174161)
			(xy 453.772026 -15.200122) (xy 459.541372 -15.200122) (xy 459.541372 -13.599922) (xy 459.54188 -13.535242)
			(xy 459.550003 -13.406136) (xy 459.566216 -13.277796) (xy 459.590456 -13.150726) (xy 459.622626 -13.02543)
			(xy 459.662601 -12.9024) (xy 459.710222 -12.782124) (xy 459.765301 -12.665075) (xy 459.827621 -12.551715)
			(xy 459.896936 -12.442492) (xy 459.972972 -12.337837) (xy 460.05543 -12.238163) (xy 460.143983 -12.143863)
			(xy 460.238283 -12.05531) (xy 460.337957 -11.972852) (xy 460.442612 -11.896816) (xy 460.551835 -11.827501)
			(xy 460.665195 -11.765181) (xy 460.782244 -11.710102) (xy 460.90252 -11.662481) (xy 461.02555 -11.622506)
			(xy 461.150846 -11.590336) (xy 461.277916 -11.566096) (xy 461.406256 -11.549883) (xy 461.535362 -11.54176)
			(xy 461.664722 -11.54176) (xy 461.793828 -11.549883) (xy 461.922168 -11.566096) (xy 462.049238 -11.590336)
			(xy 462.174534 -11.622506) (xy 462.297564 -11.662481) (xy 462.41784 -11.710102) (xy 462.534889 -11.765181)
			(xy 462.648249 -11.827501) (xy 462.757472 -11.896816) (xy 462.862127 -11.972852) (xy 462.961801 -12.05531)
			(xy 463.056101 -12.143863) (xy 463.144654 -12.238163) (xy 463.227112 -12.337837) (xy 463.303148 -12.442492)
			(xy 463.372463 -12.551715) (xy 463.434783 -12.665075) (xy 463.489862 -12.782124) (xy 463.537483 -12.9024)
			(xy 463.577458 -13.02543) (xy 463.609628 -13.150726) (xy 463.633868 -13.277796) (xy 463.650081 -13.406136)
			(xy 463.658204 -13.535242) (xy 463.658712 -13.599922) (xy 463.658712 -15.200122) (xy 463.658204 -15.264802)
			(xy 463.650081 -15.393908) (xy 463.633868 -15.522248) (xy 463.609628 -15.649318) (xy 463.577458 -15.774614)
			(xy 463.537483 -15.897644) (xy 463.489862 -16.01792) (xy 463.434783 -16.134969) (xy 463.372463 -16.248329)
			(xy 463.303148 -16.357552) (xy 463.227112 -16.462207) (xy 463.144654 -16.561881) (xy 463.056101 -16.656181)
			(xy 462.961801 -16.744734) (xy 462.862127 -16.827192) (xy 462.757472 -16.903228) (xy 462.648249 -16.972543)
			(xy 462.534889 -17.034863) (xy 462.41784 -17.089942) (xy 462.297564 -17.137563) (xy 462.174534 -17.177538)
			(xy 462.049238 -17.209708) (xy 461.922168 -17.233948) (xy 461.793828 -17.250161) (xy 461.664722 -17.258284)
			(xy 461.535362 -17.258284) (xy 461.406256 -17.250161) (xy 461.277916 -17.233948) (xy 461.150846 -17.209708)
			(xy 461.02555 -17.177538) (xy 460.90252 -17.137563) (xy 460.782244 -17.089942) (xy 460.665195 -17.034863)
			(xy 460.551835 -16.972543) (xy 460.442612 -16.903228) (xy 460.337957 -16.827192) (xy 460.238283 -16.744734)
			(xy 460.143983 -16.656181) (xy 460.05543 -16.561881) (xy 459.972972 -16.462207) (xy 459.896936 -16.357552)
			(xy 459.827621 -16.248329) (xy 459.765301 -16.134969) (xy 459.710222 -16.01792) (xy 459.662601 -15.897644)
			(xy 459.622626 -15.774614) (xy 459.590456 -15.649318) (xy 459.566216 -15.522248) (xy 459.550003 -15.393908)
			(xy 459.54188 -15.264802) (xy 459.541372 -15.200122) (xy 453.772026 -15.200122) (xy 453.785623 -15.220674)
			(xy 453.809295 -15.271171) (xy 453.825363 -15.324578) (xy 453.833483 -15.379754) (xy 453.833992 -15.40764)
			(xy 453.833483 -15.435526) (xy 453.825363 -15.490702) (xy 453.809295 -15.544109) (xy 453.785623 -15.594606)
			(xy 453.75485 -15.641119) (xy 453.717633 -15.682656) (xy 453.674765 -15.718331) (xy 453.627159 -15.747385)
			(xy 453.57583 -15.769197) (xy 453.521873 -15.783303) (xy 453.466436 -15.789403) (xy 453.410702 -15.787366)
			(xy 453.355859 -15.777236) (xy 453.303075 -15.759229) (xy 453.253475 -15.733728) (xy 453.208117 -15.701277)
			(xy 453.167968 -15.662568) (xy 453.133882 -15.618425) (xy 453.106586 -15.56979) (xy 453.086663 -15.517699)
			(xy 453.074537 -15.463262) (xy 453.070466 -15.40764) (xy 452.964936 -15.40764) (xy 452.958207 -15.453364)
			(xy 452.942139 -15.506771) (xy 452.918467 -15.557268) (xy 452.887694 -15.603781) (xy 452.850477 -15.645318)
			(xy 452.807609 -15.680993) (xy 452.760003 -15.710047) (xy 452.708674 -15.731859) (xy 452.654717 -15.745965)
			(xy 452.59928 -15.752065) (xy 452.543546 -15.750028) (xy 452.488703 -15.739898) (xy 452.435919 -15.721891)
			(xy 452.386319 -15.69639) (xy 452.340961 -15.663939) (xy 452.300812 -15.62523) (xy 452.266726 -15.581087)
			(xy 452.23943 -15.532452) (xy 452.219507 -15.480361) (xy 452.207381 -15.425924) (xy 452.20331 -15.370302)
			(xy 447.035352 -15.370302) (xy 447.045456 -15.451124) (xy 447.053702 -15.583593) (xy 447.054224 -15.649956)
			(xy 447.053748 -15.714429) (xy 447.045965 -15.843139) (xy 447.030425 -15.971144) (xy 447.007184 -16.097977)
			(xy 446.976328 -16.223176) (xy 446.937969 -16.346283) (xy 446.892246 -16.46685) (xy 446.839328 -16.584436)
			(xy 446.779406 -16.698612) (xy 446.712699 -16.808962) (xy 446.639452 -16.915083) (xy 446.559931 -17.016587)
			(xy 446.474426 -17.113105) (xy 446.383249 -17.204284) (xy 446.286733 -17.289792) (xy 446.185231 -17.369316)
			(xy 446.112422 -17.419574) (xy 450.58406 -17.419574) (xy 450.588131 -17.363952) (xy 450.600257 -17.309515)
			(xy 450.62018 -17.257424) (xy 450.647476 -17.208789) (xy 450.681562 -17.164646) (xy 450.721711 -17.125937)
			(xy 450.767069 -17.093486) (xy 450.816669 -17.067985) (xy 450.869453 -17.049978) (xy 450.924296 -17.039848)
			(xy 450.98003 -17.037811) (xy 451.035467 -17.043911) (xy 451.089424 -17.058017) (xy 451.140753 -17.079829)
			(xy 451.188359 -17.108883) (xy 451.231227 -17.144558) (xy 451.268444 -17.186095) (xy 451.299217 -17.232608)
			(xy 451.322889 -17.283105) (xy 451.338957 -17.336512) (xy 451.347077 -17.391688) (xy 451.347586 -17.419574)
			(xy 451.347077 -17.44746) (xy 451.338957 -17.502636) (xy 451.322889 -17.556043) (xy 451.299217 -17.60654)
			(xy 451.268444 -17.653053) (xy 451.231227 -17.69459) (xy 451.188359 -17.730265) (xy 451.140753 -17.759319)
			(xy 451.089424 -17.781131) (xy 451.035467 -17.795237) (xy 450.98003 -17.801337) (xy 450.924296 -17.7993)
			(xy 450.869453 -17.78917) (xy 450.816669 -17.771163) (xy 450.767069 -17.745662) (xy 450.721711 -17.713211)
			(xy 450.681562 -17.674502) (xy 450.647476 -17.630359) (xy 450.62018 -17.581724) (xy 450.600257 -17.529633)
			(xy 450.588131 -17.475196) (xy 450.58406 -17.419574) (xy 446.112422 -17.419574) (xy 446.079112 -17.442567)
			(xy 445.968764 -17.509276) (xy 445.85459 -17.569201) (xy 445.737005 -17.622123) (xy 445.61644 -17.667849)
			(xy 445.493334 -17.706212) (xy 445.368136 -17.737072) (xy 445.241303 -17.760316) (xy 445.113298 -17.77586)
			(xy 444.984589 -17.783646) (xy 444.920116 -17.784064) (xy 444.855859 -17.783584) (xy 444.727577 -17.775852)
			(xy 444.599993 -17.760413) (xy 444.473569 -17.737326) (xy 444.348764 -17.706672) (xy 444.22603 -17.668563)
			(xy 444.105811 -17.623138) (xy 443.988544 -17.570561) (xy 443.874653 -17.511022) (xy 443.764551 -17.444738)
			(xy 443.658638 -17.371948) (xy 443.557297 -17.292916) (xy 443.460895 -17.20793) (xy 443.369783 -17.117296)
			(xy 443.284289 -17.021344) (xy 443.204725 -16.920421) (xy 443.131378 -16.814892) (xy 443.064514 -16.705142)
			(xy 443.004376 -16.591566) (xy 442.951181 -16.474578) (xy 442.905123 -16.3546) (xy 442.866368 -16.232068)
			(xy 442.835057 -16.107426) (xy 442.811303 -15.981126) (xy 442.795193 -15.853625) (xy 442.786784 -15.725386)
			(xy 442.786008 -15.661132) (xy 442.786008 -15.649702) (xy 442.786544 -15.581737) (xy 442.795196 -15.446082)
			(xy 442.81246 -15.311252) (xy 442.838264 -15.177794) (xy 442.872506 -15.046247) (xy 442.915045 -14.917144)
			(xy 442.96571 -14.791009) (xy 442.994542 -14.72946) (xy 442.997082 -14.72438) (xy 442.999876 -14.712442)
			(xy 443.001556 -14.703328) (xy 442.999078 -14.684975) (xy 442.99505 -14.676628) (xy 442.994034 -14.674596)
			(xy 442.988192 -14.665452) (xy 442.98743 -14.66469) (xy 442.969396 -14.635988) (xy 442.946028 -14.59865)
			(xy 442.943742 -14.596872) (xy 442.93536 -14.58976) (xy 442.928571 -14.584824) (xy 442.912755 -14.579238)
			(xy 442.904372 -14.578838) (xy 434.41239 -14.578838) (xy 434.402322 -14.578411) (xy 434.383726 -14.570688)
			(xy 434.376322 -14.563852) (xy 432.683412 -12.870942) (xy 432.676573 -12.863541) (xy 432.668858 -12.844943)
			(xy 432.668426 -12.834874) (xy 432.668426 -1.651762) (xy 432.66836 -1.648157) (xy 432.667336 -1.641019)
			(xy 432.666394 -1.637538) (xy 432.66487 -1.632966) (xy 432.66106 -1.624076) (xy 432.653948 -1.616456)
			(xy 432.651662 -1.613916) (xy 432.647852 -1.609344) (xy 432.644296 -1.60655) (xy 432.637438 -1.599946)
			(xy 432.628802 -1.59639) (xy 432.625754 -1.595374) (xy 432.621919 -1.594216) (xy 432.61401 -1.592948)
			(xy 432.610006 -1.592834) (xy 420.609268 -1.592834) (xy 420.60368 -1.593088) (xy 420.600014 -1.593571)
			(xy 420.59287 -1.595477) (xy 420.589456 -1.596898) (xy 420.581328 -1.600454) (xy 420.57447 -1.607058)
			(xy 420.571422 -1.609598) (xy 420.569136 -1.611376) (xy 419.784784 -2.395728) (xy 419.782082 -2.398581)
			(xy 419.777496 -2.404963) (xy 419.77564 -2.408428) (xy 419.773053 -2.413854) (xy 419.770224 -2.425534)
			(xy 419.770052 -2.431542) (xy 419.770052 -13.280644) (xy 419.769619 -13.29071) (xy 419.761888 -13.309298)
			(xy 419.755066 -13.316712) (xy 419.59784 -13.473938) (xy 419.595554 -13.476478) (xy 419.594538 -13.478002)
			(xy 419.588456 -13.487066) (xy 419.583854 -13.508383) (xy 419.585648 -13.51915) (xy 419.591744 -13.546328)
			(xy 419.591744 -13.546836) (xy 419.60165 -13.590016) (xy 419.602158 -13.592048) (xy 419.605206 -13.603224)
			(xy 419.620192 -13.62075) (xy 419.620954 -13.621766) (xy 419.632892 -13.634974) (xy 419.641274 -13.64107)
			(xy 419.649656 -13.644372) (xy 419.650672 -13.64488) (xy 419.71173 -13.667653) (xy 419.83123 -13.71967)
			(xy 419.947332 -13.778883) (xy 420.059604 -13.84507) (xy 420.167628 -13.917986) (xy 420.271001 -13.997359)
			(xy 420.369337 -14.082892) (xy 420.387044 -14.100302) (xy 425.542962 -14.100302) (xy 425.547033 -14.04468)
			(xy 425.559159 -13.990243) (xy 425.579082 -13.938152) (xy 425.606378 -13.889517) (xy 425.640464 -13.845374)
			(xy 425.680613 -13.806665) (xy 425.725971 -13.774214) (xy 425.775571 -13.748713) (xy 425.828355 -13.730706)
			(xy 425.883198 -13.720576) (xy 425.938932 -13.718539) (xy 425.994369 -13.724639) (xy 426.048326 -13.738745)
			(xy 426.099655 -13.760557) (xy 426.147261 -13.789611) (xy 426.190129 -13.825286) (xy 426.227346 -13.866823)
			(xy 426.258119 -13.913336) (xy 426.281791 -13.963833) (xy 426.297859 -14.01724) (xy 426.305979 -14.072416)
			(xy 426.306488 -14.100302) (xy 426.305979 -14.128188) (xy 426.297859 -14.183364) (xy 426.281791 -14.236771)
			(xy 426.258119 -14.287268) (xy 426.227346 -14.333781) (xy 426.190129 -14.375318) (xy 426.147261 -14.410993)
			(xy 426.099655 -14.440047) (xy 426.048326 -14.461859) (xy 425.994369 -14.475965) (xy 425.938932 -14.482065)
			(xy 425.883198 -14.480028) (xy 425.828355 -14.469898) (xy 425.775571 -14.451891) (xy 425.725971 -14.42639)
			(xy 425.680613 -14.393939) (xy 425.640464 -14.35523) (xy 425.606378 -14.311087) (xy 425.579082 -14.262452)
			(xy 425.559159 -14.210361) (xy 425.547033 -14.155924) (xy 425.542962 -14.100302) (xy 420.387044 -14.100302)
			(xy 420.46227 -14.174266) (xy 420.549454 -14.271142) (xy 420.630563 -14.373157) (xy 420.705296 -14.479932)
			(xy 420.773373 -14.591069) (xy 420.834541 -14.706153) (xy 420.888572 -14.824756) (xy 420.935264 -14.946435)
			(xy 420.974444 -15.070736) (xy 421.005965 -15.197197) (xy 421.029709 -15.325345) (xy 421.038573 -15.39755)
			(xy 426.20438 -15.39755) (xy 426.20438 -15.34305) (xy 426.212136 -15.289104) (xy 426.22749 -15.236811)
			(xy 426.250129 -15.187236) (xy 426.279594 -15.141386) (xy 426.315283 -15.100197) (xy 426.35647 -15.064506)
			(xy 426.402318 -15.035039) (xy 426.451892 -15.012397) (xy 426.504185 -14.99704) (xy 426.55813 -14.989281)
			(xy 426.58538 -14.988794) (xy 426.611615 -14.989267) (xy 426.663591 -14.996459) (xy 426.714089 -15.010711)
			(xy 426.762155 -15.031753) (xy 426.806882 -15.059187) (xy 426.847425 -15.092496) (xy 426.865542 -15.111476)
			(xy 426.865796 -15.11173) (xy 426.873514 -15.119129) (xy 426.893208 -15.127394) (xy 426.903896 -15.127732)
			(xy 426.99178 -15.125446) (xy 427.011338 -15.116048) (xy 427.01845 -15.107412) (xy 427.036662 -15.086262)
			(xy 427.078202 -15.048987) (xy 427.124731 -15.018165) (xy 427.175256 -14.994454) (xy 427.228698 -14.978361)
			(xy 427.283914 -14.970229) (xy 427.31182 -14.969744) (xy 427.339067 -14.970328) (xy 427.393006 -14.978085)
			(xy 427.445291 -14.99344) (xy 427.49486 -15.01608) (xy 427.540702 -15.045543) (xy 427.581884 -15.08123)
			(xy 427.617569 -15.122414) (xy 427.64703 -15.168258) (xy 427.669667 -15.217827) (xy 427.685019 -15.270114)
			(xy 427.692774 -15.324053) (xy 427.692774 -15.378547) (xy 427.685019 -15.432486) (xy 427.669667 -15.484773)
			(xy 427.64703 -15.534342) (xy 427.617569 -15.580186) (xy 427.581884 -15.62137) (xy 427.540702 -15.657057)
			(xy 427.49486 -15.68652) (xy 427.445291 -15.70916) (xy 427.393006 -15.724515) (xy 427.339067 -15.732272)
			(xy 427.31182 -15.73276) (xy 427.285584 -15.732302) (xy 427.233608 -15.725108) (xy 427.183109 -15.710855)
			(xy 427.135042 -15.68981) (xy 427.090315 -15.662373) (xy 427.049774 -15.62906) (xy 427.031658 -15.610078)
			(xy 427.031404 -15.609824) (xy 427.023691 -15.602418) (xy 427.003993 -15.594159) (xy 426.993304 -15.593822)
			(xy 426.90542 -15.596108) (xy 426.885862 -15.605506) (xy 426.87875 -15.614142) (xy 426.860528 -15.635283)
			(xy 426.818991 -15.67256) (xy 426.772464 -15.703385) (xy 426.721941 -15.727097) (xy 426.668501 -15.743192)
			(xy 426.613286 -15.751325) (xy 426.58538 -15.75181) (xy 426.55813 -15.751319) (xy 426.504185 -15.74356)
			(xy 426.451892 -15.728203) (xy 426.402318 -15.705561) (xy 426.35647 -15.676094) (xy 426.315283 -15.640403)
			(xy 426.279594 -15.599214) (xy 426.250129 -15.553364) (xy 426.22749 -15.503789) (xy 426.212136 -15.451496)
			(xy 426.20438 -15.39755) (xy 421.038573 -15.39755) (xy 421.045589 -15.454704) (xy 421.053546 -15.584791)
			(xy 421.054022 -15.649956) (xy 421.053516 -15.715692) (xy 421.045423 -15.846913) (xy 421.029266 -15.977388)
			(xy 421.005109 -16.106621) (xy 420.973041 -16.234121) (xy 420.933185 -16.359405) (xy 420.885692 -16.481999)
			(xy 420.830743 -16.601436) (xy 420.768544 -16.717263) (xy 420.699334 -16.829042) (xy 420.623373 -16.936349)
			(xy 420.596299 -16.969994) (xy 440.048149 -16.969994) (xy 440.052154 -16.882086) (xy 440.064137 -16.794906)
			(xy 440.083997 -16.709177) (xy 440.111572 -16.625609) (xy 440.146631 -16.544895) (xy 440.188884 -16.467703)
			(xy 440.237982 -16.394674) (xy 440.293518 -16.326412) (xy 440.35503 -16.263482) (xy 440.422011 -16.206408)
			(xy 440.493904 -16.15566) (xy 440.570113 -16.11166) (xy 440.650008 -16.074773) (xy 440.732927 -16.045304)
			(xy 440.818182 -16.023497) (xy 440.905066 -16.009533) (xy 440.99286 -16.003527) (xy 441.080837 -16.005531)
			(xy 441.168267 -16.015526) (xy 441.254426 -16.03343) (xy 441.3386 -16.059094) (xy 441.420091 -16.092307)
			(xy 441.498225 -16.132793) (xy 441.572353 -16.180215) (xy 441.641861 -16.234182) (xy 441.706175 -16.294247)
			(xy 441.764759 -16.359911) (xy 441.81713 -16.43063) (xy 441.862853 -16.505818) (xy 441.90155 -16.584853)
			(xy 441.932899 -16.667079) (xy 441.956641 -16.751815) (xy 441.972579 -16.838359) (xy 441.980581 -16.925994)
			(xy 441.981082 -16.969994) (xy 441.980581 -17.013994) (xy 441.972579 -17.101629) (xy 441.956641 -17.188173)
			(xy 441.932899 -17.272909) (xy 441.90155 -17.355135) (xy 441.862853 -17.43417) (xy 441.81713 -17.509358)
			(xy 441.764759 -17.580077) (xy 441.706175 -17.645741) (xy 441.641861 -17.705806) (xy 441.572353 -17.759773)
			(xy 441.498225 -17.807195) (xy 441.420091 -17.847681) (xy 441.3386 -17.880894) (xy 441.254426 -17.906558)
			(xy 441.168267 -17.924462) (xy 441.080837 -17.934457) (xy 440.99286 -17.936461) (xy 440.905066 -17.930455)
			(xy 440.818182 -17.916491) (xy 440.732927 -17.894684) (xy 440.650008 -17.865215) (xy 440.570113 -17.828328)
			(xy 440.493904 -17.784328) (xy 440.422011 -17.73358) (xy 440.35503 -17.676506) (xy 440.293518 -17.613576)
			(xy 440.237982 -17.545314) (xy 440.188884 -17.472285) (xy 440.146631 -17.395093) (xy 440.111572 -17.314379)
			(xy 440.083997 -17.230811) (xy 440.064137 -17.145082) (xy 440.052154 -17.057902) (xy 440.048149 -16.969994)
			(xy 420.596299 -16.969994) (xy 420.540951 -17.038775) (xy 420.452379 -17.135934) (xy 420.357994 -17.227455)
			(xy 420.258155 -17.312993) (xy 420.153238 -17.392222) (xy 420.11196 -17.419574) (xy 424.584112 -17.419574)
			(xy 424.588183 -17.363952) (xy 424.600309 -17.309515) (xy 424.620232 -17.257424) (xy 424.647528 -17.208789)
			(xy 424.681614 -17.164646) (xy 424.721763 -17.125937) (xy 424.767121 -17.093486) (xy 424.816721 -17.067985)
			(xy 424.869505 -17.049978) (xy 424.924348 -17.039848) (xy 424.980082 -17.037811) (xy 425.035519 -17.043911)
			(xy 425.089476 -17.058017) (xy 425.140805 -17.079829) (xy 425.188411 -17.108883) (xy 425.231279 -17.144558)
			(xy 425.268496 -17.186095) (xy 425.299269 -17.232608) (xy 425.322941 -17.283105) (xy 425.339009 -17.336512)
			(xy 425.347129 -17.391688) (xy 425.347638 -17.419574) (xy 425.347129 -17.44746) (xy 425.339009 -17.502636)
			(xy 425.322941 -17.556043) (xy 425.299269 -17.60654) (xy 425.268496 -17.653053) (xy 425.231279 -17.69459)
			(xy 425.188411 -17.730265) (xy 425.140805 -17.759319) (xy 425.089476 -17.781131) (xy 425.035519 -17.795237)
			(xy 424.980082 -17.801337) (xy 424.924348 -17.7993) (xy 424.869505 -17.78917) (xy 424.816721 -17.771163)
			(xy 424.767121 -17.745662) (xy 424.721763 -17.713211) (xy 424.681614 -17.674502) (xy 424.647528 -17.630359)
			(xy 424.620232 -17.581724) (xy 424.600309 -17.529633) (xy 424.588183 -17.475196) (xy 424.584112 -17.419574)
			(xy 420.11196 -17.419574) (xy 420.043644 -17.464842) (xy 419.929786 -17.530577) (xy 419.812098 -17.589179)
			(xy 419.691026 -17.640425) (xy 419.567028 -17.68412) (xy 419.440576 -17.720099) (xy 419.312148 -17.748225)
			(xy 419.182233 -17.768391) (xy 419.051323 -17.780522) (xy 418.919914 -17.784571) (xy 418.788505 -17.780522)
			(xy 418.657595 -17.768391) (xy 418.52768 -17.748225) (xy 418.399252 -17.720099) (xy 418.2728 -17.68412)
			(xy 418.148802 -17.640425) (xy 418.02773 -17.589179) (xy 417.910042 -17.530577) (xy 417.796184 -17.464842)
			(xy 417.68659 -17.392222) (xy 417.581673 -17.312993) (xy 417.481834 -17.227455) (xy 417.387449 -17.135934)
			(xy 417.298877 -17.038775) (xy 417.216455 -16.936349) (xy 417.140494 -16.829042) (xy 417.071284 -16.717263)
			(xy 417.009085 -16.601436) (xy 416.954136 -16.481999) (xy 416.906643 -16.359405) (xy 416.866787 -16.234121)
			(xy 416.834719 -16.106621) (xy 416.810562 -15.977388) (xy 416.794405 -15.846913) (xy 416.786312 -15.715692)
			(xy 416.785806 -15.649956) (xy 416.786314 -15.599156) (xy 416.788286 -15.535645) (xy 416.79885 -15.409004)
			(xy 416.816929 -15.283216) (xy 416.842461 -15.158727) (xy 416.875355 -15.035978) (xy 416.915494 -14.915403)
			(xy 416.962736 -14.79743) (xy 417.016914 -14.682477) (xy 417.077835 -14.570952) (xy 417.11118 -14.516862)
			(xy 417.115244 -14.510766) (xy 417.119054 -14.504416) (xy 417.122864 -14.49832) (xy 417.127182 -14.484096)
			(xy 417.129755 -14.474204) (xy 417.127641 -14.453894) (xy 417.123118 -14.444726) (xy 417.122864 -14.444472)
			(xy 417.104576 -14.411198) (xy 417.087812 -14.380464) (xy 417.087304 -14.379956) (xy 417.08197 -14.369796)
			(xy 417.077291 -14.361786) (xy 417.063383 -14.349533) (xy 417.046028 -14.343026) (xy 417.036758 -14.342618)
			(xy 408.193748 -14.342618) (xy 408.183682 -14.342186) (xy 408.165089 -14.33446) (xy 408.15768 -14.327632)
			(xy 406.58923 -12.759182) (xy 406.582383 -12.751784) (xy 406.57465 -12.733186) (xy 406.574244 -12.723114)
			(xy 406.574244 -0.931926) (xy 406.573806 -0.921863) (xy 406.566066 -0.903283) (xy 406.559258 -0.895858)
			(xy 406.237186 -0.573786) (xy 406.229791 -0.566932) (xy 406.211192 -0.55919) (xy 406.201118 -0.5588)
			(xy 394.178282 -0.5588) (xy 394.168213 -0.559227) (xy 394.149614 -0.566946) (xy 394.142214 -0.573786)
			(xy 393.87653 -0.83947) (xy 393.869691 -0.846871) (xy 393.861978 -0.865469) (xy 393.861544 -0.875538)
			(xy 393.861544 -12.797536) (xy 393.861113 -12.807602) (xy 393.853383 -12.826192) (xy 393.846558 -12.833604)
			(xy 393.305284 -13.374878) (xy 393.302579 -13.37773) (xy 393.297988 -13.384109) (xy 393.29614 -13.387578)
			(xy 393.293559 -13.393005) (xy 393.290741 -13.404685) (xy 393.290552 -13.410692) (xy 393.290552 -13.462762)
			(xy 393.29233 -13.475716) (xy 393.303252 -13.511784) (xy 393.308332 -13.523468) (xy 393.311634 -13.528802)
			(xy 393.312904 -13.529818) (xy 393.320016 -13.536676) (xy 393.322048 -13.538454) (xy 393.334494 -13.549122)
			(xy 393.337552 -13.551675) (xy 393.344318 -13.55588) (xy 393.347956 -13.557504) (xy 393.348464 -13.557504)
			(xy 393.351512 -13.558774) (xy 393.356084 -13.560298) (xy 393.361164 -13.561568) (xy 393.425723 -13.575737)
			(xy 393.553112 -13.611033) (xy 393.678072 -13.654146) (xy 393.800124 -13.704909) (xy 393.918802 -13.763127)
			(xy 394.033648 -13.828579) (xy 394.144225 -13.901012) (xy 394.250106 -13.980149) (xy 394.350888 -14.065687)
			(xy 394.446183 -14.157298) (xy 394.535626 -14.254631) (xy 394.618874 -14.357312) (xy 394.695608 -14.464948)
			(xy 394.765534 -14.577127) (xy 394.828384 -14.693418) (xy 394.847774 -14.735302) (xy 398.879312 -14.735302)
			(xy 398.883383 -14.67968) (xy 398.895509 -14.625243) (xy 398.915432 -14.573152) (xy 398.942728 -14.524517)
			(xy 398.976814 -14.480374) (xy 399.016963 -14.441665) (xy 399.062321 -14.409214) (xy 399.111921 -14.383713)
			(xy 399.164705 -14.365706) (xy 399.219548 -14.355576) (xy 399.275282 -14.353539) (xy 399.330719 -14.359639)
			(xy 399.384676 -14.373745) (xy 399.436005 -14.395557) (xy 399.483611 -14.424611) (xy 399.526479 -14.460286)
			(xy 399.563696 -14.501823) (xy 399.594469 -14.548336) (xy 399.618141 -14.598833) (xy 399.634209 -14.65224)
			(xy 399.642329 -14.707416) (xy 399.642838 -14.735302) (xy 399.642329 -14.763188) (xy 399.634209 -14.818364)
			(xy 399.618141 -14.871771) (xy 399.594469 -14.922268) (xy 399.563696 -14.968781) (xy 399.526479 -15.010318)
			(xy 399.483611 -15.045993) (xy 399.436005 -15.075047) (xy 399.384676 -15.096859) (xy 399.330719 -15.110965)
			(xy 399.275282 -15.117065) (xy 399.219548 -15.115028) (xy 399.164705 -15.104898) (xy 399.111921 -15.086891)
			(xy 399.062321 -15.06139) (xy 399.016963 -15.028939) (xy 398.976814 -14.99023) (xy 398.942728 -14.946087)
			(xy 398.915432 -14.897452) (xy 398.895509 -14.845361) (xy 398.883383 -14.790924) (xy 398.879312 -14.735302)
			(xy 394.847774 -14.735302) (xy 394.883917 -14.813375) (xy 394.93192 -14.936539) (xy 394.972209 -15.062438)
			(xy 395.004629 -15.190589) (xy 395.029057 -15.3205) (xy 395.038657 -15.397554) (xy 400.204357 -15.397554)
			(xy 400.204357 -15.343046) (xy 400.212115 -15.289092) (xy 400.227473 -15.236792) (xy 400.250117 -15.18721)
			(xy 400.279588 -15.141356) (xy 400.315285 -15.100163) (xy 400.356482 -15.064469) (xy 400.402338 -15.035002)
			(xy 400.451922 -15.012362) (xy 400.504224 -14.997008) (xy 400.558178 -14.989255) (xy 400.585432 -14.988794)
			(xy 400.611668 -14.989232) (xy 400.663645 -14.996432) (xy 400.714144 -15.01069) (xy 400.76221 -15.031739)
			(xy 400.806937 -15.059179) (xy 400.847478 -15.092493) (xy 400.865594 -15.111476) (xy 400.865848 -15.11173)
			(xy 400.873584 -15.119107) (xy 400.893265 -15.127384) (xy 400.903948 -15.127732) (xy 400.991832 -15.125446)
			(xy 401.01139 -15.116048) (xy 401.018502 -15.107412) (xy 401.036686 -15.086237) (xy 401.078232 -15.048964)
			(xy 401.124767 -15.018145) (xy 401.175297 -14.994439) (xy 401.228744 -14.978351) (xy 401.283964 -14.970225)
			(xy 401.311872 -14.969744) (xy 401.339123 -14.970301) (xy 401.39307 -14.978054) (xy 401.445365 -14.993406)
			(xy 401.494942 -15.016044) (xy 401.540793 -15.045507) (xy 401.581984 -15.081197) (xy 401.617676 -15.122385)
			(xy 401.647143 -15.168233) (xy 401.669784 -15.217809) (xy 401.68514 -15.270103) (xy 401.692897 -15.324049)
			(xy 401.692897 -15.378551) (xy 401.68514 -15.432497) (xy 401.669784 -15.484791) (xy 401.647143 -15.534367)
			(xy 401.617676 -15.580215) (xy 401.581984 -15.621403) (xy 401.540793 -15.657093) (xy 401.494942 -15.686556)
			(xy 401.445365 -15.709194) (xy 401.39307 -15.724546) (xy 401.339123 -15.732299) (xy 401.311872 -15.73276)
			(xy 401.285635 -15.732334) (xy 401.233657 -15.725134) (xy 401.183158 -15.710874) (xy 401.135091 -15.689823)
			(xy 401.090365 -15.66238) (xy 401.049825 -15.629063) (xy 401.03171 -15.610078) (xy 401.031456 -15.609824)
			(xy 401.023724 -15.602442) (xy 401.00404 -15.594169) (xy 400.993356 -15.593822) (xy 400.905472 -15.596108)
			(xy 400.885914 -15.605506) (xy 400.878802 -15.614142) (xy 400.860605 -15.635306) (xy 400.819064 -15.672582)
			(xy 400.772531 -15.703403) (xy 400.722003 -15.727112) (xy 400.668558 -15.743202) (xy 400.613339 -15.751328)
			(xy 400.585432 -15.75181) (xy 400.558178 -15.751345) (xy 400.504224 -15.743592) (xy 400.451922 -15.728238)
			(xy 400.402338 -15.705598) (xy 400.356481 -15.676131) (xy 400.315285 -15.640437) (xy 400.279588 -15.599244)
			(xy 400.250117 -15.55339) (xy 400.227473 -15.503808) (xy 400.212115 -15.451508) (xy 400.204357 -15.397554)
			(xy 395.038657 -15.397554) (xy 395.045399 -15.451674) (xy 395.053592 -15.583608) (xy 395.054074 -15.649702)
			(xy 395.054074 -15.649956) (xy 395.053568 -15.715692) (xy 395.045475 -15.846913) (xy 395.029318 -15.977388)
			(xy 395.005161 -16.106621) (xy 394.973093 -16.234121) (xy 394.933237 -16.359405) (xy 394.885744 -16.481999)
			(xy 394.830795 -16.601436) (xy 394.768596 -16.717263) (xy 394.699386 -16.829042) (xy 394.623425 -16.936349)
			(xy 394.596351 -16.969994) (xy 414.048201 -16.969994) (xy 414.052206 -16.882086) (xy 414.064189 -16.794906)
			(xy 414.084049 -16.709177) (xy 414.111624 -16.625609) (xy 414.146683 -16.544895) (xy 414.188936 -16.467703)
			(xy 414.238034 -16.394674) (xy 414.29357 -16.326412) (xy 414.355082 -16.263482) (xy 414.422063 -16.206408)
			(xy 414.493956 -16.15566) (xy 414.570165 -16.11166) (xy 414.65006 -16.074773) (xy 414.732979 -16.045304)
			(xy 414.818234 -16.023497) (xy 414.905118 -16.009533) (xy 414.992912 -16.003527) (xy 415.080889 -16.005531)
			(xy 415.168319 -16.015526) (xy 415.254478 -16.03343) (xy 415.338652 -16.059094) (xy 415.420143 -16.092307)
			(xy 415.498277 -16.132793) (xy 415.572405 -16.180215) (xy 415.641913 -16.234182) (xy 415.706227 -16.294247)
			(xy 415.764811 -16.359911) (xy 415.817182 -16.43063) (xy 415.862905 -16.505818) (xy 415.901602 -16.584853)
			(xy 415.932951 -16.667079) (xy 415.956693 -16.751815) (xy 415.972631 -16.838359) (xy 415.980633 -16.925994)
			(xy 415.981134 -16.969994) (xy 415.980633 -17.013994) (xy 415.972631 -17.101629) (xy 415.956693 -17.188173)
			(xy 415.932951 -17.272909) (xy 415.901602 -17.355135) (xy 415.862905 -17.43417) (xy 415.817182 -17.509358)
			(xy 415.764811 -17.580077) (xy 415.706227 -17.645741) (xy 415.641913 -17.705806) (xy 415.572405 -17.759773)
			(xy 415.498277 -17.807195) (xy 415.420143 -17.847681) (xy 415.338652 -17.880894) (xy 415.254478 -17.906558)
			(xy 415.168319 -17.924462) (xy 415.080889 -17.934457) (xy 414.992912 -17.936461) (xy 414.905118 -17.930455)
			(xy 414.818234 -17.916491) (xy 414.732979 -17.894684) (xy 414.65006 -17.865215) (xy 414.570165 -17.828328)
			(xy 414.493956 -17.784328) (xy 414.422063 -17.73358) (xy 414.355082 -17.676506) (xy 414.29357 -17.613576)
			(xy 414.238034 -17.545314) (xy 414.188936 -17.472285) (xy 414.146683 -17.395093) (xy 414.111624 -17.314379)
			(xy 414.084049 -17.230811) (xy 414.064189 -17.145082) (xy 414.052206 -17.057902) (xy 414.048201 -16.969994)
			(xy 394.596351 -16.969994) (xy 394.541003 -17.038775) (xy 394.452431 -17.135934) (xy 394.358046 -17.227455)
			(xy 394.258207 -17.312993) (xy 394.15329 -17.392222) (xy 394.112012 -17.419574) (xy 398.584164 -17.419574)
			(xy 398.588235 -17.363952) (xy 398.600361 -17.309515) (xy 398.620284 -17.257424) (xy 398.64758 -17.208789)
			(xy 398.681666 -17.164646) (xy 398.721815 -17.125937) (xy 398.767173 -17.093486) (xy 398.816773 -17.067985)
			(xy 398.869557 -17.049978) (xy 398.9244 -17.039848) (xy 398.980134 -17.037811) (xy 399.035571 -17.043911)
			(xy 399.089528 -17.058017) (xy 399.140857 -17.079829) (xy 399.188463 -17.108883) (xy 399.231331 -17.144558)
			(xy 399.268548 -17.186095) (xy 399.299321 -17.232608) (xy 399.322993 -17.283105) (xy 399.339061 -17.336512)
			(xy 399.347181 -17.391688) (xy 399.34769 -17.419574) (xy 399.347181 -17.44746) (xy 399.339061 -17.502636)
			(xy 399.322993 -17.556043) (xy 399.299321 -17.60654) (xy 399.268548 -17.653053) (xy 399.231331 -17.69459)
			(xy 399.188463 -17.730265) (xy 399.140857 -17.759319) (xy 399.089528 -17.781131) (xy 399.035571 -17.795237)
			(xy 398.980134 -17.801337) (xy 398.9244 -17.7993) (xy 398.869557 -17.78917) (xy 398.816773 -17.771163)
			(xy 398.767173 -17.745662) (xy 398.721815 -17.713211) (xy 398.681666 -17.674502) (xy 398.64758 -17.630359)
			(xy 398.620284 -17.581724) (xy 398.600361 -17.529633) (xy 398.588235 -17.475196) (xy 398.584164 -17.419574)
			(xy 394.112012 -17.419574) (xy 394.043696 -17.464842) (xy 393.929838 -17.530577) (xy 393.81215 -17.589179)
			(xy 393.691078 -17.640425) (xy 393.56708 -17.68412) (xy 393.440628 -17.720099) (xy 393.3122 -17.748225)
			(xy 393.182285 -17.768391) (xy 393.051375 -17.780522) (xy 392.919966 -17.784571) (xy 392.788557 -17.780522)
			(xy 392.657647 -17.768391) (xy 392.527732 -17.748225) (xy 392.399304 -17.720099) (xy 392.272852 -17.68412)
			(xy 392.148854 -17.640425) (xy 392.027782 -17.589179) (xy 391.910094 -17.530577) (xy 391.796236 -17.464842)
			(xy 391.686642 -17.392222) (xy 391.581725 -17.312993) (xy 391.481886 -17.227455) (xy 391.387501 -17.135934)
			(xy 391.298929 -17.038775) (xy 391.216507 -16.936349) (xy 391.140546 -16.829042) (xy 391.071336 -16.717263)
			(xy 391.009137 -16.601436) (xy 390.954188 -16.481999) (xy 390.906695 -16.359405) (xy 390.866839 -16.234121)
			(xy 390.834771 -16.106621) (xy 390.810614 -15.977388) (xy 390.794457 -15.846913) (xy 390.786364 -15.715692)
			(xy 390.785858 -15.649956) (xy 390.785858 -15.64894) (xy 390.786382 -15.582774) (xy 390.794614 -15.450699)
			(xy 390.811017 -15.319388) (xy 390.835528 -15.189346) (xy 390.868053 -15.061074) (xy 390.908466 -14.935064)
			(xy 390.956613 -14.811802) (xy 390.983978 -14.751558) (xy 390.98474 -14.750034) (xy 390.98728 -14.742922)
			(xy 390.990742 -14.732065) (xy 390.988908 -14.709381) (xy 390.983724 -14.699234) (xy 390.939274 -14.629638)
			(xy 390.933432 -14.62278) (xy 390.921494 -14.610842) (xy 390.9187 -14.609064) (xy 390.918192 -14.609064)
			(xy 390.912579 -14.606171) (xy 390.900371 -14.602964) (xy 390.894062 -14.602714) (xy 382.471422 -14.602714)
			(xy 382.461358 -14.602277) (xy 382.442772 -14.594544) (xy 382.435354 -14.587728) (xy 380.792482 -12.944856)
			(xy 380.785633 -12.937459) (xy 380.777902 -12.91886) (xy 380.777496 -12.908788) (xy 380.777496 -8.367522)
			(xy 380.777007 -8.357189) (xy 380.768878 -8.338187) (xy 380.761748 -8.330692) (xy 380.700788 -8.272526)
			(xy 380.690374 -8.26897) (xy 380.680976 -8.265414) (xy 380.670054 -8.265922) (xy 380.650496 -8.26643)
			(xy 380.649734 -8.26643) (xy 380.622478 -8.265969) (xy 380.56852 -8.258216) (xy 380.516215 -8.242862)
			(xy 380.466628 -8.22022) (xy 380.420768 -8.190751) (xy 380.379569 -8.155055) (xy 380.343869 -8.113859)
			(xy 380.314396 -8.068002) (xy 380.29175 -8.018417) (xy 380.276391 -7.966113) (xy 380.268633 -7.912156)
			(xy 380.268633 -7.857644) (xy 380.276391 -7.803687) (xy 380.29175 -7.751383) (xy 380.314396 -7.701798)
			(xy 380.343869 -7.655941) (xy 380.379569 -7.614745) (xy 380.420768 -7.579049) (xy 380.466628 -7.54958)
			(xy 380.516215 -7.526938) (xy 380.56852 -7.511584) (xy 380.622478 -7.503831) (xy 380.649734 -7.503414)
			(xy 380.650496 -7.503414) (xy 380.6698 -7.503922) (xy 380.680214 -7.50443) (xy 380.693422 -7.499604)
			(xy 380.696762 -7.498099) (xy 380.703007 -7.494272) (xy 380.705868 -7.491984) (xy 380.761494 -7.439406)
			(xy 380.768729 -7.431961) (xy 380.777002 -7.412944) (xy 380.777496 -7.402576) (xy 380.777496 -6.335522)
			(xy 380.777007 -6.325189) (xy 380.768878 -6.306187) (xy 380.761748 -6.298692) (xy 380.700788 -6.240526)
			(xy 380.690374 -6.23697) (xy 380.680976 -6.233414) (xy 380.670054 -6.233922) (xy 380.650496 -6.23443)
			(xy 380.649734 -6.23443) (xy 380.622478 -6.233969) (xy 380.56852 -6.226216) (xy 380.516215 -6.210862)
			(xy 380.466628 -6.18822) (xy 380.420768 -6.158751) (xy 380.379569 -6.123055) (xy 380.343869 -6.081859)
			(xy 380.314396 -6.036002) (xy 380.29175 -5.986417) (xy 380.276391 -5.934113) (xy 380.268633 -5.880156)
			(xy 380.268633 -5.825644) (xy 380.276391 -5.771687) (xy 380.29175 -5.719383) (xy 380.314396 -5.669798)
			(xy 380.343869 -5.623941) (xy 380.379569 -5.582745) (xy 380.420768 -5.547049) (xy 380.466628 -5.51758)
			(xy 380.516215 -5.494938) (xy 380.56852 -5.479584) (xy 380.622478 -5.471831) (xy 380.649734 -5.471414)
			(xy 380.650496 -5.471414) (xy 380.6698 -5.471922) (xy 380.680214 -5.47243) (xy 380.693422 -5.467604)
			(xy 380.696762 -5.466099) (xy 380.703007 -5.462272) (xy 380.705868 -5.459984) (xy 380.761494 -5.407406)
			(xy 380.768729 -5.399961) (xy 380.777002 -5.380944) (xy 380.777496 -5.370576) (xy 380.777496 -5.319522)
			(xy 380.777007 -5.309189) (xy 380.768878 -5.290187) (xy 380.761748 -5.282692) (xy 380.700788 -5.224526)
			(xy 380.690374 -5.22097) (xy 380.680976 -5.217414) (xy 380.670054 -5.217922) (xy 380.650496 -5.21843)
			(xy 380.649734 -5.21843) (xy 380.622478 -5.217969) (xy 380.56852 -5.210216) (xy 380.516215 -5.194862)
			(xy 380.466628 -5.17222) (xy 380.420768 -5.142751) (xy 380.379569 -5.107055) (xy 380.343869 -5.065859)
			(xy 380.314396 -5.020002) (xy 380.29175 -4.970417) (xy 380.276391 -4.918113) (xy 380.268633 -4.864156)
			(xy 380.268633 -4.809644) (xy 380.276391 -4.755687) (xy 380.29175 -4.703383) (xy 380.314396 -4.653798)
			(xy 380.343869 -4.607941) (xy 380.379569 -4.566745) (xy 380.420768 -4.531049) (xy 380.466628 -4.50158)
			(xy 380.516215 -4.478938) (xy 380.56852 -4.463584) (xy 380.622478 -4.455831) (xy 380.649734 -4.455414)
			(xy 380.650496 -4.455414) (xy 380.6698 -4.455922) (xy 380.680214 -4.45643) (xy 380.693422 -4.451604)
			(xy 380.696762 -4.450099) (xy 380.703007 -4.446272) (xy 380.705868 -4.443984) (xy 380.761494 -4.391406)
			(xy 380.768729 -4.383961) (xy 380.777002 -4.364944) (xy 380.777496 -4.354576) (xy 380.777496 -2.370328)
			(xy 380.777242 -2.36474) (xy 380.776757 -2.361075) (xy 380.774846 -2.353932) (xy 380.773432 -2.350516)
			(xy 380.769876 -2.342388) (xy 380.763272 -2.33553) (xy 380.760732 -2.332482) (xy 380.758954 -2.330196)
			(xy 379.850396 -1.421638) (xy 379.847545 -1.418932) (xy 379.841166 -1.414339) (xy 379.837696 -1.412494)
			(xy 379.83227 -1.409907) (xy 379.82059 -1.407075) (xy 379.814582 -1.406906) (xy 368.03711 -1.406906)
			(xy 368.031522 -1.40716) (xy 368.027857 -1.407646) (xy 368.020716 -1.40956) (xy 368.017298 -1.41097)
			(xy 368.00917 -1.414526) (xy 368.002312 -1.42113) (xy 367.999264 -1.42367) (xy 367.996978 -1.425448)
			(xy 367.75771 -1.664716) (xy 367.755006 -1.667568) (xy 367.750417 -1.673949) (xy 367.748566 -1.677416)
			(xy 367.745982 -1.682843) (xy 367.743154 -1.694522) (xy 367.742978 -1.70053) (xy 367.742978 -4.48183)
			(xy 377.965206 -4.48183) (xy 377.969277 -4.426208) (xy 377.981403 -4.371771) (xy 378.001326 -4.31968)
			(xy 378.028622 -4.271045) (xy 378.062708 -4.226902) (xy 378.102857 -4.188193) (xy 378.148215 -4.155742)
			(xy 378.197815 -4.130241) (xy 378.250599 -4.112234) (xy 378.305442 -4.102104) (xy 378.361176 -4.100067)
			(xy 378.416613 -4.106167) (xy 378.47057 -4.120273) (xy 378.521899 -4.142085) (xy 378.569505 -4.171139)
			(xy 378.612373 -4.206814) (xy 378.64959 -4.248351) (xy 378.680363 -4.294864) (xy 378.704035 -4.345361)
			(xy 378.720103 -4.398768) (xy 378.728223 -4.453944) (xy 378.728732 -4.48183) (xy 378.728223 -4.509716)
			(xy 378.720103 -4.564892) (xy 378.704035 -4.618299) (xy 378.680363 -4.668796) (xy 378.64959 -4.715309)
			(xy 378.612373 -4.756846) (xy 378.569505 -4.792521) (xy 378.521899 -4.821575) (xy 378.47057 -4.843387)
			(xy 378.416613 -4.857493) (xy 378.361176 -4.863593) (xy 378.305442 -4.861556) (xy 378.250599 -4.851426)
			(xy 378.197815 -4.833419) (xy 378.148215 -4.807918) (xy 378.102857 -4.775467) (xy 378.062708 -4.736758)
			(xy 378.028622 -4.692615) (xy 378.001326 -4.64398) (xy 377.981403 -4.591889) (xy 377.969277 -4.537452)
			(xy 377.965206 -4.48183) (xy 367.742978 -4.48183) (xy 367.742978 -5.852922) (xy 378.220984 -5.852922)
			(xy 378.225055 -5.7973) (xy 378.237181 -5.742863) (xy 378.257104 -5.690772) (xy 378.2844 -5.642137)
			(xy 378.318486 -5.597994) (xy 378.358635 -5.559285) (xy 378.403993 -5.526834) (xy 378.453593 -5.501333)
			(xy 378.506377 -5.483326) (xy 378.56122 -5.473196) (xy 378.616954 -5.471159) (xy 378.672391 -5.477259)
			(xy 378.726348 -5.491365) (xy 378.777677 -5.513177) (xy 378.825283 -5.542231) (xy 378.868151 -5.577906)
			(xy 378.905368 -5.619443) (xy 378.936141 -5.665956) (xy 378.959813 -5.716453) (xy 378.975881 -5.76986)
			(xy 378.984001 -5.825036) (xy 378.98451 -5.852922) (xy 378.984001 -5.880808) (xy 378.975881 -5.935984)
			(xy 378.959813 -5.989391) (xy 378.936141 -6.039888) (xy 378.905368 -6.086401) (xy 378.868151 -6.127938)
			(xy 378.825283 -6.163613) (xy 378.777677 -6.192667) (xy 378.726348 -6.214479) (xy 378.672391 -6.228585)
			(xy 378.616954 -6.234685) (xy 378.56122 -6.232648) (xy 378.506377 -6.222518) (xy 378.453593 -6.204511)
			(xy 378.403993 -6.17901) (xy 378.358635 -6.146559) (xy 378.318486 -6.10785) (xy 378.2844 -6.063707)
			(xy 378.257104 -6.015072) (xy 378.237181 -5.962981) (xy 378.225055 -5.908544) (xy 378.220984 -5.852922)
			(xy 367.742978 -5.852922) (xy 367.742978 -6.71195) (xy 369.906548 -6.71195) (xy 369.910619 -6.656328)
			(xy 369.922745 -6.601891) (xy 369.942668 -6.5498) (xy 369.969964 -6.501165) (xy 370.00405 -6.457022)
			(xy 370.044199 -6.418313) (xy 370.089557 -6.385862) (xy 370.139157 -6.360361) (xy 370.191941 -6.342354)
			(xy 370.246784 -6.332224) (xy 370.302518 -6.330187) (xy 370.357955 -6.336287) (xy 370.411912 -6.350393)
			(xy 370.463241 -6.372205) (xy 370.510847 -6.401259) (xy 370.553715 -6.436934) (xy 370.590932 -6.478471)
			(xy 370.621705 -6.524984) (xy 370.645377 -6.575481) (xy 370.661445 -6.628888) (xy 370.669565 -6.684064)
			(xy 370.670074 -6.71195) (xy 370.669565 -6.739836) (xy 370.661445 -6.795012) (xy 370.645377 -6.848419)
			(xy 370.621705 -6.898916) (xy 370.590932 -6.945429) (xy 370.553715 -6.986966) (xy 370.510847 -7.022641)
			(xy 370.463241 -7.051695) (xy 370.411912 -7.073507) (xy 370.357955 -7.087613) (xy 370.302518 -7.093713)
			(xy 370.246784 -7.091676) (xy 370.191941 -7.081546) (xy 370.139157 -7.063539) (xy 370.089557 -7.038038)
			(xy 370.044199 -7.005587) (xy 370.00405 -6.966878) (xy 369.969964 -6.922735) (xy 369.942668 -6.8741)
			(xy 369.922745 -6.822009) (xy 369.910619 -6.767572) (xy 369.906548 -6.71195) (xy 367.742978 -6.71195)
			(xy 367.742978 -7.473696) (xy 378.034548 -7.473696) (xy 378.038619 -7.418074) (xy 378.050745 -7.363637)
			(xy 378.070668 -7.311546) (xy 378.097964 -7.262911) (xy 378.13205 -7.218768) (xy 378.172199 -7.180059)
			(xy 378.217557 -7.147608) (xy 378.267157 -7.122107) (xy 378.319941 -7.1041) (xy 378.374784 -7.09397)
			(xy 378.430518 -7.091933) (xy 378.485955 -7.098033) (xy 378.539912 -7.112139) (xy 378.591241 -7.133951)
			(xy 378.638847 -7.163005) (xy 378.681715 -7.19868) (xy 378.718932 -7.240217) (xy 378.749705 -7.28673)
			(xy 378.773377 -7.337227) (xy 378.789445 -7.390634) (xy 378.797565 -7.44581) (xy 378.798074 -7.473696)
			(xy 378.797565 -7.501582) (xy 378.789445 -7.556758) (xy 378.773377 -7.610165) (xy 378.749705 -7.660662)
			(xy 378.718932 -7.707175) (xy 378.681715 -7.748712) (xy 378.638847 -7.784387) (xy 378.591241 -7.813441)
			(xy 378.539912 -7.835253) (xy 378.485955 -7.849359) (xy 378.430518 -7.855459) (xy 378.374784 -7.853422)
			(xy 378.319941 -7.843292) (xy 378.267157 -7.825285) (xy 378.217557 -7.799784) (xy 378.172199 -7.767333)
			(xy 378.13205 -7.728624) (xy 378.097964 -7.684481) (xy 378.070668 -7.635846) (xy 378.050745 -7.583755)
			(xy 378.038619 -7.529318) (xy 378.034548 -7.473696) (xy 367.742978 -7.473696) (xy 367.742978 -7.740396)
			(xy 367.743334 -7.748435) (xy 367.748369 -7.763708) (xy 367.752884 -7.770368) (xy 367.757456 -7.776464)
			(xy 367.770156 -7.785862) (xy 367.778284 -7.788402) (xy 367.804011 -7.797044) (xy 367.852936 -7.820532)
			(xy 367.898093 -7.850637) (xy 367.938591 -7.886766) (xy 367.973633 -7.928208) (xy 368.002529 -7.974147)
			(xy 368.016602 -8.005572) (xy 369.78412 -8.005572) (xy 369.788191 -7.94995) (xy 369.800317 -7.895513)
			(xy 369.82024 -7.843422) (xy 369.847536 -7.794787) (xy 369.881622 -7.750644) (xy 369.921771 -7.711935)
			(xy 369.967129 -7.679484) (xy 370.016729 -7.653983) (xy 370.069513 -7.635976) (xy 370.124356 -7.625846)
			(xy 370.18009 -7.623809) (xy 370.235527 -7.629909) (xy 370.289484 -7.644015) (xy 370.340813 -7.665827)
			(xy 370.388419 -7.694881) (xy 370.431287 -7.730556) (xy 370.468504 -7.772093) (xy 370.499277 -7.818606)
			(xy 370.522949 -7.869103) (xy 370.539017 -7.92251) (xy 370.547137 -7.977686) (xy 370.547646 -8.005572)
			(xy 370.547137 -8.033458) (xy 370.539017 -8.088634) (xy 370.522949 -8.142041) (xy 370.499277 -8.192538)
			(xy 370.468504 -8.239051) (xy 370.431287 -8.280588) (xy 370.388419 -8.316263) (xy 370.340813 -8.345317)
			(xy 370.289484 -8.367129) (xy 370.235527 -8.381235) (xy 370.18009 -8.387335) (xy 370.124356 -8.385298)
			(xy 370.069513 -8.375168) (xy 370.016729 -8.357161) (xy 369.967129 -8.33166) (xy 369.921771 -8.299209)
			(xy 369.881622 -8.2605) (xy 369.847536 -8.216357) (xy 369.82024 -8.167722) (xy 369.800317 -8.115631)
			(xy 369.788191 -8.061194) (xy 369.78412 -8.005572) (xy 368.016602 -8.005572) (xy 368.02471 -8.023678)
			(xy 368.03974 -8.075827) (xy 368.047322 -8.129566) (xy 368.047778 -8.156702) (xy 368.047703 -8.16963)
			(xy 368.046051 -8.195432) (xy 368.044476 -8.208264) (xy 368.044476 -8.208772) (xy 368.043612 -8.220545)
			(xy 368.051438 -8.242784) (xy 368.059462 -8.251444) (xy 368.097054 -8.28802) (xy 368.099965 -8.290739)
			(xy 368.106472 -8.295331) (xy 368.110008 -8.297164) (xy 368.117882 -8.300212) (xy 368.12982 -8.303768)
			(xy 368.142266 -8.301228) (xy 368.161494 -8.297602) (xy 368.200426 -8.293661) (xy 368.21999 -8.293354)
			(xy 368.249926 -8.293909) (xy 368.309133 -8.302816) (xy 368.366355 -8.320431) (xy 368.42032 -8.346365)
			(xy 368.469826 -8.380038) (xy 368.513771 -8.420702) (xy 368.532918 -8.443722) (xy 368.533934 -8.444992)
			(xy 368.535204 -8.446516) (xy 368.543111 -8.454545) (xy 368.563814 -8.463366) (xy 368.575082 -8.463534)
			(xy 368.583972 -8.463026) (xy 368.58448 -8.463026) (xy 368.634518 -8.460232) (xy 368.640817 -8.459479)
			(xy 368.652766 -8.455224) (xy 368.65814 -8.45185) (xy 368.658902 -8.451342) (xy 368.67211 -8.438134)
			(xy 368.672618 -8.437372) (xy 368.674904 -8.43407) (xy 368.690227 -8.412444) (xy 368.725892 -8.373238)
			(xy 368.766637 -8.339342) (xy 368.81168 -8.311409) (xy 368.860153 -8.289976) (xy 368.911126 -8.275455)
			(xy 368.963618 -8.268126) (xy 368.990118 -8.2677) (xy 369.017368 -8.268187) (xy 369.071312 -8.275945)
			(xy 369.123604 -8.291302) (xy 369.173178 -8.313943) (xy 369.219025 -8.34341) (xy 369.260212 -8.3791)
			(xy 369.295901 -8.420289) (xy 369.325365 -8.466138) (xy 369.348005 -8.515713) (xy 369.363358 -8.568005)
			(xy 369.371114 -8.62195) (xy 369.371114 -8.67645) (xy 369.363358 -8.730395) (xy 369.348005 -8.782687)
			(xy 369.325365 -8.832262) (xy 369.295901 -8.878111) (xy 369.260212 -8.9193) (xy 369.219025 -8.95499)
			(xy 369.173178 -8.984457) (xy 369.123604 -9.007098) (xy 369.071312 -9.022455) (xy 369.017368 -9.030213)
			(xy 368.990118 -9.030716) (xy 368.962935 -9.030236) (xy 368.909119 -9.022518) (xy 368.856945 -9.007238)
			(xy 368.807469 -8.984704) (xy 368.761694 -8.955373) (xy 368.720547 -8.919839) (xy 368.702336 -8.899652)
			(xy 368.701066 -8.898128) (xy 368.69624 -8.893302) (xy 368.688437 -8.886277) (xy 368.668893 -8.87867)
			(xy 368.658394 -8.87857) (xy 368.657886 -8.87857) (xy 368.626136 -8.880094) (xy 368.625628 -8.880094)
			(xy 368.600228 -8.881618) (xy 368.599974 -8.881618) (xy 368.594089 -8.882155) (xy 368.582795 -8.88562)
			(xy 368.577622 -8.888476) (xy 368.572542 -8.891524) (xy 368.563652 -8.90016) (xy 368.56035 -8.905494)
			(xy 368.544549 -8.929872) (xy 368.507031 -8.974226) (xy 368.463507 -9.012704) (xy 368.414889 -9.044501)
			(xy 368.362193 -9.068954) (xy 368.30652 -9.08555) (xy 368.249037 -9.093942) (xy 368.21999 -9.09447)
			(xy 368.19004 -9.093911) (xy 368.13081 -9.084988) (xy 368.073569 -9.067342) (xy 368.019595 -9.041367)
			(xy 367.970091 -9.007643) (xy 367.926163 -8.966922) (xy 367.907062 -8.943848) (xy 367.905284 -8.941562)
			(xy 367.900458 -8.936736) (xy 367.893361 -8.930259) (xy 367.875719 -8.922687) (xy 367.856529 -8.922144)
			(xy 367.847372 -8.925052) (xy 367.828576 -8.93191) (xy 367.828068 -8.93191) (xy 367.77676 -8.950198)
			(xy 367.767117 -8.954187) (xy 367.751889 -8.968425) (xy 367.743543 -8.987529) (xy 367.742978 -8.99795)
			(xy 367.742978 -10.35812) (xy 375.53087 -10.35812) (xy 375.534941 -10.302498) (xy 375.547067 -10.248061)
			(xy 375.56699 -10.19597) (xy 375.594286 -10.147335) (xy 375.628372 -10.103192) (xy 375.668521 -10.064483)
			(xy 375.713879 -10.032032) (xy 375.763479 -10.006531) (xy 375.816263 -9.988524) (xy 375.871106 -9.978394)
			(xy 375.92684 -9.976357) (xy 375.982277 -9.982457) (xy 376.036234 -9.996563) (xy 376.087563 -10.018375)
			(xy 376.135169 -10.047429) (xy 376.178037 -10.083104) (xy 376.215254 -10.124641) (xy 376.246027 -10.171154)
			(xy 376.269699 -10.221651) (xy 376.285767 -10.275058) (xy 376.293887 -10.330234) (xy 376.294396 -10.35812)
			(xy 376.293887 -10.386006) (xy 376.285767 -10.441182) (xy 376.269699 -10.494589) (xy 376.246027 -10.545086)
			(xy 376.215254 -10.591599) (xy 376.178037 -10.633136) (xy 376.135169 -10.668811) (xy 376.087563 -10.697865)
			(xy 376.036234 -10.719677) (xy 375.982277 -10.733783) (xy 375.92684 -10.739883) (xy 375.871106 -10.737846)
			(xy 375.816263 -10.727716) (xy 375.763479 -10.709709) (xy 375.713879 -10.684208) (xy 375.668521 -10.651757)
			(xy 375.628372 -10.613048) (xy 375.594286 -10.568905) (xy 375.56699 -10.52027) (xy 375.547067 -10.468179)
			(xy 375.534941 -10.413742) (xy 375.53087 -10.35812) (xy 367.742978 -10.35812) (xy 367.742978 -10.954512)
			(xy 369.191284 -10.954512) (xy 369.195355 -10.89889) (xy 369.207481 -10.844453) (xy 369.227404 -10.792362)
			(xy 369.2547 -10.743727) (xy 369.288786 -10.699584) (xy 369.328935 -10.660875) (xy 369.374293 -10.628424)
			(xy 369.423893 -10.602923) (xy 369.476677 -10.584916) (xy 369.53152 -10.574786) (xy 369.587254 -10.572749)
			(xy 369.642691 -10.578849) (xy 369.696648 -10.592955) (xy 369.747977 -10.614767) (xy 369.795583 -10.643821)
			(xy 369.838451 -10.679496) (xy 369.875668 -10.721033) (xy 369.906441 -10.767546) (xy 369.930113 -10.818043)
			(xy 369.946181 -10.87145) (xy 369.954301 -10.926626) (xy 369.95481 -10.954512) (xy 369.954301 -10.982398)
			(xy 369.946181 -11.037574) (xy 369.930113 -11.090981) (xy 369.906441 -11.141478) (xy 369.875668 -11.187991)
			(xy 369.838451 -11.229528) (xy 369.795583 -11.265203) (xy 369.747977 -11.294257) (xy 369.696648 -11.316069)
			(xy 369.642691 -11.330175) (xy 369.587254 -11.336275) (xy 369.53152 -11.334238) (xy 369.476677 -11.324108)
			(xy 369.423893 -11.306101) (xy 369.374293 -11.2806) (xy 369.328935 -11.248149) (xy 369.288786 -11.20944)
			(xy 369.2547 -11.165297) (xy 369.227404 -11.116662) (xy 369.207481 -11.064571) (xy 369.195355 -11.010134)
			(xy 369.191284 -10.954512) (xy 367.742978 -10.954512) (xy 367.742978 -13.057632) (xy 367.742549 -13.067699)
			(xy 367.734823 -13.086293) (xy 367.727992 -13.0937) (xy 367.407444 -13.414248) (xy 367.399357 -13.42372)
			(xy 367.392685 -13.447687) (xy 367.394744 -13.459968) (xy 367.411508 -13.521944) (xy 367.417858 -13.545566)
			(xy 367.418112 -13.546582) (xy 367.418366 -13.547598) (xy 367.41989 -13.552678) (xy 367.421668 -13.556742)
			(xy 367.422176 -13.55725) (xy 367.427006 -13.565919) (xy 367.441905 -13.578998) (xy 367.451132 -13.58265)
			(xy 367.451386 -13.58265) (xy 367.454942 -13.58392) (xy 367.45672 -13.584428) (xy 367.457736 -13.584682)
			(xy 367.487541 -13.592569) (xy 367.546731 -13.609845) (xy 367.5761 -13.619226) (xy 367.636802 -13.639317)
			(xy 367.755925 -13.68582) (xy 367.872048 -13.739375) (xy 367.984755 -13.79979) (xy 368.093641 -13.866848)
			(xy 368.198314 -13.940307) (xy 368.2984 -14.019904) (xy 368.387914 -14.100302) (xy 373.543066 -14.100302)
			(xy 373.547137 -14.04468) (xy 373.559263 -13.990243) (xy 373.579186 -13.938152) (xy 373.606482 -13.889517)
			(xy 373.640568 -13.845374) (xy 373.680717 -13.806665) (xy 373.726075 -13.774214) (xy 373.775675 -13.748713)
			(xy 373.828459 -13.730706) (xy 373.883302 -13.720576) (xy 373.939036 -13.718539) (xy 373.994473 -13.724639)
			(xy 374.04843 -13.738745) (xy 374.099759 -13.760557) (xy 374.147365 -13.789611) (xy 374.190233 -13.825286)
			(xy 374.22745 -13.866823) (xy 374.258223 -13.913336) (xy 374.281895 -13.963833) (xy 374.297963 -14.01724)
			(xy 374.306083 -14.072416) (xy 374.306592 -14.100302) (xy 374.306083 -14.128188) (xy 374.297963 -14.183364)
			(xy 374.281895 -14.236771) (xy 374.258223 -14.287268) (xy 374.22745 -14.333781) (xy 374.190233 -14.375318)
			(xy 374.147365 -14.410993) (xy 374.099759 -14.440047) (xy 374.04843 -14.461859) (xy 373.994473 -14.475965)
			(xy 373.939036 -14.482065) (xy 373.883302 -14.480028) (xy 373.828459 -14.469898) (xy 373.775675 -14.451891)
			(xy 373.726075 -14.42639) (xy 373.680717 -14.393939) (xy 373.640568 -14.35523) (xy 373.606482 -14.311087)
			(xy 373.579186 -14.262452) (xy 373.559263 -14.210361) (xy 373.547137 -14.155924) (xy 373.543066 -14.100302)
			(xy 368.387914 -14.100302) (xy 368.393538 -14.105353) (xy 368.483386 -14.196348) (xy 368.567623 -14.292561)
			(xy 368.645946 -14.393647) (xy 368.718072 -14.499243) (xy 368.783745 -14.608969) (xy 368.842726 -14.722433)
			(xy 368.894806 -14.839225) (xy 368.939796 -14.958928) (xy 368.977536 -15.08111) (xy 369.007889 -15.205333)
			(xy 369.030746 -15.331152) (xy 369.038737 -15.39755) (xy 374.20448 -15.39755) (xy 374.20448 -15.34305)
			(xy 374.212236 -15.289104) (xy 374.22759 -15.23681) (xy 374.25023 -15.187234) (xy 374.279695 -15.141385)
			(xy 374.315384 -15.100195) (xy 374.356572 -15.064504) (xy 374.40242 -15.035038) (xy 374.451995 -15.012396)
			(xy 374.504288 -14.997039) (xy 374.558234 -14.989281) (xy 374.585484 -14.988794) (xy 374.611719 -14.989264)
			(xy 374.663695 -14.996457) (xy 374.714193 -15.01071) (xy 374.762259 -15.031752) (xy 374.806986 -15.059187)
			(xy 374.847529 -15.092496) (xy 374.865646 -15.111476) (xy 374.8659 -15.11173) (xy 374.873617 -15.119131)
			(xy 374.893312 -15.127394) (xy 374.904 -15.127732) (xy 374.991884 -15.125446) (xy 375.011442 -15.116048)
			(xy 375.018554 -15.107412) (xy 375.036763 -15.08626) (xy 375.078304 -15.048985) (xy 375.124834 -15.018164)
			(xy 375.175359 -14.994453) (xy 375.228801 -14.97836) (xy 375.284018 -14.970229) (xy 375.311924 -14.969744)
			(xy 375.339171 -14.970328) (xy 375.393109 -14.978086) (xy 375.445394 -14.993441) (xy 375.494962 -15.016081)
			(xy 375.540804 -15.045544) (xy 375.581986 -15.081231) (xy 375.61767 -15.122416) (xy 375.647131 -15.168259)
			(xy 375.669767 -15.217828) (xy 375.685119 -15.270115) (xy 375.692874 -15.324053) (xy 375.692874 -15.378547)
			(xy 375.685119 -15.432485) (xy 375.669767 -15.484772) (xy 375.647131 -15.534341) (xy 375.61767 -15.580184)
			(xy 375.581986 -15.621369) (xy 375.540804 -15.657056) (xy 375.494962 -15.686519) (xy 375.445394 -15.709159)
			(xy 375.393109 -15.724514) (xy 375.339171 -15.732272) (xy 375.311924 -15.73276) (xy 375.285688 -15.732299)
			(xy 375.233712 -15.725106) (xy 375.183213 -15.710853) (xy 375.135146 -15.689809) (xy 375.090419 -15.662372)
			(xy 375.049878 -15.62906) (xy 375.031762 -15.610078) (xy 375.031508 -15.609824) (xy 375.023794 -15.60242)
			(xy 375.004096 -15.59416) (xy 374.993408 -15.593822) (xy 374.905524 -15.596108) (xy 374.885966 -15.605506)
			(xy 374.878854 -15.614142) (xy 374.86063 -15.635281) (xy 374.819094 -15.672558) (xy 374.772567 -15.703383)
			(xy 374.722044 -15.727096) (xy 374.668605 -15.743191) (xy 374.613389 -15.751325) (xy 374.585484 -15.75181)
			(xy 374.558234 -15.751319) (xy 374.504288 -15.743561) (xy 374.451995 -15.728204) (xy 374.40242 -15.705562)
			(xy 374.356572 -15.676096) (xy 374.315384 -15.640405) (xy 374.279695 -15.599215) (xy 374.25023 -15.553366)
			(xy 374.22759 -15.50379) (xy 374.212236 -15.451496) (xy 374.20448 -15.39755) (xy 369.038737 -15.39755)
			(xy 369.046026 -15.458114) (xy 369.053674 -15.585763) (xy 369.054126 -15.649702) (xy 369.054126 -15.649956)
			(xy 369.05362 -15.715692) (xy 369.045527 -15.846913) (xy 369.02937 -15.977388) (xy 369.005213 -16.106621)
			(xy 368.973145 -16.234121) (xy 368.933289 -16.359405) (xy 368.885796 -16.481999) (xy 368.830847 -16.601436)
			(xy 368.768648 -16.717263) (xy 368.699438 -16.829042) (xy 368.623477 -16.936349) (xy 368.596403 -16.969994)
			(xy 388.048253 -16.969994) (xy 388.052258 -16.882086) (xy 388.064241 -16.794906) (xy 388.084101 -16.709177)
			(xy 388.111676 -16.625609) (xy 388.146735 -16.544895) (xy 388.188988 -16.467703) (xy 388.238086 -16.394674)
			(xy 388.293622 -16.326412) (xy 388.355134 -16.263482) (xy 388.422115 -16.206408) (xy 388.494008 -16.15566)
			(xy 388.570217 -16.11166) (xy 388.650112 -16.074773) (xy 388.733031 -16.045304) (xy 388.818286 -16.023497)
			(xy 388.90517 -16.009533) (xy 388.992964 -16.003527) (xy 389.080941 -16.005531) (xy 389.168371 -16.015526)
			(xy 389.25453 -16.03343) (xy 389.338704 -16.059094) (xy 389.420195 -16.092307) (xy 389.498329 -16.132793)
			(xy 389.572457 -16.180215) (xy 389.641965 -16.234182) (xy 389.706279 -16.294247) (xy 389.764863 -16.359911)
			(xy 389.817234 -16.43063) (xy 389.862957 -16.505818) (xy 389.901654 -16.584853) (xy 389.933003 -16.667079)
			(xy 389.956745 -16.751815) (xy 389.972683 -16.838359) (xy 389.980685 -16.925994) (xy 389.981186 -16.969994)
			(xy 389.980685 -17.013994) (xy 389.972683 -17.101629) (xy 389.956745 -17.188173) (xy 389.933003 -17.272909)
			(xy 389.901654 -17.355135) (xy 389.862957 -17.43417) (xy 389.817234 -17.509358) (xy 389.764863 -17.580077)
			(xy 389.706279 -17.645741) (xy 389.641965 -17.705806) (xy 389.572457 -17.759773) (xy 389.498329 -17.807195)
			(xy 389.420195 -17.847681) (xy 389.338704 -17.880894) (xy 389.25453 -17.906558) (xy 389.168371 -17.924462)
			(xy 389.080941 -17.934457) (xy 388.992964 -17.936461) (xy 388.90517 -17.930455) (xy 388.818286 -17.916491)
			(xy 388.733031 -17.894684) (xy 388.650112 -17.865215) (xy 388.570217 -17.828328) (xy 388.494008 -17.784328)
			(xy 388.422115 -17.73358) (xy 388.355134 -17.676506) (xy 388.293622 -17.613576) (xy 388.238086 -17.545314)
			(xy 388.188988 -17.472285) (xy 388.146735 -17.395093) (xy 388.111676 -17.314379) (xy 388.084101 -17.230811)
			(xy 388.064241 -17.145082) (xy 388.052258 -17.057902) (xy 388.048253 -16.969994) (xy 368.596403 -16.969994)
			(xy 368.541055 -17.038775) (xy 368.452483 -17.135934) (xy 368.358098 -17.227455) (xy 368.258259 -17.312993)
			(xy 368.153342 -17.392222) (xy 368.112064 -17.419574) (xy 372.584216 -17.419574) (xy 372.588287 -17.363952)
			(xy 372.600413 -17.309515) (xy 372.620336 -17.257424) (xy 372.647632 -17.208789) (xy 372.681718 -17.164646)
			(xy 372.721867 -17.125937) (xy 372.767225 -17.093486) (xy 372.816825 -17.067985) (xy 372.869609 -17.049978)
			(xy 372.924452 -17.039848) (xy 372.980186 -17.037811) (xy 373.035623 -17.043911) (xy 373.08958 -17.058017)
			(xy 373.140909 -17.079829) (xy 373.188515 -17.108883) (xy 373.231383 -17.144558) (xy 373.2686 -17.186095)
			(xy 373.299373 -17.232608) (xy 373.323045 -17.283105) (xy 373.339113 -17.336512) (xy 373.347233 -17.391688)
			(xy 373.347742 -17.419574) (xy 373.347233 -17.44746) (xy 373.339113 -17.502636) (xy 373.323045 -17.556043)
			(xy 373.299373 -17.60654) (xy 373.2686 -17.653053) (xy 373.231383 -17.69459) (xy 373.188515 -17.730265)
			(xy 373.140909 -17.759319) (xy 373.08958 -17.781131) (xy 373.035623 -17.795237) (xy 372.980186 -17.801337)
			(xy 372.924452 -17.7993) (xy 372.869609 -17.78917) (xy 372.816825 -17.771163) (xy 372.767225 -17.745662)
			(xy 372.721867 -17.713211) (xy 372.681718 -17.674502) (xy 372.647632 -17.630359) (xy 372.620336 -17.581724)
			(xy 372.600413 -17.529633) (xy 372.588287 -17.475196) (xy 372.584216 -17.419574) (xy 368.112064 -17.419574)
			(xy 368.043748 -17.464842) (xy 367.92989 -17.530577) (xy 367.812202 -17.589179) (xy 367.69113 -17.640425)
			(xy 367.567132 -17.68412) (xy 367.44068 -17.720099) (xy 367.312252 -17.748225) (xy 367.182337 -17.768391)
			(xy 367.051427 -17.780522) (xy 366.920018 -17.784571) (xy 366.788609 -17.780522) (xy 366.657699 -17.768391)
			(xy 366.527784 -17.748225) (xy 366.399356 -17.720099) (xy 366.272904 -17.68412) (xy 366.148906 -17.640425)
			(xy 366.027834 -17.589179) (xy 365.910146 -17.530577) (xy 365.796288 -17.464842) (xy 365.686694 -17.392222)
			(xy 365.581777 -17.312993) (xy 365.481938 -17.227455) (xy 365.387553 -17.135934) (xy 365.298981 -17.038775)
			(xy 365.216559 -16.936349) (xy 365.140598 -16.829042) (xy 365.071388 -16.717263) (xy 365.009189 -16.601436)
			(xy 364.95424 -16.481999) (xy 364.906747 -16.359405) (xy 364.866891 -16.234121) (xy 364.834823 -16.106621)
			(xy 364.810666 -15.977388) (xy 364.794509 -15.846913) (xy 364.786416 -15.715692) (xy 364.78591 -15.649956)
			(xy 364.78591 -15.649448) (xy 364.786465 -15.580426) (xy 364.795386 -15.442671) (xy 364.813195 -15.30578)
			(xy 364.839816 -15.170328) (xy 364.875138 -15.036879) (xy 364.919014 -14.905994) (xy 364.97126 -14.778219)
			(xy 365.031657 -14.654089) (xy 365.06531 -14.593824) (xy 365.068612 -14.587982) (xy 365.071914 -14.575536)
			(xy 365.071914 -14.568932) (xy 365.071744 -14.562779) (xy 365.068788 -14.550834) (xy 365.066072 -14.54531)
			(xy 365.037878 -14.496034) (xy 365.037878 -14.495526) (xy 365.021114 -14.466824) (xy 365.013748 -14.457172)
			(xy 365.002572 -14.448536) (xy 364.996984 -14.445488) (xy 364.990888 -14.44371) (xy 364.977426 -14.441932)
			(xy 356.290118 -14.441932) (xy 356.280067 -14.441426) (xy 356.261507 -14.433705) (xy 356.25405 -14.426946)
			(xy 354.574094 -12.74699) (xy 354.56725 -12.739591) (xy 354.55952 -12.720993) (xy 354.559108 -12.710922)
			(xy 354.559108 -1.949196) (xy 354.558854 -1.943608) (xy 354.558367 -1.939943) (xy 354.556452 -1.932803)
			(xy 354.555044 -1.929384) (xy 354.551488 -1.921256) (xy 354.544884 -1.914398) (xy 354.542344 -1.91135)
			(xy 354.540566 -1.909064) (xy 354.424996 -1.793494) (xy 354.422144 -1.79079) (xy 354.415763 -1.786201)
			(xy 354.412296 -1.78435) (xy 354.406871 -1.78176) (xy 354.395191 -1.778925) (xy 354.389182 -1.778762)
			(xy 329.75042 -1.778762) (xy 329.744832 -1.779016) (xy 329.741167 -1.779502) (xy 329.734026 -1.781416)
			(xy 329.730608 -1.782826) (xy 329.72248 -1.786382) (xy 329.715622 -1.792986) (xy 329.712574 -1.795526)
			(xy 329.710288 -1.797304) (xy 329.644248 -1.863344) (xy 329.641544 -1.866196) (xy 329.636954 -1.872576)
			(xy 329.635104 -1.876044) (xy 329.632521 -1.881471) (xy 329.629697 -1.89315) (xy 329.629516 -1.899158)
			(xy 329.629516 -5.776468) (xy 335.944462 -5.776468) (xy 335.948533 -5.720846) (xy 335.960659 -5.666409)
			(xy 335.980582 -5.614318) (xy 336.007878 -5.565683) (xy 336.041964 -5.52154) (xy 336.082113 -5.482831)
			(xy 336.127471 -5.45038) (xy 336.177071 -5.424879) (xy 336.229855 -5.406872) (xy 336.284698 -5.396742)
			(xy 336.340432 -5.394705) (xy 336.395869 -5.400805) (xy 336.449826 -5.414911) (xy 336.501155 -5.436723)
			(xy 336.548761 -5.465777) (xy 336.591629 -5.501452) (xy 336.628846 -5.542989) (xy 336.659619 -5.589502)
			(xy 336.683291 -5.639999) (xy 336.699359 -5.693406) (xy 336.707284 -5.747258) (xy 339.126066 -5.747258)
			(xy 339.130137 -5.691636) (xy 339.142263 -5.637199) (xy 339.162186 -5.585108) (xy 339.189482 -5.536473)
			(xy 339.223568 -5.49233) (xy 339.263717 -5.453621) (xy 339.309075 -5.42117) (xy 339.358675 -5.395669)
			(xy 339.411459 -5.377662) (xy 339.466302 -5.367532) (xy 339.522036 -5.365495) (xy 339.577473 -5.371595)
			(xy 339.63143 -5.385701) (xy 339.682759 -5.407513) (xy 339.730365 -5.436567) (xy 339.773233 -5.472242)
			(xy 339.81045 -5.513779) (xy 339.841223 -5.560292) (xy 339.864895 -5.610789) (xy 339.880963 -5.664196)
			(xy 339.889083 -5.719372) (xy 339.889592 -5.747258) (xy 339.889083 -5.775144) (xy 339.880963 -5.83032)
			(xy 339.864895 -5.883727) (xy 339.841223 -5.934224) (xy 339.81045 -5.980737) (xy 339.773233 -6.022274)
			(xy 339.730365 -6.057949) (xy 339.682759 -6.087003) (xy 339.63143 -6.108815) (xy 339.577473 -6.122921)
			(xy 339.522036 -6.129021) (xy 339.466302 -6.126984) (xy 339.411459 -6.116854) (xy 339.358675 -6.098847)
			(xy 339.309075 -6.073346) (xy 339.263717 -6.040895) (xy 339.223568 -6.002186) (xy 339.189482 -5.958043)
			(xy 339.162186 -5.909408) (xy 339.142263 -5.857317) (xy 339.130137 -5.80288) (xy 339.126066 -5.747258)
			(xy 336.707284 -5.747258) (xy 336.707479 -5.748582) (xy 336.707988 -5.776468) (xy 336.707479 -5.804354)
			(xy 336.699359 -5.85953) (xy 336.683291 -5.912937) (xy 336.659619 -5.963434) (xy 336.628846 -6.009947)
			(xy 336.591629 -6.051484) (xy 336.548761 -6.087159) (xy 336.501155 -6.116213) (xy 336.449826 -6.138025)
			(xy 336.395869 -6.152131) (xy 336.340432 -6.158231) (xy 336.284698 -6.156194) (xy 336.229855 -6.146064)
			(xy 336.177071 -6.128057) (xy 336.127471 -6.102556) (xy 336.082113 -6.070105) (xy 336.041964 -6.031396)
			(xy 336.007878 -5.987253) (xy 335.980582 -5.938618) (xy 335.960659 -5.886527) (xy 335.948533 -5.83209)
			(xy 335.944462 -5.776468) (xy 329.629516 -5.776468) (xy 329.629516 -6.68655) (xy 330.361288 -6.68655)
			(xy 330.365359 -6.630928) (xy 330.377485 -6.576491) (xy 330.397408 -6.5244) (xy 330.424704 -6.475765)
			(xy 330.45879 -6.431622) (xy 330.498939 -6.392913) (xy 330.544297 -6.360462) (xy 330.593897 -6.334961)
			(xy 330.646681 -6.316954) (xy 330.701524 -6.306824) (xy 330.757258 -6.304787) (xy 330.812695 -6.310887)
			(xy 330.866652 -6.324993) (xy 330.917981 -6.346805) (xy 330.965587 -6.375859) (xy 331.008455 -6.411534)
			(xy 331.045672 -6.453071) (xy 331.076445 -6.499584) (xy 331.100117 -6.550081) (xy 331.116185 -6.603488)
			(xy 331.124305 -6.658664) (xy 331.124814 -6.68655) (xy 331.124305 -6.714436) (xy 331.116185 -6.769612)
			(xy 331.100117 -6.823019) (xy 331.076445 -6.873516) (xy 331.045672 -6.920029) (xy 331.008455 -6.961566)
			(xy 330.965587 -6.997241) (xy 330.917981 -7.026295) (xy 330.866652 -7.048107) (xy 330.812695 -7.062213)
			(xy 330.757258 -7.068313) (xy 330.701524 -7.066276) (xy 330.646681 -7.056146) (xy 330.593897 -7.038139)
			(xy 330.544297 -7.012638) (xy 330.498939 -6.980187) (xy 330.45879 -6.941478) (xy 330.424704 -6.897335)
			(xy 330.397408 -6.8487) (xy 330.377485 -6.796609) (xy 330.365359 -6.742172) (xy 330.361288 -6.68655)
			(xy 329.629516 -6.68655) (xy 329.629516 -7.916672) (xy 330.525372 -7.916672) (xy 330.529443 -7.86105)
			(xy 330.541569 -7.806613) (xy 330.561492 -7.754522) (xy 330.588788 -7.705887) (xy 330.622874 -7.661744)
			(xy 330.663023 -7.623035) (xy 330.708381 -7.590584) (xy 330.757981 -7.565083) (xy 330.810765 -7.547076)
			(xy 330.865608 -7.536946) (xy 330.921342 -7.534909) (xy 330.976779 -7.541009) (xy 331.030736 -7.555115)
			(xy 331.082065 -7.576927) (xy 331.129671 -7.605981) (xy 331.172539 -7.641656) (xy 331.209756 -7.683193)
			(xy 331.240529 -7.729706) (xy 331.264201 -7.780203) (xy 331.280269 -7.83361) (xy 331.288389 -7.888786)
			(xy 331.288898 -7.916672) (xy 331.288389 -7.944558) (xy 331.280269 -7.999734) (xy 331.264201 -8.053141)
			(xy 331.240529 -8.103638) (xy 331.209756 -8.150151) (xy 331.172539 -8.191688) (xy 331.129671 -8.227363)
			(xy 331.082065 -8.256417) (xy 331.030736 -8.278229) (xy 330.976779 -8.292335) (xy 330.921342 -8.298435)
			(xy 330.865608 -8.296398) (xy 330.810765 -8.286268) (xy 330.757981 -8.268261) (xy 330.708381 -8.24276)
			(xy 330.663023 -8.210309) (xy 330.622874 -8.1716) (xy 330.588788 -8.127457) (xy 330.561492 -8.078822)
			(xy 330.541569 -8.026731) (xy 330.529443 -7.972294) (xy 330.525372 -7.916672) (xy 329.629516 -7.916672)
			(xy 329.629516 -8.128762) (xy 329.630278 -8.13689) (xy 329.631789 -8.143642) (xy 329.637979 -8.15601)
			(xy 329.64247 -8.161274) (xy 329.661774 -8.18261) (xy 329.668632 -8.189214) (xy 329.673966 -8.19277)
			(xy 329.676252 -8.19404) (xy 329.680209 -8.19606) (xy 329.688639 -8.198862) (xy 329.693016 -8.199628)
			(xy 329.720046 -8.20411) (xy 329.77254 -8.219808) (xy 329.822249 -8.242852) (xy 329.868151 -8.272769)
			(xy 329.909302 -8.308944) (xy 329.944856 -8.350632) (xy 329.974082 -8.396977) (xy 329.99638 -8.447025)
			(xy 330.01129 -8.499748) (xy 330.018506 -8.554061) (xy 330.01788 -8.608848) (xy 330.009425 -8.662983)
			(xy 329.993314 -8.715351) (xy 329.969878 -8.764877) (xy 329.939601 -8.810541) (xy 329.903103 -8.851406)
			(xy 329.861136 -8.886631) (xy 329.814562 -8.915491) (xy 329.76434 -8.937394) (xy 329.711501 -8.951888)
			(xy 329.68438 -8.955786) (xy 329.67676 -8.95985) (xy 329.673589 -8.961648) (xy 329.667732 -8.965988)
			(xy 329.665076 -8.968486) (xy 329.64755 -8.987536) (xy 329.644502 -8.991092) (xy 329.637136 -8.998204)
			(xy 329.632818 -9.009126) (xy 329.6313 -9.013414) (xy 329.629643 -9.022358) (xy 329.629516 -9.026906)
			(xy 329.629516 -9.535922) (xy 332.574644 -9.535922) (xy 332.578715 -9.4803) (xy 332.590841 -9.425863)
			(xy 332.610764 -9.373772) (xy 332.63806 -9.325137) (xy 332.672146 -9.280994) (xy 332.712295 -9.242285)
			(xy 332.757653 -9.209834) (xy 332.807253 -9.184333) (xy 332.860037 -9.166326) (xy 332.91488 -9.156196)
			(xy 332.970614 -9.154159) (xy 333.026051 -9.160259) (xy 333.080008 -9.174365) (xy 333.131337 -9.196177)
			(xy 333.178943 -9.225231) (xy 333.221811 -9.260906) (xy 333.259028 -9.302443) (xy 333.289801 -9.348956)
			(xy 333.313473 -9.399453) (xy 333.329541 -9.45286) (xy 333.337661 -9.508036) (xy 333.33817 -9.535922)
			(xy 333.337661 -9.563808) (xy 333.329541 -9.618984) (xy 333.313473 -9.672391) (xy 333.289801 -9.722888)
			(xy 333.259028 -9.769401) (xy 333.221811 -9.810938) (xy 333.178943 -9.846613) (xy 333.131337 -9.875667)
			(xy 333.080008 -9.897479) (xy 333.026051 -9.911585) (xy 332.970614 -9.917685) (xy 332.91488 -9.915648)
			(xy 332.860037 -9.905518) (xy 332.807253 -9.887511) (xy 332.757653 -9.86201) (xy 332.712295 -9.829559)
			(xy 332.672146 -9.79085) (xy 332.63806 -9.746707) (xy 332.610764 -9.698072) (xy 332.590841 -9.645981)
			(xy 332.578715 -9.591544) (xy 332.574644 -9.535922) (xy 329.629516 -9.535922) (xy 329.629516 -13.528802)
			(xy 329.629093 -13.538872) (xy 329.62138 -13.557478) (xy 329.61453 -13.56487) (xy 329.594464 -13.584936)
			(xy 329.589944 -13.589751) (xy 329.583379 -13.601207) (xy 329.58151 -13.607542) (xy 329.579581 -13.616088)
			(xy 329.580967 -13.633541) (xy 329.588128 -13.649517) (xy 329.593956 -13.656056) (xy 329.60183 -13.664184)
			(xy 329.61199 -13.668248) (xy 329.673892 -13.693547) (xy 329.794731 -13.750859) (xy 329.911745 -13.815625)
			(xy 330.024472 -13.887591) (xy 330.132472 -13.966475) (xy 330.235321 -14.051968) (xy 330.332613 -14.143733)
			(xy 330.423968 -14.241411) (xy 330.509028 -14.344617) (xy 330.587457 -14.452948) (xy 330.658949 -14.565977)
			(xy 330.723223 -14.683262) (xy 330.780025 -14.804341) (xy 330.829135 -14.928739) (xy 330.870358 -15.055969)
			(xy 330.903532 -15.18553) (xy 330.928529 -15.316915) (xy 330.945249 -15.449607) (xy 330.953626 -15.583085)
			(xy 330.954126 -15.649956) (xy 330.95365 -15.714429) (xy 330.945867 -15.843139) (xy 330.930327 -15.971144)
			(xy 330.907086 -16.097977) (xy 330.87623 -16.223176) (xy 330.837871 -16.346283) (xy 330.792148 -16.46685)
			(xy 330.73923 -16.584436) (xy 330.679308 -16.698612) (xy 330.612601 -16.808962) (xy 330.539354 -16.915083)
			(xy 330.459833 -17.016588) (xy 330.374328 -17.113106) (xy 330.283151 -17.204285) (xy 330.186635 -17.289793)
			(xy 330.085133 -17.369317) (xy 329.979014 -17.442568) (xy 329.868666 -17.509277) (xy 329.754492 -17.569203)
			(xy 329.636907 -17.622125) (xy 329.516342 -17.667851) (xy 329.393236 -17.706213) (xy 329.268038 -17.737073)
			(xy 329.141205 -17.760318) (xy 329.0132 -17.775861) (xy 328.884491 -17.783648) (xy 328.820018 -17.784064)
			(xy 328.769218 -17.783556) (xy 328.703582 -17.78149) (xy 328.572728 -17.770297) (xy 328.442809 -17.751078)
			(xy 328.314319 -17.723907) (xy 328.187742 -17.688885) (xy 328.063559 -17.646146) (xy 327.942238 -17.595851)
			(xy 327.82424 -17.538191) (xy 327.710012 -17.473384) (xy 327.599985 -17.401675) (xy 327.494575 -17.323335)
			(xy 327.394183 -17.238662) (xy 327.299187 -17.147976) (xy 327.209949 -17.051619) (xy 327.126804 -16.949957)
			(xy 327.050068 -16.843375) (xy 326.980032 -16.732275) (xy 326.91696 -16.617079) (xy 326.861092 -16.498223)
			(xy 326.812638 -16.376155) (xy 326.771783 -16.25134) (xy 326.73868 -16.124248) (xy 326.713456 -15.99536)
			(xy 326.696205 -15.865166) (xy 326.686993 -15.734157) (xy 326.68591 -15.668498) (xy 326.685656 -15.649702)
			(xy 326.685656 -15.649448) (xy 326.686129 -15.586497) (xy 326.69358 -15.460815) (xy 326.708429 -15.33579)
			(xy 326.730624 -15.211859) (xy 326.760089 -15.089453) (xy 326.79672 -14.968997) (xy 326.84039 -14.85091)
			(xy 326.890948 -14.735604) (xy 326.948217 -14.62348) (xy 327.011998 -14.514928) (xy 327.082069 -14.410326)
			(xy 327.119742 -14.35989) (xy 327.121774 -14.357096) (xy 327.127362 -14.346936) (xy 327.130918 -14.336776)
			(xy 327.132442 -14.32687) (xy 327.131172 -14.315948) (xy 327.130156 -14.312646) (xy 327.130156 -14.312392)
			(xy 327.129394 -14.309852) (xy 327.1266 -14.302486) (xy 327.106534 -14.262608) (xy 327.106534 -14.2621)
			(xy 327.08977 -14.22908) (xy 327.087886 -14.225528) (xy 327.083162 -14.219022) (xy 327.080372 -14.216126)
			(xy 327.073006 -14.20876) (xy 327.069276 -14.205238) (xy 327.060702 -14.199608) (xy 327.055988 -14.197584)
			(xy 327.047352 -14.194028) (xy 317.53302 -14.194028) (xy 317.522969 -14.193522) (xy 317.504409 -14.185801)
			(xy 317.496952 -14.179042) (xy 316.783212 -13.465302) (xy 316.776364 -13.457904) (xy 316.768627 -13.439306)
			(xy 316.768226 -13.429234) (xy 316.768226 -1.70561) (xy 316.76774 -1.695599) (xy 316.760083 -1.677099)
			(xy 316.745931 -1.662937) (xy 316.727437 -1.655267) (xy 316.717426 -1.65481) (xy 304.300128 -1.65481)
			(xy 304.29454 -1.655064) (xy 304.290875 -1.655549) (xy 304.283732 -1.65746) (xy 304.280316 -1.658874)
			(xy 304.272188 -1.66243) (xy 304.26533 -1.669034) (xy 304.262282 -1.671574) (xy 304.259996 -1.673352)
			(xy 303.649126 -2.284222) (xy 303.646422 -2.287074) (xy 303.641832 -2.293454) (xy 303.639982 -2.296922)
			(xy 303.637397 -2.302349) (xy 303.63457 -2.314028) (xy 303.634394 -2.320036) (xy 303.634394 -11.000994)
			(xy 303.63541 -11.010392) (xy 303.63541 -11.0109) (xy 303.637117 -11.018058) (xy 303.643954 -11.03108)
			(xy 303.648872 -11.036554) (xy 303.668938 -11.05662) (xy 303.675788 -11.064017) (xy 303.683525 -11.082615)
			(xy 303.683924 -11.092688) (xy 303.683924 -12.68603) (xy 303.683496 -12.696098) (xy 303.675777 -12.714697)
			(xy 303.668938 -12.722098) (xy 303.030636 -13.3604) (xy 303.024227 -13.367426) (xy 303.01668 -13.384868)
			(xy 303.015989 -13.403859) (xy 303.018698 -13.412978) (xy 303.018698 -13.414756) (xy 303.029366 -13.44422)
			(xy 303.029366 -13.444728) (xy 303.047908 -13.49883) (xy 303.049178 -13.502132) (xy 303.052535 -13.509169)
			(xy 303.062743 -13.520944) (xy 303.069244 -13.525246) (xy 303.08042 -13.531342) (xy 303.090072 -13.532612)
			(xy 303.153701 -13.541225) (xy 303.279873 -13.56513) (xy 303.404379 -13.596576) (xy 303.526769 -13.63545)
			(xy 303.646601 -13.681611) (xy 303.763442 -13.734893) (xy 303.876868 -13.795102) (xy 303.986469 -13.862021)
			(xy 304.09185 -13.935407) (xy 304.192628 -14.014996) (xy 304.288217 -14.100302) (xy 309.442864 -14.100302)
			(xy 309.446935 -14.04468) (xy 309.459061 -13.990243) (xy 309.478984 -13.938152) (xy 309.50628 -13.889517)
			(xy 309.540366 -13.845374) (xy 309.580515 -13.806665) (xy 309.625873 -13.774214) (xy 309.675473 -13.748713)
			(xy 309.728257 -13.730706) (xy 309.7831 -13.720576) (xy 309.838834 -13.718539) (xy 309.894271 -13.724639)
			(xy 309.948228 -13.738745) (xy 309.999557 -13.760557) (xy 310.047163 -13.789611) (xy 310.090031 -13.825286)
			(xy 310.127248 -13.866823) (xy 310.158021 -13.913336) (xy 310.181693 -13.963833) (xy 310.197761 -14.01724)
			(xy 310.205881 -14.072416) (xy 310.20639 -14.100302) (xy 310.205881 -14.128188) (xy 310.197761 -14.183364)
			(xy 310.181693 -14.236771) (xy 310.158021 -14.287268) (xy 310.127248 -14.333781) (xy 310.090031 -14.375318)
			(xy 310.047163 -14.410993) (xy 309.999557 -14.440047) (xy 309.948228 -14.461859) (xy 309.894271 -14.475965)
			(xy 309.838834 -14.482065) (xy 309.7831 -14.480028) (xy 309.728257 -14.469898) (xy 309.675473 -14.451891)
			(xy 309.625873 -14.42639) (xy 309.580515 -14.393939) (xy 309.540366 -14.35523) (xy 309.50628 -14.311087)
			(xy 309.478984 -14.262452) (xy 309.459061 -14.210361) (xy 309.446935 -14.155924) (xy 309.442864 -14.100302)
			(xy 304.288217 -14.100302) (xy 304.288439 -14.1005) (xy 304.378937 -14.191608) (xy 304.463795 -14.287992)
			(xy 304.542704 -14.389302) (xy 304.615381 -14.495174) (xy 304.681562 -14.605222) (xy 304.741007 -14.71905)
			(xy 304.793503 -14.836246) (xy 304.838858 -14.956386) (xy 304.876908 -15.079035) (xy 304.907517 -15.203749)
			(xy 304.930573 -15.330079) (xy 304.938734 -15.39755) (xy 310.10428 -15.39755) (xy 310.10428 -15.34305)
			(xy 310.112036 -15.289104) (xy 310.12739 -15.236811) (xy 310.15003 -15.187235) (xy 310.179494 -15.141386)
			(xy 310.215183 -15.100196) (xy 310.256371 -15.064505) (xy 310.302219 -15.035038) (xy 310.351794 -15.012396)
			(xy 310.404086 -14.99704) (xy 310.458032 -14.989281) (xy 310.485282 -14.988794) (xy 310.511517 -14.989266)
			(xy 310.563493 -14.996458) (xy 310.613991 -15.01071) (xy 310.662057 -15.031752) (xy 310.706784 -15.059187)
			(xy 310.747327 -15.092496) (xy 310.765444 -15.111476) (xy 310.765698 -15.11173) (xy 310.773416 -15.11913)
			(xy 310.79311 -15.127394) (xy 310.803798 -15.127732) (xy 310.891682 -15.125446) (xy 310.91124 -15.116048)
			(xy 310.918352 -15.107412) (xy 310.936563 -15.086261) (xy 310.978103 -15.048986) (xy 311.024632 -15.018164)
			(xy 311.075158 -14.994454) (xy 311.128599 -14.978361) (xy 311.183816 -14.970229) (xy 311.211722 -14.969744)
			(xy 311.238969 -14.970328) (xy 311.292907 -14.978086) (xy 311.345193 -14.993441) (xy 311.394761 -15.01608)
			(xy 311.440603 -15.045543) (xy 311.481785 -15.08123) (xy 311.51747 -15.122415) (xy 311.54693 -15.168258)
			(xy 311.569567 -15.217828) (xy 311.584919 -15.270114) (xy 311.592674 -15.324053) (xy 311.592674 -15.378547)
			(xy 311.584919 -15.432486) (xy 311.569567 -15.484772) (xy 311.54693 -15.534342) (xy 311.51747 -15.580185)
			(xy 311.481785 -15.62137) (xy 311.440603 -15.657057) (xy 311.394761 -15.68652) (xy 311.345193 -15.709159)
			(xy 311.292907 -15.724514) (xy 311.238969 -15.732272) (xy 311.211722 -15.73276) (xy 311.185486 -15.7323)
			(xy 311.13351 -15.725107) (xy 311.083011 -15.710854) (xy 311.034944 -15.68981) (xy 310.990217 -15.662372)
			(xy 310.949676 -15.62906) (xy 310.93156 -15.610078) (xy 310.931306 -15.609824) (xy 310.923593 -15.602419)
			(xy 310.903894 -15.59416) (xy 310.893206 -15.593822) (xy 310.805322 -15.596108) (xy 310.785764 -15.605506)
			(xy 310.778652 -15.614142) (xy 310.760429 -15.635282) (xy 310.718892 -15.672559) (xy 310.672366 -15.703384)
			(xy 310.621843 -15.727097) (xy 310.568403 -15.743192) (xy 310.513188 -15.751325) (xy 310.485282 -15.75181)
			(xy 310.458032 -15.751319) (xy 310.404086 -15.74356) (xy 310.351794 -15.728204) (xy 310.302219 -15.705562)
			(xy 310.256371 -15.676095) (xy 310.215183 -15.640404) (xy 310.179494 -15.599214) (xy 310.15003 -15.553365)
			(xy 310.12739 -15.503789) (xy 310.112036 -15.451496) (xy 310.10428 -15.39755) (xy 304.938734 -15.39755)
			(xy 304.945993 -15.457565) (xy 304.953722 -15.585748) (xy 304.954178 -15.649956) (xy 304.953702 -15.714428)
			(xy 304.945919 -15.843137) (xy 304.930379 -15.971141) (xy 304.907138 -16.097974) (xy 304.876282 -16.223171)
			(xy 304.837922 -16.346277) (xy 304.792199 -16.466843) (xy 304.73928 -16.584427) (xy 304.679358 -16.698602)
			(xy 304.612652 -16.808951) (xy 304.539404 -16.91507) (xy 304.496374 -16.969994) (xy 323.948051 -16.969994)
			(xy 323.952056 -16.882086) (xy 323.964039 -16.794906) (xy 323.983899 -16.709177) (xy 324.011474 -16.625609)
			(xy 324.046533 -16.544895) (xy 324.088786 -16.467703) (xy 324.137884 -16.394674) (xy 324.19342 -16.326412)
			(xy 324.254932 -16.263482) (xy 324.321913 -16.206408) (xy 324.393806 -16.15566) (xy 324.470015 -16.11166)
			(xy 324.54991 -16.074773) (xy 324.632829 -16.045304) (xy 324.718084 -16.023497) (xy 324.804968 -16.009533)
			(xy 324.892762 -16.003527) (xy 324.980739 -16.005531) (xy 325.068169 -16.015526) (xy 325.154328 -16.03343)
			(xy 325.238502 -16.059094) (xy 325.319993 -16.092307) (xy 325.398127 -16.132793) (xy 325.472255 -16.180215)
			(xy 325.541763 -16.234182) (xy 325.606077 -16.294247) (xy 325.664661 -16.359911) (xy 325.717032 -16.43063)
			(xy 325.762755 -16.505818) (xy 325.801452 -16.584853) (xy 325.832801 -16.667079) (xy 325.856543 -16.751815)
			(xy 325.872481 -16.838359) (xy 325.880483 -16.925994) (xy 325.880984 -16.969994) (xy 325.880483 -17.013994)
			(xy 325.872481 -17.101629) (xy 325.856543 -17.188173) (xy 325.832801 -17.272909) (xy 325.801452 -17.355135)
			(xy 325.762755 -17.43417) (xy 325.717032 -17.509358) (xy 325.664661 -17.580077) (xy 325.606077 -17.645741)
			(xy 325.541763 -17.705806) (xy 325.472255 -17.759773) (xy 325.398127 -17.807195) (xy 325.319993 -17.847681)
			(xy 325.238502 -17.880894) (xy 325.154328 -17.906558) (xy 325.068169 -17.924462) (xy 324.980739 -17.934457)
			(xy 324.892762 -17.936461) (xy 324.804968 -17.930455) (xy 324.718084 -17.916491) (xy 324.632829 -17.894684)
			(xy 324.54991 -17.865215) (xy 324.470015 -17.828328) (xy 324.393806 -17.784328) (xy 324.321913 -17.73358)
			(xy 324.254932 -17.676506) (xy 324.19342 -17.613576) (xy 324.137884 -17.545314) (xy 324.088786 -17.472285)
			(xy 324.046533 -17.395093) (xy 324.011474 -17.314379) (xy 323.983899 -17.230811) (xy 323.964039 -17.145082)
			(xy 323.952056 -17.057902) (xy 323.948051 -16.969994) (xy 304.496374 -16.969994) (xy 304.459882 -17.016573)
			(xy 304.374377 -17.11309) (xy 304.2832 -17.204267) (xy 304.186684 -17.289773) (xy 304.085182 -17.369296)
			(xy 304.012341 -17.419574) (xy 308.484014 -17.419574) (xy 308.488085 -17.363952) (xy 308.500211 -17.309515)
			(xy 308.520134 -17.257424) (xy 308.54743 -17.208789) (xy 308.581516 -17.164646) (xy 308.621665 -17.125937)
			(xy 308.667023 -17.093486) (xy 308.716623 -17.067985) (xy 308.769407 -17.049978) (xy 308.82425 -17.039848)
			(xy 308.879984 -17.037811) (xy 308.935421 -17.043911) (xy 308.989378 -17.058017) (xy 309.040707 -17.079829)
			(xy 309.088313 -17.108883) (xy 309.131181 -17.144558) (xy 309.168398 -17.186095) (xy 309.199171 -17.232608)
			(xy 309.222843 -17.283105) (xy 309.238911 -17.336512) (xy 309.247031 -17.391688) (xy 309.24754 -17.419574)
			(xy 309.247031 -17.44746) (xy 309.238911 -17.502636) (xy 309.222843 -17.556043) (xy 309.199171 -17.60654)
			(xy 309.168398 -17.653053) (xy 309.131181 -17.69459) (xy 309.088313 -17.730265) (xy 309.040707 -17.759319)
			(xy 308.989378 -17.781131) (xy 308.935421 -17.795237) (xy 308.879984 -17.801337) (xy 308.82425 -17.7993)
			(xy 308.769407 -17.78917) (xy 308.716623 -17.771163) (xy 308.667023 -17.745662) (xy 308.621665 -17.713211)
			(xy 308.581516 -17.674502) (xy 308.54743 -17.630359) (xy 308.520134 -17.581724) (xy 308.500211 -17.529633)
			(xy 308.488085 -17.475196) (xy 308.484014 -17.419574) (xy 304.012341 -17.419574) (xy 303.979063 -17.442544)
			(xy 303.868715 -17.509251) (xy 303.75454 -17.569174) (xy 303.636956 -17.622094) (xy 303.516391 -17.667818)
			(xy 303.393285 -17.706178) (xy 303.268087 -17.737035) (xy 303.141255 -17.760277) (xy 303.013251 -17.775818)
			(xy 302.884542 -17.783602) (xy 302.82007 -17.784064) (xy 302.755706 -17.78358) (xy 302.627213 -17.775818)
			(xy 302.499421 -17.760326) (xy 302.372795 -17.73716) (xy 302.247796 -17.706402) (xy 302.124878 -17.668167)
			(xy 302.004488 -17.622591) (xy 301.887064 -17.569842) (xy 301.773033 -17.510111) (xy 301.66281 -17.443615)
			(xy 301.556796 -17.370597) (xy 301.455375 -17.291321) (xy 301.358918 -17.206075) (xy 301.267774 -17.115171)
			(xy 301.182275 -17.018938) (xy 301.102732 -16.917726) (xy 301.029435 -16.811904) (xy 300.96265 -16.701857)
			(xy 300.902619 -16.587983) (xy 300.849561 -16.470699) (xy 300.803669 -16.350429) (xy 300.76511 -16.227612)
			(xy 300.734024 -16.102694) (xy 300.710524 -15.97613) (xy 300.694696 -15.848379) (xy 300.686597 -15.719906)
			(xy 300.685962 -15.655544) (xy 300.685962 -15.649448) (xy 300.686527 -15.580406) (xy 300.695471 -15.442612)
			(xy 300.713304 -15.305685) (xy 300.739953 -15.170197) (xy 300.775305 -15.036715) (xy 300.819214 -14.905799)
			(xy 300.871494 -14.777994) (xy 300.931928 -14.653838) (xy 300.965616 -14.59357) (xy 300.96841 -14.588744)
			(xy 300.970303 -14.583944) (xy 300.972357 -14.573836) (xy 300.972474 -14.568678) (xy 300.972474 -14.554962)
			(xy 300.93158 -14.484604) (xy 300.922436 -14.468856) (xy 300.922182 -14.468602) (xy 300.92015 -14.46403)
			(xy 300.910498 -14.453108) (xy 300.904402 -14.449298) (xy 300.899151 -14.446242) (xy 300.887589 -14.44252)
			(xy 300.881542 -14.441932) (xy 300.877732 -14.441678) (xy 291.661596 -14.441678) (xy 291.651527 -14.441254)
			(xy 291.632925 -14.433536) (xy 291.625528 -14.426692) (xy 290.366958 -13.168122) (xy 290.360117 -13.160722)
			(xy 290.352402 -13.142123) (xy 290.351972 -13.132054) (xy 290.351972 -2.221484) (xy 290.351972 -2.22123)
			(xy 290.351833 -2.21634) (xy 290.349911 -2.206749) (xy 290.348162 -2.20218) (xy 290.347908 -2.201672)
			(xy 290.347908 -0.91059) (xy 290.347484 -0.90052) (xy 290.339767 -0.881918) (xy 290.332922 -0.874522)
			(xy 290.159186 -0.700786) (xy 290.151791 -0.693932) (xy 290.133192 -0.68619) (xy 290.123118 -0.6858)
			(xy 278.506682 -0.6858) (xy 278.496613 -0.686227) (xy 278.478014 -0.693946) (xy 278.470614 -0.700786)
			(xy 278.273764 -0.897636) (xy 278.266916 -0.905033) (xy 278.259185 -0.923632) (xy 278.258778 -0.933704)
			(xy 278.258778 -12.190222) (xy 278.25835 -12.20029) (xy 278.250628 -12.218887) (xy 278.243792 -12.22629)
			(xy 277.100284 -13.369798) (xy 277.093902 -13.376635) (xy 277.086261 -13.393692) (xy 277.085298 -13.412358)
			(xy 277.087838 -13.42136) (xy 277.101808 -13.464286) (xy 277.101808 -13.464794) (xy 277.116286 -13.508228)
			(xy 277.118716 -13.514747) (xy 277.126573 -13.526221) (xy 277.13178 -13.530834) (xy 277.156164 -13.54201)
			(xy 277.162006 -13.543026) (xy 277.163276 -13.54328) (xy 277.227735 -13.554281) (xy 277.355283 -13.583172)
			(xy 277.480823 -13.619819) (xy 277.603882 -13.664086) (xy 277.724 -13.715806) (xy 277.840724 -13.774785)
			(xy 277.953618 -13.840802) (xy 278.062257 -13.913608) (xy 278.166233 -13.992931) (xy 278.265156 -14.078473)
			(xy 278.358655 -14.169912) (xy 278.446379 -14.266905) (xy 278.527998 -14.369089) (xy 278.603206 -14.476079)
			(xy 278.671721 -14.587475) (xy 278.733285 -14.702857) (xy 278.74812 -14.735302) (xy 282.772356 -14.735302)
			(xy 282.776427 -14.67968) (xy 282.788553 -14.625243) (xy 282.808476 -14.573152) (xy 282.835772 -14.524517)
			(xy 282.869858 -14.480374) (xy 282.910007 -14.441665) (xy 282.955365 -14.409214) (xy 283.004965 -14.383713)
			(xy 283.057749 -14.365706) (xy 283.112592 -14.355576) (xy 283.168326 -14.353539) (xy 283.223763 -14.359639)
			(xy 283.27772 -14.373745) (xy 283.329049 -14.395557) (xy 283.376655 -14.424611) (xy 283.419523 -14.460286)
			(xy 283.45674 -14.501823) (xy 283.487513 -14.548336) (xy 283.511185 -14.598833) (xy 283.527253 -14.65224)
			(xy 283.535373 -14.707416) (xy 283.535882 -14.735302) (xy 283.535373 -14.763188) (xy 283.527253 -14.818364)
			(xy 283.511185 -14.871771) (xy 283.487513 -14.922268) (xy 283.45674 -14.968781) (xy 283.419523 -15.010318)
			(xy 283.376655 -15.045993) (xy 283.329049 -15.075047) (xy 283.27772 -15.096859) (xy 283.223763 -15.110965)
			(xy 283.168326 -15.117065) (xy 283.112592 -15.115028) (xy 283.057749 -15.104898) (xy 283.004965 -15.086891)
			(xy 282.955365 -15.06139) (xy 282.910007 -15.028939) (xy 282.869858 -14.99023) (xy 282.835772 -14.946087)
			(xy 282.808476 -14.897452) (xy 282.788553 -14.845361) (xy 282.776427 -14.790924) (xy 282.772356 -14.735302)
			(xy 278.74812 -14.735302) (xy 278.787667 -14.821793) (xy 278.834664 -14.943836) (xy 278.874098 -15.068528)
			(xy 278.905822 -15.195401) (xy 278.929717 -15.323978) (xy 278.938773 -15.397554) (xy 284.104257 -15.397554)
			(xy 284.104257 -15.343046) (xy 284.112015 -15.289092) (xy 284.127373 -15.236792) (xy 284.150018 -15.18721)
			(xy 284.179489 -15.141355) (xy 284.215186 -15.100162) (xy 284.256382 -15.064468) (xy 284.30224 -15.035001)
			(xy 284.351824 -15.012361) (xy 284.404125 -14.997008) (xy 284.45808 -14.989255) (xy 284.485334 -14.988794)
			(xy 284.511571 -14.989231) (xy 284.563547 -14.996431) (xy 284.614046 -15.01069) (xy 284.662112 -15.031738)
			(xy 284.706839 -15.059179) (xy 284.74738 -15.092493) (xy 284.765496 -15.111476) (xy 284.76575 -15.11173)
			(xy 284.773486 -15.119108) (xy 284.793167 -15.127385) (xy 284.80385 -15.127732) (xy 284.891734 -15.125446)
			(xy 284.911292 -15.116048) (xy 284.918404 -15.107412) (xy 284.936587 -15.086236) (xy 284.978133 -15.048963)
			(xy 285.024668 -15.018144) (xy 285.075199 -14.994438) (xy 285.128646 -14.97835) (xy 285.183866 -14.970225)
			(xy 285.211774 -14.969744) (xy 285.239025 -14.970301) (xy 285.292972 -14.978054) (xy 285.345266 -14.993406)
			(xy 285.394843 -15.016044) (xy 285.440694 -15.045508) (xy 285.481884 -15.081197) (xy 285.517576 -15.122385)
			(xy 285.547043 -15.168234) (xy 285.569685 -15.21781) (xy 285.58504 -15.270103) (xy 285.592797 -15.324049)
			(xy 285.592797 -15.378551) (xy 285.58504 -15.432497) (xy 285.569685 -15.48479) (xy 285.547043 -15.534366)
			(xy 285.517576 -15.580215) (xy 285.481884 -15.621403) (xy 285.440694 -15.657092) (xy 285.394843 -15.686556)
			(xy 285.345266 -15.709194) (xy 285.292972 -15.724546) (xy 285.239025 -15.732299) (xy 285.211774 -15.73276)
			(xy 285.185537 -15.732332) (xy 285.133559 -15.725133) (xy 285.08306 -15.710873) (xy 285.034993 -15.689823)
			(xy 284.990267 -15.66238) (xy 284.949727 -15.629063) (xy 284.931612 -15.610078) (xy 284.931358 -15.609824)
			(xy 284.923625 -15.602443) (xy 284.903942 -15.59417) (xy 284.893258 -15.593822) (xy 284.805374 -15.596108)
			(xy 284.785816 -15.605506) (xy 284.778704 -15.614142) (xy 284.760506 -15.635305) (xy 284.718965 -15.672581)
			(xy 284.672433 -15.703402) (xy 284.621905 -15.727111) (xy 284.56846 -15.743201) (xy 284.513241 -15.751328)
			(xy 284.485334 -15.75181) (xy 284.45808 -15.751345) (xy 284.404125 -15.743592) (xy 284.351824 -15.728239)
			(xy 284.30224 -15.705599) (xy 284.256382 -15.676132) (xy 284.215186 -15.640438) (xy 284.179489 -15.599245)
			(xy 284.150018 -15.55339) (xy 284.127373 -15.503808) (xy 284.112015 -15.451508) (xy 284.104257 -15.397554)
			(xy 278.938773 -15.397554) (xy 278.945693 -15.453778) (xy 278.953689 -15.584312) (xy 278.95423 -15.649702)
			(xy 278.95423 -15.649956) (xy 278.953754 -15.714429) (xy 278.945971 -15.843139) (xy 278.930431 -15.971144)
			(xy 278.90719 -16.097978) (xy 278.876334 -16.223177) (xy 278.837975 -16.346284) (xy 278.792252 -16.466851)
			(xy 278.739334 -16.584437) (xy 278.679412 -16.698613) (xy 278.612706 -16.808963) (xy 278.539458 -16.915084)
			(xy 278.49644 -16.969994) (xy 297.948103 -16.969994) (xy 297.952108 -16.882086) (xy 297.964091 -16.794906)
			(xy 297.983951 -16.709177) (xy 298.011526 -16.625609) (xy 298.046585 -16.544895) (xy 298.088838 -16.467703)
			(xy 298.137936 -16.394674) (xy 298.193472 -16.326412) (xy 298.254984 -16.263482) (xy 298.321965 -16.206408)
			(xy 298.393858 -16.15566) (xy 298.470067 -16.11166) (xy 298.549962 -16.074773) (xy 298.632881 -16.045304)
			(xy 298.718136 -16.023497) (xy 298.80502 -16.009533) (xy 298.892814 -16.003527) (xy 298.980791 -16.005531)
			(xy 299.068221 -16.015526) (xy 299.15438 -16.03343) (xy 299.238554 -16.059094) (xy 299.320045 -16.092307)
			(xy 299.398179 -16.132793) (xy 299.472307 -16.180215) (xy 299.541815 -16.234182) (xy 299.606129 -16.294247)
			(xy 299.664713 -16.359911) (xy 299.717084 -16.43063) (xy 299.762807 -16.505818) (xy 299.801504 -16.584853)
			(xy 299.832853 -16.667079) (xy 299.856595 -16.751815) (xy 299.872533 -16.838359) (xy 299.880535 -16.925994)
			(xy 299.881036 -16.969994) (xy 299.880535 -17.013994) (xy 299.872533 -17.101629) (xy 299.856595 -17.188173)
			(xy 299.832853 -17.272909) (xy 299.801504 -17.355135) (xy 299.762807 -17.43417) (xy 299.717084 -17.509358)
			(xy 299.664713 -17.580077) (xy 299.606129 -17.645741) (xy 299.541815 -17.705806) (xy 299.472307 -17.759773)
			(xy 299.398179 -17.807195) (xy 299.320045 -17.847681) (xy 299.238554 -17.880894) (xy 299.15438 -17.906558)
			(xy 299.068221 -17.924462) (xy 298.980791 -17.934457) (xy 298.892814 -17.936461) (xy 298.80502 -17.930455)
			(xy 298.718136 -17.916491) (xy 298.632881 -17.894684) (xy 298.549962 -17.865215) (xy 298.470067 -17.828328)
			(xy 298.393858 -17.784328) (xy 298.321965 -17.73358) (xy 298.254984 -17.676506) (xy 298.193472 -17.613576)
			(xy 298.137936 -17.545314) (xy 298.088838 -17.472285) (xy 298.046585 -17.395093) (xy 298.011526 -17.314379)
			(xy 297.983951 -17.230811) (xy 297.964091 -17.145082) (xy 297.952108 -17.057902) (xy 297.948103 -16.969994)
			(xy 278.49644 -16.969994) (xy 278.459937 -17.016589) (xy 278.374432 -17.113107) (xy 278.283255 -17.204287)
			(xy 278.18674 -17.289795) (xy 278.085237 -17.369319) (xy 278.012433 -17.419574) (xy 282.484066 -17.419574)
			(xy 282.488137 -17.363952) (xy 282.500263 -17.309515) (xy 282.520186 -17.257424) (xy 282.547482 -17.208789)
			(xy 282.581568 -17.164646) (xy 282.621717 -17.125937) (xy 282.667075 -17.093486) (xy 282.716675 -17.067985)
			(xy 282.769459 -17.049978) (xy 282.824302 -17.039848) (xy 282.880036 -17.037811) (xy 282.935473 -17.043911)
			(xy 282.98943 -17.058017) (xy 283.040759 -17.079829) (xy 283.088365 -17.108883) (xy 283.131233 -17.144558)
			(xy 283.16845 -17.186095) (xy 283.199223 -17.232608) (xy 283.222895 -17.283105) (xy 283.238963 -17.336512)
			(xy 283.247083 -17.391688) (xy 283.247592 -17.419574) (xy 283.247083 -17.44746) (xy 283.238963 -17.502636)
			(xy 283.222895 -17.556043) (xy 283.199223 -17.60654) (xy 283.16845 -17.653053) (xy 283.131233 -17.69459)
			(xy 283.088365 -17.730265) (xy 283.040759 -17.759319) (xy 282.98943 -17.781131) (xy 282.935473 -17.795237)
			(xy 282.880036 -17.801337) (xy 282.824302 -17.7993) (xy 282.769459 -17.78917) (xy 282.716675 -17.771163)
			(xy 282.667075 -17.745662) (xy 282.621717 -17.713211) (xy 282.581568 -17.674502) (xy 282.547482 -17.630359)
			(xy 282.520186 -17.581724) (xy 282.500263 -17.529633) (xy 282.488137 -17.475196) (xy 282.484066 -17.419574)
			(xy 278.012433 -17.419574) (xy 277.979119 -17.44257) (xy 277.868771 -17.50928) (xy 277.754596 -17.569205)
			(xy 277.637012 -17.622127) (xy 277.516446 -17.667853) (xy 277.39334 -17.706216) (xy 277.268142 -17.737077)
			(xy 277.141309 -17.760321) (xy 277.013304 -17.775865) (xy 276.884595 -17.783652) (xy 276.820122 -17.784064)
			(xy 276.75585 -17.783584) (xy 276.627539 -17.775848) (xy 276.499926 -17.760403) (xy 276.373474 -17.737305)
			(xy 276.248642 -17.706638) (xy 276.125882 -17.668512) (xy 276.005639 -17.623067) (xy 275.88835 -17.570467)
			(xy 275.774439 -17.510902) (xy 275.66432 -17.444589) (xy 275.558393 -17.371768) (xy 275.45704 -17.292703)
			(xy 275.36063 -17.207681) (xy 275.269513 -17.117011) (xy 275.184018 -17.02102) (xy 275.104456 -16.920057)
			(xy 275.031115 -16.814489) (xy 274.964261 -16.704697) (xy 274.904137 -16.591081) (xy 274.850961 -16.474052)
			(xy 274.804925 -16.354034) (xy 274.766196 -16.231463) (xy 274.734916 -16.106783) (xy 274.711196 -15.980446)
			(xy 274.695124 -15.852911) (xy 274.686758 -15.724639) (xy 274.686014 -15.66037) (xy 274.686014 -15.647924)
			(xy 274.686504 -15.586166) (xy 274.693741 -15.462861) (xy 274.708094 -15.34018) (xy 274.729516 -15.218534)
			(xy 274.757933 -15.098331) (xy 274.793253 -14.979971) (xy 274.835355 -14.86385) (xy 274.8841 -14.750358)
			(xy 274.911312 -14.694916) (xy 274.912836 -14.691868) (xy 274.916138 -14.68247) (xy 274.917662 -14.676628)
			(xy 274.917662 -14.676374) (xy 274.919948 -14.6685) (xy 274.920456 -14.666214) (xy 274.918932 -14.656308)
			(xy 274.918052 -14.651492) (xy 274.914735 -14.642283) (xy 274.912328 -14.63802) (xy 274.901152 -14.619732)
			(xy 274.901152 -14.619224) (xy 274.870672 -14.570202) (xy 274.86483 -14.56309) (xy 274.85721 -14.55547)
			(xy 274.85348 -14.551947) (xy 274.844907 -14.546316) (xy 274.840192 -14.544294) (xy 274.831556 -14.540738)
			(xy 265.790426 -14.540738) (xy 265.780363 -14.5403) (xy 265.761784 -14.532559) (xy 265.754358 -14.525752)
			(xy 264.396474 -13.167868) (xy 264.389625 -13.160471) (xy 264.38189 -13.141872) (xy 264.381488 -13.1318)
			(xy 264.381488 -1.92405) (xy 264.381234 -1.918462) (xy 264.38075 -1.914796) (xy 264.378842 -1.907653)
			(xy 264.377424 -1.904238) (xy 264.373868 -1.89611) (xy 264.367264 -1.889252) (xy 264.364724 -1.886204)
			(xy 264.362946 -1.883918) (xy 264.04951 -1.570482) (xy 264.046658 -1.567778) (xy 264.040278 -1.563188)
			(xy 264.03681 -1.561338) (xy 264.031383 -1.558758) (xy 264.019703 -1.555943) (xy 264.013696 -1.55575)
			(xy 252.464062 -1.55575) (xy 252.454156 -1.556766) (xy 252.453902 -1.556766) (xy 252.438916 -1.559814)
			(xy 252.431042 -1.56337) (xy 252.423168 -1.570482) (xy 252.42266 -1.57099) (xy 252.420882 -1.572514)
			(xy 252.418596 -1.574292) (xy 251.807726 -2.185162) (xy 251.805019 -2.188012) (xy 251.800422 -2.194389)
			(xy 251.798582 -2.197862) (xy 251.796002 -2.20329) (xy 251.793183 -2.214969) (xy 251.792994 -2.220976)
			(xy 251.792994 -12.98321) (xy 251.792569 -12.993279) (xy 251.784851 -13.01188) (xy 251.778008 -13.019278)
			(xy 251.365512 -13.431774) (xy 251.362972 -13.434568) (xy 251.356291 -13.443674) (xy 251.350758 -13.465544)
			(xy 251.352304 -13.476732) (xy 251.369576 -13.544042) (xy 251.369576 -13.54455) (xy 251.374402 -13.562584)
			(xy 251.378466 -13.573506) (xy 251.383105 -13.581492) (xy 251.396901 -13.593748) (xy 251.40539 -13.597382)
			(xy 251.408946 -13.598652) (xy 251.410978 -13.599414) (xy 251.412502 -13.599922) (xy 251.412756 -13.599922)
			(xy 251.475553 -13.618604) (xy 251.598952 -13.662662) (xy 251.719417 -13.714208) (xy 251.836492 -13.773047)
			(xy 251.949737 -13.838959) (xy 252.058724 -13.911694) (xy 252.163044 -13.990978) (xy 252.262303 -14.076514)
			(xy 252.286705 -14.100302) (xy 257.442968 -14.100302) (xy 257.447039 -14.04468) (xy 257.459165 -13.990243)
			(xy 257.479088 -13.938152) (xy 257.506384 -13.889517) (xy 257.54047 -13.845374) (xy 257.580619 -13.806665)
			(xy 257.625977 -13.774214) (xy 257.675577 -13.748713) (xy 257.728361 -13.730706) (xy 257.783204 -13.720576)
			(xy 257.838938 -13.718539) (xy 257.894375 -13.724639) (xy 257.948332 -13.738745) (xy 257.999661 -13.760557)
			(xy 258.047267 -13.789611) (xy 258.090135 -13.825286) (xy 258.127352 -13.866823) (xy 258.158125 -13.913336)
			(xy 258.181797 -13.963833) (xy 258.197865 -14.01724) (xy 258.205985 -14.072416) (xy 258.206494 -14.100302)
			(xy 258.205985 -14.128188) (xy 258.197865 -14.183364) (xy 258.181797 -14.236771) (xy 258.158125 -14.287268)
			(xy 258.127352 -14.333781) (xy 258.090135 -14.375318) (xy 258.047267 -14.410993) (xy 257.999661 -14.440047)
			(xy 257.948332 -14.461859) (xy 257.894375 -14.475965) (xy 257.838938 -14.482065) (xy 257.783204 -14.480028)
			(xy 257.728361 -14.469898) (xy 257.675577 -14.451891) (xy 257.625977 -14.42639) (xy 257.580619 -14.393939)
			(xy 257.54047 -14.35523) (xy 257.506384 -14.311087) (xy 257.479088 -14.262452) (xy 257.459165 -14.210361)
			(xy 257.447039 -14.155924) (xy 257.442968 -14.100302) (xy 252.286705 -14.100302) (xy 252.356127 -14.167978)
			(xy 252.444164 -14.265025) (xy 252.52608 -14.367292) (xy 252.601568 -14.474391) (xy 252.670343 -14.58592)
			(xy 252.732146 -14.701458) (xy 252.786744 -14.82057) (xy 252.833932 -14.942807) (xy 252.873531 -15.06771)
			(xy 252.905393 -15.194806) (xy 252.929397 -15.323618) (xy 252.938525 -15.39755) (xy 258.10438 -15.39755)
			(xy 258.10438 -15.34305) (xy 258.112136 -15.289103) (xy 258.12749 -15.23681) (xy 258.15013 -15.187234)
			(xy 258.179595 -15.141384) (xy 258.215285 -15.100195) (xy 258.256473 -15.064503) (xy 258.302322 -15.035037)
			(xy 258.351897 -15.012395) (xy 258.40419 -14.997039) (xy 258.458136 -14.989281) (xy 258.485386 -14.988794)
			(xy 258.511621 -14.989263) (xy 258.563597 -14.996456) (xy 258.614095 -15.010709) (xy 258.662161 -15.031751)
			(xy 258.706889 -15.059186) (xy 258.747431 -15.092496) (xy 258.765548 -15.111476) (xy 258.765802 -15.11173)
			(xy 258.773518 -15.119132) (xy 258.793214 -15.127395) (xy 258.803902 -15.127732) (xy 258.891786 -15.125446)
			(xy 258.911344 -15.116048) (xy 258.918456 -15.107412) (xy 258.936664 -15.086259) (xy 258.978205 -15.048984)
			(xy 259.024735 -15.018163) (xy 259.075261 -14.994453) (xy 259.128703 -14.97836) (xy 259.18392 -14.970229)
			(xy 259.211826 -14.969744) (xy 259.239073 -14.970328) (xy 259.293011 -14.978086) (xy 259.345296 -14.993442)
			(xy 259.394863 -15.016082) (xy 259.440705 -15.045545) (xy 259.481887 -15.081232) (xy 259.517571 -15.122416)
			(xy 259.547031 -15.16826) (xy 259.569667 -15.217829) (xy 259.585019 -15.270115) (xy 259.592774 -15.324053)
			(xy 259.592774 -15.378547) (xy 259.585019 -15.432485) (xy 259.569667 -15.484771) (xy 259.547031 -15.53434)
			(xy 259.517571 -15.580184) (xy 259.481887 -15.621368) (xy 259.440705 -15.657055) (xy 259.394863 -15.686518)
			(xy 259.345296 -15.709158) (xy 259.293011 -15.724514) (xy 259.239073 -15.732272) (xy 259.211826 -15.73276)
			(xy 259.18559 -15.732298) (xy 259.133614 -15.725105) (xy 259.083115 -15.710852) (xy 259.035048 -15.689809)
			(xy 258.990321 -15.662372) (xy 258.94978 -15.62906) (xy 258.931664 -15.610078) (xy 258.93141 -15.609824)
			(xy 258.923695 -15.602421) (xy 258.903998 -15.59416) (xy 258.89331 -15.593822) (xy 258.805426 -15.596108)
			(xy 258.785868 -15.605506) (xy 258.778756 -15.614142) (xy 258.760531 -15.63528) (xy 258.718995 -15.672558)
			(xy 258.672469 -15.703382) (xy 258.621946 -15.727096) (xy 258.568506 -15.743191) (xy 258.513291 -15.751324)
			(xy 258.485386 -15.75181) (xy 258.458136 -15.751319) (xy 258.40419 -15.743561) (xy 258.351897 -15.728205)
			(xy 258.302322 -15.705563) (xy 258.256473 -15.676097) (xy 258.215285 -15.640405) (xy 258.179595 -15.599216)
			(xy 258.15013 -15.553366) (xy 258.12749 -15.50379) (xy 258.112136 -15.451497) (xy 258.10438 -15.39755)
			(xy 252.938525 -15.39755) (xy 252.945453 -15.45366) (xy 252.9535 -15.584441) (xy 252.954028 -15.649956)
			(xy 252.953552 -15.714429) (xy 252.945769 -15.843139) (xy 252.930229 -15.971144) (xy 252.906988 -16.097977)
			(xy 252.876132 -16.223176) (xy 252.837773 -16.346284) (xy 252.79205 -16.46685) (xy 252.739132 -16.584436)
			(xy 252.67921 -16.698613) (xy 252.612504 -16.808963) (xy 252.539256 -16.915084) (xy 252.496238 -16.969994)
			(xy 271.948155 -16.969994) (xy 271.95216 -16.882086) (xy 271.964143 -16.794906) (xy 271.984003 -16.709177)
			(xy 272.011578 -16.625609) (xy 272.046637 -16.544895) (xy 272.08889 -16.467703) (xy 272.137988 -16.394674)
			(xy 272.193524 -16.326412) (xy 272.255036 -16.263482) (xy 272.322017 -16.206408) (xy 272.39391 -16.15566)
			(xy 272.470119 -16.11166) (xy 272.550014 -16.074773) (xy 272.632933 -16.045304) (xy 272.718188 -16.023497)
			(xy 272.805072 -16.009533) (xy 272.892866 -16.003527) (xy 272.980843 -16.005531) (xy 273.068273 -16.015526)
			(xy 273.154432 -16.03343) (xy 273.238606 -16.059094) (xy 273.320097 -16.092307) (xy 273.398231 -16.132793)
			(xy 273.472359 -16.180215) (xy 273.541867 -16.234182) (xy 273.606181 -16.294247) (xy 273.664765 -16.359911)
			(xy 273.717136 -16.43063) (xy 273.762859 -16.505818) (xy 273.801556 -16.584853) (xy 273.832905 -16.667079)
			(xy 273.856647 -16.751815) (xy 273.872585 -16.838359) (xy 273.880587 -16.925994) (xy 273.881088 -16.969994)
			(xy 273.880587 -17.013994) (xy 273.872585 -17.101629) (xy 273.856647 -17.188173) (xy 273.832905 -17.272909)
			(xy 273.801556 -17.355135) (xy 273.762859 -17.43417) (xy 273.717136 -17.509358) (xy 273.664765 -17.580077)
			(xy 273.606181 -17.645741) (xy 273.541867 -17.705806) (xy 273.472359 -17.759773) (xy 273.398231 -17.807195)
			(xy 273.320097 -17.847681) (xy 273.238606 -17.880894) (xy 273.154432 -17.906558) (xy 273.068273 -17.924462)
			(xy 272.980843 -17.934457) (xy 272.892866 -17.936461) (xy 272.805072 -17.930455) (xy 272.718188 -17.916491)
			(xy 272.632933 -17.894684) (xy 272.550014 -17.865215) (xy 272.470119 -17.828328) (xy 272.39391 -17.784328)
			(xy 272.322017 -17.73358) (xy 272.255036 -17.676506) (xy 272.193524 -17.613576) (xy 272.137988 -17.545314)
			(xy 272.08889 -17.472285) (xy 272.046637 -17.395093) (xy 272.011578 -17.314379) (xy 271.984003 -17.230811)
			(xy 271.964143 -17.145082) (xy 271.95216 -17.057902) (xy 271.948155 -16.969994) (xy 252.496238 -16.969994)
			(xy 252.459735 -17.016588) (xy 252.37423 -17.113107) (xy 252.283053 -17.204286) (xy 252.186538 -17.289794)
			(xy 252.085035 -17.369318) (xy 252.012229 -17.419574) (xy 256.484118 -17.419574) (xy 256.488189 -17.363952)
			(xy 256.500315 -17.309515) (xy 256.520238 -17.257424) (xy 256.547534 -17.208789) (xy 256.58162 -17.164646)
			(xy 256.621769 -17.125937) (xy 256.667127 -17.093486) (xy 256.716727 -17.067985) (xy 256.769511 -17.049978)
			(xy 256.824354 -17.039848) (xy 256.880088 -17.037811) (xy 256.935525 -17.043911) (xy 256.989482 -17.058017)
			(xy 257.040811 -17.079829) (xy 257.088417 -17.108883) (xy 257.131285 -17.144558) (xy 257.168502 -17.186095)
			(xy 257.199275 -17.232608) (xy 257.222947 -17.283105) (xy 257.239015 -17.336512) (xy 257.247135 -17.391688)
			(xy 257.247644 -17.419574) (xy 257.247135 -17.44746) (xy 257.239015 -17.502636) (xy 257.222947 -17.556043)
			(xy 257.199275 -17.60654) (xy 257.168502 -17.653053) (xy 257.131285 -17.69459) (xy 257.088417 -17.730265)
			(xy 257.040811 -17.759319) (xy 256.989482 -17.781131) (xy 256.935525 -17.795237) (xy 256.880088 -17.801337)
			(xy 256.824354 -17.7993) (xy 256.769511 -17.78917) (xy 256.716727 -17.771163) (xy 256.667127 -17.745662)
			(xy 256.621769 -17.713211) (xy 256.58162 -17.674502) (xy 256.547534 -17.630359) (xy 256.520238 -17.581724)
			(xy 256.500315 -17.529633) (xy 256.488189 -17.475196) (xy 256.484118 -17.419574) (xy 252.012229 -17.419574)
			(xy 251.978916 -17.442569) (xy 251.868568 -17.509278) (xy 251.754394 -17.569204) (xy 251.636809 -17.622126)
			(xy 251.516244 -17.667852) (xy 251.393138 -17.706215) (xy 251.26794 -17.737075) (xy 251.141107 -17.760319)
			(xy 251.013102 -17.775863) (xy 250.884393 -17.78365) (xy 250.81992 -17.784064) (xy 250.815094 -17.784064)
			(xy 250.750623 -17.783586) (xy 250.621917 -17.775801) (xy 250.493915 -17.760258) (xy 250.367085 -17.737015)
			(xy 250.24189 -17.706156) (xy 250.118787 -17.667795) (xy 249.998225 -17.622071) (xy 249.880643 -17.569151)
			(xy 249.766471 -17.509227) (xy 249.656126 -17.44252) (xy 249.550009 -17.369272) (xy 249.448509 -17.28975)
			(xy 249.351996 -17.204244) (xy 249.260821 -17.113068) (xy 249.175318 -17.016552) (xy 249.095799 -16.91505)
			(xy 249.022553 -16.808932) (xy 248.955848 -16.698585) (xy 248.895928 -16.584412) (xy 248.84301 -16.466829)
			(xy 248.797289 -16.346266) (xy 248.75893 -16.223161) (xy 248.728075 -16.097966) (xy 248.704835 -15.971136)
			(xy 248.689295 -15.843134) (xy 248.681512 -15.714427) (xy 248.680986 -15.649956) (xy 248.680986 -15.64894)
			(xy 248.681525 -15.580122) (xy 248.690373 -15.44277) (xy 248.708055 -15.306274) (xy 248.734496 -15.171201)
			(xy 248.769588 -15.038113) (xy 248.813183 -14.907563) (xy 248.865101 -14.780095) (xy 248.925127 -14.656237)
			(xy 248.958608 -14.59611) (xy 248.962418 -14.589252) (xy 248.965466 -14.57452) (xy 248.966516 -14.566315)
			(xy 248.963937 -14.549986) (xy 248.960386 -14.542516) (xy 248.940574 -14.50848) (xy 248.919238 -14.472158)
			(xy 248.915936 -14.466316) (xy 248.914666 -14.464284) (xy 248.90715 -14.454223) (xy 248.885041 -14.442375)
			(xy 248.872502 -14.441678) (xy 240.166906 -14.441678) (xy 240.156836 -14.441255) (xy 240.138232 -14.43354)
			(xy 240.130838 -14.426692) (xy 238.574834 -12.870688) (xy 238.567986 -12.86329) (xy 238.56025 -12.844692)
			(xy 238.559848 -12.83462) (xy 238.559848 -1.774698) (xy 238.559594 -1.770126) (xy 238.559107 -1.766461)
			(xy 238.557193 -1.75932) (xy 238.555784 -1.755902) (xy 238.552228 -1.747774) (xy 238.545624 -1.740916)
			(xy 238.543084 -1.737868) (xy 238.541306 -1.735582) (xy 238.364014 -1.55829) (xy 238.361162 -1.555585)
			(xy 238.354783 -1.550994) (xy 238.351314 -1.549146) (xy 238.345887 -1.546565) (xy 238.334207 -1.543749)
			(xy 238.3282 -1.543558) (xy 232.06964 -1.543558) (xy 232.059576 -1.543123) (xy 232.040991 -1.535388)
			(xy 232.033572 -1.528572) (xy 231.277668 -0.772668) (xy 231.270271 -0.765819) (xy 231.251672 -0.758086)
			(xy 231.2416 -0.757682) (xy 220.345 -0.757682) (xy 220.334929 -0.758105) (xy 220.316323 -0.765817)
			(xy 220.308932 -0.772668) (xy 219.553028 -1.528572) (xy 219.545627 -1.53541) (xy 219.527028 -1.543123)
			(xy 219.51696 -1.543558) (xy 214.053674 -1.543558) (xy 214.043768 -1.544574) (xy 214.043514 -1.544574)
			(xy 214.028528 -1.547622) (xy 214.020654 -1.551178) (xy 214.01278 -1.55829) (xy 214.012272 -1.558798)
			(xy 214.010494 -1.560322) (xy 214.008208 -1.5621) (xy 213.367874 -2.202434) (xy 213.365168 -2.205285)
			(xy 213.360576 -2.211664) (xy 213.35873 -2.215134) (xy 213.356145 -2.22056) (xy 213.353317 -2.23224)
			(xy 213.353142 -2.238248) (xy 213.353142 -12.52982) (xy 213.352714 -12.539887) (xy 213.344988 -12.558481)
			(xy 213.338156 -12.565888) (xy 212.560154 -13.34389) (xy 212.555549 -13.348747) (xy 212.548864 -13.360337)
			(xy 212.546946 -13.36675) (xy 212.546692 -13.367004) (xy 212.545781 -13.370551) (xy 212.544892 -13.37782)
			(xy 212.544914 -13.381482) (xy 212.546946 -13.393674) (xy 212.546946 -13.393928) (xy 212.547708 -13.396214)
			(xy 212.54974 -13.401548) (xy 212.56879 -13.444728) (xy 212.56879 -13.445236) (xy 212.586824 -13.486384)
			(xy 212.593174 -13.497306) (xy 212.602572 -13.506704) (xy 212.611716 -13.512292) (xy 212.611716 -13.512546)
			(xy 212.617369 -13.514983) (xy 212.629435 -13.51741) (xy 212.635592 -13.517372) (xy 212.716364 -13.515848)
			(xy 212.71992 -13.515848) (xy 212.785657 -13.516355) (xy 212.91688 -13.524449) (xy 213.047357 -13.540607)
			(xy 213.176591 -13.564766) (xy 213.304093 -13.596835) (xy 213.429379 -13.636693) (xy 213.551973 -13.684187)
			(xy 213.671412 -13.739138) (xy 213.787241 -13.801338) (xy 213.899021 -13.870551) (xy 214.006329 -13.946513)
			(xy 214.108756 -14.028937) (xy 214.18704 -14.100302) (xy 219.342968 -14.100302) (xy 219.347039 -14.04468)
			(xy 219.359165 -13.990243) (xy 219.379088 -13.938152) (xy 219.406384 -13.889517) (xy 219.44047 -13.845374)
			(xy 219.480619 -13.806665) (xy 219.525977 -13.774214) (xy 219.575577 -13.748713) (xy 219.628361 -13.730706)
			(xy 219.683204 -13.720576) (xy 219.738938 -13.718539) (xy 219.794375 -13.724639) (xy 219.848332 -13.738745)
			(xy 219.899661 -13.760557) (xy 219.947267 -13.789611) (xy 219.990135 -13.825286) (xy 220.027352 -13.866823)
			(xy 220.058125 -13.913336) (xy 220.081797 -13.963833) (xy 220.097865 -14.01724) (xy 220.105985 -14.072416)
			(xy 220.106494 -14.100302) (xy 220.105985 -14.128188) (xy 220.097865 -14.183364) (xy 220.081797 -14.236771)
			(xy 220.058125 -14.287268) (xy 220.027352 -14.333781) (xy 219.990135 -14.375318) (xy 219.947267 -14.410993)
			(xy 219.899661 -14.440047) (xy 219.848332 -14.461859) (xy 219.794375 -14.475965) (xy 219.738938 -14.482065)
			(xy 219.683204 -14.480028) (xy 219.628361 -14.469898) (xy 219.575577 -14.451891) (xy 219.525977 -14.42639)
			(xy 219.480619 -14.393939) (xy 219.44047 -14.35523) (xy 219.406384 -14.311087) (xy 219.379088 -14.262452)
			(xy 219.359165 -14.210361) (xy 219.347039 -14.155924) (xy 219.342968 -14.100302) (xy 214.18704 -14.100302)
			(xy 214.205916 -14.11751) (xy 214.297438 -14.211897) (xy 214.382976 -14.311738) (xy 214.462206 -14.416657)
			(xy 214.534827 -14.526253) (xy 214.600563 -14.640112) (xy 214.659165 -14.757802) (xy 214.710411 -14.878877)
			(xy 214.754107 -15.002876) (xy 214.790086 -15.129331) (xy 214.818212 -15.25776) (xy 214.838379 -15.387677)
			(xy 214.839294 -15.39755) (xy 220.00438 -15.39755) (xy 220.00438 -15.34305) (xy 220.012136 -15.289103)
			(xy 220.02749 -15.23681) (xy 220.05013 -15.187234) (xy 220.079595 -15.141384) (xy 220.115285 -15.100195)
			(xy 220.156473 -15.064503) (xy 220.202322 -15.035037) (xy 220.251897 -15.012395) (xy 220.30419 -14.997039)
			(xy 220.358136 -14.989281) (xy 220.385386 -14.988794) (xy 220.411621 -14.989263) (xy 220.463597 -14.996456)
			(xy 220.514095 -15.010709) (xy 220.562161 -15.031751) (xy 220.606889 -15.059186) (xy 220.647431 -15.092496)
			(xy 220.665548 -15.111476) (xy 220.665802 -15.11173) (xy 220.673518 -15.119132) (xy 220.693214 -15.127395)
			(xy 220.703902 -15.127732) (xy 220.791786 -15.125446) (xy 220.811344 -15.116048) (xy 220.818456 -15.107412)
			(xy 220.836664 -15.086259) (xy 220.878205 -15.048984) (xy 220.924735 -15.018163) (xy 220.975261 -14.994453)
			(xy 221.028703 -14.97836) (xy 221.08392 -14.970229) (xy 221.111826 -14.969744) (xy 221.139073 -14.970328)
			(xy 221.193011 -14.978086) (xy 221.245296 -14.993442) (xy 221.294863 -15.016082) (xy 221.340705 -15.045545)
			(xy 221.381887 -15.081232) (xy 221.417571 -15.122416) (xy 221.447031 -15.16826) (xy 221.469667 -15.217829)
			(xy 221.485019 -15.270115) (xy 221.492774 -15.324053) (xy 221.492774 -15.378547) (xy 221.485019 -15.432485)
			(xy 221.469667 -15.484771) (xy 221.447031 -15.53434) (xy 221.417571 -15.580184) (xy 221.381887 -15.621368)
			(xy 221.340705 -15.657055) (xy 221.294863 -15.686518) (xy 221.245296 -15.709158) (xy 221.193011 -15.724514)
			(xy 221.139073 -15.732272) (xy 221.111826 -15.73276) (xy 221.08559 -15.732298) (xy 221.033614 -15.725105)
			(xy 220.983115 -15.710852) (xy 220.935048 -15.689809) (xy 220.890321 -15.662372) (xy 220.84978 -15.62906)
			(xy 220.831664 -15.610078) (xy 220.83141 -15.609824) (xy 220.823695 -15.602421) (xy 220.803998 -15.59416)
			(xy 220.79331 -15.593822) (xy 220.705426 -15.596108) (xy 220.685868 -15.605506) (xy 220.678756 -15.614142)
			(xy 220.660531 -15.63528) (xy 220.618995 -15.672558) (xy 220.572469 -15.703382) (xy 220.521946 -15.727096)
			(xy 220.468506 -15.743191) (xy 220.413291 -15.751324) (xy 220.385386 -15.75181) (xy 220.358136 -15.751319)
			(xy 220.30419 -15.743561) (xy 220.251897 -15.728205) (xy 220.202322 -15.705563) (xy 220.156473 -15.676097)
			(xy 220.115285 -15.640405) (xy 220.079595 -15.599216) (xy 220.05013 -15.553366) (xy 220.02749 -15.50379)
			(xy 220.012136 -15.451497) (xy 220.00438 -15.39755) (xy 214.839294 -15.39755) (xy 214.85051 -15.518589)
			(xy 214.854559 -15.65) (xy 214.85051 -15.781411) (xy 214.838379 -15.912323) (xy 214.818212 -16.04224)
			(xy 214.790086 -16.170669) (xy 214.754107 -16.297124) (xy 214.710411 -16.421123) (xy 214.659165 -16.542198)
			(xy 214.600563 -16.659888) (xy 214.534827 -16.773747) (xy 214.462206 -16.883343) (xy 214.396771 -16.969994)
			(xy 245.948207 -16.969994) (xy 245.952212 -16.882086) (xy 245.964195 -16.794906) (xy 245.984055 -16.709177)
			(xy 246.01163 -16.625609) (xy 246.046689 -16.544895) (xy 246.088942 -16.467703) (xy 246.13804 -16.394674)
			(xy 246.193576 -16.326412) (xy 246.255088 -16.263482) (xy 246.322069 -16.206408) (xy 246.393962 -16.15566)
			(xy 246.470171 -16.11166) (xy 246.550066 -16.074773) (xy 246.632985 -16.045304) (xy 246.71824 -16.023497)
			(xy 246.805124 -16.009533) (xy 246.892918 -16.003527) (xy 246.980895 -16.005531) (xy 247.068325 -16.015526)
			(xy 247.154484 -16.03343) (xy 247.238658 -16.059094) (xy 247.320149 -16.092307) (xy 247.398283 -16.132793)
			(xy 247.472411 -16.180215) (xy 247.541919 -16.234182) (xy 247.606233 -16.294247) (xy 247.664817 -16.359911)
			(xy 247.717188 -16.43063) (xy 247.762911 -16.505818) (xy 247.801608 -16.584853) (xy 247.832957 -16.667079)
			(xy 247.856699 -16.751815) (xy 247.872637 -16.838359) (xy 247.880639 -16.925994) (xy 247.88114 -16.969994)
			(xy 247.880639 -17.013994) (xy 247.872637 -17.101629) (xy 247.856699 -17.188173) (xy 247.832957 -17.272909)
			(xy 247.801608 -17.355135) (xy 247.762911 -17.43417) (xy 247.717188 -17.509358) (xy 247.664817 -17.580077)
			(xy 247.606233 -17.645741) (xy 247.541919 -17.705806) (xy 247.472411 -17.759773) (xy 247.398283 -17.807195)
			(xy 247.320149 -17.847681) (xy 247.238658 -17.880894) (xy 247.154484 -17.906558) (xy 247.068325 -17.924462)
			(xy 246.980895 -17.934457) (xy 246.892918 -17.936461) (xy 246.805124 -17.930455) (xy 246.71824 -17.916491)
			(xy 246.632985 -17.894684) (xy 246.550066 -17.865215) (xy 246.470171 -17.828328) (xy 246.393962 -17.784328)
			(xy 246.322069 -17.73358) (xy 246.255088 -17.676506) (xy 246.193576 -17.613576) (xy 246.13804 -17.545314)
			(xy 246.088942 -17.472285) (xy 246.046689 -17.395093) (xy 246.01163 -17.314379) (xy 245.984055 -17.230811)
			(xy 245.964195 -17.145082) (xy 245.952212 -17.057902) (xy 245.948207 -16.969994) (xy 214.396771 -16.969994)
			(xy 214.382976 -16.988262) (xy 214.297438 -17.088103) (xy 214.205916 -17.18249) (xy 214.108756 -17.271063)
			(xy 214.006329 -17.353487) (xy 213.912971 -17.419574) (xy 218.384118 -17.419574) (xy 218.388189 -17.363952)
			(xy 218.400315 -17.309515) (xy 218.420238 -17.257424) (xy 218.447534 -17.208789) (xy 218.48162 -17.164646)
			(xy 218.521769 -17.125937) (xy 218.567127 -17.093486) (xy 218.616727 -17.067985) (xy 218.669511 -17.049978)
			(xy 218.724354 -17.039848) (xy 218.780088 -17.037811) (xy 218.835525 -17.043911) (xy 218.889482 -17.058017)
			(xy 218.940811 -17.079829) (xy 218.988417 -17.108883) (xy 219.031285 -17.144558) (xy 219.068502 -17.186095)
			(xy 219.099275 -17.232608) (xy 219.122947 -17.283105) (xy 219.139015 -17.336512) (xy 219.147135 -17.391688)
			(xy 219.147644 -17.419574) (xy 219.147135 -17.44746) (xy 219.139015 -17.502636) (xy 219.122947 -17.556043)
			(xy 219.099275 -17.60654) (xy 219.068502 -17.653053) (xy 219.031285 -17.69459) (xy 218.988417 -17.730265)
			(xy 218.940811 -17.759319) (xy 218.889482 -17.781131) (xy 218.835525 -17.795237) (xy 218.780088 -17.801337)
			(xy 218.724354 -17.7993) (xy 218.669511 -17.78917) (xy 218.616727 -17.771163) (xy 218.567127 -17.745662)
			(xy 218.521769 -17.713211) (xy 218.48162 -17.674502) (xy 218.447534 -17.630359) (xy 218.420238 -17.581724)
			(xy 218.400315 -17.529633) (xy 218.388189 -17.475196) (xy 218.384118 -17.419574) (xy 213.912971 -17.419574)
			(xy 213.899021 -17.429449) (xy 213.787241 -17.498662) (xy 213.671412 -17.560862) (xy 213.551973 -17.615813)
			(xy 213.429379 -17.663307) (xy 213.304093 -17.703165) (xy 213.176591 -17.735234) (xy 213.047357 -17.759393)
			(xy 212.91688 -17.775551) (xy 212.785657 -17.783645) (xy 212.71992 -17.784064) (xy 212.655575 -17.783582)
			(xy 212.527118 -17.775828) (xy 212.399362 -17.760348) (xy 212.272771 -17.737197) (xy 212.147805 -17.706461)
			(xy 212.024918 -17.66825) (xy 211.904557 -17.622703) (xy 211.78716 -17.569986) (xy 211.673152 -17.510291)
			(xy 211.562949 -17.443834) (xy 211.456951 -17.370857) (xy 211.355542 -17.291626) (xy 211.259093 -17.206427)
			(xy 211.167953 -17.115572) (xy 211.082453 -17.01939) (xy 211.002904 -16.91823) (xy 210.929596 -16.812461)
			(xy 210.862795 -16.702466) (xy 210.802743 -16.588646) (xy 210.749659 -16.471414) (xy 210.703736 -16.351196)
			(xy 210.66514 -16.22843) (xy 210.634012 -16.10356) (xy 210.610466 -15.977042) (xy 210.594586 -15.849335)
			(xy 210.58643 -15.720904) (xy 210.585812 -15.65656) (xy 210.585812 -15.649448) (xy 210.586263 -15.587623)
			(xy 210.593437 -15.464182) (xy 210.607747 -15.341363) (xy 210.629143 -15.219579) (xy 210.657555 -15.099238)
			(xy 210.692888 -14.980744) (xy 210.735022 -14.864495) (xy 210.783816 -14.75088) (xy 210.839107 -14.640281)
			(xy 210.86953 -14.586458) (xy 210.869784 -14.58595) (xy 210.876388 -14.561312) (xy 210.876277 -14.555174)
			(xy 210.873442 -14.543232) (xy 210.8708 -14.53769) (xy 210.82762 -14.463522) (xy 210.822664 -14.454464)
			(xy 210.807072 -14.440957) (xy 210.797394 -14.43736) (xy 210.787742 -14.434312) (xy 202.39609 -14.434312)
			(xy 202.38602 -14.433888) (xy 202.367417 -14.426172) (xy 202.360022 -14.419326) (xy 200.754488 -12.813792)
			(xy 200.747633 -12.806397) (xy 200.739888 -12.787798) (xy 200.739502 -12.777724) (xy 200.739502 -1.953006)
			(xy 200.739439 -1.9494) (xy 200.73842 -1.942261) (xy 200.73747 -1.938782) (xy 200.735946 -1.93421)
			(xy 200.732136 -1.925066) (xy 200.09739 -1.29032) (xy 200.094538 -1.287615) (xy 200.088159 -1.283025)
			(xy 200.08469 -1.281176) (xy 200.079264 -1.27859) (xy 200.067584 -1.275761) (xy 200.061576 -1.275588)
			(xy 188.177424 -1.275588) (xy 188.167518 -1.276604) (xy 188.167264 -1.276604) (xy 188.152278 -1.279652)
			(xy 188.144404 -1.283208) (xy 188.13653 -1.29032) (xy 188.136022 -1.290828) (xy 188.134244 -1.292352)
			(xy 188.131958 -1.29413) (xy 187.422028 -2.00406) (xy 187.419321 -2.00691) (xy 187.414724 -2.013286)
			(xy 187.412884 -2.01676) (xy 187.410303 -2.022187) (xy 187.407484 -2.033867) (xy 187.407296 -2.039874)
			(xy 187.407296 -12.860782) (xy 187.406858 -12.870845) (xy 187.399122 -12.889428) (xy 187.39231 -12.89685)
			(xy 186.926474 -13.362686) (xy 186.924442 -13.365734) (xy 186.924188 -13.366242) (xy 186.921394 -13.37056)
			(xy 186.916314 -13.382244) (xy 186.914643 -13.388594) (xy 186.914263 -13.401713) (xy 186.915552 -13.408152)
			(xy 186.917584 -13.415518) (xy 186.946794 -13.499592) (xy 186.949366 -13.505498) (xy 186.956943 -13.515911)
			(xy 186.96178 -13.520166) (xy 186.962034 -13.520166) (xy 186.97321 -13.52931) (xy 187.037306 -13.537444)
			(xy 187.164451 -13.56049) (xy 187.28997 -13.591181) (xy 187.413404 -13.629405) (xy 187.5343 -13.675023)
			(xy 187.652217 -13.727868) (xy 187.766723 -13.787746) (xy 187.877399 -13.854438) (xy 187.983839 -13.9277)
			(xy 188.085655 -14.007264) (xy 188.182474 -14.092839) (xy 188.189953 -14.100302) (xy 193.34302 -14.100302)
			(xy 193.347091 -14.04468) (xy 193.359217 -13.990243) (xy 193.37914 -13.938152) (xy 193.406436 -13.889517)
			(xy 193.440522 -13.845374) (xy 193.480671 -13.806665) (xy 193.526029 -13.774214) (xy 193.575629 -13.748713)
			(xy 193.628413 -13.730706) (xy 193.683256 -13.720576) (xy 193.73899 -13.718539) (xy 193.794427 -13.724639)
			(xy 193.848384 -13.738745) (xy 193.899713 -13.760557) (xy 193.947319 -13.789611) (xy 193.990187 -13.825286)
			(xy 194.027404 -13.866823) (xy 194.058177 -13.913336) (xy 194.081849 -13.963833) (xy 194.097917 -14.01724)
			(xy 194.106037 -14.072416) (xy 194.106546 -14.100302) (xy 194.106037 -14.128188) (xy 194.097917 -14.183364)
			(xy 194.081849 -14.236771) (xy 194.058177 -14.287268) (xy 194.027404 -14.333781) (xy 193.990187 -14.375318)
			(xy 193.947319 -14.410993) (xy 193.899713 -14.440047) (xy 193.848384 -14.461859) (xy 193.794427 -14.475965)
			(xy 193.73899 -14.482065) (xy 193.683256 -14.480028) (xy 193.628413 -14.469898) (xy 193.575629 -14.451891)
			(xy 193.526029 -14.42639) (xy 193.480671 -14.393939) (xy 193.440522 -14.35523) (xy 193.406436 -14.311087)
			(xy 193.37914 -14.262452) (xy 193.359217 -14.210361) (xy 193.347091 -14.155924) (xy 193.34302 -14.100302)
			(xy 188.189953 -14.100302) (xy 188.273941 -14.184112) (xy 188.359723 -14.280748) (xy 188.439503 -14.382394)
			(xy 188.512992 -14.488679) (xy 188.57992 -14.599212) (xy 188.640042 -14.71359) (xy 188.693138 -14.831394)
			(xy 188.739013 -14.952193) (xy 188.7775 -15.075545) (xy 188.808459 -15.200998) (xy 188.831775 -15.328094)
			(xy 188.840216 -15.397554) (xy 194.004357 -15.397554) (xy 194.004357 -15.343046) (xy 194.012115 -15.289092)
			(xy 194.027473 -15.236791) (xy 194.050118 -15.187209) (xy 194.07959 -15.141354) (xy 194.115287 -15.10016)
			(xy 194.156484 -15.064467) (xy 194.202342 -15.035) (xy 194.251927 -15.01236) (xy 194.304229 -14.997007)
			(xy 194.358184 -14.989255) (xy 194.385438 -14.988794) (xy 194.411675 -14.989228) (xy 194.463652 -14.996429)
			(xy 194.51415 -15.010688) (xy 194.562217 -15.031737) (xy 194.606943 -15.059178) (xy 194.647484 -15.092493)
			(xy 194.6656 -15.111476) (xy 194.665854 -15.11173) (xy 194.673588 -15.11911) (xy 194.69327 -15.127385)
			(xy 194.703954 -15.127732) (xy 194.791838 -15.125446) (xy 194.811396 -15.116048) (xy 194.818508 -15.107412)
			(xy 194.836689 -15.086234) (xy 194.878235 -15.048961) (xy 194.924771 -15.018143) (xy 194.975302 -14.994437)
			(xy 195.028749 -14.97835) (xy 195.08397 -14.970225) (xy 195.111878 -14.969744) (xy 195.139128 -14.970302)
			(xy 195.193075 -14.978055) (xy 195.245369 -14.993407) (xy 195.294946 -15.016046) (xy 195.340796 -15.045509)
			(xy 195.381986 -15.081199) (xy 195.417677 -15.122387) (xy 195.447144 -15.168235) (xy 195.469785 -15.21781)
			(xy 195.48514 -15.270104) (xy 195.492897 -15.32405) (xy 195.492897 -15.37855) (xy 195.48514 -15.432497)
			(xy 195.469785 -15.48479) (xy 195.447144 -15.534365) (xy 195.417677 -15.580213) (xy 195.381986 -15.621401)
			(xy 195.340796 -15.657091) (xy 195.294946 -15.686554) (xy 195.245369 -15.709193) (xy 195.193075 -15.724545)
			(xy 195.139128 -15.732298) (xy 195.111878 -15.73276) (xy 195.085641 -15.73233) (xy 195.033663 -15.725131)
			(xy 194.983164 -15.710872) (xy 194.935097 -15.689822) (xy 194.890371 -15.662379) (xy 194.849831 -15.629062)
			(xy 194.831716 -15.610078) (xy 194.831462 -15.609824) (xy 194.823728 -15.602445) (xy 194.804046 -15.594171)
			(xy 194.793362 -15.593822) (xy 194.705478 -15.596108) (xy 194.68592 -15.605506) (xy 194.678808 -15.614142)
			(xy 194.660608 -15.635303) (xy 194.619067 -15.672579) (xy 194.572535 -15.703401) (xy 194.522008 -15.72711)
			(xy 194.468564 -15.7432) (xy 194.413345 -15.751328) (xy 194.385438 -15.75181) (xy 194.358184 -15.751345)
			(xy 194.304229 -15.743593) (xy 194.251927 -15.72824) (xy 194.202342 -15.7056) (xy 194.156484 -15.676133)
			(xy 194.115287 -15.64044) (xy 194.07959 -15.599246) (xy 194.050118 -15.553391) (xy 194.027473 -15.503809)
			(xy 194.012115 -15.451508) (xy 194.004357 -15.397554) (xy 188.840216 -15.397554) (xy 188.847363 -15.456367)
			(xy 188.855167 -15.585348) (xy 188.855604 -15.649956) (xy 188.855097 -15.715739) (xy 188.846998 -15.847054)
			(xy 188.83083 -15.977622) (xy 188.806655 -16.106947) (xy 188.774565 -16.234538) (xy 188.73468 -16.359912)
			(xy 188.687154 -16.482593) (xy 188.632165 -16.602115) (xy 188.569922 -16.718025) (xy 188.500662 -16.829884)
			(xy 188.424647 -16.937267) (xy 188.398312 -16.969994) (xy 207.848207 -16.969994) (xy 207.852212 -16.882086)
			(xy 207.864195 -16.794906) (xy 207.884055 -16.709177) (xy 207.91163 -16.625609) (xy 207.946689 -16.544895)
			(xy 207.988942 -16.467703) (xy 208.03804 -16.394674) (xy 208.093576 -16.326412) (xy 208.155088 -16.263482)
			(xy 208.222069 -16.206408) (xy 208.293962 -16.15566) (xy 208.370171 -16.11166) (xy 208.450066 -16.074773)
			(xy 208.532985 -16.045304) (xy 208.61824 -16.023497) (xy 208.705124 -16.009533) (xy 208.792918 -16.003527)
			(xy 208.880895 -16.005531) (xy 208.968325 -16.015526) (xy 209.054484 -16.03343) (xy 209.138658 -16.059094)
			(xy 209.220149 -16.092307) (xy 209.298283 -16.132793) (xy 209.372411 -16.180215) (xy 209.441919 -16.234182)
			(xy 209.506233 -16.294247) (xy 209.564817 -16.359911) (xy 209.617188 -16.43063) (xy 209.662911 -16.505818)
			(xy 209.701608 -16.584853) (xy 209.732957 -16.667079) (xy 209.756699 -16.751815) (xy 209.772637 -16.838359)
			(xy 209.780639 -16.925994) (xy 209.78114 -16.969994) (xy 209.780639 -17.013994) (xy 209.772637 -17.101629)
			(xy 209.756699 -17.188173) (xy 209.732957 -17.272909) (xy 209.701608 -17.355135) (xy 209.662911 -17.43417)
			(xy 209.617188 -17.509358) (xy 209.564817 -17.580077) (xy 209.506233 -17.645741) (xy 209.441919 -17.705806)
			(xy 209.372411 -17.759773) (xy 209.298283 -17.807195) (xy 209.220149 -17.847681) (xy 209.138658 -17.880894)
			(xy 209.054484 -17.906558) (xy 208.968325 -17.924462) (xy 208.880895 -17.934457) (xy 208.792918 -17.936461)
			(xy 208.705124 -17.930455) (xy 208.61824 -17.916491) (xy 208.532985 -17.894684) (xy 208.450066 -17.865215)
			(xy 208.370171 -17.828328) (xy 208.293962 -17.784328) (xy 208.222069 -17.73358) (xy 208.155088 -17.676506)
			(xy 208.093576 -17.613576) (xy 208.03804 -17.545314) (xy 207.988942 -17.472285) (xy 207.946689 -17.395093)
			(xy 207.91163 -17.314379) (xy 207.884055 -17.230811) (xy 207.864195 -17.145082) (xy 207.852212 -17.057902)
			(xy 207.848207 -16.969994) (xy 188.398312 -16.969994) (xy 188.342166 -17.039767) (xy 188.253531 -17.136995)
			(xy 188.159079 -17.228581) (xy 188.059168 -17.31418) (xy 187.954177 -17.393466) (xy 187.914776 -17.419574)
			(xy 192.38417 -17.419574) (xy 192.388241 -17.363952) (xy 192.400367 -17.309515) (xy 192.42029 -17.257424)
			(xy 192.447586 -17.208789) (xy 192.481672 -17.164646) (xy 192.521821 -17.125937) (xy 192.567179 -17.093486)
			(xy 192.616779 -17.067985) (xy 192.669563 -17.049978) (xy 192.724406 -17.039848) (xy 192.78014 -17.037811)
			(xy 192.835577 -17.043911) (xy 192.889534 -17.058017) (xy 192.940863 -17.079829) (xy 192.988469 -17.108883)
			(xy 193.031337 -17.144558) (xy 193.068554 -17.186095) (xy 193.099327 -17.232608) (xy 193.122999 -17.283105)
			(xy 193.139067 -17.336512) (xy 193.147187 -17.391688) (xy 193.147696 -17.419574) (xy 193.147187 -17.44746)
			(xy 193.139067 -17.502636) (xy 193.122999 -17.556043) (xy 193.099327 -17.60654) (xy 193.068554 -17.653053)
			(xy 193.031337 -17.69459) (xy 192.988469 -17.730265) (xy 192.940863 -17.759319) (xy 192.889534 -17.781131)
			(xy 192.835577 -17.795237) (xy 192.78014 -17.801337) (xy 192.724406 -17.7993) (xy 192.669563 -17.78917)
			(xy 192.616779 -17.771163) (xy 192.567179 -17.745662) (xy 192.521821 -17.713211) (xy 192.481672 -17.674502)
			(xy 192.447586 -17.630359) (xy 192.42029 -17.581724) (xy 192.400367 -17.529633) (xy 192.388241 -17.475196)
			(xy 192.38417 -17.419574) (xy 187.914776 -17.419574) (xy 187.844504 -17.466138) (xy 187.730565 -17.53192)
			(xy 187.612793 -17.590564) (xy 187.491634 -17.641846) (xy 187.367548 -17.685572) (xy 187.241005 -17.721577)
			(xy 187.112486 -17.749723) (xy 186.982478 -17.769904) (xy 186.851475 -17.782043) (xy 186.719972 -17.786095)
			(xy 186.588469 -17.782043) (xy 186.457466 -17.769904) (xy 186.327458 -17.749723) (xy 186.198939 -17.721577)
			(xy 186.072396 -17.685572) (xy 185.94831 -17.641846) (xy 185.827151 -17.590564) (xy 185.709379 -17.53192)
			(xy 185.59544 -17.466138) (xy 185.485767 -17.393466) (xy 185.380776 -17.31418) (xy 185.280865 -17.228581)
			(xy 185.186413 -17.136995) (xy 185.097778 -17.039767) (xy 185.015297 -16.937267) (xy 184.939282 -16.829884)
			(xy 184.870022 -16.718025) (xy 184.807779 -16.602115) (xy 184.75279 -16.482593) (xy 184.705264 -16.359912)
			(xy 184.665379 -16.234538) (xy 184.633289 -16.106947) (xy 184.609114 -15.977622) (xy 184.592946 -15.847054)
			(xy 184.584847 -15.715739) (xy 184.58434 -15.649956) (xy 184.58434 -15.649448) (xy 184.584788 -15.587692)
			(xy 184.591943 -15.464387) (xy 184.606213 -15.341702) (xy 184.627552 -15.220047) (xy 184.655888 -15.099829)
			(xy 184.691126 -14.98145) (xy 184.733148 -14.865306) (xy 184.781814 -14.751785) (xy 184.836961 -14.641268)
			(xy 184.867296 -14.587474) (xy 184.868566 -14.585188) (xy 184.870344 -14.58214) (xy 184.872884 -14.573758)
			(xy 184.8739 -14.569186) (xy 184.875306 -14.560115) (xy 184.872303 -14.54202) (xy 184.868058 -14.53388)
			(xy 184.839864 -14.484858) (xy 184.82564 -14.459966) (xy 184.817766 -14.449552) (xy 184.811532 -14.443865)
			(xy 184.796368 -14.436485) (xy 184.788048 -14.435074) (xy 184.78754 -14.435074) (xy 184.781444 -14.434566)
			(xy 176.294034 -14.434566) (xy 176.28397 -14.43413) (xy 176.265386 -14.426395) (xy 176.257966 -14.41958)
			(xy 174.596044 -12.757658) (xy 174.5892 -12.750259) (xy 174.581473 -12.731661) (xy 174.581058 -12.72159)
			(xy 174.581058 -1.417066) (xy 174.580627 -1.407) (xy 174.5729 -1.388408) (xy 174.566072 -1.380998)
			(xy 173.957742 -0.772668) (xy 173.950344 -0.765823) (xy 173.931745 -0.758099) (xy 173.921674 -0.757682)
			(xy 161.898838 -0.757682) (xy 161.888772 -0.758116) (xy 161.870183 -0.765844) (xy 161.86277 -0.772668)
			(xy 161.412428 -1.22301) (xy 161.40558 -1.230408) (xy 161.397845 -1.249006) (xy 161.397442 -1.259078)
			(xy 161.397442 -12.523978) (xy 161.397003 -12.534041) (xy 161.389262 -12.552619) (xy 161.382456 -12.560046)
			(xy 160.599628 -13.342874) (xy 160.59375 -13.349249) (xy 160.586293 -13.36489) (xy 160.584476 -13.382122)
			(xy 160.586166 -13.390626) (xy 160.587944 -13.397738) (xy 160.59785 -13.42009) (xy 160.59785 -13.420344)
			(xy 160.626044 -13.485622) (xy 160.628857 -13.491535) (xy 160.636959 -13.501819) (xy 160.642046 -13.505942)
			(xy 160.64883 -13.510691) (xy 160.664506 -13.515997) (xy 160.67278 -13.516356) (xy 160.67405 -13.516356)
			(xy 160.720024 -13.515848) (xy 160.78576 -13.516355) (xy 160.916984 -13.52445) (xy 161.04746 -13.540607)
			(xy 161.176694 -13.564767) (xy 161.304196 -13.596836) (xy 161.429482 -13.636694) (xy 161.552076 -13.684188)
			(xy 161.671514 -13.73914) (xy 161.787343 -13.80134) (xy 161.899123 -13.870552) (xy 162.00643 -13.946514)
			(xy 162.108858 -14.028938) (xy 162.206017 -14.117512) (xy 162.297539 -14.211898) (xy 162.383077 -14.31174)
			(xy 162.462307 -14.416658) (xy 162.534928 -14.526254) (xy 162.600664 -14.640113) (xy 162.648062 -14.735302)
			(xy 166.62476 -14.735302) (xy 166.628831 -14.67968) (xy 166.640957 -14.625243) (xy 166.66088 -14.573152)
			(xy 166.688176 -14.524517) (xy 166.722262 -14.480374) (xy 166.762411 -14.441665) (xy 166.807769 -14.409214)
			(xy 166.857369 -14.383713) (xy 166.910153 -14.365706) (xy 166.964996 -14.355576) (xy 167.02073 -14.353539)
			(xy 167.076167 -14.359639) (xy 167.130124 -14.373745) (xy 167.181453 -14.395557) (xy 167.229059 -14.424611)
			(xy 167.271927 -14.460286) (xy 167.309144 -14.501823) (xy 167.339917 -14.548336) (xy 167.363589 -14.598833)
			(xy 167.379657 -14.65224) (xy 167.387777 -14.707416) (xy 167.388286 -14.735302) (xy 167.387777 -14.763188)
			(xy 167.379657 -14.818364) (xy 167.363589 -14.871771) (xy 167.339917 -14.922268) (xy 167.309144 -14.968781)
			(xy 167.271927 -15.010318) (xy 167.229059 -15.045993) (xy 167.181453 -15.075047) (xy 167.130124 -15.096859)
			(xy 167.076167 -15.110965) (xy 167.02073 -15.117065) (xy 166.964996 -15.115028) (xy 166.910153 -15.104898)
			(xy 166.857369 -15.086891) (xy 166.807769 -15.06139) (xy 166.762411 -15.028939) (xy 166.722262 -14.99023)
			(xy 166.688176 -14.946087) (xy 166.66088 -14.897452) (xy 166.640957 -14.845361) (xy 166.628831 -14.790924)
			(xy 166.62476 -14.735302) (xy 162.648062 -14.735302) (xy 162.659266 -14.757803) (xy 162.710512 -14.878878)
			(xy 162.754207 -15.002877) (xy 162.790186 -15.129331) (xy 162.818312 -15.25776) (xy 162.838479 -15.387677)
			(xy 162.839394 -15.397551) (xy 168.00448 -15.397551) (xy 168.00448 -15.343049) (xy 168.012236 -15.289103)
			(xy 168.02759 -15.236809) (xy 168.050231 -15.187233) (xy 168.079696 -15.141383) (xy 168.115386 -15.100193)
			(xy 168.156575 -15.064502) (xy 168.202424 -15.035036) (xy 168.252 -15.012394) (xy 168.304293 -14.997038)
			(xy 168.358239 -14.98928) (xy 168.38549 -14.988794) (xy 168.411726 -14.98926) (xy 168.463701 -14.996454)
			(xy 168.514199 -15.010707) (xy 168.562266 -15.03175) (xy 168.606993 -15.059186) (xy 168.647535 -15.092495)
			(xy 168.665652 -15.111476) (xy 168.665906 -15.11173) (xy 168.673621 -15.119134) (xy 168.693318 -15.127396)
			(xy 168.704006 -15.127732) (xy 168.79189 -15.125446) (xy 168.811448 -15.116048) (xy 168.81856 -15.107412)
			(xy 168.836766 -15.086257) (xy 168.878307 -15.048983) (xy 168.924838 -15.018161) (xy 168.975364 -14.994451)
			(xy 169.028806 -14.978359) (xy 169.084024 -14.970228) (xy 169.11193 -14.969744) (xy 169.139176 -14.970328)
			(xy 169.193114 -14.978087) (xy 169.245399 -14.993443) (xy 169.294966 -15.016083) (xy 169.340807 -15.045546)
			(xy 169.381988 -15.081233) (xy 169.417672 -15.122418) (xy 169.447131 -15.168261) (xy 169.469768 -15.21783)
			(xy 169.485119 -15.270115) (xy 169.492874 -15.324054) (xy 169.492874 -15.378546) (xy 169.485119 -15.432485)
			(xy 169.469768 -15.48477) (xy 169.447131 -15.534339) (xy 169.417672 -15.580182) (xy 169.381988 -15.621367)
			(xy 169.340807 -15.657054) (xy 169.294966 -15.686517) (xy 169.245399 -15.709157) (xy 169.193114 -15.724513)
			(xy 169.139176 -15.732272) (xy 169.11193 -15.73276) (xy 169.085692 -15.732362) (xy 169.033713 -15.725156)
			(xy 168.983213 -15.710891) (xy 168.935146 -15.689835) (xy 168.890421 -15.662387) (xy 168.849882 -15.629065)
			(xy 168.831768 -15.610078) (xy 168.831514 -15.609824) (xy 168.823798 -15.602423) (xy 168.804102 -15.594161)
			(xy 168.793414 -15.593822) (xy 168.70553 -15.596108) (xy 168.685972 -15.605506) (xy 168.67886 -15.614142)
			(xy 168.660632 -15.635278) (xy 168.619097 -15.672556) (xy 168.572571 -15.703381) (xy 168.522049 -15.727094)
			(xy 168.46861 -15.74319) (xy 168.413395 -15.751324) (xy 168.38549 -15.75181) (xy 168.358239 -15.75132)
			(xy 168.304293 -15.743562) (xy 168.252 -15.728206) (xy 168.202424 -15.705564) (xy 168.156575 -15.676098)
			(xy 168.115386 -15.640407) (xy 168.079696 -15.599217) (xy 168.050231 -15.553367) (xy 168.02759 -15.503791)
			(xy 168.012236 -15.451497) (xy 168.00448 -15.397551) (xy 162.839394 -15.397551) (xy 162.85061 -15.518589)
			(xy 162.854659 -15.65) (xy 162.85061 -15.781411) (xy 162.838479 -15.912323) (xy 162.818312 -16.04224)
			(xy 162.790186 -16.170669) (xy 162.754207 -16.297123) (xy 162.710512 -16.421122) (xy 162.659266 -16.542197)
			(xy 162.600664 -16.659887) (xy 162.534928 -16.773746) (xy 162.462307 -16.883342) (xy 162.396871 -16.969994)
			(xy 181.848259 -16.969994) (xy 181.852264 -16.882086) (xy 181.864247 -16.794906) (xy 181.884107 -16.709177)
			(xy 181.911682 -16.625609) (xy 181.946741 -16.544895) (xy 181.988994 -16.467703) (xy 182.038092 -16.394674)
			(xy 182.093628 -16.326412) (xy 182.15514 -16.263482) (xy 182.222121 -16.206408) (xy 182.294014 -16.15566)
			(xy 182.370223 -16.11166) (xy 182.450118 -16.074773) (xy 182.533037 -16.045304) (xy 182.618292 -16.023497)
			(xy 182.705176 -16.009533) (xy 182.79297 -16.003527) (xy 182.880947 -16.005531) (xy 182.968377 -16.015526)
			(xy 183.054536 -16.03343) (xy 183.13871 -16.059094) (xy 183.220201 -16.092307) (xy 183.298335 -16.132793)
			(xy 183.372463 -16.180215) (xy 183.441971 -16.234182) (xy 183.506285 -16.294247) (xy 183.564869 -16.359911)
			(xy 183.61724 -16.43063) (xy 183.662963 -16.505818) (xy 183.70166 -16.584853) (xy 183.733009 -16.667079)
			(xy 183.756751 -16.751815) (xy 183.772689 -16.838359) (xy 183.780691 -16.925994) (xy 183.781192 -16.969994)
			(xy 183.780691 -17.013994) (xy 183.772689 -17.101629) (xy 183.756751 -17.188173) (xy 183.733009 -17.272909)
			(xy 183.70166 -17.355135) (xy 183.662963 -17.43417) (xy 183.61724 -17.509358) (xy 183.564869 -17.580077)
			(xy 183.506285 -17.645741) (xy 183.441971 -17.705806) (xy 183.372463 -17.759773) (xy 183.298335 -17.807195)
			(xy 183.220201 -17.847681) (xy 183.13871 -17.880894) (xy 183.054536 -17.906558) (xy 182.968377 -17.924462)
			(xy 182.880947 -17.934457) (xy 182.79297 -17.936461) (xy 182.705176 -17.930455) (xy 182.618292 -17.916491)
			(xy 182.533037 -17.894684) (xy 182.450118 -17.865215) (xy 182.370223 -17.828328) (xy 182.294014 -17.784328)
			(xy 182.222121 -17.73358) (xy 182.15514 -17.676506) (xy 182.093628 -17.613576) (xy 182.038092 -17.545314)
			(xy 181.988994 -17.472285) (xy 181.946741 -17.395093) (xy 181.911682 -17.314379) (xy 181.884107 -17.230811)
			(xy 181.864247 -17.145082) (xy 181.852264 -17.057902) (xy 181.848259 -16.969994) (xy 162.396871 -16.969994)
			(xy 162.383077 -16.98826) (xy 162.297539 -17.088102) (xy 162.206017 -17.182488) (xy 162.108858 -17.271062)
			(xy 162.00643 -17.353486) (xy 161.913071 -17.419574) (xy 166.384222 -17.419574) (xy 166.388293 -17.363952)
			(xy 166.400419 -17.309515) (xy 166.420342 -17.257424) (xy 166.447638 -17.208789) (xy 166.481724 -17.164646)
			(xy 166.521873 -17.125937) (xy 166.567231 -17.093486) (xy 166.616831 -17.067985) (xy 166.669615 -17.049978)
			(xy 166.724458 -17.039848) (xy 166.780192 -17.037811) (xy 166.835629 -17.043911) (xy 166.889586 -17.058017)
			(xy 166.940915 -17.079829) (xy 166.988521 -17.108883) (xy 167.031389 -17.144558) (xy 167.068606 -17.186095)
			(xy 167.099379 -17.232608) (xy 167.123051 -17.283105) (xy 167.139119 -17.336512) (xy 167.147239 -17.391688)
			(xy 167.147748 -17.419574) (xy 167.147239 -17.44746) (xy 167.139119 -17.502636) (xy 167.123051 -17.556043)
			(xy 167.099379 -17.60654) (xy 167.068606 -17.653053) (xy 167.031389 -17.69459) (xy 166.988521 -17.730265)
			(xy 166.940915 -17.759319) (xy 166.889586 -17.781131) (xy 166.835629 -17.795237) (xy 166.780192 -17.801337)
			(xy 166.724458 -17.7993) (xy 166.669615 -17.78917) (xy 166.616831 -17.771163) (xy 166.567231 -17.745662)
			(xy 166.521873 -17.713211) (xy 166.481724 -17.674502) (xy 166.447638 -17.630359) (xy 166.420342 -17.581724)
			(xy 166.400419 -17.529633) (xy 166.388293 -17.475196) (xy 166.384222 -17.419574) (xy 161.913071 -17.419574)
			(xy 161.899123 -17.429448) (xy 161.787343 -17.49866) (xy 161.671514 -17.56086) (xy 161.552076 -17.615812)
			(xy 161.429482 -17.663306) (xy 161.304196 -17.703164) (xy 161.176694 -17.735233) (xy 161.04746 -17.759393)
			(xy 160.916984 -17.77555) (xy 160.78576 -17.783645) (xy 160.720024 -17.784064) (xy 160.655597 -17.783579)
			(xy 160.526977 -17.775806) (xy 160.39906 -17.760286) (xy 160.272314 -17.737076) (xy 160.147198 -17.70626)
			(xy 160.02417 -17.667952) (xy 159.903677 -17.622289) (xy 159.78616 -17.56944) (xy 159.672045 -17.509596)
			(xy 159.561749 -17.442976) (xy 159.455673 -17.369822) (xy 159.354205 -17.2904) (xy 159.257715 -17.205001)
			(xy 159.166552 -17.113936) (xy 159.081051 -17.017536) (xy 159.001522 -16.916152) (xy 158.928255 -16.810154)
			(xy 158.861518 -16.699929) (xy 158.801553 -16.585878) (xy 158.748579 -16.468416) (xy 158.702788 -16.347972)
			(xy 158.664349 -16.224985) (xy 158.633401 -16.099902) (xy 158.610056 -15.97318) (xy 158.5944 -15.84528)
			(xy 158.58649 -15.716669) (xy 158.585916 -15.652242) (xy 158.585916 -15.649448) (xy 158.586428 -15.583022)
			(xy 158.594704 -15.450427) (xy 158.611214 -15.318604) (xy 158.635894 -15.188064) (xy 158.668649 -15.059312)
			(xy 158.709352 -14.932848) (xy 158.757845 -14.809162) (xy 158.813939 -14.688732) (xy 158.84525 -14.630146)
			(xy 158.845504 -14.629892) (xy 158.846774 -14.627352) (xy 158.847536 -14.626082) (xy 158.847536 -14.625828)
			(xy 158.85541 -14.61135) (xy 158.857442 -14.602206) (xy 158.85795 -14.598904) (xy 158.85795 -14.585696)
			(xy 158.856172 -14.572488) (xy 158.855391 -14.567613) (xy 158.852195 -14.558275) (xy 158.849822 -14.553946)
			(xy 158.810706 -14.486636) (xy 158.810706 -14.486382) (xy 158.803702 -14.475748) (xy 158.781969 -14.462544)
			(xy 158.769304 -14.461236) (xy 149.985984 -14.461236) (xy 149.975916 -14.460808) (xy 149.957322 -14.453083)
			(xy 149.949916 -14.44625) (xy 148.194268 -12.690602) (xy 148.187414 -12.683207) (xy 148.179668 -12.664608)
			(xy 148.179282 -12.654534) (xy 148.179282 -1.950212) (xy 148.179028 -1.94564) (xy 148.178543 -1.941975)
			(xy 148.176631 -1.934833) (xy 148.175218 -1.931416) (xy 148.171662 -1.923288) (xy 148.165058 -1.91643)
			(xy 148.162518 -1.913382) (xy 148.16074 -1.911096) (xy 147.806664 -1.55702) (xy 147.803811 -1.554316)
			(xy 147.79743 -1.549729) (xy 147.793964 -1.547876) (xy 147.788537 -1.545293) (xy 147.776858 -1.542469)
			(xy 147.77085 -1.542288) (xy 136.015476 -1.542288) (xy 136.00557 -1.543304) (xy 136.005316 -1.543304)
			(xy 135.99033 -1.546352) (xy 135.982456 -1.549908) (xy 135.974582 -1.55702) (xy 135.974074 -1.557528)
			(xy 135.972296 -1.559052) (xy 135.97001 -1.56083) (xy 135.63981 -1.89103) (xy 135.637107 -1.893883)
			(xy 135.632519 -1.900264) (xy 135.630666 -1.90373) (xy 135.628083 -1.909157) (xy 135.625258 -1.920836)
			(xy 135.625078 -1.926844) (xy 135.625078 -13.019532) (xy 135.624649 -13.029599) (xy 135.616923 -13.048193)
			(xy 135.610092 -13.0556) (xy 135.242808 -13.422884) (xy 135.236934 -13.42926) (xy 135.229483 -13.4449)
			(xy 135.22767 -13.46213) (xy 135.229346 -13.470636) (xy 135.231378 -13.478764) (xy 135.244078 -13.526516)
			(xy 135.244078 -13.52677) (xy 135.248904 -13.545566) (xy 135.250928 -13.551452) (xy 135.257344 -13.562112)
			(xy 135.261604 -13.566648) (xy 135.278114 -13.583158) (xy 135.288274 -13.591032) (xy 135.293862 -13.594334)
			(xy 135.300212 -13.596112) (xy 135.363427 -13.614496) (xy 135.48768 -13.658048) (xy 135.609012 -13.709175)
			(xy 135.726962 -13.767684) (xy 135.841081 -13.833352) (xy 135.950935 -13.90593) (xy 136.056106 -13.985142)
			(xy 136.156195 -14.070686) (xy 136.186806 -14.100302) (xy 141.343124 -14.100302) (xy 141.347195 -14.04468)
			(xy 141.359321 -13.990243) (xy 141.379244 -13.938152) (xy 141.40654 -13.889517) (xy 141.440626 -13.845374)
			(xy 141.480775 -13.806665) (xy 141.526133 -13.774214) (xy 141.575733 -13.748713) (xy 141.628517 -13.730706)
			(xy 141.68336 -13.720576) (xy 141.739094 -13.718539) (xy 141.794531 -13.724639) (xy 141.848488 -13.738745)
			(xy 141.899817 -13.760557) (xy 141.947423 -13.789611) (xy 141.990291 -13.825286) (xy 142.027508 -13.866823)
			(xy 142.058281 -13.913336) (xy 142.081953 -13.963833) (xy 142.098021 -14.01724) (xy 142.106141 -14.072416)
			(xy 142.10665 -14.100302) (xy 142.106141 -14.128188) (xy 142.098021 -14.183364) (xy 142.081953 -14.236771)
			(xy 142.058281 -14.287268) (xy 142.027508 -14.333781) (xy 141.990291 -14.375318) (xy 141.947423 -14.410993)
			(xy 141.899817 -14.440047) (xy 141.848488 -14.461859) (xy 141.794531 -14.475965) (xy 141.739094 -14.482065)
			(xy 141.68336 -14.480028) (xy 141.628517 -14.469898) (xy 141.575733 -14.451891) (xy 141.526133 -14.42639)
			(xy 141.480775 -14.393939) (xy 141.440626 -14.35523) (xy 141.40654 -14.311087) (xy 141.379244 -14.262452)
			(xy 141.359321 -14.210361) (xy 141.347195 -14.155924) (xy 141.343124 -14.100302) (xy 136.186806 -14.100302)
			(xy 136.25082 -14.162236) (xy 136.339622 -14.259446) (xy 136.422263 -14.361944) (xy 136.498429 -14.469342)
			(xy 136.56783 -14.58123) (xy 136.630202 -14.697184) (xy 136.685307 -14.816761) (xy 136.732938 -14.939508)
			(xy 136.772911 -15.064958) (xy 136.805075 -15.192633) (xy 136.829308 -15.322048) (xy 136.838675 -15.397555)
			(xy 142.004457 -15.397555) (xy 142.004457 -15.343045) (xy 142.012215 -15.289091) (xy 142.027574 -15.23679)
			(xy 142.050219 -15.187207) (xy 142.079691 -15.141353) (xy 142.115389 -15.100159) (xy 142.156586 -15.064466)
			(xy 142.202444 -15.034999) (xy 142.25203 -15.012359) (xy 142.304332 -14.997007) (xy 142.358287 -14.989254)
			(xy 142.385542 -14.988794) (xy 142.411779 -14.989226) (xy 142.463756 -14.996426) (xy 142.514254 -15.010686)
			(xy 142.562321 -15.031736) (xy 142.607047 -15.059178) (xy 142.647588 -15.092493) (xy 142.665704 -15.111476)
			(xy 142.665958 -15.11173) (xy 142.673691 -15.119112) (xy 142.693374 -15.127386) (xy 142.704058 -15.127732)
			(xy 142.791942 -15.125446) (xy 142.8115 -15.116048) (xy 142.818612 -15.107412) (xy 142.83679 -15.086232)
			(xy 142.878337 -15.048959) (xy 142.924874 -15.018141) (xy 142.975405 -14.994435) (xy 143.028853 -14.978349)
			(xy 143.084074 -14.970225) (xy 143.111982 -14.969744) (xy 143.139232 -14.970302) (xy 143.193178 -14.978056)
			(xy 143.245472 -14.993408) (xy 143.295048 -15.016047) (xy 143.340898 -15.045511) (xy 143.382087 -15.0812)
			(xy 143.417778 -15.122388) (xy 143.447244 -15.168236) (xy 143.469885 -15.217811) (xy 143.48524 -15.270104)
			(xy 143.492997 -15.32405) (xy 143.492997 -15.37855) (xy 143.48524 -15.432496) (xy 143.469885 -15.484789)
			(xy 143.447244 -15.534364) (xy 143.417778 -15.580212) (xy 143.382087 -15.6214) (xy 143.340898 -15.657089)
			(xy 143.295048 -15.686553) (xy 143.245472 -15.709192) (xy 143.193178 -15.724544) (xy 143.139232 -15.732298)
			(xy 143.111982 -15.73276) (xy 143.085745 -15.732327) (xy 143.033768 -15.725129) (xy 142.983268 -15.71087)
			(xy 142.935202 -15.689821) (xy 142.890475 -15.662379) (xy 142.849935 -15.629062) (xy 142.83182 -15.610078)
			(xy 142.831566 -15.609824) (xy 142.82383 -15.602446) (xy 142.804149 -15.594171) (xy 142.793466 -15.593822)
			(xy 142.705582 -15.596108) (xy 142.686024 -15.605506) (xy 142.678912 -15.614142) (xy 142.66071 -15.635301)
			(xy 142.619169 -15.672577) (xy 142.572638 -15.703399) (xy 142.522111 -15.727109) (xy 142.468667 -15.7432)
			(xy 142.413449 -15.751328) (xy 142.385542 -15.75181) (xy 142.358287 -15.751346) (xy 142.304332 -15.743593)
			(xy 142.25203 -15.728241) (xy 142.202444 -15.705601) (xy 142.156586 -15.676134) (xy 142.115389 -15.640441)
			(xy 142.079691 -15.599247) (xy 142.050219 -15.553393) (xy 142.027574 -15.50381) (xy 142.012215 -15.451509)
			(xy 142.004457 -15.397555) (xy 136.838675 -15.397555) (xy 136.845518 -15.452711) (xy 136.853643 -15.584124)
			(xy 136.854184 -15.649956) (xy 136.853678 -15.715692) (xy 136.845585 -15.846913) (xy 136.829428 -15.977388)
			(xy 136.805271 -16.106621) (xy 136.773203 -16.234121) (xy 136.733347 -16.359405) (xy 136.685854 -16.481999)
			(xy 136.630905 -16.601436) (xy 136.568706 -16.717263) (xy 136.499496 -16.829042) (xy 136.423535 -16.936349)
			(xy 136.396461 -16.969994) (xy 155.848311 -16.969994) (xy 155.852316 -16.882086) (xy 155.864299 -16.794906)
			(xy 155.884159 -16.709177) (xy 155.911734 -16.625609) (xy 155.946793 -16.544895) (xy 155.989046 -16.467703)
			(xy 156.038144 -16.394674) (xy 156.09368 -16.326412) (xy 156.155192 -16.263482) (xy 156.222173 -16.206408)
			(xy 156.294066 -16.15566) (xy 156.370275 -16.11166) (xy 156.45017 -16.074773) (xy 156.533089 -16.045304)
			(xy 156.618344 -16.023497) (xy 156.705228 -16.009533) (xy 156.793022 -16.003527) (xy 156.880999 -16.005531)
			(xy 156.968429 -16.015526) (xy 157.054588 -16.03343) (xy 157.138762 -16.059094) (xy 157.220253 -16.092307)
			(xy 157.298387 -16.132793) (xy 157.372515 -16.180215) (xy 157.442023 -16.234182) (xy 157.506337 -16.294247)
			(xy 157.564921 -16.359911) (xy 157.617292 -16.43063) (xy 157.663015 -16.505818) (xy 157.701712 -16.584853)
			(xy 157.733061 -16.667079) (xy 157.756803 -16.751815) (xy 157.772741 -16.838359) (xy 157.780743 -16.925994)
			(xy 157.781244 -16.969994) (xy 157.780743 -17.013994) (xy 157.772741 -17.101629) (xy 157.756803 -17.188173)
			(xy 157.733061 -17.272909) (xy 157.701712 -17.355135) (xy 157.663015 -17.43417) (xy 157.617292 -17.509358)
			(xy 157.564921 -17.580077) (xy 157.506337 -17.645741) (xy 157.442023 -17.705806) (xy 157.372515 -17.759773)
			(xy 157.298387 -17.807195) (xy 157.220253 -17.847681) (xy 157.138762 -17.880894) (xy 157.054588 -17.906558)
			(xy 156.968429 -17.924462) (xy 156.880999 -17.934457) (xy 156.793022 -17.936461) (xy 156.705228 -17.930455)
			(xy 156.618344 -17.916491) (xy 156.533089 -17.894684) (xy 156.45017 -17.865215) (xy 156.370275 -17.828328)
			(xy 156.294066 -17.784328) (xy 156.222173 -17.73358) (xy 156.155192 -17.676506) (xy 156.09368 -17.613576)
			(xy 156.038144 -17.545314) (xy 155.989046 -17.472285) (xy 155.946793 -17.395093) (xy 155.911734 -17.314379)
			(xy 155.884159 -17.230811) (xy 155.864299 -17.145082) (xy 155.852316 -17.057902) (xy 155.848311 -16.969994)
			(xy 136.396461 -16.969994) (xy 136.341113 -17.038775) (xy 136.252541 -17.135934) (xy 136.158156 -17.227455)
			(xy 136.058317 -17.312993) (xy 135.9534 -17.392222) (xy 135.912122 -17.419574) (xy 140.384274 -17.419574)
			(xy 140.388345 -17.363952) (xy 140.400471 -17.309515) (xy 140.420394 -17.257424) (xy 140.44769 -17.208789)
			(xy 140.481776 -17.164646) (xy 140.521925 -17.125937) (xy 140.567283 -17.093486) (xy 140.616883 -17.067985)
			(xy 140.669667 -17.049978) (xy 140.72451 -17.039848) (xy 140.780244 -17.037811) (xy 140.835681 -17.043911)
			(xy 140.889638 -17.058017) (xy 140.940967 -17.079829) (xy 140.988573 -17.108883) (xy 141.031441 -17.144558)
			(xy 141.068658 -17.186095) (xy 141.099431 -17.232608) (xy 141.123103 -17.283105) (xy 141.139171 -17.336512)
			(xy 141.147291 -17.391688) (xy 141.1478 -17.419574) (xy 141.147291 -17.44746) (xy 141.139171 -17.502636)
			(xy 141.123103 -17.556043) (xy 141.099431 -17.60654) (xy 141.068658 -17.653053) (xy 141.031441 -17.69459)
			(xy 140.988573 -17.730265) (xy 140.940967 -17.759319) (xy 140.889638 -17.781131) (xy 140.835681 -17.795237)
			(xy 140.780244 -17.801337) (xy 140.72451 -17.7993) (xy 140.669667 -17.78917) (xy 140.616883 -17.771163)
			(xy 140.567283 -17.745662) (xy 140.521925 -17.713211) (xy 140.481776 -17.674502) (xy 140.44769 -17.630359)
			(xy 140.420394 -17.581724) (xy 140.400471 -17.529633) (xy 140.388345 -17.475196) (xy 140.384274 -17.419574)
			(xy 135.912122 -17.419574) (xy 135.843806 -17.464842) (xy 135.729948 -17.530577) (xy 135.61226 -17.589179)
			(xy 135.491188 -17.640425) (xy 135.36719 -17.68412) (xy 135.240738 -17.720099) (xy 135.11231 -17.748225)
			(xy 134.982395 -17.768391) (xy 134.851485 -17.780522) (xy 134.720076 -17.784571) (xy 134.588667 -17.780522)
			(xy 134.457757 -17.768391) (xy 134.327842 -17.748225) (xy 134.199414 -17.720099) (xy 134.072962 -17.68412)
			(xy 133.948964 -17.640425) (xy 133.827892 -17.589179) (xy 133.710204 -17.530577) (xy 133.596346 -17.464842)
			(xy 133.486752 -17.392222) (xy 133.381835 -17.312993) (xy 133.281996 -17.227455) (xy 133.187611 -17.135934)
			(xy 133.099039 -17.038775) (xy 133.016617 -16.936349) (xy 132.940656 -16.829042) (xy 132.871446 -16.717263)
			(xy 132.809247 -16.601436) (xy 132.754298 -16.481999) (xy 132.706805 -16.359405) (xy 132.666949 -16.234121)
			(xy 132.634881 -16.106621) (xy 132.610724 -15.977388) (xy 132.594567 -15.846913) (xy 132.586474 -15.715692)
			(xy 132.585968 -15.649956) (xy 132.586476 -15.599156) (xy 132.588436 -15.536369) (xy 132.598827 -15.411169)
			(xy 132.616562 -15.286796) (xy 132.641582 -15.163681) (xy 132.673798 -15.042251) (xy 132.7131 -14.922926)
			(xy 132.759352 -14.806118) (xy 132.812392 -14.692233) (xy 132.872039 -14.581664) (xy 132.938085 -14.474794)
			(xy 132.973826 -14.423136) (xy 132.975604 -14.420596) (xy 132.978769 -14.415172) (xy 132.982628 -14.403225)
			(xy 132.983224 -14.396974) (xy 132.983986 -14.383258) (xy 132.935726 -14.290548) (xy 132.93471 -14.288262)
			(xy 132.931296 -14.282892) (xy 132.922299 -14.273898) (xy 132.91693 -14.270482) (xy 132.911088 -14.266926)
			(xy 132.904738 -14.265148) (xy 132.890768 -14.263116) (xy 123.778518 -14.263116) (xy 123.768454 -14.262678)
			(xy 123.74987 -14.254945) (xy 123.74245 -14.24813) (xy 122.700034 -13.205714) (xy 122.693197 -13.198313)
			(xy 122.685489 -13.179714) (xy 122.685048 -13.169646) (xy 122.685048 -2.169922) (xy 122.684987 -2.166316)
			(xy 122.683971 -2.159176) (xy 122.683016 -2.155698) (xy 122.681492 -2.151126) (xy 122.677682 -2.141982)
			(xy 121.927366 -1.391666) (xy 121.924515 -1.38896) (xy 121.918136 -1.384369) (xy 121.914666 -1.382522)
			(xy 121.90924 -1.379937) (xy 121.89756 -1.37711) (xy 121.891552 -1.376934) (xy 98.281998 -1.376934)
			(xy 98.272092 -1.37795) (xy 98.271838 -1.37795) (xy 98.256852 -1.380998) (xy 98.248978 -1.384554)
			(xy 98.241104 -1.391666) (xy 98.240596 -1.392174) (xy 98.238818 -1.393698) (xy 98.236532 -1.395476)
			(xy 97.575878 -2.05613) (xy 97.573176 -2.058984) (xy 97.568591 -2.065366) (xy 97.566734 -2.06883)
			(xy 97.564148 -2.074256) (xy 97.561319 -2.085936) (xy 97.561146 -2.091944) (xy 97.561146 -5.747258)
			(xy 103.958388 -5.747258) (xy 103.962459 -5.691636) (xy 103.974585 -5.637199) (xy 103.994508 -5.585108)
			(xy 104.021804 -5.536473) (xy 104.05589 -5.49233) (xy 104.096039 -5.453621) (xy 104.141397 -5.42117)
			(xy 104.190997 -5.395669) (xy 104.243781 -5.377662) (xy 104.298624 -5.367532) (xy 104.354358 -5.365495)
			(xy 104.409795 -5.371595) (xy 104.463752 -5.385701) (xy 104.515081 -5.407513) (xy 104.562687 -5.436567)
			(xy 104.605555 -5.472242) (xy 104.642772 -5.513779) (xy 104.673545 -5.560292) (xy 104.697217 -5.610789)
			(xy 104.713285 -5.664196) (xy 104.721405 -5.719372) (xy 104.721914 -5.747258) (xy 106.926124 -5.747258)
			(xy 106.930195 -5.691636) (xy 106.942321 -5.637199) (xy 106.962244 -5.585108) (xy 106.98954 -5.536473)
			(xy 107.023626 -5.49233) (xy 107.063775 -5.453621) (xy 107.109133 -5.42117) (xy 107.158733 -5.395669)
			(xy 107.211517 -5.377662) (xy 107.26636 -5.367532) (xy 107.322094 -5.365495) (xy 107.377531 -5.371595)
			(xy 107.431488 -5.385701) (xy 107.482817 -5.407513) (xy 107.530423 -5.436567) (xy 107.573291 -5.472242)
			(xy 107.610508 -5.513779) (xy 107.641281 -5.560292) (xy 107.664953 -5.610789) (xy 107.681021 -5.664196)
			(xy 107.689141 -5.719372) (xy 107.68965 -5.747258) (xy 107.689141 -5.775144) (xy 107.681021 -5.83032)
			(xy 107.664953 -5.883727) (xy 107.641281 -5.934224) (xy 107.610508 -5.980737) (xy 107.573291 -6.022274)
			(xy 107.530423 -6.057949) (xy 107.482817 -6.087003) (xy 107.431488 -6.108815) (xy 107.377531 -6.122921)
			(xy 107.322094 -6.129021) (xy 107.26636 -6.126984) (xy 107.211517 -6.116854) (xy 107.158733 -6.098847)
			(xy 107.109133 -6.073346) (xy 107.063775 -6.040895) (xy 107.023626 -6.002186) (xy 106.98954 -5.958043)
			(xy 106.962244 -5.909408) (xy 106.942321 -5.857317) (xy 106.930195 -5.80288) (xy 106.926124 -5.747258)
			(xy 104.721914 -5.747258) (xy 104.721405 -5.775144) (xy 104.713285 -5.83032) (xy 104.697217 -5.883727)
			(xy 104.673545 -5.934224) (xy 104.642772 -5.980737) (xy 104.605555 -6.022274) (xy 104.562687 -6.057949)
			(xy 104.515081 -6.087003) (xy 104.463752 -6.108815) (xy 104.409795 -6.122921) (xy 104.354358 -6.129021)
			(xy 104.298624 -6.126984) (xy 104.243781 -6.116854) (xy 104.190997 -6.098847) (xy 104.141397 -6.073346)
			(xy 104.096039 -6.040895) (xy 104.05589 -6.002186) (xy 104.021804 -5.958043) (xy 103.994508 -5.909408)
			(xy 103.974585 -5.857317) (xy 103.962459 -5.80288) (xy 103.958388 -5.747258) (xy 97.561146 -5.747258)
			(xy 97.561146 -6.931152) (xy 98.156774 -6.931152) (xy 98.160845 -6.87553) (xy 98.172971 -6.821093)
			(xy 98.192894 -6.769002) (xy 98.22019 -6.720367) (xy 98.254276 -6.676224) (xy 98.294425 -6.637515)
			(xy 98.339783 -6.605064) (xy 98.389383 -6.579563) (xy 98.442167 -6.561556) (xy 98.49701 -6.551426)
			(xy 98.552744 -6.549389) (xy 98.608181 -6.555489) (xy 98.662138 -6.569595) (xy 98.713467 -6.591407)
			(xy 98.761073 -6.620461) (xy 98.803941 -6.656136) (xy 98.841158 -6.697673) (xy 98.871931 -6.744186)
			(xy 98.895603 -6.794683) (xy 98.911671 -6.84809) (xy 98.919791 -6.903266) (xy 98.9203 -6.931152)
			(xy 98.919791 -6.959038) (xy 98.911671 -7.014214) (xy 98.895603 -7.067621) (xy 98.871931 -7.118118)
			(xy 98.841158 -7.164631) (xy 98.803941 -7.206168) (xy 98.761073 -7.241843) (xy 98.713467 -7.270897)
			(xy 98.662138 -7.292709) (xy 98.608181 -7.306815) (xy 98.552744 -7.312915) (xy 98.49701 -7.310878)
			(xy 98.442167 -7.300748) (xy 98.389383 -7.282741) (xy 98.339783 -7.25724) (xy 98.294425 -7.224789)
			(xy 98.254276 -7.18608) (xy 98.22019 -7.141937) (xy 98.192894 -7.093302) (xy 98.172971 -7.041211)
			(xy 98.160845 -6.986774) (xy 98.156774 -6.931152) (xy 97.561146 -6.931152) (xy 97.561146 -7.381748)
			(xy 97.561393 -7.389163) (xy 97.565641 -7.40337) (xy 97.569528 -7.409688) (xy 97.573338 -7.41553)
			(xy 97.584006 -7.424674) (xy 97.591372 -7.427976) (xy 97.616394 -7.43953) (xy 97.663105 -7.468778)
			(xy 97.70512 -7.504445) (xy 97.741564 -7.545788) (xy 97.771677 -7.591946) (xy 97.794834 -7.641957)
			(xy 97.810552 -7.694781) (xy 97.818502 -7.749316) (xy 97.818521 -7.804429) (xy 97.810606 -7.85897)
			(xy 97.794924 -7.911804) (xy 97.792674 -7.916672) (xy 98.32543 -7.916672) (xy 98.329501 -7.86105)
			(xy 98.341627 -7.806613) (xy 98.36155 -7.754522) (xy 98.388846 -7.705887) (xy 98.422932 -7.661744)
			(xy 98.463081 -7.623035) (xy 98.508439 -7.590584) (xy 98.558039 -7.565083) (xy 98.610823 -7.547076)
			(xy 98.665666 -7.536946) (xy 98.7214 -7.534909) (xy 98.776837 -7.541009) (xy 98.830794 -7.555115)
			(xy 98.882123 -7.576927) (xy 98.929729 -7.605981) (xy 98.972597 -7.641656) (xy 99.009814 -7.683193)
			(xy 99.040587 -7.729706) (xy 99.064259 -7.780203) (xy 99.080327 -7.83361) (xy 99.088447 -7.888786)
			(xy 99.088956 -7.916672) (xy 99.088447 -7.944558) (xy 99.080327 -7.999734) (xy 99.064259 -8.053141)
			(xy 99.040587 -8.103638) (xy 99.009814 -8.150151) (xy 98.972597 -8.191688) (xy 98.929729 -8.227363)
			(xy 98.882123 -8.256417) (xy 98.830794 -8.278229) (xy 98.776837 -8.292335) (xy 98.7214 -8.298435)
			(xy 98.665666 -8.296398) (xy 98.610823 -8.286268) (xy 98.558039 -8.268261) (xy 98.508439 -8.24276)
			(xy 98.463081 -8.210309) (xy 98.422932 -8.1716) (xy 98.388846 -8.127457) (xy 98.36155 -8.078822)
			(xy 98.341627 -8.026731) (xy 98.329501 -7.972294) (xy 98.32543 -7.916672) (xy 97.792674 -7.916672)
			(xy 97.771801 -7.961831) (xy 97.741718 -8.008009) (xy 97.705302 -8.049376) (xy 97.663311 -8.085071)
			(xy 97.616619 -8.11435) (xy 97.591626 -8.125968) (xy 97.591372 -8.125968) (xy 97.590864 -8.126222)
			(xy 97.584395 -8.129445) (xy 97.573425 -8.138848) (xy 97.569274 -8.144764) (xy 97.56521 -8.15086)
			(xy 97.563178 -8.157972) (xy 97.562229 -8.161451) (xy 97.56121 -8.16859) (xy 97.561146 -8.172196)
			(xy 97.561146 -8.181848) (xy 97.561393 -8.189263) (xy 97.565641 -8.20347) (xy 97.569528 -8.209788)
			(xy 97.573338 -8.21563) (xy 97.584006 -8.224774) (xy 97.591372 -8.228076) (xy 97.616394 -8.23963)
			(xy 97.663105 -8.268878) (xy 97.70512 -8.304545) (xy 97.741564 -8.345888) (xy 97.771677 -8.392046)
			(xy 97.794834 -8.442057) (xy 97.810552 -8.494881) (xy 97.818502 -8.549416) (xy 97.818521 -8.604529)
			(xy 97.810606 -8.65907) (xy 97.794924 -8.711904) (xy 97.771801 -8.761931) (xy 97.741718 -8.808109)
			(xy 97.705302 -8.849476) (xy 97.663311 -8.885171) (xy 97.616619 -8.91445) (xy 97.591626 -8.926068)
			(xy 97.591372 -8.926068) (xy 97.590864 -8.926322) (xy 97.584395 -8.929545) (xy 97.573425 -8.938948)
			(xy 97.569274 -8.944864) (xy 97.56521 -8.95096) (xy 97.563178 -8.958072) (xy 97.562229 -8.961551)
			(xy 97.56121 -8.96869) (xy 97.561146 -8.972296) (xy 97.561146 -9.535922) (xy 100.374702 -9.535922)
			(xy 100.378773 -9.4803) (xy 100.390899 -9.425863) (xy 100.410822 -9.373772) (xy 100.438118 -9.325137)
			(xy 100.472204 -9.280994) (xy 100.512353 -9.242285) (xy 100.557711 -9.209834) (xy 100.607311 -9.184333)
			(xy 100.660095 -9.166326) (xy 100.714938 -9.156196) (xy 100.770672 -9.154159) (xy 100.826109 -9.160259)
			(xy 100.880066 -9.174365) (xy 100.931395 -9.196177) (xy 100.979001 -9.225231) (xy 101.021869 -9.260906)
			(xy 101.059086 -9.302443) (xy 101.089859 -9.348956) (xy 101.113531 -9.399453) (xy 101.129599 -9.45286)
			(xy 101.137719 -9.508036) (xy 101.138228 -9.535922) (xy 101.137719 -9.563808) (xy 101.129599 -9.618984)
			(xy 101.113531 -9.672391) (xy 101.089859 -9.722888) (xy 101.059086 -9.769401) (xy 101.021869 -9.810938)
			(xy 100.979001 -9.846613) (xy 100.931395 -9.875667) (xy 100.880066 -9.897479) (xy 100.826109 -9.911585)
			(xy 100.770672 -9.917685) (xy 100.714938 -9.915648) (xy 100.660095 -9.905518) (xy 100.607311 -9.887511)
			(xy 100.557711 -9.86201) (xy 100.512353 -9.829559) (xy 100.472204 -9.79085) (xy 100.438118 -9.746707)
			(xy 100.410822 -9.698072) (xy 100.390899 -9.645981) (xy 100.378773 -9.591544) (xy 100.374702 -9.535922)
			(xy 97.561146 -9.535922) (xy 97.561146 -12.776454) (xy 97.5614 -12.776708) (xy 96.95688 -13.381228)
			(xy 96.948833 -13.390642) (xy 96.942186 -13.41447) (xy 96.94418 -13.426694) (xy 96.94418 -13.427456)
			(xy 96.946974 -13.437362) (xy 96.971866 -13.517372) (xy 96.971866 -13.517626) (xy 96.974152 -13.524076)
			(xy 96.981615 -13.535542) (xy 96.986598 -13.540232) (xy 96.991678 -13.54455) (xy 97.004124 -13.550646)
			(xy 97.010982 -13.551916) (xy 97.07414 -13.564174) (xy 97.198983 -13.59532) (xy 97.321722 -13.633931)
			(xy 97.441913 -13.679867) (xy 97.559117 -13.732962) (xy 97.672909 -13.793022) (xy 97.782876 -13.859828)
			(xy 97.888618 -13.933139) (xy 97.98975 -14.012688) (xy 98.085906 -14.098186) (xy 98.176736 -14.189322)
			(xy 98.26191 -14.285765) (xy 98.341118 -14.387164) (xy 98.414073 -14.493152) (xy 98.480509 -14.603343)
			(xy 98.540186 -14.717337) (xy 98.592886 -14.834719) (xy 98.638417 -14.955063) (xy 98.676616 -15.077931)
			(xy 98.707341 -15.202878) (xy 98.730483 -15.32945) (xy 98.745956 -15.457185) (xy 98.753706 -15.585621)
			(xy 98.754184 -15.649956) (xy 98.753708 -15.714428) (xy 98.745925 -15.843137) (xy 98.730385 -15.971142)
			(xy 98.707144 -16.097974) (xy 98.676288 -16.223172) (xy 98.637928 -16.346278) (xy 98.592206 -16.466844)
			(xy 98.539287 -16.584428) (xy 98.479365 -16.698604) (xy 98.412658 -16.808952) (xy 98.33941 -16.915072)
			(xy 98.259888 -17.016575) (xy 98.174383 -17.113092) (xy 98.083206 -17.20427) (xy 97.986691 -17.289776)
			(xy 97.885188 -17.369298) (xy 97.779069 -17.442547) (xy 97.668721 -17.509255) (xy 97.554546 -17.569178)
			(xy 97.436962 -17.622098) (xy 97.316397 -17.667822) (xy 97.193291 -17.706182) (xy 97.068094 -17.73704)
			(xy 96.941261 -17.760282) (xy 96.813257 -17.775823) (xy 96.684548 -17.783607) (xy 96.620076 -17.784064)
			(xy 96.555683 -17.783579) (xy 96.427131 -17.775811) (xy 96.299281 -17.760305) (xy 96.172599 -17.737118)
			(xy 96.047546 -17.706333) (xy 95.924577 -17.668063) (xy 95.80414 -17.622448) (xy 95.686672 -17.569652)
			(xy 95.572602 -17.509869) (xy 95.462345 -17.443315) (xy 95.356302 -17.370234) (xy 95.254859 -17.290892)
			(xy 95.158386 -17.205576) (xy 95.067233 -17.114597) (xy 94.981732 -17.018288) (xy 94.902194 -16.916997)
			(xy 94.82891 -16.811095) (xy 94.762145 -16.700965) (xy 94.702143 -16.587011) (xy 94.649122 -16.469645)
			(xy 94.603275 -16.349295) (xy 94.56477 -16.2264) (xy 94.533745 -16.101406) (xy 94.510314 -15.974769)
			(xy 94.494563 -15.846949) (xy 94.486549 -15.718412) (xy 94.485968 -15.65402) (xy 94.485968 -15.649702)
			(xy 94.486459 -15.584439) (xy 94.494438 -15.454157) (xy 94.510365 -15.324606) (xy 94.534182 -15.196271)
			(xy 94.565799 -15.069632) (xy 94.605097 -14.945162) (xy 94.651931 -14.823328) (xy 94.706124 -14.704583)
			(xy 94.767475 -14.589374) (xy 94.835753 -14.47813) (xy 94.87281 -14.424406) (xy 94.873572 -14.42339)
			(xy 94.880938 -14.412214) (xy 94.886934 -14.401731) (xy 94.889442 -14.377744) (xy 94.885764 -14.36624)
			(xy 94.881192 -14.357096) (xy 94.878906 -14.353794) (xy 94.871032 -14.34465) (xy 94.869508 -14.342872)
			(xy 94.866968 -14.340078) (xy 94.859094 -14.331442) (xy 94.858586 -14.330934) (xy 94.850458 -14.319758)
			(xy 94.832678 -14.28496) (xy 94.826836 -14.279118) (xy 94.819724 -14.271752) (xy 94.810326 -14.267688)
			(xy 94.806903 -14.266293) (xy 94.799764 -14.264378) (xy 94.796102 -14.263878) (xy 94.790514 -14.263624)
			(xy 88.502744 -14.263624) (xy 88.492678 -14.263191) (xy 88.474086 -14.255465) (xy 88.466676 -14.248638)
			(xy 87.785702 -13.567664) (xy 87.782852 -13.564957) (xy 87.776475 -13.560361) (xy 87.773002 -13.55852)
			(xy 87.767576 -13.555931) (xy 87.755897 -13.553096) (xy 87.749888 -13.552932) (xy 86.3346 -13.552932)
			(xy 86.324529 -13.55251) (xy 86.305922 -13.544799) (xy 86.298532 -13.537946) (xy 85.21446 -12.453874)
			(xy 85.207611 -12.446477) (xy 85.199877 -12.427878) (xy 85.199474 -12.417806) (xy 85.199474 -1.262888)
			(xy 85.19941 -1.259282) (xy 85.19839 -1.252143) (xy 85.197442 -1.248664) (xy 85.195918 -1.244092)
			(xy 85.192108 -1.234948) (xy 84.860638 -0.903478) (xy 84.857787 -0.900773) (xy 84.851408 -0.89618)
			(xy 84.847938 -0.894334) (xy 84.842511 -0.891751) (xy 84.830831 -0.88893) (xy 84.824824 -0.888746)
			(xy 84.686648 -0.888746) (xy 84.676583 -0.888312) (xy 84.657998 -0.880578) (xy 84.65058 -0.87376)
			(xy 84.398612 -0.621792) (xy 84.39576 -0.619087) (xy 84.389381 -0.614497) (xy 84.385912 -0.612648)
			(xy 84.380485 -0.610068) (xy 84.368805 -0.607252) (xy 84.362798 -0.60706) (xy 71.585836 -0.60706)
			(xy 71.58223 -0.60712) (xy 71.575089 -0.608135) (xy 71.571612 -0.609092) (xy 71.56704 -0.610616)
			(xy 71.557896 -0.614426) (xy 70.671182 -1.50114) (xy 70.66848 -1.503994) (xy 70.663896 -1.510377)
			(xy 70.662038 -1.51384) (xy 70.659453 -1.519266) (xy 70.656626 -1.530946) (xy 70.65645 -1.536954)
			(xy 70.65645 -3.659632) (xy 81.365342 -3.659632) (xy 81.369413 -3.60401) (xy 81.381539 -3.549573)
			(xy 81.401462 -3.497482) (xy 81.428758 -3.448847) (xy 81.462844 -3.404704) (xy 81.502993 -3.365995)
			(xy 81.548351 -3.333544) (xy 81.597951 -3.308043) (xy 81.650735 -3.290036) (xy 81.705578 -3.279906)
			(xy 81.761312 -3.277869) (xy 81.816749 -3.283969) (xy 81.870706 -3.298075) (xy 81.922035 -3.319887)
			(xy 81.969641 -3.348941) (xy 82.012509 -3.384616) (xy 82.049726 -3.426153) (xy 82.080499 -3.472666)
			(xy 82.104171 -3.523163) (xy 82.120239 -3.57657) (xy 82.128359 -3.631746) (xy 82.128868 -3.659632)
			(xy 82.128359 -3.687518) (xy 82.120239 -3.742694) (xy 82.104171 -3.796101) (xy 82.080499 -3.846598)
			(xy 82.049726 -3.893111) (xy 82.012509 -3.934648) (xy 81.969641 -3.970323) (xy 81.922035 -3.999377)
			(xy 81.88592 -4.014724) (xy 83.667852 -4.014724) (xy 83.671923 -3.959102) (xy 83.684049 -3.904665)
			(xy 83.703972 -3.852574) (xy 83.731268 -3.803939) (xy 83.765354 -3.759796) (xy 83.805503 -3.721087)
			(xy 83.850861 -3.688636) (xy 83.900461 -3.663135) (xy 83.953245 -3.645128) (xy 84.008088 -3.634998)
			(xy 84.063822 -3.632961) (xy 84.119259 -3.639061) (xy 84.173216 -3.653167) (xy 84.224545 -3.674979)
			(xy 84.272151 -3.704033) (xy 84.315019 -3.739708) (xy 84.352236 -3.781245) (xy 84.383009 -3.827758)
			(xy 84.406681 -3.878255) (xy 84.422749 -3.931662) (xy 84.430869 -3.986838) (xy 84.431378 -4.014724)
			(xy 84.430869 -4.04261) (xy 84.422749 -4.097786) (xy 84.406681 -4.151193) (xy 84.383009 -4.20169)
			(xy 84.352236 -4.248203) (xy 84.315019 -4.28974) (xy 84.272151 -4.325415) (xy 84.224545 -4.354469)
			(xy 84.173216 -4.376281) (xy 84.119259 -4.390387) (xy 84.063822 -4.396487) (xy 84.008088 -4.39445)
			(xy 83.953245 -4.38432) (xy 83.900461 -4.366313) (xy 83.850861 -4.340812) (xy 83.805503 -4.308361)
			(xy 83.765354 -4.269652) (xy 83.731268 -4.225509) (xy 83.703972 -4.176874) (xy 83.684049 -4.124783)
			(xy 83.671923 -4.070346) (xy 83.667852 -4.014724) (xy 81.88592 -4.014724) (xy 81.870706 -4.021189)
			(xy 81.816749 -4.035295) (xy 81.761312 -4.041395) (xy 81.705578 -4.039358) (xy 81.650735 -4.029228)
			(xy 81.597951 -4.011221) (xy 81.548351 -3.98572) (xy 81.502993 -3.953269) (xy 81.462844 -3.91456)
			(xy 81.428758 -3.870417) (xy 81.401462 -3.821782) (xy 81.381539 -3.769691) (xy 81.369413 -3.715254)
			(xy 81.365342 -3.659632) (xy 70.65645 -3.659632) (xy 70.65645 -3.964686) (xy 70.657466 -3.974084)
			(xy 70.657466 -3.974592) (xy 70.65917 -3.981751) (xy 70.666001 -3.994779) (xy 70.670928 -4.000246)
			(xy 71.17969 -4.509008) (xy 71.184269 -4.513958) (xy 71.190944 -4.525667) (xy 71.192898 -4.532122)
			(xy 71.192898 -4.532376) (xy 71.195184 -4.541012) (xy 71.20001 -4.548378) (xy 71.20224 -4.551498)
			(xy 71.207471 -4.557107) (xy 71.210424 -4.559554) (xy 71.280782 -4.610608) (xy 71.285114 -4.613615)
			(xy 71.294715 -4.61797) (xy 71.299832 -4.619244) (xy 71.309738 -4.621276) (xy 71.32701 -4.618736)
			(xy 71.33082 -4.617466) (xy 71.358078 -4.60951) (xy 71.414192 -4.600831) (xy 71.44258 -4.600194)
			(xy 71.449438 -4.600194) (xy 71.476464 -4.601007) (xy 71.529888 -4.609318) (xy 71.581605 -4.625088)
			(xy 71.630577 -4.648001) (xy 71.675824 -4.677598) (xy 71.716439 -4.713286) (xy 71.75161 -4.754351)
			(xy 71.780631 -4.79997) (xy 71.802921 -4.849228) (xy 71.818034 -4.901141) (xy 71.825666 -4.954666)
			(xy 71.825666 -5.008734) (xy 71.82253 -5.030724) (xy 81.62112 -5.030724) (xy 81.625191 -4.975102)
			(xy 81.637317 -4.920665) (xy 81.65724 -4.868574) (xy 81.684536 -4.819939) (xy 81.718622 -4.775796)
			(xy 81.758771 -4.737087) (xy 81.804129 -4.704636) (xy 81.853729 -4.679135) (xy 81.906513 -4.661128)
			(xy 81.961356 -4.650998) (xy 82.01709 -4.648961) (xy 82.072527 -4.655061) (xy 82.126484 -4.669167)
			(xy 82.177813 -4.690979) (xy 82.225419 -4.720033) (xy 82.268287 -4.755708) (xy 82.305504 -4.797245)
			(xy 82.336277 -4.843758) (xy 82.359949 -4.894255) (xy 82.376017 -4.947662) (xy 82.384137 -5.002838)
			(xy 82.384646 -5.030724) (xy 83.667852 -5.030724) (xy 83.671923 -4.975102) (xy 83.684049 -4.920665)
			(xy 83.703972 -4.868574) (xy 83.731268 -4.819939) (xy 83.765354 -4.775796) (xy 83.805503 -4.737087)
			(xy 83.850861 -4.704636) (xy 83.900461 -4.679135) (xy 83.953245 -4.661128) (xy 84.008088 -4.650998)
			(xy 84.063822 -4.648961) (xy 84.119259 -4.655061) (xy 84.173216 -4.669167) (xy 84.224545 -4.690979)
			(xy 84.272151 -4.720033) (xy 84.315019 -4.755708) (xy 84.352236 -4.797245) (xy 84.383009 -4.843758)
			(xy 84.406681 -4.894255) (xy 84.422749 -4.947662) (xy 84.430869 -5.002838) (xy 84.431378 -5.030724)
			(xy 84.430869 -5.05861) (xy 84.422749 -5.113786) (xy 84.406681 -5.167193) (xy 84.383009 -5.21769)
			(xy 84.352236 -5.264203) (xy 84.315019 -5.30574) (xy 84.272151 -5.341415) (xy 84.224545 -5.370469)
			(xy 84.173216 -5.392281) (xy 84.119259 -5.406387) (xy 84.063822 -5.412487) (xy 84.008088 -5.41045)
			(xy 83.953245 -5.40032) (xy 83.900461 -5.382313) (xy 83.850861 -5.356812) (xy 83.805503 -5.324361)
			(xy 83.765354 -5.285652) (xy 83.731268 -5.241509) (xy 83.703972 -5.192874) (xy 83.684049 -5.140783)
			(xy 83.671923 -5.086346) (xy 83.667852 -5.030724) (xy 82.384646 -5.030724) (xy 82.384137 -5.05861)
			(xy 82.376017 -5.113786) (xy 82.359949 -5.167193) (xy 82.336277 -5.21769) (xy 82.305504 -5.264203)
			(xy 82.268287 -5.30574) (xy 82.225419 -5.341415) (xy 82.177813 -5.370469) (xy 82.126484 -5.392281)
			(xy 82.072527 -5.406387) (xy 82.01709 -5.412487) (xy 81.961356 -5.41045) (xy 81.906513 -5.40032)
			(xy 81.853729 -5.382313) (xy 81.804129 -5.356812) (xy 81.758771 -5.324361) (xy 81.718622 -5.285652)
			(xy 81.684536 -5.241509) (xy 81.65724 -5.192874) (xy 81.637317 -5.140783) (xy 81.625191 -5.086346)
			(xy 81.62112 -5.030724) (xy 71.82253 -5.030724) (xy 71.818034 -5.062259) (xy 71.802921 -5.114172)
			(xy 71.780631 -5.16343) (xy 71.75161 -5.209049) (xy 71.716439 -5.250114) (xy 71.675824 -5.285802)
			(xy 71.630577 -5.315399) (xy 71.581605 -5.338312) (xy 71.529888 -5.354082) (xy 71.476463 -5.362393)
			(xy 71.449438 -5.36321) (xy 71.444104 -5.36321) (xy 71.415333 -5.362667) (xy 71.358446 -5.353994)
			(xy 71.33082 -5.345938) (xy 71.32701 -5.344668) (xy 71.318374 -5.343398) (xy 71.309738 -5.343398)
			(xy 71.305932 -5.343467) (xy 71.298407 -5.34462) (xy 71.294752 -5.345684) (xy 71.286878 -5.348224)
			(xy 71.222616 -5.39496) (xy 71.21525 -5.400294) (xy 71.214742 -5.400802) (xy 71.212964 -5.401818)
			(xy 71.20882 -5.405396) (xy 71.202026 -5.413978) (xy 71.199502 -5.418836) (xy 71.199502 -5.41909)
			(xy 71.197046 -5.424417) (xy 71.194364 -5.435833) (xy 71.194168 -5.441696) (xy 71.194168 -5.889752)
			(xy 73.306684 -5.889752) (xy 73.310755 -5.83413) (xy 73.322881 -5.779693) (xy 73.342804 -5.727602)
			(xy 73.3701 -5.678967) (xy 73.404186 -5.634824) (xy 73.444335 -5.596115) (xy 73.489693 -5.563664)
			(xy 73.539293 -5.538163) (xy 73.592077 -5.520156) (xy 73.64692 -5.510026) (xy 73.702654 -5.507989)
			(xy 73.758091 -5.514089) (xy 73.812048 -5.528195) (xy 73.863377 -5.550007) (xy 73.910983 -5.579061)
			(xy 73.953851 -5.614736) (xy 73.991068 -5.656273) (xy 74.021841 -5.702786) (xy 74.045513 -5.753283)
			(xy 74.061581 -5.80669) (xy 74.069701 -5.861866) (xy 74.07021 -5.889752) (xy 74.069701 -5.917638)
			(xy 74.061581 -5.972814) (xy 74.045513 -6.026221) (xy 74.021841 -6.076718) (xy 73.991068 -6.123231)
			(xy 73.953851 -6.164768) (xy 73.910983 -6.200443) (xy 73.863377 -6.229497) (xy 73.812048 -6.251309)
			(xy 73.758091 -6.265415) (xy 73.702654 -6.271515) (xy 73.64692 -6.269478) (xy 73.592077 -6.259348)
			(xy 73.539293 -6.241341) (xy 73.489693 -6.21584) (xy 73.444335 -6.183389) (xy 73.404186 -6.14468)
			(xy 73.3701 -6.100537) (xy 73.342804 -6.051902) (xy 73.322881 -5.999811) (xy 73.310755 -5.945374)
			(xy 73.306684 -5.889752) (xy 71.194168 -5.889752) (xy 71.194168 -6.651498) (xy 81.434684 -6.651498)
			(xy 81.438755 -6.595876) (xy 81.450881 -6.541439) (xy 81.470804 -6.489348) (xy 81.4981 -6.440713)
			(xy 81.532186 -6.39657) (xy 81.572335 -6.357861) (xy 81.617693 -6.32541) (xy 81.667293 -6.299909)
			(xy 81.720077 -6.281902) (xy 81.77492 -6.271772) (xy 81.830654 -6.269735) (xy 81.886091 -6.275835)
			(xy 81.940048 -6.289941) (xy 81.991377 -6.311753) (xy 82.038983 -6.340807) (xy 82.081851 -6.376482)
			(xy 82.119068 -6.418019) (xy 82.149841 -6.464532) (xy 82.173513 -6.515029) (xy 82.189581 -6.568436)
			(xy 82.197701 -6.623612) (xy 82.19821 -6.651498) (xy 82.197701 -6.679384) (xy 82.189581 -6.73456)
			(xy 82.173513 -6.787967) (xy 82.149841 -6.838464) (xy 82.119068 -6.884977) (xy 82.081851 -6.926514)
			(xy 82.038983 -6.962189) (xy 81.991377 -6.991243) (xy 81.940048 -7.013055) (xy 81.886091 -7.027161)
			(xy 81.830654 -7.033261) (xy 81.77492 -7.031224) (xy 81.720077 -7.021094) (xy 81.667293 -7.003087)
			(xy 81.617693 -6.977586) (xy 81.572335 -6.945135) (xy 81.532186 -6.906426) (xy 81.4981 -6.862283)
			(xy 81.470804 -6.813648) (xy 81.450881 -6.761557) (xy 81.438755 -6.70712) (xy 81.434684 -6.651498)
			(xy 71.194168 -6.651498) (xy 71.194168 -7.183374) (xy 73.184256 -7.183374) (xy 73.188327 -7.127752)
			(xy 73.200453 -7.073315) (xy 73.220376 -7.021224) (xy 73.247672 -6.972589) (xy 73.281758 -6.928446)
			(xy 73.321907 -6.889737) (xy 73.367265 -6.857286) (xy 73.416865 -6.831785) (xy 73.469649 -6.813778)
			(xy 73.524492 -6.803648) (xy 73.580226 -6.801611) (xy 73.635663 -6.807711) (xy 73.68962 -6.821817)
			(xy 73.740949 -6.843629) (xy 73.788555 -6.872683) (xy 73.831423 -6.908358) (xy 73.86864 -6.949895)
			(xy 73.899413 -6.996408) (xy 73.923085 -7.046905) (xy 73.927844 -7.062724) (xy 83.667852 -7.062724)
			(xy 83.671923 -7.007102) (xy 83.684049 -6.952665) (xy 83.703972 -6.900574) (xy 83.731268 -6.851939)
			(xy 83.765354 -6.807796) (xy 83.805503 -6.769087) (xy 83.850861 -6.736636) (xy 83.900461 -6.711135)
			(xy 83.953245 -6.693128) (xy 84.008088 -6.682998) (xy 84.063822 -6.680961) (xy 84.119259 -6.687061)
			(xy 84.173216 -6.701167) (xy 84.224545 -6.722979) (xy 84.272151 -6.752033) (xy 84.315019 -6.787708)
			(xy 84.352236 -6.829245) (xy 84.383009 -6.875758) (xy 84.406681 -6.926255) (xy 84.422749 -6.979662)
			(xy 84.430869 -7.034838) (xy 84.431378 -7.062724) (xy 84.430869 -7.09061) (xy 84.422749 -7.145786)
			(xy 84.406681 -7.199193) (xy 84.383009 -7.24969) (xy 84.352236 -7.296203) (xy 84.315019 -7.33774)
			(xy 84.272151 -7.373415) (xy 84.224545 -7.402469) (xy 84.173216 -7.424281) (xy 84.119259 -7.438387)
			(xy 84.063822 -7.444487) (xy 84.008088 -7.44245) (xy 83.953245 -7.43232) (xy 83.900461 -7.414313)
			(xy 83.850861 -7.388812) (xy 83.805503 -7.356361) (xy 83.765354 -7.317652) (xy 83.731268 -7.273509)
			(xy 83.703972 -7.224874) (xy 83.684049 -7.172783) (xy 83.671923 -7.118346) (xy 83.667852 -7.062724)
			(xy 73.927844 -7.062724) (xy 73.939153 -7.100312) (xy 73.947273 -7.155488) (xy 73.947782 -7.183374)
			(xy 73.947273 -7.21126) (xy 73.939153 -7.266436) (xy 73.923085 -7.319843) (xy 73.899413 -7.37034)
			(xy 73.86864 -7.416853) (xy 73.831423 -7.45839) (xy 73.788555 -7.494065) (xy 73.740949 -7.523119)
			(xy 73.68962 -7.544931) (xy 73.635663 -7.559037) (xy 73.580226 -7.565137) (xy 73.524492 -7.5631)
			(xy 73.469649 -7.55297) (xy 73.416865 -7.534963) (xy 73.367265 -7.509462) (xy 73.321907 -7.477011)
			(xy 73.281758 -7.438302) (xy 73.247672 -7.394159) (xy 73.220376 -7.345524) (xy 73.200453 -7.293433)
			(xy 73.188327 -7.238996) (xy 73.184256 -7.183374) (xy 71.194168 -7.183374) (xy 71.194168 -8.653272)
			(xy 71.923146 -8.653272) (xy 71.927217 -8.59765) (xy 71.939343 -8.543213) (xy 71.959266 -8.491122)
			(xy 71.986562 -8.442487) (xy 72.020648 -8.398344) (xy 72.060797 -8.359635) (xy 72.106155 -8.327184)
			(xy 72.155755 -8.301683) (xy 72.208539 -8.283676) (xy 72.263382 -8.273546) (xy 72.319116 -8.271509)
			(xy 72.374553 -8.277609) (xy 72.42851 -8.291715) (xy 72.479839 -8.313527) (xy 72.527445 -8.342581)
			(xy 72.570313 -8.378256) (xy 72.60753 -8.419793) (xy 72.638303 -8.466306) (xy 72.661975 -8.516803)
			(xy 72.678043 -8.57021) (xy 72.686163 -8.625386) (xy 72.686672 -8.653272) (xy 72.686163 -8.681158)
			(xy 72.678043 -8.736334) (xy 72.661975 -8.789741) (xy 72.638303 -8.840238) (xy 72.60753 -8.886751)
			(xy 72.570313 -8.928288) (xy 72.527445 -8.963963) (xy 72.479839 -8.993017) (xy 72.42851 -9.014829)
			(xy 72.374553 -9.028935) (xy 72.319116 -9.035035) (xy 72.263382 -9.032998) (xy 72.208539 -9.022868)
			(xy 72.155755 -9.004861) (xy 72.106155 -8.97936) (xy 72.060797 -8.946909) (xy 72.020648 -8.9082)
			(xy 71.986562 -8.864057) (xy 71.959266 -8.815422) (xy 71.939343 -8.763331) (xy 71.927217 -8.708894)
			(xy 71.923146 -8.653272) (xy 71.194168 -8.653272) (xy 71.194168 -9.33069) (xy 73.22642 -9.33069)
			(xy 73.230491 -9.275068) (xy 73.242617 -9.220631) (xy 73.26254 -9.16854) (xy 73.289836 -9.119905)
			(xy 73.323922 -9.075762) (xy 73.364071 -9.037053) (xy 73.409429 -9.004602) (xy 73.459029 -8.979101)
			(xy 73.511813 -8.961094) (xy 73.566656 -8.950964) (xy 73.62239 -8.948927) (xy 73.677827 -8.955027)
			(xy 73.731784 -8.969133) (xy 73.783113 -8.990945) (xy 73.830719 -9.019999) (xy 73.873587 -9.055674)
			(xy 73.910804 -9.097211) (xy 73.941577 -9.143724) (xy 73.965249 -9.194221) (xy 73.981317 -9.247628)
			(xy 73.989437 -9.302804) (xy 73.989946 -9.33069) (xy 73.989437 -9.358576) (xy 73.981317 -9.413752)
			(xy 73.965249 -9.467159) (xy 73.941577 -9.517656) (xy 73.929492 -9.535922) (xy 78.931006 -9.535922)
			(xy 78.935077 -9.4803) (xy 78.947203 -9.425863) (xy 78.967126 -9.373772) (xy 78.994422 -9.325137)
			(xy 79.028508 -9.280994) (xy 79.068657 -9.242285) (xy 79.114015 -9.209834) (xy 79.163615 -9.184333)
			(xy 79.216399 -9.166326) (xy 79.271242 -9.156196) (xy 79.326976 -9.154159) (xy 79.382413 -9.160259)
			(xy 79.43637 -9.174365) (xy 79.487699 -9.196177) (xy 79.535305 -9.225231) (xy 79.578173 -9.260906)
			(xy 79.61539 -9.302443) (xy 79.646163 -9.348956) (xy 79.669835 -9.399453) (xy 79.685903 -9.45286)
			(xy 79.694023 -9.508036) (xy 79.694532 -9.535922) (xy 79.694023 -9.563808) (xy 79.685903 -9.618984)
			(xy 79.669835 -9.672391) (xy 79.646163 -9.722888) (xy 79.61539 -9.769401) (xy 79.578173 -9.810938)
			(xy 79.535305 -9.846613) (xy 79.487699 -9.875667) (xy 79.43637 -9.897479) (xy 79.382413 -9.911585)
			(xy 79.326976 -9.917685) (xy 79.271242 -9.915648) (xy 79.216399 -9.905518) (xy 79.163615 -9.887511)
			(xy 79.114015 -9.86201) (xy 79.068657 -9.829559) (xy 79.028508 -9.79085) (xy 78.994422 -9.746707)
			(xy 78.967126 -9.698072) (xy 78.947203 -9.645981) (xy 78.935077 -9.591544) (xy 78.931006 -9.535922)
			(xy 73.929492 -9.535922) (xy 73.910804 -9.564169) (xy 73.873587 -9.605706) (xy 73.830719 -9.641381)
			(xy 73.783113 -9.670435) (xy 73.731784 -9.692247) (xy 73.677827 -9.706353) (xy 73.62239 -9.712453)
			(xy 73.566656 -9.710416) (xy 73.511813 -9.700286) (xy 73.459029 -9.682279) (xy 73.409429 -9.656778)
			(xy 73.364071 -9.624327) (xy 73.323922 -9.585618) (xy 73.289836 -9.541475) (xy 73.26254 -9.49284)
			(xy 73.242617 -9.440749) (xy 73.230491 -9.386312) (xy 73.22642 -9.33069) (xy 71.194168 -9.33069)
			(xy 71.194168 -12.821412) (xy 71.193742 -12.831481) (xy 71.186021 -12.850079) (xy 71.179182 -12.85748)
			(xy 70.690232 -13.34643) (xy 70.682313 -13.355128) (xy 70.674773 -13.377379) (xy 70.675754 -13.389102)
			(xy 70.67677 -13.39596) (xy 70.710552 -13.486892) (xy 70.715414 -13.496995) (xy 70.732015 -13.512027)
			(xy 70.742556 -13.515848) (xy 70.753478 -13.518134) (xy 70.817768 -13.52263) (xy 70.94569 -13.538398)
			(xy 71.072429 -13.561852) (xy 71.197522 -13.592906) (xy 71.320515 -13.631448) (xy 71.44096 -13.677337)
			(xy 71.558418 -13.730406) (xy 71.672463 -13.790461) (xy 71.782677 -13.857285) (xy 71.888662 -13.930634)
			(xy 71.99003 -14.010241) (xy 72.086413 -14.095816) (xy 72.09089 -14.100302) (xy 77.242922 -14.100302)
			(xy 77.246993 -14.04468) (xy 77.259119 -13.990243) (xy 77.279042 -13.938152) (xy 77.306338 -13.889517)
			(xy 77.340424 -13.845374) (xy 77.380573 -13.806665) (xy 77.425931 -13.774214) (xy 77.475531 -13.748713)
			(xy 77.528315 -13.730706) (xy 77.583158 -13.720576) (xy 77.638892 -13.718539) (xy 77.694329 -13.724639)
			(xy 77.748286 -13.738745) (xy 77.799615 -13.760557) (xy 77.847221 -13.789611) (xy 77.890089 -13.825286)
			(xy 77.927306 -13.866823) (xy 77.958079 -13.913336) (xy 77.981751 -13.963833) (xy 77.997819 -14.01724)
			(xy 78.005939 -14.072416) (xy 78.006448 -14.100302) (xy 78.005939 -14.128188) (xy 77.997819 -14.183364)
			(xy 77.981751 -14.236771) (xy 77.958079 -14.287268) (xy 77.927306 -14.333781) (xy 77.890089 -14.375318)
			(xy 77.847221 -14.410993) (xy 77.799615 -14.440047) (xy 77.748286 -14.461859) (xy 77.694329 -14.475965)
			(xy 77.638892 -14.482065) (xy 77.583158 -14.480028) (xy 77.528315 -14.469898) (xy 77.475531 -14.451891)
			(xy 77.425931 -14.42639) (xy 77.380573 -14.393939) (xy 77.340424 -14.35523) (xy 77.306338 -14.311087)
			(xy 77.279042 -14.262452) (xy 77.259119 -14.210361) (xy 77.246993 -14.155924) (xy 77.242922 -14.100302)
			(xy 72.09089 -14.100302) (xy 72.177459 -14.187048) (xy 72.262838 -14.283604) (xy 72.342239 -14.385134)
			(xy 72.415372 -14.491267) (xy 72.481972 -14.601617) (xy 72.541796 -14.715783) (xy 72.594626 -14.833349)
			(xy 72.64027 -14.953887) (xy 72.678562 -15.076958) (xy 72.709362 -15.202114) (xy 72.732558 -15.3289)
			(xy 72.741376 -15.401652) (xy 77.829644 -15.401652) (xy 77.829644 -15.347148) (xy 77.8374 -15.293199)
			(xy 77.852755 -15.240902) (xy 77.875395 -15.191323) (xy 77.904861 -15.14547) (xy 77.940552 -15.104277)
			(xy 77.981741 -15.068582) (xy 78.027591 -15.039113) (xy 78.077168 -15.016467) (xy 78.129463 -15.001108)
			(xy 78.183412 -14.993346) (xy 78.210664 -14.992858) (xy 78.236798 -14.993271) (xy 78.288576 -15.00042)
			(xy 78.338895 -15.014563) (xy 78.386816 -15.035434) (xy 78.431443 -15.062645) (xy 78.471943 -15.095687)
			(xy 78.490064 -15.114524) (xy 78.497684 -15.122906) (xy 78.518258 -15.131288) (xy 78.618588 -15.126462)
			(xy 78.638146 -15.116302) (xy 78.645004 -15.107412) (xy 78.663187 -15.084652) (xy 78.705279 -15.044382)
			(xy 78.753006 -15.010982) (xy 78.805256 -14.985228) (xy 78.860816 -14.96772) (xy 78.918392 -14.958864)
			(xy 78.947518 -14.958314) (xy 78.97477 -14.958757) (xy 79.028719 -14.966516) (xy 79.081014 -14.981874)
			(xy 79.130592 -15.004517) (xy 79.176443 -15.033986) (xy 79.217634 -15.069679) (xy 79.253325 -15.110871)
			(xy 79.282791 -15.156724) (xy 79.305433 -15.206302) (xy 79.320788 -15.258599) (xy 79.328544 -15.312548)
			(xy 79.328544 -15.367052) (xy 79.320788 -15.421001) (xy 79.305433 -15.473298) (xy 79.282791 -15.522876)
			(xy 79.253325 -15.568729) (xy 79.217634 -15.609921) (xy 79.176443 -15.645614) (xy 79.130592 -15.675083)
			(xy 79.081014 -15.697726) (xy 79.028719 -15.713084) (xy 78.97477 -15.720843) (xy 78.947518 -15.72133)
			(xy 78.921385 -15.720867) (xy 78.86961 -15.713728) (xy 78.819292 -15.699596) (xy 78.771371 -15.678734)
			(xy 78.726742 -15.651531) (xy 78.68624 -15.618497) (xy 78.668118 -15.599664) (xy 78.660498 -15.591282)
			(xy 78.639924 -15.5829) (xy 78.539594 -15.587726) (xy 78.520036 -15.597886) (xy 78.513178 -15.606776)
			(xy 78.495002 -15.629542) (xy 78.452909 -15.669812) (xy 78.405181 -15.703212) (xy 78.352929 -15.728965)
			(xy 78.297368 -15.746472) (xy 78.239791 -15.755326) (xy 78.210664 -15.755874) (xy 78.183412 -15.755454)
			(xy 78.129463 -15.747692) (xy 78.077168 -15.732333) (xy 78.027591 -15.709687) (xy 77.981741 -15.680218)
			(xy 77.940552 -15.644523) (xy 77.904861 -15.60333) (xy 77.875395 -15.557477) (xy 77.852755 -15.507898)
			(xy 77.8374 -15.455601) (xy 77.829644 -15.401652) (xy 72.741376 -15.401652) (xy 72.748066 -15.456854)
			(xy 72.75583 -15.585511) (xy 72.756268 -15.649956) (xy 72.755762 -15.715754) (xy 72.74766 -15.847101)
			(xy 72.731489 -15.9777) (xy 72.707308 -16.107055) (xy 72.67521 -16.234677) (xy 72.635316 -16.360081)
			(xy 72.587778 -16.482791) (xy 72.532776 -16.602342) (xy 72.470519 -16.71828) (xy 72.401242 -16.830165)
			(xy 72.325209 -16.937573) (xy 72.29912 -16.969994) (xy 91.748109 -16.969994) (xy 91.752114 -16.882086)
			(xy 91.764097 -16.794906) (xy 91.783957 -16.709177) (xy 91.811532 -16.625609) (xy 91.846591 -16.544895)
			(xy 91.888844 -16.467703) (xy 91.937942 -16.394674) (xy 91.993478 -16.326412) (xy 92.05499 -16.263482)
			(xy 92.121971 -16.206408) (xy 92.193864 -16.15566) (xy 92.270073 -16.11166) (xy 92.349968 -16.074773)
			(xy 92.432887 -16.045304) (xy 92.518142 -16.023497) (xy 92.605026 -16.009533) (xy 92.69282 -16.003527)
			(xy 92.780797 -16.005531) (xy 92.868227 -16.015526) (xy 92.954386 -16.03343) (xy 93.03856 -16.059094)
			(xy 93.120051 -16.092307) (xy 93.198185 -16.132793) (xy 93.272313 -16.180215) (xy 93.341821 -16.234182)
			(xy 93.406135 -16.294247) (xy 93.464719 -16.359911) (xy 93.51709 -16.43063) (xy 93.562813 -16.505818)
			(xy 93.60151 -16.584853) (xy 93.632859 -16.667079) (xy 93.656601 -16.751815) (xy 93.672539 -16.838359)
			(xy 93.680541 -16.925994) (xy 93.681042 -16.969994) (xy 93.680541 -17.013994) (xy 93.672539 -17.101629)
			(xy 93.656601 -17.188173) (xy 93.632859 -17.272909) (xy 93.60151 -17.355135) (xy 93.562813 -17.43417)
			(xy 93.51709 -17.509358) (xy 93.464719 -17.580077) (xy 93.406135 -17.645741) (xy 93.341821 -17.705806)
			(xy 93.272313 -17.759773) (xy 93.198185 -17.807195) (xy 93.120051 -17.847681) (xy 93.03856 -17.880894)
			(xy 92.954386 -17.906558) (xy 92.868227 -17.924462) (xy 92.780797 -17.934457) (xy 92.69282 -17.936461)
			(xy 92.605026 -17.930455) (xy 92.518142 -17.916491) (xy 92.432887 -17.894684) (xy 92.349968 -17.865215)
			(xy 92.270073 -17.828328) (xy 92.193864 -17.784328) (xy 92.121971 -17.73358) (xy 92.05499 -17.676506)
			(xy 91.993478 -17.613576) (xy 91.937942 -17.545314) (xy 91.888844 -17.472285) (xy 91.846591 -17.395093)
			(xy 91.811532 -17.314379) (xy 91.783957 -17.230811) (xy 91.764097 -17.145082) (xy 91.752114 -17.057902)
			(xy 91.748109 -16.969994) (xy 72.29912 -16.969994) (xy 72.242708 -17.040098) (xy 72.154052 -17.137349)
			(xy 72.059578 -17.228957) (xy 71.959643 -17.314576) (xy 71.854627 -17.393881) (xy 71.815852 -17.419574)
			(xy 76.284072 -17.419574) (xy 76.288143 -17.363952) (xy 76.300269 -17.309515) (xy 76.320192 -17.257424)
			(xy 76.347488 -17.208789) (xy 76.381574 -17.164646) (xy 76.421723 -17.125937) (xy 76.467081 -17.093486)
			(xy 76.516681 -17.067985) (xy 76.569465 -17.049978) (xy 76.624308 -17.039848) (xy 76.680042 -17.037811)
			(xy 76.735479 -17.043911) (xy 76.789436 -17.058017) (xy 76.840765 -17.079829) (xy 76.888371 -17.108883)
			(xy 76.931239 -17.144558) (xy 76.968456 -17.186095) (xy 76.999229 -17.232608) (xy 77.022901 -17.283105)
			(xy 77.038969 -17.336512) (xy 77.047089 -17.391688) (xy 77.047598 -17.419574) (xy 77.047089 -17.44746)
			(xy 77.038969 -17.502636) (xy 77.022901 -17.556043) (xy 76.999229 -17.60654) (xy 76.968456 -17.653053)
			(xy 76.931239 -17.69459) (xy 76.888371 -17.730265) (xy 76.840765 -17.759319) (xy 76.789436 -17.781131)
			(xy 76.735479 -17.795237) (xy 76.680042 -17.801337) (xy 76.624308 -17.7993) (xy 76.569465 -17.78917)
			(xy 76.516681 -17.771163) (xy 76.467081 -17.745662) (xy 76.421723 -17.713211) (xy 76.381574 -17.674502)
			(xy 76.347488 -17.630359) (xy 76.320192 -17.581724) (xy 76.300269 -17.529633) (xy 76.288143 -17.475196)
			(xy 76.284072 -17.419574) (xy 71.815852 -17.419574) (xy 71.744928 -17.46657) (xy 71.630962 -17.532368)
			(xy 71.513162 -17.591026) (xy 71.391974 -17.64232) (xy 71.267858 -17.686057) (xy 71.141286 -17.72207)
			(xy 71.012736 -17.750223) (xy 70.882697 -17.770408) (xy 70.751662 -17.78255) (xy 70.620128 -17.786603)
			(xy 70.488594 -17.78255) (xy 70.357559 -17.770408) (xy 70.22752 -17.750223) (xy 70.09897 -17.72207)
			(xy 69.972398 -17.686057) (xy 69.848282 -17.64232) (xy 69.727094 -17.591026) (xy 69.609294 -17.532368)
			(xy 69.495328 -17.46657) (xy 69.385629 -17.393881) (xy 69.280613 -17.314576) (xy 69.180678 -17.228957)
			(xy 69.086204 -17.137349) (xy 68.997548 -17.040098) (xy 68.915047 -16.937573) (xy 68.839014 -16.830165)
			(xy 68.769737 -16.71828) (xy 68.70748 -16.602342) (xy 68.652478 -16.482791) (xy 68.60494 -16.360081)
			(xy 68.565046 -16.234677) (xy 68.532948 -16.107055) (xy 68.508767 -15.9777) (xy 68.492596 -15.847101)
			(xy 68.484494 -15.715754) (xy 68.483988 -15.649956) (xy 68.484475 -15.585064) (xy 68.492351 -15.45552)
			(xy 68.508078 -15.326693) (xy 68.531598 -15.199058) (xy 68.562824 -15.073087) (xy 68.60164 -14.949244)
			(xy 68.647904 -14.827986) (xy 68.701445 -14.709761) (xy 68.762065 -14.595004) (xy 68.829541 -14.48414)
			(xy 68.903623 -14.377578) (xy 68.943474 -14.326362) (xy 68.944744 -14.324838) (xy 68.949852 -14.31719)
			(xy 68.954742 -14.299477) (xy 68.953028 -14.281181) (xy 68.949316 -14.272768) (xy 68.914772 -14.20114)
			(xy 68.912919 -14.197453) (xy 68.908193 -14.190691) (xy 68.905374 -14.187678) (xy 68.904612 -14.186916)
			(xy 68.89623 -14.178534) (xy 68.892503 -14.175007) (xy 68.883934 -14.169366) (xy 68.879212 -14.167358)
			(xy 68.870576 -14.163802) (xy 59.914536 -14.163802) (xy 59.904471 -14.163367) (xy 59.885883 -14.155637)
			(xy 59.878468 -14.148816) (xy 58.553858 -12.824206) (xy 58.547004 -12.816811) (xy 58.539258 -12.798212)
			(xy 58.538872 -12.788138) (xy 58.538872 -2.091182) (xy 58.538618 -2.08661) (xy 58.538131 -2.082945)
			(xy 58.536215 -2.075805) (xy 58.534808 -2.072386) (xy 58.531252 -2.064258) (xy 58.524648 -2.0574)
			(xy 58.522108 -2.054352) (xy 58.52033 -2.052066) (xy 57.95899 -1.490726) (xy 57.956138 -1.488021)
			(xy 57.949759 -1.48343) (xy 57.94629 -1.481582) (xy 57.940864 -1.478996) (xy 57.929184 -1.476166)
			(xy 57.923176 -1.475994) (xy 45.977048 -1.475994) (xy 45.967142 -1.47701) (xy 45.966888 -1.47701)
			(xy 45.951902 -1.480058) (xy 45.944028 -1.483614) (xy 45.936154 -1.490726) (xy 45.935646 -1.491234)
			(xy 45.933868 -1.492758) (xy 45.931582 -1.494536) (xy 45.336968 -2.08915) (xy 45.334258 -2.091998)
			(xy 45.329657 -2.098373) (xy 45.327824 -2.10185) (xy 45.32524 -2.107277) (xy 45.322417 -2.118956)
			(xy 45.322236 -2.124964) (xy 45.322236 -13.449046) (xy 45.321903 -13.45765) (xy 45.31619 -13.473881)
			(xy 45.31106 -13.480796) (xy 45.310044 -13.482066) (xy 45.306977 -13.486388) (xy 45.302499 -13.49599)
			(xy 45.301154 -13.501116) (xy 45.29836 -13.512292) (xy 45.304964 -13.543788) (xy 45.304964 -13.544296)
			(xy 45.319442 -13.609066) (xy 45.32057 -13.613234) (xy 45.324018 -13.621149) (xy 45.3263 -13.624814)
			(xy 45.329348 -13.628878) (xy 45.332098 -13.632121) (xy 45.338482 -13.637738) (xy 45.342048 -13.640054)
			(xy 45.349922 -13.644626) (xy 45.35424 -13.64615) (xy 45.415166 -13.669006) (xy 45.534402 -13.72115)
			(xy 45.650239 -13.780464) (xy 45.762246 -13.846726) (xy 45.870006 -13.919691) (xy 45.973121 -13.999087)
			(xy 46.071205 -14.08462) (xy 46.087117 -14.100302) (xy 51.242974 -14.100302) (xy 51.247045 -14.04468)
			(xy 51.259171 -13.990243) (xy 51.279094 -13.938152) (xy 51.30639 -13.889517) (xy 51.340476 -13.845374)
			(xy 51.380625 -13.806665) (xy 51.425983 -13.774214) (xy 51.475583 -13.748713) (xy 51.528367 -13.730706)
			(xy 51.58321 -13.720576) (xy 51.638944 -13.718539) (xy 51.694381 -13.724639) (xy 51.748338 -13.738745)
			(xy 51.799667 -13.760557) (xy 51.847273 -13.789611) (xy 51.890141 -13.825286) (xy 51.927358 -13.866823)
			(xy 51.958131 -13.913336) (xy 51.981803 -13.963833) (xy 51.997871 -14.01724) (xy 52.005991 -14.072416)
			(xy 52.0065 -14.100302) (xy 52.005991 -14.128188) (xy 51.997871 -14.183364) (xy 51.981803 -14.236771)
			(xy 51.958131 -14.287268) (xy 51.927358 -14.333781) (xy 51.890141 -14.375318) (xy 51.847273 -14.410993)
			(xy 51.799667 -14.440047) (xy 51.748338 -14.461859) (xy 51.694381 -14.475965) (xy 51.638944 -14.482065)
			(xy 51.58321 -14.480028) (xy 51.528367 -14.469898) (xy 51.475583 -14.451891) (xy 51.425983 -14.42639)
			(xy 51.380625 -14.393939) (xy 51.340476 -14.35523) (xy 51.30639 -14.311087) (xy 51.279094 -14.262452)
			(xy 51.259171 -14.210361) (xy 51.247045 -14.155924) (xy 51.242974 -14.100302) (xy 46.087117 -14.100302)
			(xy 46.163895 -14.17597) (xy 46.250845 -14.272799) (xy 46.331733 -14.374747) (xy 46.406259 -14.481435)
			(xy 46.474144 -14.592466) (xy 46.535137 -14.707427) (xy 46.589011 -14.825892) (xy 46.635566 -14.947419)
			(xy 46.674628 -15.071558) (xy 46.706053 -15.197846) (xy 46.729724 -15.325815) (xy 46.738514 -15.397551)
			(xy 51.90438 -15.397551) (xy 51.90438 -15.343049) (xy 51.912136 -15.289103) (xy 51.927491 -15.236809)
			(xy 51.950131 -15.187232) (xy 51.979596 -15.141382) (xy 52.015287 -15.100193) (xy 52.056476 -15.064501)
			(xy 52.102325 -15.035035) (xy 52.151901 -15.012393) (xy 52.204195 -14.997038) (xy 52.258141 -14.98928)
			(xy 52.285392 -14.988794) (xy 52.31501 -14.989396) (xy 52.373535 -14.998549) (xy 52.429941 -15.016637)
			(xy 52.482876 -15.043224) (xy 52.531065 -15.077673) (xy 52.5526 -15.098014) (xy 52.560524 -15.105065)
			(xy 52.580347 -15.112546) (xy 52.590954 -15.112492) (xy 52.676298 -15.10792) (xy 52.695094 -15.098522)
			(xy 52.701952 -15.090394) (xy 52.720189 -15.069186) (xy 52.761774 -15.031783) (xy 52.808373 -15.000848)
			(xy 52.858987 -14.977046) (xy 52.912533 -14.960886) (xy 52.967864 -14.952713) (xy 52.99583 -14.952218)
			(xy 53.023082 -14.952654) (xy 53.07703 -14.960414) (xy 53.129325 -14.975773) (xy 53.178901 -14.998418)
			(xy 53.224751 -15.027887) (xy 53.265941 -15.063581) (xy 53.301631 -15.104773) (xy 53.331097 -15.150625)
			(xy 53.353737 -15.200204) (xy 53.369092 -15.252499) (xy 53.376848 -15.306448) (xy 53.376848 -15.360952)
			(xy 53.369092 -15.414901) (xy 53.353737 -15.467196) (xy 53.331097 -15.516775) (xy 53.301631 -15.562627)
			(xy 53.265941 -15.603819) (xy 53.224751 -15.639513) (xy 53.178901 -15.668982) (xy 53.129325 -15.691627)
			(xy 53.07703 -15.706986) (xy 53.023082 -15.714746) (xy 52.99583 -15.715234) (xy 52.966209 -15.714701)
			(xy 52.90768 -15.705534) (xy 52.851272 -15.687431) (xy 52.798339 -15.660828) (xy 52.750154 -15.626363)
			(xy 52.728622 -15.606014) (xy 52.720697 -15.598964) (xy 52.700875 -15.591485) (xy 52.690268 -15.591536)
			(xy 52.604924 -15.596108) (xy 52.586128 -15.605506) (xy 52.57927 -15.613634) (xy 52.561081 -15.634885)
			(xy 52.519485 -15.672284) (xy 52.472876 -15.703212) (xy 52.422253 -15.727007) (xy 52.368699 -15.743158)
			(xy 52.31336 -15.751321) (xy 52.285392 -15.75181) (xy 52.258141 -15.75132) (xy 52.204195 -15.743562)
			(xy 52.151901 -15.728207) (xy 52.102325 -15.705565) (xy 52.056476 -15.676099) (xy 52.015287 -15.640407)
			(xy 51.979596 -15.599218) (xy 51.950131 -15.553368) (xy 51.927491 -15.503791) (xy 51.912136 -15.451497)
			(xy 51.90438 -15.397551) (xy 46.738514 -15.397551) (xy 46.745552 -15.454988) (xy 46.75348 -15.584886)
			(xy 46.754034 -15.649956) (xy 46.753557 -15.714428) (xy 46.745772 -15.843135) (xy 46.730229 -15.971138)
			(xy 46.706987 -16.097969) (xy 46.676129 -16.223166) (xy 46.637768 -16.34627) (xy 46.592044 -16.466834)
			(xy 46.539125 -16.584418) (xy 46.479202 -16.698591) (xy 46.412495 -16.808938) (xy 46.339247 -16.915056)
			(xy 46.296206 -16.969994) (xy 65.748161 -16.969994) (xy 65.752166 -16.882086) (xy 65.764149 -16.794906)
			(xy 65.784009 -16.709177) (xy 65.811584 -16.625609) (xy 65.846643 -16.544895) (xy 65.888896 -16.467703)
			(xy 65.937994 -16.394674) (xy 65.99353 -16.326412) (xy 66.055042 -16.263482) (xy 66.122023 -16.206408)
			(xy 66.193916 -16.15566) (xy 66.270125 -16.11166) (xy 66.35002 -16.074773) (xy 66.432939 -16.045304)
			(xy 66.518194 -16.023497) (xy 66.605078 -16.009533) (xy 66.692872 -16.003527) (xy 66.780849 -16.005531)
			(xy 66.868279 -16.015526) (xy 66.954438 -16.03343) (xy 67.038612 -16.059094) (xy 67.120103 -16.092307)
			(xy 67.198237 -16.132793) (xy 67.272365 -16.180215) (xy 67.341873 -16.234182) (xy 67.406187 -16.294247)
			(xy 67.464771 -16.359911) (xy 67.517142 -16.43063) (xy 67.562865 -16.505818) (xy 67.601562 -16.584853)
			(xy 67.632911 -16.667079) (xy 67.656653 -16.751815) (xy 67.672591 -16.838359) (xy 67.680593 -16.925994)
			(xy 67.681094 -16.969994) (xy 67.680593 -17.013994) (xy 67.672591 -17.101629) (xy 67.656653 -17.188173)
			(xy 67.632911 -17.272909) (xy 67.601562 -17.355135) (xy 67.562865 -17.43417) (xy 67.517142 -17.509358)
			(xy 67.464771 -17.580077) (xy 67.406187 -17.645741) (xy 67.341873 -17.705806) (xy 67.272365 -17.759773)
			(xy 67.198237 -17.807195) (xy 67.120103 -17.847681) (xy 67.038612 -17.880894) (xy 66.954438 -17.906558)
			(xy 66.868279 -17.924462) (xy 66.780849 -17.934457) (xy 66.692872 -17.936461) (xy 66.605078 -17.930455)
			(xy 66.518194 -17.916491) (xy 66.432939 -17.894684) (xy 66.35002 -17.865215) (xy 66.270125 -17.828328)
			(xy 66.193916 -17.784328) (xy 66.122023 -17.73358) (xy 66.055042 -17.676506) (xy 65.99353 -17.613576)
			(xy 65.937994 -17.545314) (xy 65.888896 -17.472285) (xy 65.846643 -17.395093) (xy 65.811584 -17.314379)
			(xy 65.784009 -17.230811) (xy 65.764149 -17.145082) (xy 65.752166 -17.057902) (xy 65.748161 -16.969994)
			(xy 46.296206 -16.969994) (xy 46.259725 -17.016558) (xy 46.17422 -17.113074) (xy 46.083044 -17.20425)
			(xy 45.986528 -17.289755) (xy 45.885026 -17.369277) (xy 45.812158 -17.419574) (xy 50.284124 -17.419574)
			(xy 50.288195 -17.363952) (xy 50.300321 -17.309515) (xy 50.320244 -17.257424) (xy 50.34754 -17.208789)
			(xy 50.381626 -17.164646) (xy 50.421775 -17.125937) (xy 50.467133 -17.093486) (xy 50.516733 -17.067985)
			(xy 50.569517 -17.049978) (xy 50.62436 -17.039848) (xy 50.680094 -17.037811) (xy 50.735531 -17.043911)
			(xy 50.789488 -17.058017) (xy 50.840817 -17.079829) (xy 50.888423 -17.108883) (xy 50.931291 -17.144558)
			(xy 50.968508 -17.186095) (xy 50.999281 -17.232608) (xy 51.022953 -17.283105) (xy 51.039021 -17.336512)
			(xy 51.047141 -17.391688) (xy 51.04765 -17.419574) (xy 51.047141 -17.44746) (xy 51.039021 -17.502636)
			(xy 51.022953 -17.556043) (xy 50.999281 -17.60654) (xy 50.968508 -17.653053) (xy 50.931291 -17.69459)
			(xy 50.888423 -17.730265) (xy 50.840817 -17.759319) (xy 50.789488 -17.781131) (xy 50.735531 -17.795237)
			(xy 50.680094 -17.801337) (xy 50.62436 -17.7993) (xy 50.569517 -17.78917) (xy 50.516733 -17.771163)
			(xy 50.467133 -17.745662) (xy 50.421775 -17.713211) (xy 50.381626 -17.674502) (xy 50.34754 -17.630359)
			(xy 50.320244 -17.581724) (xy 50.300321 -17.529633) (xy 50.288195 -17.475196) (xy 50.284124 -17.419574)
			(xy 45.812158 -17.419574) (xy 45.778908 -17.442525) (xy 45.668561 -17.509232) (xy 45.554388 -17.569155)
			(xy 45.436804 -17.622074) (xy 45.31624 -17.667798) (xy 45.193136 -17.706159) (xy 45.067939 -17.737017)
			(xy 44.941108 -17.760259) (xy 44.813105 -17.775802) (xy 44.684398 -17.783587) (xy 44.619926 -17.784064)
			(xy 44.555499 -17.783579) (xy 44.426879 -17.775806) (xy 44.298962 -17.760286) (xy 44.172215 -17.737076)
			(xy 44.0471 -17.706261) (xy 43.924071 -17.667952) (xy 43.803579 -17.62229) (xy 43.686061 -17.569441)
			(xy 43.571946 -17.509597) (xy 43.46165 -17.442976) (xy 43.355574 -17.369822) (xy 43.254106 -17.290401)
			(xy 43.157615 -17.205002) (xy 43.066453 -17.113936) (xy 42.980951 -17.017536) (xy 42.901422 -16.916153)
			(xy 42.828156 -16.810155) (xy 42.761418 -16.69993) (xy 42.701453 -16.585879) (xy 42.648479 -16.468417)
			(xy 42.602689 -16.347973) (xy 42.564249 -16.224985) (xy 42.533301 -16.099903) (xy 42.509956 -15.97318)
			(xy 42.4943 -15.84528) (xy 42.48639 -15.716669) (xy 42.485818 -15.652242) (xy 42.485818 -15.649702)
			(xy 42.486321 -15.583634) (xy 42.494492 -15.451751) (xy 42.510809 -15.320626) (xy 42.535208 -15.190763)
			(xy 42.567598 -15.062658) (xy 42.607853 -14.936803) (xy 42.655819 -14.81368) (xy 42.711313 -14.693762)
			(xy 42.774121 -14.577508) (xy 42.808652 -14.52118) (xy 42.809414 -14.51991) (xy 42.812208 -14.514322)
			(xy 42.812208 -14.480794) (xy 42.811976 -14.474422) (xy 42.80876 -14.462088) (xy 42.805858 -14.45641)
			(xy 42.77233 -14.395196) (xy 42.770533 -14.392082) (xy 42.7662 -14.386344) (xy 42.763694 -14.383766)
			(xy 42.7482 -14.368272) (xy 42.744136 -14.365986) (xy 42.73804 -14.364208) (xy 42.724578 -14.36243)
			(xy 33.878266 -14.36243) (xy 33.868198 -14.362001) (xy 33.8496 -14.354282) (xy 33.842198 -14.347444)
			(xy 32.5501 -13.055346) (xy 32.543262 -13.047945) (xy 32.535547 -13.029346) (xy 32.535114 -13.019278)
			(xy 32.535114 -1.926082) (xy 32.53486 -1.92151) (xy 32.534373 -1.917845) (xy 32.532459 -1.910704)
			(xy 32.53105 -1.907286) (xy 32.527494 -1.899158) (xy 32.52089 -1.8923) (xy 32.51835 -1.889252) (xy 32.516572 -1.886966)
			(xy 32.054292 -1.424686) (xy 32.051439 -1.421983) (xy 32.045058 -1.417394) (xy 32.041592 -1.415542)
			(xy 32.036166 -1.412953) (xy 32.024487 -1.410119) (xy 32.018478 -1.409954) (xy 19.794728 -1.409954)
			(xy 19.784665 -1.410392) (xy 19.766085 -1.418131) (xy 19.75866 -1.42494) (xy 19.496786 -1.686814)
			(xy 19.489932 -1.694209) (xy 19.48219 -1.712808) (xy 19.4818 -1.722882) (xy 19.4818 -11.688318) (xy 19.481373 -11.698387)
			(xy 19.473654 -11.716986) (xy 19.466814 -11.724386) (xy 17.744186 -13.447014) (xy 17.736791 -13.453868)
			(xy 17.718192 -13.46161) (xy 17.708118 -13.462) (xy 8.276082 -13.462) (xy 8.266013 -13.461573) (xy 8.247414 -13.453854)
			(xy 8.240014 -13.447014) (xy 7.228586 -12.435586) (xy 7.221732 -12.428191) (xy 7.21399 -12.409592)
			(xy 7.2136 -12.399518) (xy 7.2136 -1.32461) (xy 7.213078 -1.313682) (xy 7.203993 -1.293804) (xy 7.196074 -1.286256)
			(xy 6.58876 -0.760984) (xy 6.58205 -0.755609) (xy 6.566086 -0.749251) (xy 6.557518 -0.748538) (xy 1.764538 -0.54483)
			(xy 1.75397 -0.544874) (xy 1.734277 -0.552476) (xy 1.726438 -0.559562) (xy 0.700786 -1.585214) (xy 0.693932 -1.592609)
			(xy 0.68619 -1.611208) (xy 0.6858 -1.621282) (xy 0.6858 -14.05636) (xy 6.84225 -14.05636) (xy 6.846321 -14.000738)
			(xy 6.858447 -13.946301) (xy 6.87837 -13.89421) (xy 6.905666 -13.845575) (xy 6.939752 -13.801432)
			(xy 6.979901 -13.762723) (xy 7.025259 -13.730272) (xy 7.074859 -13.704771) (xy 7.127643 -13.686764)
			(xy 7.182486 -13.676634) (xy 7.23822 -13.674597) (xy 7.293657 -13.680697) (xy 7.347614 -13.694803)
			(xy 7.398943 -13.716615) (xy 7.446549 -13.745669) (xy 7.489417 -13.781344) (xy 7.526634 -13.822881)
			(xy 7.557407 -13.869394) (xy 7.581079 -13.919891) (xy 7.597147 -13.973298) (xy 7.605267 -14.028474)
			(xy 7.605776 -14.05636) (xy 7.605267 -14.084246) (xy 7.597147 -14.139422) (xy 7.581079 -14.192829)
			(xy 7.557407 -14.243326) (xy 7.526634 -14.289839) (xy 7.489417 -14.331376) (xy 7.446549 -14.367051)
			(xy 7.398943 -14.396105) (xy 7.347614 -14.417917) (xy 7.293657 -14.432023) (xy 7.23822 -14.438123)
			(xy 7.182486 -14.436086) (xy 7.127643 -14.425956) (xy 7.074859 -14.407949) (xy 7.025259 -14.382448)
			(xy 6.979901 -14.349997) (xy 6.939752 -14.311288) (xy 6.905666 -14.267145) (xy 6.87837 -14.21851)
			(xy 6.858447 -14.166419) (xy 6.846321 -14.111982) (xy 6.84225 -14.05636) (xy 0.6858 -14.05636) (xy 0.6858 -15.128748)
			(xy 7.834882 -15.128748) (xy 7.838953 -15.073126) (xy 7.851079 -15.018689) (xy 7.871002 -14.966598)
			(xy 7.898298 -14.917963) (xy 7.932384 -14.87382) (xy 7.972533 -14.835111) (xy 8.017891 -14.80266)
			(xy 8.067491 -14.777159) (xy 8.120275 -14.759152) (xy 8.175118 -14.749022) (xy 8.230852 -14.746985)
			(xy 8.286289 -14.753085) (xy 8.340246 -14.767191) (xy 8.391575 -14.789003) (xy 8.439181 -14.818057)
			(xy 8.482049 -14.853732) (xy 8.519266 -14.895269) (xy 8.550039 -14.941782) (xy 8.573711 -14.992279)
			(xy 8.589779 -15.045686) (xy 8.597899 -15.100862) (xy 8.598408 -15.128748) (xy 8.597899 -15.156634)
			(xy 8.589779 -15.21181) (xy 8.573711 -15.265217) (xy 8.550039 -15.315714) (xy 8.519266 -15.362227)
			(xy 8.482049 -15.403764) (xy 8.439181 -15.439439) (xy 8.391575 -15.468493) (xy 8.340246 -15.490305)
			(xy 8.286289 -15.504411) (xy 8.230852 -15.510511) (xy 8.175118 -15.508474) (xy 8.120275 -15.498344)
			(xy 8.067491 -15.480337) (xy 8.017891 -15.454836) (xy 7.972533 -15.422385) (xy 7.932384 -15.383676)
			(xy 7.898298 -15.339533) (xy 7.871002 -15.290898) (xy 7.851079 -15.238807) (xy 7.838953 -15.18437)
			(xy 7.834882 -15.128748) (xy 0.6858 -15.128748) (xy 0.6858 -16.144748) (xy 7.834882 -16.144748) (xy 7.838953 -16.089126)
			(xy 7.851079 -16.034689) (xy 7.871002 -15.982598) (xy 7.898298 -15.933963) (xy 7.932384 -15.88982)
			(xy 7.972533 -15.851111) (xy 8.017891 -15.81866) (xy 8.067491 -15.793159) (xy 8.120275 -15.775152)
			(xy 8.175118 -15.765022) (xy 8.230852 -15.762985) (xy 8.286289 -15.769085) (xy 8.340246 -15.783191)
			(xy 8.391575 -15.805003) (xy 8.439181 -15.834057) (xy 8.482049 -15.869732) (xy 8.519266 -15.911269)
			(xy 8.550039 -15.957782) (xy 8.573711 -16.008279) (xy 8.589779 -16.061686) (xy 8.597899 -16.116862)
			(xy 8.598408 -16.144748) (xy 8.597899 -16.172634) (xy 8.589779 -16.22781) (xy 8.573711 -16.281217)
			(xy 8.550039 -16.331714) (xy 8.519266 -16.378227) (xy 8.482049 -16.419764) (xy 8.439181 -16.455439)
			(xy 8.391575 -16.484493) (xy 8.340246 -16.506305) (xy 8.286289 -16.520411) (xy 8.230852 -16.526511)
			(xy 8.175118 -16.524474) (xy 8.120275 -16.514344) (xy 8.067491 -16.496337) (xy 8.017891 -16.470836)
			(xy 7.972533 -16.438385) (xy 7.932384 -16.399676) (xy 7.898298 -16.355533) (xy 7.871002 -16.306898)
			(xy 7.851079 -16.254807) (xy 7.838953 -16.20037) (xy 7.834882 -16.144748) (xy 0.6858 -16.144748)
			(xy 0.6858 -17.160748) (xy 7.834882 -17.160748) (xy 7.838953 -17.105126) (xy 7.851079 -17.050689)
			(xy 7.871002 -16.998598) (xy 7.898298 -16.949963) (xy 7.932384 -16.90582) (xy 7.972533 -16.867111)
			(xy 8.017891 -16.83466) (xy 8.067491 -16.809159) (xy 8.120275 -16.791152) (xy 8.175118 -16.781022)
			(xy 8.230852 -16.778985) (xy 8.286289 -16.785085) (xy 8.340246 -16.799191) (xy 8.391575 -16.821003)
			(xy 8.439181 -16.850057) (xy 8.482049 -16.885732) (xy 8.519266 -16.927269) (xy 8.550039 -16.973782)
			(xy 8.573711 -17.024279) (xy 8.589779 -17.077686) (xy 8.597899 -17.132862) (xy 8.598408 -17.160748)
			(xy 8.597899 -17.188634) (xy 8.589779 -17.24381) (xy 8.573711 -17.297217) (xy 8.550039 -17.347714)
			(xy 8.519266 -17.394227) (xy 8.482049 -17.435764) (xy 8.439181 -17.471439) (xy 8.391575 -17.500493)
			(xy 8.340246 -17.522305) (xy 8.286289 -17.536411) (xy 8.230852 -17.542511) (xy 8.175118 -17.540474)
			(xy 8.120275 -17.530344) (xy 8.067491 -17.512337) (xy 8.017891 -17.486836) (xy 7.972533 -17.454385)
			(xy 7.932384 -17.415676) (xy 7.898298 -17.371533) (xy 7.871002 -17.322898) (xy 7.851079 -17.270807)
			(xy 7.838953 -17.21637) (xy 7.834882 -17.160748) (xy 0.6858 -17.160748) (xy 0.6858 -20.24888) (xy 2.414776 -20.24888)
			(xy 2.418847 -20.193258) (xy 2.430973 -20.138821) (xy 2.450896 -20.08673) (xy 2.478192 -20.038095)
			(xy 2.512278 -19.993952) (xy 2.552427 -19.955243) (xy 2.597785 -19.922792) (xy 2.647385 -19.897291)
			(xy 2.700169 -19.879284) (xy 2.755012 -19.869154) (xy 2.810746 -19.867117) (xy 2.866183 -19.873217)
			(xy 2.92014 -19.887323) (xy 2.971469 -19.909135) (xy 3.019075 -19.938189) (xy 3.061943 -19.973864)
			(xy 3.09916 -20.015401) (xy 3.129933 -20.061914) (xy 3.153605 -20.112411) (xy 3.169673 -20.165818)
			(xy 3.177793 -20.220994) (xy 3.178302 -20.24888) (xy 3.177793 -20.276766) (xy 3.169673 -20.331942)
			(xy 3.153605 -20.385349) (xy 3.129933 -20.435846) (xy 3.09916 -20.482359) (xy 3.061943 -20.523896)
			(xy 3.019075 -20.559571) (xy 2.971469 -20.588625) (xy 2.92014 -20.610437) (xy 2.866183 -20.624543)
			(xy 2.810746 -20.630643) (xy 2.755012 -20.628606) (xy 2.700169 -20.618476) (xy 2.647385 -20.600469)
			(xy 2.597785 -20.574968) (xy 2.552427 -20.542517) (xy 2.512278 -20.503808) (xy 2.478192 -20.459665)
			(xy 2.450896 -20.41103) (xy 2.430973 -20.358939) (xy 2.418847 -20.304502) (xy 2.414776 -20.24888)
			(xy 0.6858 -20.24888) (xy 0.6858 -20.72005) (xy 5.185422 -20.72005) (xy 5.189392 -20.589916) (xy 5.201288 -20.460266)
			(xy 5.221067 -20.331583) (xy 5.248653 -20.204344) (xy 5.283946 -20.079025) (xy 5.326812 -19.956089)
			(xy 5.377094 -19.835996) (xy 5.434603 -19.719192) (xy 5.499127 -19.60611) (xy 5.570424 -19.497173)
			(xy 5.648229 -19.392785) (xy 5.732254 -19.293334) (xy 5.822186 -19.199191) (xy 5.91769 -19.110706)
			(xy 6.01841 -19.028207) (xy 6.123972 -18.952002) (xy 6.233984 -18.882375) (xy 6.348036 -18.819584)
			(xy 6.465704 -18.763862) (xy 6.58655 -18.715418) (xy 6.710125 -18.674431) (xy 6.835968 -18.641054)
			(xy 6.963613 -18.615411) (xy 7.092583 -18.597597) (xy 7.222399 -18.587679) (xy 7.352578 -18.585694)
			(xy 7.482637 -18.591648) (xy 7.61209 -18.605521) (xy 7.740457 -18.627259) (xy 7.86726 -18.656783)
			(xy 7.992027 -18.693982) (xy 8.114294 -18.738718) (xy 8.233607 -18.790826) (xy 8.34952 -18.850109)
			(xy 8.461605 -18.91635) (xy 8.569442 -18.9893) (xy 8.672631 -19.068688) (xy 8.770789 -19.15422) (xy 8.86355 -19.245577)
			(xy 8.950569 -19.342419) (xy 9.031522 -19.444386) (xy 9.106108 -19.551098) (xy 9.174049 -19.662159)
			(xy 9.235094 -19.777155) (xy 9.289015 -19.895659) (xy 9.33561 -20.01723) (xy 9.374708 -20.141415)
			(xy 9.406162 -20.267753) (xy 9.429856 -20.395774) (xy 9.4457 -20.525) (xy 9.453638 -20.654953) (xy 9.454134 -20.72005)
			(xy 9.453638 -20.785147) (xy 9.4457 -20.9151) (xy 9.429856 -21.044326) (xy 9.406162 -21.172347) (xy 9.374708 -21.298685)
			(xy 9.33561 -21.42287) (xy 9.289015 -21.544441) (xy 9.245979 -21.639022) (xy 16.073882 -21.639022)
			(xy 16.074424 -21.610284) (xy 16.083043 -21.553458) (xy 16.100089 -21.498567) (xy 16.125176 -21.446855)
			(xy 16.157737 -21.399492) (xy 16.177006 -21.378164) (xy 16.18361 -21.371306) (xy 16.190722 -21.353272)
			(xy 16.190722 -21.264372) (xy 16.18361 -21.246338) (xy 16.177006 -21.23948) (xy 16.157758 -21.218134)
			(xy 16.125193 -21.170774) (xy 16.100102 -21.119065) (xy 16.083051 -21.064178) (xy 16.074427 -21.007354)
			(xy 16.074424 -20.949879) (xy 16.083044 -20.893053) (xy 16.10009 -20.838164) (xy 16.125177 -20.786454)
			(xy 16.157738 -20.739091) (xy 16.177006 -20.717764) (xy 16.18361 -20.710906) (xy 16.190722 -20.692872)
			(xy 16.190722 -20.603972) (xy 16.18361 -20.585938) (xy 16.177006 -20.57908) (xy 16.157758 -20.557734)
			(xy 16.125193 -20.510374) (xy 16.100102 -20.458665) (xy 16.083051 -20.403778) (xy 16.074427 -20.346954)
			(xy 16.074424 -20.289479) (xy 16.083044 -20.232653) (xy 16.10009 -20.177764) (xy 16.125177 -20.126054)
			(xy 16.157738 -20.078691) (xy 16.177006 -20.057364) (xy 16.18361 -20.050506) (xy 16.190722 -20.032472)
			(xy 16.190722 -19.943572) (xy 16.18361 -19.925538) (xy 16.177006 -19.91868) (xy 16.157758 -19.897334)
			(xy 16.125193 -19.849974) (xy 16.100102 -19.798265) (xy 16.083051 -19.743378) (xy 16.074427 -19.686554)
			(xy 16.074424 -19.629079) (xy 16.083044 -19.572253) (xy 16.10009 -19.517364) (xy 16.125177 -19.465654)
			(xy 16.157738 -19.418291) (xy 16.177006 -19.396964) (xy 16.18361 -19.390106) (xy 16.190722 -19.372072)
			(xy 16.190722 -19.283172) (xy 16.18361 -19.265138) (xy 16.177006 -19.25828) (xy 16.157757 -19.236934)
			(xy 16.125186 -19.189578) (xy 16.100088 -19.137872) (xy 16.083032 -19.082985) (xy 16.074405 -19.02616)
			(xy 16.073882 -18.997422) (xy 16.074368 -18.970171) (xy 16.082124 -18.916223) (xy 16.097479 -18.863928)
			(xy 16.120121 -18.814351) (xy 16.149587 -18.768501) (xy 16.185278 -18.72731) (xy 16.226469 -18.691619)
			(xy 16.272319 -18.662153) (xy 16.321896 -18.639511) (xy 16.374191 -18.624156) (xy 16.428139 -18.6164)
			(xy 16.482641 -18.6164) (xy 16.536589 -18.624156) (xy 16.588884 -18.639511) (xy 16.638461 -18.662153)
			(xy 16.684311 -18.691619) (xy 16.725502 -18.72731) (xy 16.761193 -18.768501) (xy 16.790659 -18.814351)
			(xy 16.813301 -18.863928) (xy 16.828656 -18.916223) (xy 16.836412 -18.970171) (xy 16.836898 -18.997422)
			(xy 16.836388 -19.026161) (xy 16.827762 -19.082989) (xy 16.810709 -19.13788) (xy 16.785614 -19.189592)
			(xy 16.753046 -19.236954) (xy 16.733774 -19.25828) (xy 16.72717 -19.265138) (xy 16.720058 -19.283172)
			(xy 16.720058 -19.372072) (xy 16.72717 -19.390106) (xy 16.733774 -19.396964) (xy 16.753067 -19.418272)
			(xy 16.785631 -19.465637) (xy 16.810722 -19.517352) (xy 16.82777 -19.572246) (xy 16.836391 -19.629076)
			(xy 16.836389 -19.686556) (xy 16.827763 -19.743385) (xy 16.81071 -19.798278) (xy 16.785615 -19.84999)
			(xy 16.753047 -19.897353) (xy 16.733774 -19.91868) (xy 16.72717 -19.925538) (xy 16.720058 -19.943572)
			(xy 16.720058 -20.032472) (xy 16.72717 -20.050506) (xy 16.733774 -20.057364) (xy 16.753067 -20.078672)
			(xy 16.785631 -20.126037) (xy 16.810722 -20.177752) (xy 16.82777 -20.232646) (xy 16.836391 -20.289476)
			(xy 16.836389 -20.346956) (xy 16.827763 -20.403785) (xy 16.81071 -20.458678) (xy 16.785615 -20.51039)
			(xy 16.753047 -20.557753) (xy 16.733774 -20.57908) (xy 16.72717 -20.585938) (xy 16.720058 -20.603972)
			(xy 16.720058 -20.692872) (xy 16.72717 -20.710906) (xy 16.733774 -20.717764) (xy 16.753067 -20.739072)
			(xy 16.785631 -20.786437) (xy 16.810722 -20.838152) (xy 16.82777 -20.893046) (xy 16.836391 -20.949876)
			(xy 16.836389 -21.007356) (xy 16.827763 -21.064185) (xy 16.81071 -21.119078) (xy 16.785615 -21.17079)
			(xy 16.753047 -21.218153) (xy 16.733774 -21.23948) (xy 16.72717 -21.246338) (xy 16.720058 -21.264372)
			(xy 16.720058 -21.353272) (xy 16.72717 -21.371306) (xy 16.733774 -21.378164) (xy 16.753057 -21.39948)
			(xy 16.785621 -21.446845) (xy 16.810711 -21.49856) (xy 16.827759 -21.553453) (xy 16.836379 -21.610282)
			(xy 16.836898 -21.639022) (xy 16.836412 -21.666273) (xy 16.828656 -21.720221) (xy 16.813301 -21.772516)
			(xy 16.790659 -21.822093) (xy 16.761193 -21.867943) (xy 16.725502 -21.909134) (xy 16.684311 -21.944825)
			(xy 16.638461 -21.974291) (xy 16.588884 -21.996933) (xy 16.536589 -22.012288) (xy 16.482641 -22.020044)
			(xy 16.428139 -22.020044) (xy 16.374191 -22.012288) (xy 16.321896 -21.996933) (xy 16.272319 -21.974291)
			(xy 16.226469 -21.944825) (xy 16.185278 -21.909134) (xy 16.149587 -21.867943) (xy 16.120121 -21.822093)
			(xy 16.097479 -21.772516) (xy 16.082124 -21.720221) (xy 16.074368 -21.666273) (xy 16.073882 -21.639022)
			(xy 9.245979 -21.639022) (xy 9.235094 -21.662945) (xy 9.174049 -21.777941) (xy 9.106108 -21.889002)
			(xy 9.031522 -21.995714) (xy 8.950569 -22.097681) (xy 8.86355 -22.194523) (xy 8.770789 -22.28588)
			(xy 8.672631 -22.371412) (xy 8.569442 -22.4508) (xy 8.461605 -22.52375) (xy 8.34952 -22.589991) (xy 8.233607 -22.649274)
			(xy 8.114294 -22.701382) (xy 7.992027 -22.746118) (xy 7.86726 -22.783317) (xy 7.740457 -22.812841)
			(xy 7.61209 -22.834579) (xy 7.482637 -22.848452) (xy 7.352578 -22.854406) (xy 7.222399 -22.852421)
			(xy 7.092583 -22.842503) (xy 6.963613 -22.824689) (xy 6.835968 -22.799046) (xy 6.710125 -22.765669)
			(xy 6.58655 -22.724682) (xy 6.465704 -22.676238) (xy 6.348036 -22.620516) (xy 6.233984 -22.557725)
			(xy 6.123972 -22.488098) (xy 6.01841 -22.411893) (xy 5.91769 -22.329394) (xy 5.822186 -22.240909)
			(xy 5.732254 -22.146766) (xy 5.648229 -22.047315) (xy 5.570424 -21.942927) (xy 5.499127 -21.83399)
			(xy 5.434603 -21.720908) (xy 5.377094 -21.604104) (xy 5.326812 -21.484011) (xy 5.283946 -21.361075)
			(xy 5.248653 -21.235756) (xy 5.221067 -21.108517) (xy 5.201288 -20.979834) (xy 5.189392 -20.850184)
			(xy 5.185422 -20.72005) (xy 0.6858 -20.72005) (xy 0.6858 -27.19197) (xy 0.686224 -27.202016) (xy 0.693931 -27.22057)
			(xy 0.708165 -27.23475) (xy 0.717296 -27.23896) (xy 0.73152 -27.245056) (xy 0.761492 -27.23896) (xy 1.701038 -26.299414)
			(xy 1.704239 -26.296047) (xy 1.709485 -26.288382) (xy 1.711452 -26.284174) (xy 1.712722 -26.28138)
			(xy 1.716198 -26.27026) (xy 1.713817 -26.247109) (xy 1.70815 -26.23693) (xy 1.70815 -26.236676) (xy 1.69449 -26.213878)
			(xy 1.672924 -26.165303) (xy 1.65831 -26.114205) (xy 1.650932 -26.061573) (xy 1.650492 -26.035) (xy 1.650985 -26.00734)
			(xy 1.658975 -25.952601) (xy 1.674787 -25.89959) (xy 1.698089 -25.849418) (xy 1.728392 -25.803137)
			(xy 1.765061 -25.761717) (xy 1.807328 -25.726028) (xy 1.854306 -25.696816) (xy 1.905009 -25.674695)
			(xy 1.958376 -25.660128) (xy 1.985772 -25.656286) (xy 1.994978 -25.654795) (xy 2.011503 -25.646185)
			(xy 2.01803 -25.639522) (xy 2.023872 -25.632664) (xy 2.030476 -25.615392) (xy 2.030476 -25.104852)
			(xy 2.030222 -25.099772) (xy 2.029056 -25.09134) (xy 2.021923 -25.075894) (xy 2.016252 -25.069546)
			(xy 1.617726 -24.671274) (xy 1.594829 -24.64771) (xy 1.553876 -24.596326) (xy 1.51893 -24.540683)
			(xy 1.490429 -24.48148) (xy 1.46873 -24.419459) (xy 1.454107 -24.3554) (xy 1.446743 -24.290107) (xy 1.446276 -24.257254)
			(xy 1.446276 -23.672546) (xy 1.446734 -23.639691) (xy 1.454085 -23.574394) (xy 1.468701 -23.510331)
			(xy 1.490398 -23.448307) (xy 1.518902 -23.389102) (xy 1.553855 -23.33346) (xy 1.594819 -23.282082)
			(xy 1.617726 -23.258526) (xy 1.982978 -22.893274) (xy 1.989924 -22.885577) (xy 1.997515 -22.866304)
			(xy 1.99771 -22.855936) (xy 1.995424 -22.781514) (xy 1.995165 -22.776397) (xy 1.992855 -22.766418)
			(xy 1.990852 -22.761702) (xy 1.986534 -22.752558) (xy 1.97866 -22.745446) (xy 1.958824 -22.727272)
			(xy 1.923954 -22.686307) (xy 1.895192 -22.640844) (xy 1.873111 -22.591788) (xy 1.858148 -22.540114)
			(xy 1.850603 -22.486849) (xy 1.850136 -22.45995) (xy 1.850599 -22.432697) (xy 1.858356 -22.378747)
			(xy 1.873712 -22.326449) (xy 1.896355 -22.276869) (xy 1.925823 -22.231016) (xy 1.961517 -22.189824)
			(xy 2.002709 -22.154131) (xy 2.048563 -22.124663) (xy 2.098143 -22.102021) (xy 2.15044 -22.086665)
			(xy 2.204391 -22.078909) (xy 2.231644 -22.078442) (xy 2.260466 -22.078966) (xy 2.317454 -22.087633)
			(xy 2.372488 -22.104778) (xy 2.424315 -22.13001) (xy 2.471755 -22.162755) (xy 2.513726 -22.202267)
			(xy 2.549272 -22.247645) (xy 2.563876 -22.272498) (xy 2.568176 -22.279499) (xy 2.580354 -22.290514)
			(xy 2.587752 -22.294088) (xy 2.617978 -22.305772) (xy 2.618232 -22.305772) (xy 2.626027 -22.308451)
			(xy 2.642481 -22.309241) (xy 2.65049 -22.307296) (xy 2.681679 -22.296855) (xy 2.745796 -22.282184)
			(xy 2.811151 -22.274776) (xy 2.844038 -22.274276) (xy 2.869946 -22.274276) (xy 2.874214 -22.2473)
			(xy 2.889458 -22.194856) (xy 2.912022 -22.14512) (xy 2.941447 -22.099109) (xy 2.97713 -22.057763)
			(xy 3.018343 -22.021927) (xy 3.064245 -21.992332) (xy 3.113896 -21.969582) (xy 3.166283 -21.954144)
			(xy 3.220337 -21.946332) (xy 3.247644 -21.945854) (xy 3.260382 -21.94593) (xy 3.285804 -21.94758)
			(xy 3.298444 -21.949156) (xy 3.326623 -21.953471) (xy 3.381365 -21.969375) (xy 3.433129 -21.99325)
			(xy 3.480762 -22.024565) (xy 3.523204 -22.062621) (xy 3.559508 -22.106571) (xy 3.588864 -22.155436)
			(xy 3.61062 -22.208126) (xy 3.617976 -22.235668) (xy 3.618484 -22.238208) (xy 3.621944 -22.248007)
			(xy 3.635305 -22.263898) (xy 3.653868 -22.273196) (xy 3.664204 -22.274276) (xy 4.572 -22.274276)
			(xy 4.607397 -22.27481) (xy 4.677676 -22.283343) (xy 4.746414 -22.300286) (xy 4.812608 -22.32539)
			(xy 4.875294 -22.35829) (xy 4.933557 -22.398506) (xy 4.986548 -22.445452) (xy 5.033494 -22.498443)
			(xy 5.07371 -22.556706) (xy 5.10661 -22.619392) (xy 5.131714 -22.685586) (xy 5.148657 -22.754324)
			(xy 5.15719 -22.824603) (xy 5.157724 -22.86) (xy 5.157724 -22.860508) (xy 5.157199 -22.895456) (xy 5.148848 -22.964851)
			(xy 5.132303 -23.03276) (xy 5.107796 -23.098219) (xy 5.092192 -23.129494) (xy 5.087621 -23.139228)
			(xy 5.086309 -23.160674) (xy 5.089652 -23.170896) (xy 5.093716 -23.179532) (xy 5.138928 -23.2537)
			(xy 5.143746 -23.26096) (xy 5.157248 -23.271954) (xy 5.173656 -23.277778) (xy 5.182362 -23.278084)
			(xy 10.54354 -23.278084) (xy 10.55125 -23.277855) (xy 10.565988 -23.273333) (xy 10.572496 -23.269194)
			(xy 10.57656 -23.265892) (xy 11.266678 -22.575774) (xy 11.290242 -22.552877) (xy 11.341626 -22.511924)
			(xy 11.397269 -22.476978) (xy 11.456472 -22.448477) (xy 11.518493 -22.426779) (xy 11.582552 -22.412157)
			(xy 11.647845 -22.404793) (xy 11.680698 -22.404324) (xy 11.680952 -22.404324) (xy 11.716352 -22.404834)
			(xy 11.786635 -22.413363) (xy 11.855378 -22.430303) (xy 11.921577 -22.455406) (xy 11.984268 -22.488306)
			(xy 12.042535 -22.528523) (xy 12.095529 -22.575471) (xy 12.142477 -22.628465) (xy 12.182694 -22.686732)
			(xy 12.215594 -22.749423) (xy 12.240697 -22.815622) (xy 12.257637 -22.884365) (xy 12.266166 -22.954648)
			(xy 12.266676 -22.990048) (xy 12.266422 -23.008844) (xy 12.266422 -23.009098) (xy 12.266545 -23.018123)
			(xy 12.272393 -23.035185) (xy 12.277852 -23.042372) (xy 12.319762 -23.094188) (xy 12.325824 -23.101021)
			(xy 12.341577 -23.110242) (xy 12.350496 -23.112222) (xy 12.37169 -23.116248) (xy 12.413064 -23.128473)
			(xy 12.433046 -23.136606) (xy 12.437618 -23.138638) (xy 12.456922 -23.142702) (xy 12.463567 -23.142518)
			(xy 12.47643 -23.139177) (xy 12.482322 -23.136098) (xy 12.49553 -23.125176) (xy 12.501209 -23.118054)
			(xy 12.507587 -23.101003) (xy 12.507976 -23.091902) (xy 12.507976 -23.01621) (xy 12.508471 -22.982124)
			(xy 12.516386 -22.914414) (xy 12.532107 -22.84808) (xy 12.555423 -22.78402) (xy 12.586018 -22.7231)
			(xy 12.623479 -22.666143) (xy 12.667299 -22.613921) (xy 12.716885 -22.567139) (xy 12.771567 -22.52643)
			(xy 12.830605 -22.492344) (xy 12.893201 -22.465343) (xy 12.958508 -22.445791) (xy 13.025644 -22.433953)
			(xy 13.0937 -22.42999) (xy 13.161756 -22.433953) (xy 13.228892 -22.445791) (xy 13.294199 -22.465343)
			(xy 13.356795 -22.492344) (xy 13.415833 -22.52643) (xy 13.470515 -22.567139) (xy 13.520101 -22.613921)
			(xy 13.563921 -22.666143) (xy 13.601382 -22.7231) (xy 13.631977 -22.78402) (xy 13.655293 -22.84808)
			(xy 13.671014 -22.914414) (xy 13.678929 -22.982124) (xy 13.679424 -23.01621) (xy 13.679424 -23.469092)
			(xy 13.678964 -23.501946) (xy 13.671609 -23.567241) (xy 13.656989 -23.631302) (xy 13.63529 -23.693323)
			(xy 13.606783 -23.752525) (xy 13.571828 -23.808163) (xy 13.530863 -23.859539) (xy 13.507974 -23.883112)
			(xy 12.653264 -24.737822) (xy 12.6297 -24.760721) (xy 12.578318 -24.801678) (xy 12.522676 -24.836628)
			(xy 12.463473 -24.865134) (xy 12.401452 -24.886836) (xy 12.337392 -24.901463) (xy 12.272098 -24.908831)
			(xy 12.239244 -24.909272) (xy 9.406636 -24.909272) (xy 9.406382 -24.909272) (xy 9.396621 -24.909769)
			(xy 9.378547 -24.917162) (xy 9.364532 -24.93076) (xy 9.360154 -24.939498) (xy 9.359138 -24.942292)
			(xy 9.34909 -24.967523) (xy 9.322881 -25.015087) (xy 9.290191 -25.058454) (xy 9.251682 -25.096748)
			(xy 9.208132 -25.129193) (xy 9.160421 -25.155134) (xy 9.109513 -25.174048) (xy 9.056438 -25.185551)
			(xy 9.002268 -25.189411) (xy 8.948098 -25.185551) (xy 8.895023 -25.174048) (xy 8.844115 -25.155134)
			(xy 8.796404 -25.129193) (xy 8.752854 -25.096748) (xy 8.714345 -25.058454) (xy 8.681655 -25.015087)
			(xy 8.655446 -24.967523) (xy 8.645398 -24.942292) (xy 8.644382 -24.939498) (xy 8.640027 -24.930743)
			(xy 8.626012 -24.917133) (xy 8.60792 -24.909762) (xy 8.598154 -24.909272) (xy 7.15772 -24.909272)
			(xy 7.157466 -24.909272) (xy 7.147696 -24.909755) (xy 7.129598 -24.91713) (xy 7.115557 -24.930725)
			(xy 7.111238 -24.939498) (xy 7.110222 -24.942292) (xy 7.100174 -24.967523) (xy 7.073965 -25.015087)
			(xy 7.041275 -25.058454) (xy 7.002766 -25.096748) (xy 6.959216 -25.129193) (xy 6.911505 -25.155134)
			(xy 6.860597 -25.174048) (xy 6.807522 -25.185551) (xy 6.753352 -25.189411) (xy 6.699182 -25.185551)
			(xy 6.646107 -25.174048) (xy 6.595199 -25.155134) (xy 6.547488 -25.129193) (xy 6.503938 -25.096748)
			(xy 6.465429 -25.058454) (xy 6.432739 -25.015087) (xy 6.40653 -24.967523) (xy 6.396482 -24.942292)
			(xy 6.395466 -24.939498) (xy 6.39111 -24.930745) (xy 6.377095 -24.91714) (xy 6.359003 -24.909774)
			(xy 6.349238 -24.909272) (xy 5.150104 -24.909272) (xy 5.142393 -24.909495) (xy 5.12765 -24.914011)
			(xy 5.121148 -24.918162) (xy 5.117084 -24.921464) (xy 4.986274 -25.052274) (xy 4.96271 -25.075172)
			(xy 4.911326 -25.116126) (xy 4.855683 -25.151074) (xy 4.79648 -25.179578) (xy 4.73446 -25.201279)
			(xy 4.670401 -25.215906) (xy 4.605108 -25.223274) (xy 4.572254 -25.223724) (xy 3.304794 -25.223724)
			(xy 3.300041 -25.223824) (xy 3.290707 -25.225619) (xy 3.286252 -25.22728) (xy 3.276346 -25.23109)
			(xy 3.217164 -25.289002) (xy 3.215386 -25.29078) (xy 3.209522 -25.297638) (xy 3.202621 -25.314296)
			(xy 3.201924 -25.323292) (xy 3.201924 -25.943814) (xy 4.265674 -25.943814) (xy 4.269745 -25.888192)
			(xy 4.281871 -25.833755) (xy 4.301794 -25.781664) (xy 4.32909 -25.733029) (xy 4.363176 -25.688886)
			(xy 4.403325 -25.650177) (xy 4.448683 -25.617726) (xy 4.498283 -25.592225) (xy 4.551067 -25.574218)
			(xy 4.60591 -25.564088) (xy 4.661644 -25.562051) (xy 4.717081 -25.568151) (xy 4.771038 -25.582257)
			(xy 4.822367 -25.604069) (xy 4.869973 -25.633123) (xy 4.912841 -25.668798) (xy 4.950058 -25.710335)
			(xy 4.980831 -25.756848) (xy 5.004503 -25.807345) (xy 5.020571 -25.860752) (xy 5.028691 -25.915928)
			(xy 5.0292 -25.943814) (xy 5.028691 -25.9717) (xy 5.020571 -26.026876) (xy 5.018509 -26.03373) (xy 5.317488 -26.03373)
			(xy 5.321559 -25.978108) (xy 5.333685 -25.923671) (xy 5.353608 -25.87158) (xy 5.380904 -25.822945)
			(xy 5.41499 -25.778802) (xy 5.455139 -25.740093) (xy 5.500497 -25.707642) (xy 5.550097 -25.682141)
			(xy 5.602881 -25.664134) (xy 5.657724 -25.654004) (xy 5.713458 -25.651967) (xy 5.768895 -25.658067)
			(xy 5.822852 -25.672173) (xy 5.874181 -25.693985) (xy 5.921787 -25.723039) (xy 5.964655 -25.758714)
			(xy 6.001872 -25.800251) (xy 6.032645 -25.846764) (xy 6.056317 -25.897261) (xy 6.072385 -25.950668)
			(xy 6.080505 -26.005844) (xy 6.081014 -26.03373) (xy 6.080505 -26.061616) (xy 6.072385 -26.116792)
			(xy 6.056317 -26.170199) (xy 6.032645 -26.220696) (xy 6.001872 -26.267209) (xy 5.964655 -26.308746)
			(xy 5.921787 -26.344421) (xy 5.874181 -26.373475) (xy 5.822852 -26.395287) (xy 5.768895 -26.409393)
			(xy 5.713458 -26.415493) (xy 5.657724 -26.413456) (xy 5.602881 -26.403326) (xy 5.550097 -26.385319)
			(xy 5.500497 -26.359818) (xy 5.455139 -26.327367) (xy 5.41499 -26.288658) (xy 5.380904 -26.244515)
			(xy 5.353608 -26.19588) (xy 5.333685 -26.143789) (xy 5.321559 -26.089352) (xy 5.317488 -26.03373)
			(xy 5.018509 -26.03373) (xy 5.004503 -26.080283) (xy 4.980831 -26.13078) (xy 4.950058 -26.177293)
			(xy 4.912841 -26.21883) (xy 4.869973 -26.254505) (xy 4.822367 -26.283559) (xy 4.771038 -26.305371)
			(xy 4.717081 -26.319477) (xy 4.661644 -26.325577) (xy 4.60591 -26.32354) (xy 4.551067 -26.31341)
			(xy 4.498283 -26.295403) (xy 4.448683 -26.269902) (xy 4.403325 -26.237451) (xy 4.363176 -26.198742)
			(xy 4.32909 -26.154599) (xy 4.301794 -26.105964) (xy 4.281871 -26.053873) (xy 4.269745 -25.999436)
			(xy 4.265674 -25.943814) (xy 3.201924 -25.943814) (xy 3.201924 -26.213054) (xy 3.201466 -26.245909)
			(xy 3.194115 -26.311206) (xy 3.179499 -26.375269) (xy 3.157802 -26.437293) (xy 3.129298 -26.496498)
			(xy 3.094345 -26.55214) (xy 3.053381 -26.603518) (xy 3.030474 -26.627074) (xy 2.201672 -27.455876)
			(xy 2.198963 -27.458725) (xy 2.194365 -27.465101) (xy 2.192528 -27.468576) (xy 2.189947 -27.474003)
			(xy 2.187129 -27.485683) (xy 2.18694 -27.49169) (xy 2.18694 -28.433522) (xy 2.187473 -28.443475)
			(xy 2.195134 -28.461855) (xy 2.209189 -28.47596) (xy 2.218182 -28.480258) (xy 2.218436 -28.480258)
			(xy 2.225362 -28.482864) (xy 2.240073 -28.484402) (xy 2.247392 -28.483306) (xy 2.254758 -28.481782)
			(xy 2.267966 -28.47467) (xy 2.38252 -28.360116) (xy 2.401292 -28.342086) (xy 2.44341 -28.311512)
			(xy 2.489786 -28.287891) (xy 2.539283 -28.271803) (xy 2.590686 -28.263645) (xy 2.616708 -28.263088)
			(xy 5.859526 -28.263088) (xy 5.86994 -28.262072) (xy 5.877072 -28.260339) (xy 5.889983 -28.253372)
			(xy 5.89534 -28.248356) (xy 7.311644 -26.831798) (xy 7.330424 -26.813685) (xy 7.372622 -26.783001)
			(xy 7.419103 -26.759301) (xy 7.468721 -26.743172) (xy 7.520253 -26.735009) (xy 7.54634 -26.734516)
			(xy 8.741918 -26.734516) (xy 8.745982 -26.734262) (xy 8.750234 -26.733842) (xy 8.758528 -26.731793)
			(xy 8.762492 -26.730198) (xy 8.765286 -26.728674) (xy 8.781288 -26.721054) (xy 8.789162 -26.716482)
			(xy 8.796664 -26.71081) (xy 8.807278 -26.695306) (xy 8.81159 -26.677018) (xy 8.809021 -26.658405)
			(xy 8.799916 -26.641969) (xy 8.785499 -26.62992) (xy 8.776716 -26.626566) (xy 8.752109 -26.617557)
			(xy 8.705432 -26.593743) (xy 8.662456 -26.563759) (xy 8.623993 -26.528172) (xy 8.590768 -26.48765)
			(xy 8.563406 -26.44296) (xy 8.542424 -26.394943) (xy 8.528217 -26.344504) (xy 8.521054 -26.292595)
			(xy 8.520684 -26.266394) (xy 8.52117 -26.239143) (xy 8.528926 -26.185195) (xy 8.544281 -26.1329)
			(xy 8.566923 -26.083323) (xy 8.596389 -26.037473) (xy 8.63208 -25.996282) (xy 8.673271 -25.960591)
			(xy 8.719121 -25.931125) (xy 8.768698 -25.908483) (xy 8.820993 -25.893128) (xy 8.874941 -25.885372)
			(xy 8.929443 -25.885372) (xy 8.983391 -25.893128) (xy 9.035686 -25.908483) (xy 9.085263 -25.931125)
			(xy 9.131113 -25.960591) (xy 9.172304 -25.996282) (xy 9.207995 -26.037473) (xy 9.237461 -26.083323)
			(xy 9.260103 -26.1329) (xy 9.275458 -26.185195) (xy 9.283214 -26.239143) (xy 9.2837 -26.266394) (xy 9.283227 -26.293463)
			(xy 9.27557 -26.347056) (xy 9.26041 -26.399028) (xy 9.238051 -26.448333) (xy 9.208944 -26.493979)
			(xy 9.173672 -26.53505) (xy 9.132946 -26.570719) (xy 9.087584 -26.600269) (xy 9.063228 -26.612088)
			(xy 9.054211 -26.616714) (xy 9.040511 -26.631626) (xy 9.033647 -26.650677) (xy 9.034689 -26.6709)
			(xy 9.043475 -26.689145) (xy 9.058636 -26.702569) (xy 9.068054 -26.706322) (xy 9.081359 -26.71106)
			(xy 9.107295 -26.722246) (xy 9.11987 -26.728674) (xy 9.122664 -26.730198) (xy 9.126614 -26.731833)
			(xy 9.134917 -26.733869) (xy 9.139174 -26.734262) (xy 9.143238 -26.734516) (xy 13.88872 -26.734516)
			(xy 13.898372 -26.7335) (xy 13.905615 -26.731871) (xy 13.918784 -26.725029) (xy 13.92428 -26.720038)
			(xy 15.339568 -25.30475) (xy 15.346246 -25.29735) (xy 15.353836 -25.278939) (xy 15.353829 -25.259026)
			(xy 15.35049 -25.249632) (xy 15.348204 -25.244044) (xy 15.344648 -25.235154) (xy 15.331694 -25.226518)
			(xy 15.325365 -25.22265) (xy 15.311167 -25.218384) (xy 15.303754 -25.218136) (xy 14.853412 -25.218136)
			(xy 14.84884 -25.21839) (xy 14.840196 -25.219536) (xy 14.824359 -25.226809) (xy 14.817852 -25.232614)
			(xy 14.650212 -25.400508) (xy 14.567916 -25.482804) (xy 14.564191 -25.486666) (xy 14.558308 -25.495636)
			(xy 14.556232 -25.500584) (xy 14.55547 -25.503378) (xy 14.547034 -25.528936) (xy 14.523981 -25.57757)
			(xy 14.494324 -25.622482) (xy 14.45865 -25.662781) (xy 14.417667 -25.697668) (xy 14.372189 -25.726451)
			(xy 14.323119 -25.748557) (xy 14.271428 -25.76355) (xy 14.218144 -25.771131) (xy 14.191234 -25.771602)
			(xy 14.16398 -25.771141) (xy 14.110025 -25.763388) (xy 14.057724 -25.748035) (xy 14.00814 -25.725394)
			(xy 13.962283 -25.695927) (xy 13.921087 -25.660233) (xy 13.88539 -25.61904) (xy 13.855919 -25.573185)
			(xy 13.833275 -25.523602) (xy 13.817918 -25.471302) (xy 13.810161 -25.417348) (xy 13.809726 -25.390094)
			(xy 13.810187 -25.363193) (xy 13.817746 -25.309923) (xy 13.832712 -25.258244) (xy 13.85479 -25.20918)
			(xy 13.883541 -25.163703) (xy 13.918395 -25.122716) (xy 13.958661 -25.087032) (xy 14.003541 -25.057358)
			(xy 14.052144 -25.034282) (xy 14.077696 -25.025858) (xy 14.07795 -25.025858) (xy 14.080744 -25.025096)
			(xy 14.085687 -25.023013) (xy 14.094651 -25.017123) (xy 14.098524 -25.013412) (xy 14.173962 -24.937974)
			(xy 14.181555 -24.927978) (xy 14.186754 -24.903454) (xy 14.183868 -24.891238) (xy 14.159484 -24.816562)
			(xy 14.157051 -24.810045) (xy 14.14919 -24.798576) (xy 14.14399 -24.793956) (xy 14.120368 -24.773636)
			(xy 14.107922 -24.767794) (xy 14.101318 -24.766778) (xy 14.067872 -24.760325) (xy 14.002643 -24.740694)
			(xy 13.940129 -24.713634) (xy 13.881175 -24.679507) (xy 13.826575 -24.638776) (xy 13.777065 -24.591989)
			(xy 13.733314 -24.539778) (xy 13.695912 -24.482846) (xy 13.665362 -24.421961) (xy 13.642078 -24.357945)
			(xy 13.626372 -24.291661) (xy 13.618458 -24.224003) (xy 13.617956 -24.189944) (xy 13.618681 -24.149143)
			(xy 13.630026 -24.068332) (xy 13.640562 -24.028908) (xy 13.651317 -23.993321) (xy 13.680597 -23.924986)
			(xy 13.718287 -23.860905) (xy 13.76378 -23.802105) (xy 13.78966 -23.775416) (xy 14.873224 -22.691852)
			(xy 14.896777 -22.668903) (xy 14.948175 -22.627878) (xy 15.003845 -22.592869) (xy 15.063087 -22.564318)
			(xy 15.125155 -22.542584) (xy 15.189267 -22.527941) (xy 15.254616 -22.520573) (xy 15.287498 -22.520148)
			(xy 20.00377 -22.520148) (xy 20.013717 -22.519606) (xy 20.032081 -22.511934) (xy 20.046169 -22.497877)
			(xy 20.050506 -22.488906) (xy 20.050506 -22.488652) (xy 20.053122 -22.481727) (xy 20.054684 -22.467012)
			(xy 20.053554 -22.459696) (xy 20.05203 -22.45233) (xy 20.044918 -22.439122) (xy 19.958304 -22.352508)
			(xy 19.940273 -22.333737) (xy 19.909696 -22.291619) (xy 19.886072 -22.245243) (xy 19.869981 -22.195746)
			(xy 19.861818 -22.144343) (xy 19.861276 -22.11832) (xy 19.861276 -19.462496) (xy 19.860514 -19.453352)
			(xy 19.858877 -19.445865) (xy 19.851757 -19.432301) (xy 19.846544 -19.426682) (xy 18.795492 -18.375884)
			(xy 18.788081 -18.369203) (xy 18.769645 -18.361626) (xy 18.759678 -18.361152) (xy 2.047494 -18.361152)
			(xy 2.04343 -18.361406) (xy 2.039178 -18.361825) (xy 2.030882 -18.363871) (xy 2.02692 -18.36547)
			(xy 2.024126 -18.366994) (xy 1.996626 -18.380765) (xy 1.938289 -18.400236) (xy 1.877584 -18.410093)
			(xy 1.846834 -18.410682) (xy 1.819583 -18.410196) (xy 1.765635 -18.40244) (xy 1.71334 -18.387085)
			(xy 1.663763 -18.364443) (xy 1.617913 -18.334977) (xy 1.576722 -18.299286) (xy 1.541031 -18.258095)
			(xy 1.511565 -18.212245) (xy 1.488923 -18.162668) (xy 1.473568 -18.110373) (xy 1.465812 -18.056425)
			(xy 1.465812 -18.001923) (xy 1.473568 -17.947975) (xy 1.488923 -17.89568) (xy 1.511565 -17.846103)
			(xy 1.541031 -17.800253) (xy 1.576722 -17.759062) (xy 1.617913 -17.723371) (xy 1.663763 -17.693905)
			(xy 1.71334 -17.671263) (xy 1.765635 -17.655908) (xy 1.819583 -17.648152) (xy 1.846834 -17.647666)
			(xy 1.877581 -17.648286) (xy 1.938278 -17.658152) (xy 1.996608 -17.677623) (xy 2.024126 -17.691354)
			(xy 2.03073 -17.694656) (xy 2.041398 -17.697196) (xy 13.850112 -17.697196) (xy 13.85189 -17.697196)
			(xy 13.860377 -17.696589) (xy 13.876242 -17.690467) (xy 13.889213 -17.67947) (xy 13.8938 -17.672304)
			(xy 13.895324 -17.66951) (xy 13.936726 -17.58823) (xy 13.940154 -17.580493) (xy 13.942223 -17.563706)
			(xy 13.938729 -17.547157) (xy 13.934694 -17.539716) (xy 13.932154 -17.53616) (xy 13.906747 -17.500212)
			(xy 13.861849 -17.424487) (xy 13.824029 -17.34499) (xy 13.7936 -17.262381) (xy 13.770815 -17.177346)
			(xy 13.755863 -17.09059) (xy 13.748868 -17.002834) (xy 13.749889 -16.914805) (xy 13.758916 -16.827234)
			(xy 13.775875 -16.740848) (xy 13.800625 -16.656364) (xy 13.832961 -16.574483) (xy 13.872614 -16.495885)
			(xy 13.919256 -16.421221) (xy 13.972498 -16.351111) (xy 14.0319 -16.286138) (xy 14.096968 -16.22684)
			(xy 14.167163 -16.173709) (xy 14.241901 -16.127187) (xy 14.320563 -16.08766) (xy 14.402496 -16.055455)
			(xy 14.48702 -16.03084) (xy 14.573432 -16.014019) (xy 14.661018 -16.005132) (xy 14.749048 -16.004252)
			(xy 14.79296 -16.007334) (xy 14.837216 -16.01143) (xy 14.924774 -16.026722) (xy 15.010557 -16.049994)
			(xy 15.093839 -16.081048) (xy 15.173916 -16.119622) (xy 15.250111 -16.16539) (xy 15.321778 -16.217965)
			(xy 15.388312 -16.276901) (xy 15.449151 -16.341701) (xy 15.503778 -16.411817) (xy 15.551733 -16.486654)
			(xy 15.592609 -16.565581) (xy 15.626061 -16.647929) (xy 15.651806 -16.733003) (xy 15.669627 -16.820082)
			(xy 15.679372 -16.908429) (xy 15.680959 -16.997299) (xy 15.674374 -17.085938) (xy 15.659674 -17.173598)
			(xy 15.636982 -17.259536) (xy 15.606491 -17.343027) (xy 15.568458 -17.423362) (xy 15.523206 -17.499864)
			(xy 15.497556 -17.53616) (xy 15.497302 -17.536414) (xy 15.493539 -17.542134) (xy 15.488897 -17.555008)
			(xy 15.488158 -17.561814) (xy 15.487396 -17.56918) (xy 15.49019 -17.582642) (xy 15.53464 -17.66951)
			(xy 15.539057 -17.677342) (xy 15.552267 -17.689524) (xy 15.56886 -17.69642) (xy 15.57782 -17.697196)
			(xy 17.518888 -17.697196) (xy 17.530056 -17.69664) (xy 17.55029 -17.687185) (xy 17.564581 -17.670022)
			(xy 17.56791 -17.65935) (xy 17.580356 -17.611852) (xy 17.593564 -17.562068) (xy 17.595351 -17.551423)
			(xy 17.590833 -17.530337) (xy 17.578055 -17.512966) (xy 17.568926 -17.507204) (xy 17.511494 -17.474122)
			(xy 17.4004 -17.401816) (xy 17.294009 -17.322752) (xy 17.192731 -17.237236) (xy 17.096957 -17.145598)
			(xy 17.007057 -17.048191) (xy 16.923376 -16.945392) (xy 16.846239 -16.837595) (xy 16.775942 -16.725219)
			(xy 16.712757 -16.608695) (xy 16.656927 -16.488473) (xy 16.608668 -16.365018) (xy 16.568166 -16.238805)
			(xy 16.535577 -16.110321) (xy 16.511027 -15.980062) (xy 16.49461 -15.84853) (xy 16.486391 -15.716232)
			(xy 16.48587 -15.649956) (xy 16.486376 -15.58422) (xy 16.494469 -15.452999) (xy 16.510626 -15.322524)
			(xy 16.534783 -15.193291) (xy 16.566851 -15.065791) (xy 16.606707 -14.940507) (xy 16.6542 -14.817913)
			(xy 16.709149 -14.698476) (xy 16.771348 -14.582649) (xy 16.840558 -14.47087) (xy 16.916519 -14.363563)
			(xy 16.998941 -14.261137) (xy 17.087513 -14.163978) (xy 17.181898 -14.072457) (xy 17.281737 -13.986919)
			(xy 17.386654 -13.90769) (xy 17.496248 -13.83507) (xy 17.610106 -13.769335) (xy 17.727794 -13.710733)
			(xy 17.848866 -13.659487) (xy 17.972864 -13.615792) (xy 18.099316 -13.579813) (xy 18.227744 -13.551687)
			(xy 18.357659 -13.531521) (xy 18.488569 -13.51939) (xy 18.619978 -13.515342) (xy 18.751387 -13.51939)
			(xy 18.882297 -13.531521) (xy 19.012212 -13.551687) (xy 19.14064 -13.579813) (xy 19.267092 -13.615792)
			(xy 19.39109 -13.659487) (xy 19.512162 -13.710733) (xy 19.62985 -13.769335) (xy 19.743708 -13.83507)
			(xy 19.853302 -13.90769) (xy 19.958219 -13.986919) (xy 20.058058 -14.072457) (xy 20.152443 -14.163978)
			(xy 20.241015 -14.261137) (xy 20.323437 -14.363563) (xy 20.399398 -14.47087) (xy 20.468608 -14.582649)
			(xy 20.530807 -14.698476) (xy 20.585756 -14.817913) (xy 20.633249 -14.940507) (xy 20.673105 -15.065791)
			(xy 20.705173 -15.193291) (xy 20.72933 -15.322524) (xy 20.745487 -15.452999) (xy 20.75358 -15.58422)
			(xy 20.754086 -15.649956) (xy 20.753599 -15.714393) (xy 20.745821 -15.843033) (xy 20.730294 -15.970969)
			(xy 20.707075 -16.097735) (xy 20.676248 -16.222869) (xy 20.637927 -16.345915) (xy 20.59225 -16.466423)
			(xy 20.539384 -16.583956) (xy 20.479522 -16.698085) (xy 20.412882 -16.808393) (xy 20.339708 -16.914478)
			(xy 20.296246 -16.969994) (xy 39.748213 -16.969994) (xy 39.752218 -16.882086) (xy 39.764201 -16.794906)
			(xy 39.784061 -16.709177) (xy 39.811636 -16.625609) (xy 39.846695 -16.544895) (xy 39.888948 -16.467703)
			(xy 39.938046 -16.394674) (xy 39.993582 -16.326412) (xy 40.055094 -16.263482) (xy 40.122075 -16.206408)
			(xy 40.193968 -16.15566) (xy 40.270177 -16.11166) (xy 40.350072 -16.074773) (xy 40.432991 -16.045304)
			(xy 40.518246 -16.023497) (xy 40.60513 -16.009533) (xy 40.692924 -16.003527) (xy 40.780901 -16.005531)
			(xy 40.868331 -16.015526) (xy 40.95449 -16.03343) (xy 41.038664 -16.059094) (xy 41.120155 -16.092307)
			(xy 41.198289 -16.132793) (xy 41.272417 -16.180215) (xy 41.341925 -16.234182) (xy 41.406239 -16.294247)
			(xy 41.464823 -16.359911) (xy 41.517194 -16.43063) (xy 41.562917 -16.505818) (xy 41.601614 -16.584853)
			(xy 41.632963 -16.667079) (xy 41.656705 -16.751815) (xy 41.672643 -16.838359) (xy 41.680645 -16.925994)
			(xy 41.681146 -16.969994) (xy 41.680645 -17.013994) (xy 41.672643 -17.101629) (xy 41.656705 -17.188173)
			(xy 41.632963 -17.272909) (xy 41.601614 -17.355135) (xy 41.562917 -17.43417) (xy 41.517194 -17.509358)
			(xy 41.464823 -17.580077) (xy 41.406239 -17.645741) (xy 41.341925 -17.705806) (xy 41.272417 -17.759773)
			(xy 41.198289 -17.807195) (xy 41.120155 -17.847681) (xy 41.038664 -17.880894) (xy 40.95449 -17.906558)
			(xy 40.868331 -17.924462) (xy 40.780901 -17.934457) (xy 40.692924 -17.936461) (xy 40.60513 -17.930455)
			(xy 40.518246 -17.916491) (xy 40.432991 -17.894684) (xy 40.350072 -17.865215) (xy 40.270177 -17.828328)
			(xy 40.193968 -17.784328) (xy 40.122075 -17.73358) (xy 40.055094 -17.676506) (xy 39.993582 -17.613576)
			(xy 39.938046 -17.545314) (xy 39.888948 -17.472285) (xy 39.846695 -17.395093) (xy 39.811636 -17.314379)
			(xy 39.784061 -17.230811) (xy 39.764201 -17.145082) (xy 39.752218 -17.057902) (xy 39.748213 -16.969994)
			(xy 20.296246 -16.969994) (xy 20.260264 -17.015955) (xy 20.174842 -17.112453) (xy 20.083753 -17.20362)
			(xy 19.987327 -17.289124) (xy 19.885918 -17.368653) (xy 19.779895 -17.441918) (xy 19.669644 -17.508652)
			(xy 19.555566 -17.56861) (xy 19.438078 -17.621576) (xy 19.317608 -17.667355) (xy 19.256248 -17.687036)
			(xy 19.25574 -17.687036) (xy 19.254978 -17.68729) (xy 19.249036 -17.689468) (xy 19.238379 -17.696285)
			(xy 19.233896 -17.700752) (xy 19.229578 -17.705324) (xy 19.223482 -17.7165) (xy 19.220688 -17.727168)
			(xy 19.200368 -17.810226) (xy 19.199207 -17.817668) (xy 19.200756 -17.832643) (xy 19.203416 -17.83969)
			(xy 19.205448 -17.844008) (xy 19.207242 -17.847182) (xy 19.21158 -17.853042) (xy 19.214084 -17.855692)
			(xy 20.427696 -19.069304) (xy 20.445726 -19.088076) (xy 20.476302 -19.130194) (xy 20.499924 -19.17657)
			(xy 20.516013 -19.226067) (xy 20.524174 -19.277469) (xy 20.524724 -19.303492) (xy 20.524724 -20.72005)
			(xy 31.18537 -20.72005) (xy 31.18934 -20.589916) (xy 31.201236 -20.460266) (xy 31.221015 -20.331583)
			(xy 31.248601 -20.204344) (xy 31.283894 -20.079025) (xy 31.32676 -19.956089) (xy 31.377042 -19.835996)
			(xy 31.434551 -19.719192) (xy 31.499075 -19.60611) (xy 31.570372 -19.497173) (xy 31.648177 -19.392785)
			(xy 31.732202 -19.293334) (xy 31.822134 -19.199191) (xy 31.917638 -19.110706) (xy 32.018358 -19.028207)
			(xy 32.12392 -18.952002) (xy 32.233932 -18.882375) (xy 32.347984 -18.819584) (xy 32.465652 -18.763862)
			(xy 32.586498 -18.715418) (xy 32.710073 -18.674431) (xy 32.835916 -18.641054) (xy 32.963561 -18.615411)
			(xy 33.092531 -18.597597) (xy 33.222347 -18.587679) (xy 33.352526 -18.585694) (xy 33.482585 -18.591648)
			(xy 33.612038 -18.605521) (xy 33.740405 -18.627259) (xy 33.867208 -18.656783) (xy 33.991975 -18.693982)
			(xy 34.114242 -18.738718) (xy 34.233555 -18.790826) (xy 34.349468 -18.850109) (xy 34.461553 -18.91635)
			(xy 34.56939 -18.9893) (xy 34.672579 -19.068688) (xy 34.770737 -19.15422) (xy 34.863498 -19.245577)
			(xy 34.950517 -19.342419) (xy 35.03147 -19.444386) (xy 35.106056 -19.551098) (xy 35.173997 -19.662159)
			(xy 35.235042 -19.777155) (xy 35.288963 -19.895659) (xy 35.335558 -20.01723) (xy 35.374656 -20.141415)
			(xy 35.40611 -20.267753) (xy 35.429804 -20.395774) (xy 35.445648 -20.525) (xy 35.453586 -20.654953)
			(xy 35.454082 -20.72005) (xy 35.453586 -20.785147) (xy 35.445648 -20.9151) (xy 35.429804 -21.044326)
			(xy 35.40611 -21.172347) (xy 35.374656 -21.298685) (xy 35.335558 -21.42287) (xy 35.288963 -21.544441)
			(xy 35.235042 -21.662945) (xy 35.173997 -21.777941) (xy 35.106056 -21.889002) (xy 35.03147 -21.995714)
			(xy 34.950517 -22.097681) (xy 34.863498 -22.194523) (xy 34.770737 -22.28588) (xy 34.672579 -22.371412)
			(xy 34.56939 -22.4508) (xy 34.461553 -22.52375) (xy 34.349468 -22.589991) (xy 34.233555 -22.649274)
			(xy 34.114242 -22.701382) (xy 33.991975 -22.746118) (xy 33.867208 -22.783317) (xy 33.740405 -22.812841)
			(xy 33.612038 -22.834579) (xy 33.482585 -22.848452) (xy 33.352526 -22.854406) (xy 33.222347 -22.852421)
			(xy 33.092531 -22.842503) (xy 32.963561 -22.824689) (xy 32.835916 -22.799046) (xy 32.710073 -22.765669)
			(xy 32.586498 -22.724682) (xy 32.465652 -22.676238) (xy 32.347984 -22.620516) (xy 32.233932 -22.557725)
			(xy 32.12392 -22.488098) (xy 32.018358 -22.411893) (xy 31.917638 -22.329394) (xy 31.822134 -22.240909)
			(xy 31.732202 -22.146766) (xy 31.648177 -22.047315) (xy 31.570372 -21.942927) (xy 31.499075 -21.83399)
			(xy 31.434551 -21.720908) (xy 31.377042 -21.604104) (xy 31.32676 -21.484011) (xy 31.283894 -21.361075)
			(xy 31.248601 -21.235756) (xy 31.221015 -21.108517) (xy 31.201236 -20.979834) (xy 31.18934 -20.850184)
			(xy 31.18537 -20.72005) (xy 20.524724 -20.72005) (xy 20.524724 -21.959316) (xy 20.524806 -21.963525)
			(xy 20.526213 -21.971824) (xy 20.527518 -21.975826) (xy 20.529534 -21.981189) (xy 20.535552 -21.990937)
			(xy 20.539456 -21.99513) (xy 23.351864 -24.807418) (xy 32.371282 -24.807418) (xy 32.375353 -24.751796)
			(xy 32.387479 -24.697359) (xy 32.407402 -24.645268) (xy 32.434698 -24.596633) (xy 32.468784 -24.55249)
			(xy 32.508933 -24.513781) (xy 32.554291 -24.48133) (xy 32.603891 -24.455829) (xy 32.656675 -24.437822)
			(xy 32.711518 -24.427692) (xy 32.767252 -24.425655) (xy 32.822689 -24.431755) (xy 32.876646 -24.445861)
			(xy 32.927975 -24.467673) (xy 32.975581 -24.496727) (xy 33.018449 -24.532402) (xy 33.055666 -24.573939)
			(xy 33.086439 -24.620452) (xy 33.110111 -24.670949) (xy 33.126179 -24.724356) (xy 33.134299 -24.779532)
			(xy 33.134808 -24.807418) (xy 33.134299 -24.835304) (xy 33.126179 -24.89048) (xy 33.110111 -24.943887)
			(xy 33.086439 -24.994384) (xy 33.055666 -25.040897) (xy 33.018449 -25.082434) (xy 32.975581 -25.118109)
			(xy 32.927975 -25.147163) (xy 32.876646 -25.168975) (xy 32.822689 -25.183081) (xy 32.767252 -25.189181)
			(xy 32.711518 -25.187144) (xy 32.656675 -25.177014) (xy 32.603891 -25.159007) (xy 32.554291 -25.133506)
			(xy 32.508933 -25.101055) (xy 32.468784 -25.062346) (xy 32.434698 -25.018203) (xy 32.407402 -24.969568)
			(xy 32.387479 -24.917477) (xy 32.375353 -24.86304) (xy 32.371282 -24.807418) (xy 23.351864 -24.807418)
			(xy 24.578228 -26.03373) (xy 31.267906 -26.03373) (xy 31.271977 -25.978108) (xy 31.284103 -25.923671)
			(xy 31.304026 -25.87158) (xy 31.331322 -25.822945) (xy 31.365408 -25.778802) (xy 31.405557 -25.740093)
			(xy 31.450915 -25.707642) (xy 31.500515 -25.682141) (xy 31.553299 -25.664134) (xy 31.608142 -25.654004)
			(xy 31.663876 -25.651967) (xy 31.719313 -25.658067) (xy 31.77327 -25.672173) (xy 31.824599 -25.693985)
			(xy 31.872205 -25.723039) (xy 31.915073 -25.758714) (xy 31.95229 -25.800251) (xy 31.983063 -25.846764)
			(xy 32.006735 -25.897261) (xy 32.022803 -25.950668) (xy 32.030923 -26.005844) (xy 32.031432 -26.03373)
			(xy 32.030923 -26.061616) (xy 32.022803 -26.116792) (xy 32.006735 -26.170199) (xy 31.983063 -26.220696)
			(xy 31.95229 -26.267209) (xy 31.915073 -26.308746) (xy 31.872205 -26.344421) (xy 31.824599 -26.373475)
			(xy 31.77327 -26.395287) (xy 31.719313 -26.409393) (xy 31.663876 -26.415493) (xy 31.608142 -26.413456)
			(xy 31.553299 -26.403326) (xy 31.500515 -26.385319) (xy 31.450915 -26.359818) (xy 31.405557 -26.327367)
			(xy 31.365408 -26.288658) (xy 31.331322 -26.244515) (xy 31.304026 -26.19588) (xy 31.284103 -26.143789)
			(xy 31.271977 -26.089352) (xy 31.267906 -26.03373) (xy 24.578228 -26.03373) (xy 26.498296 -27.953716)
			(xy 26.516325 -27.972488) (xy 26.546899 -28.014606) (xy 26.57052 -28.060983) (xy 26.586607 -28.11048)
			(xy 26.591156 -28.139136) (xy 28.39796 -28.139136) (xy 28.402031 -28.083514) (xy 28.414157 -28.029077)
			(xy 28.43408 -27.976986) (xy 28.461376 -27.928351) (xy 28.495462 -27.884208) (xy 28.535611 -27.845499)
			(xy 28.580969 -27.813048) (xy 28.630569 -27.787547) (xy 28.683353 -27.76954) (xy 28.738196 -27.75941)
			(xy 28.79393 -27.757373) (xy 28.849367 -27.763473) (xy 28.903324 -27.777579) (xy 28.954653 -27.799391)
			(xy 29.002259 -27.828445) (xy 29.045127 -27.86412) (xy 29.082344 -27.905657) (xy 29.113117 -27.95217)
			(xy 29.136789 -28.002667) (xy 29.152857 -28.056074) (xy 29.160977 -28.11125) (xy 29.161486 -28.139136)
			(xy 29.66796 -28.139136) (xy 29.672031 -28.083514) (xy 29.684157 -28.029077) (xy 29.70408 -27.976986)
			(xy 29.731376 -27.928351) (xy 29.765462 -27.884208) (xy 29.805611 -27.845499) (xy 29.850969 -27.813048)
			(xy 29.900569 -27.787547) (xy 29.953353 -27.76954) (xy 30.008196 -27.75941) (xy 30.06393 -27.757373)
			(xy 30.119367 -27.763473) (xy 30.173324 -27.777579) (xy 30.224653 -27.799391) (xy 30.272259 -27.828445)
			(xy 30.315127 -27.86412) (xy 30.352344 -27.905657) (xy 30.383117 -27.95217) (xy 30.406789 -28.002667)
			(xy 30.422857 -28.056074) (xy 30.430977 -28.11125) (xy 30.431486 -28.139136) (xy 30.430977 -28.167022)
			(xy 30.422857 -28.222198) (xy 30.406789 -28.275605) (xy 30.383117 -28.326102) (xy 30.352344 -28.372615)
			(xy 30.315127 -28.414152) (xy 30.272259 -28.449827) (xy 30.224653 -28.478881) (xy 30.173324 -28.500693)
			(xy 30.119367 -28.514799) (xy 30.06393 -28.520899) (xy 30.008196 -28.518862) (xy 29.953353 -28.508732)
			(xy 29.900569 -28.490725) (xy 29.850969 -28.465224) (xy 29.805611 -28.432773) (xy 29.765462 -28.394064)
			(xy 29.731376 -28.349921) (xy 29.70408 -28.301286) (xy 29.684157 -28.249195) (xy 29.672031 -28.194758)
			(xy 29.66796 -28.139136) (xy 29.161486 -28.139136) (xy 29.160977 -28.167022) (xy 29.152857 -28.222198)
			(xy 29.136789 -28.275605) (xy 29.113117 -28.326102) (xy 29.082344 -28.372615) (xy 29.045127 -28.414152)
			(xy 29.002259 -28.449827) (xy 28.954653 -28.478881) (xy 28.903324 -28.500693) (xy 28.849367 -28.514799)
			(xy 28.79393 -28.520899) (xy 28.738196 -28.518862) (xy 28.683353 -28.508732) (xy 28.630569 -28.490725)
			(xy 28.580969 -28.465224) (xy 28.535611 -28.432773) (xy 28.495462 -28.394064) (xy 28.461376 -28.349921)
			(xy 28.43408 -28.301286) (xy 28.414157 -28.249195) (xy 28.402031 -28.194758) (xy 28.39796 -28.139136)
			(xy 26.591156 -28.139136) (xy 26.594766 -28.161882) (xy 26.595324 -28.187904) (xy 26.595324 -30.376876)
			(xy 26.888948 -30.376876) (xy 26.889503 -30.34796) (xy 26.898222 -30.29079) (xy 26.915471 -30.235591)
			(xy 26.940856 -30.183629) (xy 26.973794 -30.136094) (xy 27.013531 -30.094077) (xy 27.036014 -30.075886)
			(xy 27.04482 -30.068277) (xy 27.055003 -30.047378) (xy 27.055572 -30.035754) (xy 27.055572 -29.955998)
			(xy 27.055029 -29.944366) (xy 27.044844 -29.923456) (xy 27.036014 -29.915866) (xy 27.013517 -29.897691)
			(xy 26.973782 -29.855668) (xy 26.940844 -29.80813) (xy 26.915458 -29.756166) (xy 26.898205 -29.700965)
			(xy 26.88948 -29.643793) (xy 26.888948 -29.614876) (xy 26.889434 -29.587625) (xy 26.89719 -29.533677)
			(xy 26.912545 -29.481382) (xy 26.935187 -29.431805) (xy 26.964653 -29.385955) (xy 27.000344 -29.344764)
			(xy 27.041535 -29.309073) (xy 27.087385 -29.279607) (xy 27.136962 -29.256965) (xy 27.189257 -29.24161)
			(xy 27.243205 -29.233854) (xy 27.297707 -29.233854) (xy 27.351655 -29.24161) (xy 27.40395 -29.256965)
			(xy 27.453527 -29.279607) (xy 27.499377 -29.309073) (xy 27.540568 -29.344764) (xy 27.576259 -29.385955)
			(xy 27.605725 -29.431805) (xy 27.628367 -29.481382) (xy 27.643722 -29.533677) (xy 27.651478 -29.587625)
			(xy 27.651964 -29.614876) (xy 27.651442 -29.643793) (xy 27.642716 -29.700965) (xy 27.625459 -29.756164)
			(xy 27.600069 -29.808126) (xy 27.567125 -29.85566) (xy 27.527384 -29.897676) (xy 27.504898 -29.915866)
			(xy 27.496116 -29.923497) (xy 27.485919 -29.94438) (xy 27.48534 -29.955998) (xy 27.48534 -30.035754)
			(xy 27.485848 -30.04739) (xy 27.496058 -30.0683) (xy 27.504898 -30.075886) (xy 27.527374 -30.094085)
			(xy 27.56711 -30.136103) (xy 27.60005 -30.183637) (xy 27.62544 -30.235596) (xy 27.642697 -30.290792)
			(xy 27.651428 -30.34796) (xy 27.651964 -30.376876) (xy 27.651478 -30.404127) (xy 27.643722 -30.458075)
			(xy 27.628367 -30.51037) (xy 27.605725 -30.559947) (xy 27.576259 -30.605797) (xy 27.540568 -30.646988)
			(xy 27.499377 -30.682679) (xy 27.453527 -30.712145) (xy 27.40395 -30.734787) (xy 27.351655 -30.750142)
			(xy 27.297707 -30.757898) (xy 27.243205 -30.757898) (xy 27.189257 -30.750142) (xy 27.136962 -30.734787)
			(xy 27.087385 -30.712145) (xy 27.041535 -30.682679) (xy 27.000344 -30.646988) (xy 26.964653 -30.605797)
			(xy 26.935187 -30.559947) (xy 26.912545 -30.51037) (xy 26.89719 -30.458075) (xy 26.889434 -30.404127)
			(xy 26.888948 -30.376876) (xy 26.595324 -30.376876) (xy 26.595324 -31.567882) (xy 26.998674 -31.567882)
			(xy 27.002745 -31.51226) (xy 27.014871 -31.457823) (xy 27.034794 -31.405732) (xy 27.06209 -31.357097)
			(xy 27.096176 -31.312954) (xy 27.136325 -31.274245) (xy 27.181683 -31.241794) (xy 27.231283 -31.216293)
			(xy 27.284067 -31.198286) (xy 27.33891 -31.188156) (xy 27.394644 -31.186119) (xy 27.450081 -31.192219)
			(xy 27.504038 -31.206325) (xy 27.555367 -31.228137) (xy 27.602973 -31.257191) (xy 27.645841 -31.292866)
			(xy 27.683058 -31.334403) (xy 27.713831 -31.380916) (xy 27.737503 -31.431413) (xy 27.753571 -31.48482)
			(xy 27.761691 -31.539996) (xy 27.7622 -31.567882) (xy 27.761691 -31.595768) (xy 27.753571 -31.650944)
			(xy 27.737503 -31.704351) (xy 27.730511 -31.719266) (xy 28.285438 -31.719266) (xy 28.289509 -31.663644)
			(xy 28.301635 -31.609207) (xy 28.321558 -31.557116) (xy 28.348854 -31.508481) (xy 28.38294 -31.464338)
			(xy 28.423089 -31.425629) (xy 28.468447 -31.393178) (xy 28.518047 -31.367677) (xy 28.570831 -31.34967)
			(xy 28.625674 -31.33954) (xy 28.681408 -31.337503) (xy 28.736845 -31.343603) (xy 28.790802 -31.357709)
			(xy 28.842131 -31.379521) (xy 28.889737 -31.408575) (xy 28.932605 -31.44425) (xy 28.969822 -31.485787)
			(xy 29.000595 -31.5323) (xy 29.024267 -31.582797) (xy 29.040335 -31.636204) (xy 29.044485 -31.664402)
			(xy 29.561026 -31.664402) (xy 29.565097 -31.60878) (xy 29.577223 -31.554343) (xy 29.597146 -31.502252)
			(xy 29.624442 -31.453617) (xy 29.658528 -31.409474) (xy 29.698677 -31.370765) (xy 29.744035 -31.338314)
			(xy 29.793635 -31.312813) (xy 29.846419 -31.294806) (xy 29.901262 -31.284676) (xy 29.956996 -31.282639)
			(xy 30.012433 -31.288739) (xy 30.06639 -31.302845) (xy 30.117719 -31.324657) (xy 30.165325 -31.353711)
			(xy 30.208193 -31.389386) (xy 30.24541 -31.430923) (xy 30.276183 -31.477436) (xy 30.299855 -31.527933)
			(xy 30.315923 -31.58134) (xy 30.324043 -31.636516) (xy 30.324552 -31.664402) (xy 30.324043 -31.692288)
			(xy 30.315923 -31.747464) (xy 30.299855 -31.800871) (xy 30.276183 -31.851368) (xy 30.24541 -31.897881)
			(xy 30.208193 -31.939418) (xy 30.165325 -31.975093) (xy 30.117719 -32.004147) (xy 30.06639 -32.025959)
			(xy 30.012433 -32.040065) (xy 29.956996 -32.046165) (xy 29.901262 -32.044128) (xy 29.846419 -32.033998)
			(xy 29.793635 -32.015991) (xy 29.744035 -31.99049) (xy 29.698677 -31.958039) (xy 29.658528 -31.91933)
			(xy 29.624442 -31.875187) (xy 29.597146 -31.826552) (xy 29.577223 -31.774461) (xy 29.565097 -31.720024)
			(xy 29.561026 -31.664402) (xy 29.044485 -31.664402) (xy 29.048455 -31.69138) (xy 29.048964 -31.719266)
			(xy 29.048455 -31.747152) (xy 29.040335 -31.802328) (xy 29.024267 -31.855735) (xy 29.000595 -31.906232)
			(xy 28.969822 -31.952745) (xy 28.932605 -31.994282) (xy 28.889737 -32.029957) (xy 28.842131 -32.059011)
			(xy 28.790802 -32.080823) (xy 28.736845 -32.094929) (xy 28.681408 -32.101029) (xy 28.625674 -32.098992)
			(xy 28.570831 -32.088862) (xy 28.518047 -32.070855) (xy 28.468447 -32.045354) (xy 28.423089 -32.012903)
			(xy 28.38294 -31.974194) (xy 28.348854 -31.930051) (xy 28.321558 -31.881416) (xy 28.301635 -31.829325)
			(xy 28.289509 -31.774888) (xy 28.285438 -31.719266) (xy 27.730511 -31.719266) (xy 27.713831 -31.754848)
			(xy 27.683058 -31.801361) (xy 27.645841 -31.842898) (xy 27.602973 -31.878573) (xy 27.555367 -31.907627)
			(xy 27.504038 -31.929439) (xy 27.450081 -31.943545) (xy 27.394644 -31.949645) (xy 27.33891 -31.947608)
			(xy 27.284067 -31.937478) (xy 27.231283 -31.919471) (xy 27.181683 -31.89397) (xy 27.136325 -31.861519)
			(xy 27.096176 -31.82281) (xy 27.06209 -31.778667) (xy 27.034794 -31.730032) (xy 27.014871 -31.677941)
			(xy 27.002745 -31.623504) (xy 26.998674 -31.567882) (xy 26.595324 -31.567882) (xy 26.595324 -33.649666)
			(xy 26.595421 -33.654543) (xy 26.597212 -33.664132) (xy 26.59888 -33.668716) (xy 26.600921 -33.673364)
			(xy 26.606548 -33.681811) (xy 26.610056 -33.68548) (xy 28.189462 -35.264852) (xy 29.902402 -35.264852)
			(xy 29.906473 -35.20923) (xy 29.918599 -35.154793) (xy 29.938522 -35.102702) (xy 29.965818 -35.054067)
			(xy 29.999904 -35.009924) (xy 30.040053 -34.971215) (xy 30.085411 -34.938764) (xy 30.135011 -34.913263)
			(xy 30.187795 -34.895256) (xy 30.242638 -34.885126) (xy 30.298372 -34.883089) (xy 30.353809 -34.889189)
			(xy 30.407766 -34.903295) (xy 30.459095 -34.925107) (xy 30.506701 -34.954161) (xy 30.549569 -34.989836)
			(xy 30.586786 -35.031373) (xy 30.617559 -35.077886) (xy 30.641231 -35.128383) (xy 30.657299 -35.18179)
			(xy 30.665419 -35.236966) (xy 30.665928 -35.264852) (xy 30.665419 -35.292738) (xy 30.657299 -35.347914)
			(xy 30.641231 -35.401321) (xy 30.617559 -35.451818) (xy 30.586786 -35.498331) (xy 30.549569 -35.539868)
			(xy 30.506701 -35.575543) (xy 30.459095 -35.604597) (xy 30.407766 -35.626409) (xy 30.353809 -35.640515)
			(xy 30.298372 -35.646615) (xy 30.242638 -35.644578) (xy 30.187795 -35.634448) (xy 30.135011 -35.616441)
			(xy 30.085411 -35.59094) (xy 30.040053 -35.558489) (xy 29.999904 -35.51978) (xy 29.965818 -35.475637)
			(xy 29.938522 -35.427002) (xy 29.918599 -35.374911) (xy 29.906473 -35.320474) (xy 29.902402 -35.264852)
			(xy 28.189462 -35.264852) (xy 29.21158 -36.286948) (xy 31.200342 -36.286948) (xy 31.204413 -36.231326)
			(xy 31.216539 -36.176889) (xy 31.236462 -36.124798) (xy 31.263758 -36.076163) (xy 31.297844 -36.03202)
			(xy 31.337993 -35.993311) (xy 31.383351 -35.96086) (xy 31.432951 -35.935359) (xy 31.485735 -35.917352)
			(xy 31.540578 -35.907222) (xy 31.596312 -35.905185) (xy 31.651749 -35.911285) (xy 31.705706 -35.925391)
			(xy 31.757035 -35.947203) (xy 31.804641 -35.976257) (xy 31.847509 -36.011932) (xy 31.884726 -36.053469)
			(xy 31.915499 -36.099982) (xy 31.939171 -36.150479) (xy 31.955239 -36.203886) (xy 31.963359 -36.259062)
			(xy 31.963868 -36.286948) (xy 31.963359 -36.314834) (xy 31.955239 -36.37001) (xy 31.939171 -36.423417)
			(xy 31.915499 -36.473914) (xy 31.884726 -36.520427) (xy 31.847509 -36.561964) (xy 31.804641 -36.597639)
			(xy 31.757035 -36.626693) (xy 31.705706 -36.648505) (xy 31.651749 -36.662611) (xy 31.596312 -36.668711)
			(xy 31.540578 -36.666674) (xy 31.485735 -36.656544) (xy 31.432951 -36.638537) (xy 31.383351 -36.613036)
			(xy 31.337993 -36.580585) (xy 31.297844 -36.541876) (xy 31.263758 -36.497733) (xy 31.236462 -36.449098)
			(xy 31.216539 -36.397007) (xy 31.204413 -36.34257) (xy 31.200342 -36.286948) (xy 29.21158 -36.286948)
			(xy 30.698782 -37.774118) (xy 31.464756 -37.774118) (xy 31.468827 -37.718496) (xy 31.480953 -37.664059)
			(xy 31.500876 -37.611968) (xy 31.528172 -37.563333) (xy 31.562258 -37.51919) (xy 31.602407 -37.480481)
			(xy 31.647765 -37.44803) (xy 31.697365 -37.422529) (xy 31.750149 -37.404522) (xy 31.804992 -37.394392)
			(xy 31.860726 -37.392355) (xy 31.916163 -37.398455) (xy 31.97012 -37.412561) (xy 32.021449 -37.434373)
			(xy 32.069055 -37.463427) (xy 32.111923 -37.499102) (xy 32.14914 -37.540639) (xy 32.179913 -37.587152)
			(xy 32.203585 -37.637649) (xy 32.219653 -37.691056) (xy 32.227773 -37.746232) (xy 32.228282 -37.774118)
			(xy 32.227773 -37.802004) (xy 32.219653 -37.85718) (xy 32.203585 -37.910587) (xy 32.179913 -37.961084)
			(xy 32.14914 -38.007597) (xy 32.111923 -38.049134) (xy 32.069055 -38.084809) (xy 32.021449 -38.113863)
			(xy 31.97012 -38.135675) (xy 31.916163 -38.149781) (xy 31.860726 -38.155881) (xy 31.804992 -38.153844)
			(xy 31.750149 -38.143714) (xy 31.697365 -38.125707) (xy 31.647765 -38.100206) (xy 31.602407 -38.067755)
			(xy 31.562258 -38.029046) (xy 31.528172 -37.984903) (xy 31.500876 -37.936268) (xy 31.480953 -37.884177)
			(xy 31.468827 -37.82974) (xy 31.464756 -37.774118) (xy 30.698782 -37.774118) (xy 38.395402 -45.470572)
			(xy 38.402457 -45.47703) (xy 38.42001 -45.484588) (xy 38.439114 -45.485138) (xy 38.448234 -45.482256)
			(xy 38.45052 -45.48124) (xy 38.457504 -45.478078) (xy 38.46937 -45.468385) (xy 38.473888 -45.46219)
			(xy 38.477698 -45.456348) (xy 38.482016 -45.442378) (xy 38.482016 -44.05249) (xy 38.481965 -44.048418)
			(xy 38.480693 -44.040374) (xy 38.479476 -44.036488) (xy 38.477466 -44.030966) (xy 38.471302 -44.020965)
			(xy 38.467284 -44.016676) (xy 33.161478 -38.711124) (xy 33.143368 -38.692342) (xy 33.11269 -38.650144)
			(xy 33.088996 -38.603662) (xy 33.072872 -38.554044) (xy 33.064715 -38.502514) (xy 33.064196 -38.476428)
			(xy 33.064196 -36.716208) (xy 33.063942 -36.712144) (xy 33.063524 -36.707892) (xy 33.061478 -36.699596)
			(xy 33.059878 -36.695634) (xy 33.058354 -36.69284) (xy 33.051491 -36.679425) (xy 33.039662 -36.651707)
			(xy 33.034732 -36.637468) (xy 33.034478 -36.63696) (xy 33.032954 -36.632388) (xy 33.031938 -36.629086)
			(xy 33.031938 -36.628832) (xy 33.031176 -36.626038) (xy 33.029091 -36.621096) (xy 33.023197 -36.612137)
			(xy 33.019492 -36.608258) (xy 31.528766 -35.117532) (xy 31.510656 -35.09875) (xy 31.479978 -35.056551)
			(xy 31.456284 -35.01007) (xy 31.440159 -34.960452) (xy 31.432001 -34.908922) (xy 31.431484 -34.882836)
			(xy 31.431484 -32.45358) (xy 31.431484 -32.45231) (xy 31.430865 -32.442847) (xy 31.423565 -32.425357)
			(xy 31.41726 -32.418274) (xy 31.41345 -32.414718) (xy 31.354014 -32.36468) (xy 31.349559 -32.361154)
			(xy 31.33943 -32.356013) (xy 31.333948 -32.35452) (xy 31.32328 -32.351726) (xy 31.312104 -32.353758)
			(xy 31.286356 -32.358142) (xy 31.234335 -32.36285) (xy 31.208218 -32.363156) (xy 31.172804 -32.362643)
			(xy 31.102491 -32.354108) (xy 31.033721 -32.337159) (xy 30.967494 -32.312044) (xy 30.904778 -32.279129)
			(xy 30.846488 -32.238894) (xy 30.793472 -32.191926) (xy 30.746504 -32.138909) (xy 30.706269 -32.080618)
			(xy 30.673355 -32.017902) (xy 30.64824 -31.951676) (xy 30.631291 -31.882905) (xy 30.622756 -31.812592)
			(xy 30.62224 -31.777178) (xy 30.62224 -30.811724) (xy 30.621855 -30.803164) (xy 30.616125 -30.787026)
			(xy 30.605423 -30.773657) (xy 30.598364 -30.768798) (xy 30.52572 -30.723078) (xy 30.520128 -30.719796)
			(xy 30.507791 -30.715819) (xy 30.501336 -30.715204) (xy 30.488382 -30.714696) (xy 30.476698 -30.720284)
			(xy 30.450675 -30.73231) (xy 30.395922 -30.749286) (xy 30.339244 -30.757878) (xy 30.310582 -30.758384)
			(xy 30.283331 -30.757919) (xy 30.229383 -30.75016) (xy 30.177089 -30.734802) (xy 30.127512 -30.712159)
			(xy 30.081663 -30.68269) (xy 30.040475 -30.646996) (xy 30.004785 -30.605803) (xy 29.975321 -30.559951)
			(xy 29.952683 -30.510372) (xy 29.937331 -30.458076) (xy 29.929578 -30.404127) (xy 29.929074 -30.376876)
			(xy 29.929569 -30.348848) (xy 29.937768 -30.293395) (xy 29.953988 -30.239736) (xy 29.977878 -30.189026)
			(xy 30.008926 -30.142353) (xy 30.046465 -30.100722) (xy 30.067758 -30.08249) (xy 30.072076 -30.079188)
			(xy 30.078934 -30.070552) (xy 30.090618 -30.046422) (xy 30.09296 -30.041199) (xy 30.095521 -30.030045)
			(xy 30.095698 -30.024324) (xy 30.095698 -29.967428) (xy 30.095548 -29.961704) (xy 30.092979 -29.950547)
			(xy 30.090618 -29.94533) (xy 30.078934 -29.9212) (xy 30.072076 -29.912564) (xy 30.067758 -29.909262)
			(xy 30.046459 -29.891035) (xy 30.008916 -29.849406) (xy 29.977865 -29.802733) (xy 29.953974 -29.752021)
			(xy 29.937756 -29.698361) (xy 29.929561 -29.642905) (xy 29.929074 -29.614876) (xy 29.929561 -29.587625)
			(xy 29.937321 -29.533679) (xy 29.952678 -29.481386) (xy 29.97532 -29.431811) (xy 30.004787 -29.385962)
			(xy 30.040478 -29.344774) (xy 30.081667 -29.309083) (xy 30.127516 -29.279617) (xy 30.177092 -29.256976)
			(xy 30.229385 -29.241619) (xy 30.283331 -29.233861) (xy 30.310582 -29.233368) (xy 30.310582 -29.233114)
			(xy 30.339179 -29.233623) (xy 30.395732 -29.242156) (xy 30.450379 -29.259034) (xy 30.501894 -29.283878)
			(xy 30.549125 -29.316133) (xy 30.570424 -29.335222) (xy 30.578298 -29.342842) (xy 30.578552 -29.343096)
			(xy 30.588966 -29.346652) (xy 30.594272 -29.348245) (xy 30.605288 -29.349389) (xy 30.61081 -29.348938)
			(xy 30.64891 -29.34462) (xy 30.649418 -29.34462) (xy 30.687518 -29.340048) (xy 30.693021 -29.339296)
			(xy 30.703529 -29.335703) (xy 30.708346 -29.332936) (xy 30.717236 -29.327348) (xy 30.723586 -29.318458)
			(xy 30.723586 -29.31795) (xy 30.7394 -29.295388) (xy 30.774641 -29.253029) (xy 30.793944 -29.233368)
			(xy 32.08909 -27.938476) (xy 33.234884 -26.792428) (xy 33.238186 -26.788364) (xy 33.242323 -26.781854)
			(xy 33.246856 -26.767118) (xy 33.247076 -26.759408) (xy 33.247076 -24.158194) (xy 33.247571 -24.124108)
			(xy 33.255486 -24.056398) (xy 33.271207 -23.990064) (xy 33.294523 -23.926004) (xy 33.325118 -23.865084)
			(xy 33.362579 -23.808127) (xy 33.406399 -23.755905) (xy 33.455985 -23.709123) (xy 33.510667 -23.668414)
			(xy 33.569705 -23.634328) (xy 33.632301 -23.607327) (xy 33.697608 -23.587775) (xy 33.764744 -23.575937)
			(xy 33.8328 -23.571974) (xy 33.900856 -23.575937) (xy 33.967992 -23.587775) (xy 34.033299 -23.607327)
			(xy 34.095895 -23.634328) (xy 34.154933 -23.668414) (xy 34.209615 -23.709123) (xy 34.259201 -23.755905)
			(xy 34.303021 -23.808127) (xy 34.340482 -23.865084) (xy 34.371077 -23.926004) (xy 34.394393 -23.990064)
			(xy 34.410114 -24.056398) (xy 34.418029 -24.124108) (xy 34.418524 -24.158194) (xy 34.418524 -24.807418)
			(xy 34.620198 -24.807418) (xy 34.624269 -24.751796) (xy 34.636395 -24.697359) (xy 34.656318 -24.645268)
			(xy 34.683614 -24.596633) (xy 34.7177 -24.55249) (xy 34.757849 -24.513781) (xy 34.803207 -24.48133)
			(xy 34.852807 -24.455829) (xy 34.905591 -24.437822) (xy 34.960434 -24.427692) (xy 35.016168 -24.425655)
			(xy 35.071605 -24.431755) (xy 35.125562 -24.445861) (xy 35.176891 -24.467673) (xy 35.224497 -24.496727)
			(xy 35.267365 -24.532402) (xy 35.304582 -24.573939) (xy 35.335355 -24.620452) (xy 35.359027 -24.670949)
			(xy 35.375095 -24.724356) (xy 35.383215 -24.779532) (xy 35.383724 -24.807418) (xy 35.383215 -24.835304)
			(xy 35.375095 -24.89048) (xy 35.359027 -24.943887) (xy 35.335355 -24.994384) (xy 35.304582 -25.040897)
			(xy 35.267365 -25.082434) (xy 35.224497 -25.118109) (xy 35.176891 -25.147163) (xy 35.125562 -25.168975)
			(xy 35.071605 -25.183081) (xy 35.016168 -25.189181) (xy 34.960434 -25.187144) (xy 34.905591 -25.177014)
			(xy 34.852807 -25.159007) (xy 34.803207 -25.133506) (xy 34.757849 -25.101055) (xy 34.7177 -25.062346)
			(xy 34.683614 -25.018203) (xy 34.656318 -24.969568) (xy 34.636395 -24.917477) (xy 34.624269 -24.86304)
			(xy 34.620198 -24.807418) (xy 34.418524 -24.807418) (xy 34.418524 -26.683716) (xy 34.418947 -26.693733)
			(xy 34.426621 -26.712241) (xy 34.440793 -26.726402) (xy 34.459306 -26.734061) (xy 34.469324 -26.734516)
			(xy 34.741866 -26.734516) (xy 34.74593 -26.734262) (xy 34.750183 -26.733846) (xy 34.75848 -26.731805)
			(xy 34.76244 -26.730198) (xy 34.765234 -26.728674) (xy 34.781236 -26.721054) (xy 34.78911 -26.716482)
			(xy 34.796607 -26.710807) (xy 34.80721 -26.6953) (xy 34.811518 -26.677015) (xy 34.80895 -26.658406)
			(xy 34.799853 -26.641971) (xy 34.785446 -26.629915) (xy 34.776664 -26.626566) (xy 34.75206 -26.617555)
			(xy 34.705388 -26.593737) (xy 34.662418 -26.56375) (xy 34.62396 -26.528161) (xy 34.59074 -26.48764)
			(xy 34.563382 -26.442951) (xy 34.542403 -26.394936) (xy 34.528199 -26.3445) (xy 34.521037 -26.292593)
			(xy 34.520632 -26.266394) (xy 34.521118 -26.239143) (xy 34.528874 -26.185195) (xy 34.544229 -26.1329)
			(xy 34.566871 -26.083323) (xy 34.596337 -26.037473) (xy 34.632028 -25.996282) (xy 34.673219 -25.960591)
			(xy 34.719069 -25.931125) (xy 34.768646 -25.908483) (xy 34.820941 -25.893128) (xy 34.874889 -25.885372)
			(xy 34.929391 -25.885372) (xy 34.983339 -25.893128) (xy 35.035634 -25.908483) (xy 35.085211 -25.931125)
			(xy 35.131061 -25.960591) (xy 35.172252 -25.996282) (xy 35.207943 -26.037473) (xy 35.237409 -26.083323)
			(xy 35.260051 -26.1329) (xy 35.275406 -26.185195) (xy 35.283162 -26.239143) (xy 35.283648 -26.266394)
			(xy 35.283077 -26.295879) (xy 35.273963 -26.354142) (xy 35.255999 -26.41031) (xy 35.22961 -26.463048)
			(xy 35.195426 -26.5111) (xy 35.154258 -26.553324) (xy 35.130994 -26.571448) (xy 35.125914 -26.575258)
			(xy 35.11804 -26.58491) (xy 35.1155 -26.590498) (xy 35.113059 -26.596212) (xy 35.110755 -26.608417)
			(xy 35.110928 -26.614628) (xy 35.114484 -26.68651) (xy 35.115028 -26.6926) (xy 35.118616 -26.704285)
			(xy 35.121596 -26.709624) (xy 35.136328 -26.734262) (xy 35.144456 -26.742898) (xy 35.149536 -26.745946)
			(xy 35.172105 -26.761118) (xy 35.213112 -26.796833) (xy 35.248638 -26.838004) (xy 35.277965 -26.883798)
			(xy 35.300499 -26.933289) (xy 35.315785 -26.985476) (xy 35.323514 -27.039304) (xy 35.324034 -27.066494)
			(xy 35.323549 -27.093746) (xy 35.315793 -27.147696) (xy 35.300439 -27.199993) (xy 35.277798 -27.249573)
			(xy 35.248332 -27.295426) (xy 35.212641 -27.336619) (xy 35.171451 -27.372313) (xy 35.125601 -27.401783)
			(xy 35.076023 -27.424427) (xy 35.023727 -27.439786) (xy 34.969778 -27.447546) (xy 34.942526 -27.448002)
			(xy 34.911778 -27.447387) (xy 34.851076 -27.437531) (xy 34.79274 -27.418071) (xy 34.765234 -27.404314)
			(xy 34.75863 -27.401012) (xy 34.747962 -27.398472) (xy 34.598356 -27.398472) (xy 34.592346 -27.398638)
			(xy 34.580662 -27.40146) (xy 34.575242 -27.40406) (xy 34.571764 -27.405895) (xy 34.565378 -27.41048)
			(xy 34.562542 -27.413204) (xy 32.853376 -29.12237) (xy 34.606992 -29.12237) (xy 34.606992 -28.25877)
			(xy 34.607482 -28.228802) (xy 34.615305 -28.16938) (xy 34.630818 -28.111487) (xy 34.653754 -28.056114)
			(xy 34.683721 -28.004208) (xy 34.720208 -27.956658) (xy 34.762588 -27.914278) (xy 34.810138 -27.877791)
			(xy 34.862044 -27.847824) (xy 34.917417 -27.824888) (xy 34.97531 -27.809375) (xy 35.034732 -27.801552)
			(xy 35.094668 -27.801552) (xy 35.15409 -27.809375) (xy 35.211983 -27.824888) (xy 35.267356 -27.847824)
			(xy 35.319262 -27.877791) (xy 35.366812 -27.914278) (xy 35.409192 -27.956658) (xy 35.445679 -28.004208)
			(xy 35.475646 -28.056114) (xy 35.498582 -28.111487) (xy 35.514095 -28.16938) (xy 35.521918 -28.228802)
			(xy 35.522408 -28.25877) (xy 35.522408 -29.12237) (xy 35.521918 -29.152338) (xy 35.514095 -29.21176)
			(xy 35.498582 -29.269653) (xy 35.475646 -29.325026) (xy 35.445679 -29.376932) (xy 35.409192 -29.424482)
			(xy 35.366812 -29.466862) (xy 35.319262 -29.503349) (xy 35.267356 -29.533316) (xy 35.211983 -29.556252)
			(xy 35.15409 -29.571765) (xy 35.094668 -29.579588) (xy 35.034732 -29.579588) (xy 34.97531 -29.571765)
			(xy 34.917417 -29.556252) (xy 34.862044 -29.533316) (xy 34.810138 -29.503349) (xy 34.762588 -29.466862)
			(xy 34.720208 -29.424482) (xy 34.683721 -29.376932) (xy 34.653754 -29.325026) (xy 34.630818 -29.269653)
			(xy 34.615305 -29.21176) (xy 34.607482 -29.152338) (xy 34.606992 -29.12237) (xy 32.853376 -29.12237)
			(xy 32.110172 -29.865574) (xy 32.107463 -29.868423) (xy 32.102864 -29.874798) (xy 32.101028 -29.878274)
			(xy 32.098447 -29.883701) (xy 32.095629 -29.895381) (xy 32.09544 -29.901388) (xy 32.09544 -30.922468)
			(xy 32.752792 -30.922468) (xy 32.752792 -30.058868) (xy 32.753282 -30.0289) (xy 32.761105 -29.969478)
			(xy 32.776618 -29.911585) (xy 32.799554 -29.856212) (xy 32.829521 -29.804306) (xy 32.866008 -29.756756)
			(xy 32.908388 -29.714376) (xy 32.955938 -29.677889) (xy 33.007844 -29.647922) (xy 33.063217 -29.624986)
			(xy 33.12111 -29.609473) (xy 33.180532 -29.60165) (xy 33.240468 -29.60165) (xy 33.29989 -29.609473)
			(xy 33.357783 -29.624986) (xy 33.413156 -29.647922) (xy 33.465062 -29.677889) (xy 33.512612 -29.714376)
			(xy 33.554992 -29.756756) (xy 33.591479 -29.804306) (xy 33.621446 -29.856212) (xy 33.644382 -29.911585)
			(xy 33.659895 -29.969478) (xy 33.667718 -30.0289) (xy 33.668208 -30.058868) (xy 33.668208 -30.92069)
			(xy 47.489364 -30.92069) (xy 47.489364 -30.05709) (xy 47.489854 -30.027106) (xy 47.497682 -29.96765)
			(xy 47.513203 -29.909725) (xy 47.536152 -29.854321) (xy 47.566136 -29.802387) (xy 47.602642 -29.754811)
			(xy 47.645047 -29.712406) (xy 47.692623 -29.6759) (xy 47.744557 -29.645916) (xy 47.799961 -29.622967)
			(xy 47.857886 -29.607446) (xy 47.917342 -29.599618) (xy 47.97731 -29.599618) (xy 48.036766 -29.607446)
			(xy 48.094691 -29.622967) (xy 48.150095 -29.645916) (xy 48.202029 -29.6759) (xy 48.249605 -29.712406)
			(xy 48.29201 -29.754811) (xy 48.328516 -29.802387) (xy 48.3585 -29.854321) (xy 48.381449 -29.909725)
			(xy 48.39697 -29.96765) (xy 48.404798 -30.027106) (xy 48.405288 -30.05709) (xy 48.405288 -30.92069)
			(xy 48.404798 -30.950674) (xy 48.39697 -31.01013) (xy 48.381449 -31.068055) (xy 48.3585 -31.123459)
			(xy 48.328516 -31.175393) (xy 48.29201 -31.222969) (xy 48.249605 -31.265374) (xy 48.202029 -31.30188)
			(xy 48.150095 -31.331864) (xy 48.094691 -31.354813) (xy 48.036766 -31.370334) (xy 47.97731 -31.378162)
			(xy 47.917342 -31.378162) (xy 47.857886 -31.370334) (xy 47.799961 -31.354813) (xy 47.744557 -31.331864)
			(xy 47.692623 -31.30188) (xy 47.645047 -31.265374) (xy 47.602642 -31.222969) (xy 47.566136 -31.175393)
			(xy 47.536152 -31.123459) (xy 47.513203 -31.068055) (xy 47.497682 -31.01013) (xy 47.489854 -30.950674)
			(xy 47.489364 -30.92069) (xy 33.668208 -30.92069) (xy 33.668208 -30.922468) (xy 33.667718 -30.952436)
			(xy 33.659895 -31.011858) (xy 33.644382 -31.069751) (xy 33.621446 -31.125124) (xy 33.591479 -31.17703)
			(xy 33.554992 -31.22458) (xy 33.512612 -31.26696) (xy 33.465062 -31.303447) (xy 33.413156 -31.333414)
			(xy 33.357783 -31.35635) (xy 33.29989 -31.371863) (xy 33.240468 -31.379686) (xy 33.180532 -31.379686)
			(xy 33.12111 -31.371863) (xy 33.063217 -31.35635) (xy 33.007844 -31.333414) (xy 32.955938 -31.303447)
			(xy 32.908388 -31.26696) (xy 32.866008 -31.22458) (xy 32.829521 -31.17703) (xy 32.799554 -31.125124)
			(xy 32.776618 -31.069751) (xy 32.761105 -31.011858) (xy 32.753282 -30.952436) (xy 32.752792 -30.922468)
			(xy 32.09544 -30.922468) (xy 32.09544 -32.722312) (xy 34.606992 -32.722312) (xy 34.606992 -31.858712)
			(xy 34.607482 -31.828744) (xy 34.615305 -31.769322) (xy 34.630818 -31.711429) (xy 34.653754 -31.656056)
			(xy 34.683721 -31.60415) (xy 34.720208 -31.5566) (xy 34.762588 -31.51422) (xy 34.810138 -31.477733)
			(xy 34.862044 -31.447766) (xy 34.917417 -31.42483) (xy 34.97531 -31.409317) (xy 35.034732 -31.401494)
			(xy 35.094668 -31.401494) (xy 35.15409 -31.409317) (xy 35.211983 -31.42483) (xy 35.267356 -31.447766)
			(xy 35.319262 -31.477733) (xy 35.366812 -31.51422) (xy 35.409192 -31.5566) (xy 35.445679 -31.60415)
			(xy 35.475646 -31.656056) (xy 35.498582 -31.711429) (xy 35.514095 -31.769322) (xy 35.521918 -31.828744)
			(xy 35.522408 -31.858712) (xy 35.522408 -32.714184) (xy 44.847256 -32.714184) (xy 44.847256 -31.850584)
			(xy 44.847746 -31.8206) (xy 44.855574 -31.761144) (xy 44.871095 -31.703219) (xy 44.894044 -31.647815)
			(xy 44.924028 -31.595881) (xy 44.960534 -31.548305) (xy 45.002939 -31.5059) (xy 45.050515 -31.469394)
			(xy 45.102449 -31.43941) (xy 45.157853 -31.416461) (xy 45.215778 -31.40094) (xy 45.275234 -31.393112)
			(xy 45.335202 -31.393112) (xy 45.394658 -31.40094) (xy 45.452583 -31.416461) (xy 45.507987 -31.43941)
			(xy 45.559921 -31.469394) (xy 45.607497 -31.5059) (xy 45.649902 -31.548305) (xy 45.686408 -31.595881)
			(xy 45.716392 -31.647815) (xy 45.739341 -31.703219) (xy 45.754862 -31.761144) (xy 45.76269 -31.8206)
			(xy 45.76318 -31.850584) (xy 45.76318 -32.714184) (xy 45.76269 -32.744168) (xy 45.754862 -32.803624)
			(xy 45.739341 -32.861549) (xy 45.716392 -32.916953) (xy 45.686408 -32.968887) (xy 45.649902 -33.016463)
			(xy 45.607497 -33.058868) (xy 45.559921 -33.095374) (xy 45.507987 -33.125358) (xy 45.452583 -33.148307)
			(xy 45.394658 -33.163828) (xy 45.335202 -33.171656) (xy 45.275234 -33.171656) (xy 45.215778 -33.163828)
			(xy 45.157853 -33.148307) (xy 45.102449 -33.125358) (xy 45.050515 -33.095374) (xy 45.002939 -33.058868)
			(xy 44.960534 -33.016463) (xy 44.924028 -32.968887) (xy 44.894044 -32.916953) (xy 44.871095 -32.861549)
			(xy 44.855574 -32.803624) (xy 44.847746 -32.744168) (xy 44.847256 -32.714184) (xy 35.522408 -32.714184)
			(xy 35.522408 -32.722312) (xy 35.521918 -32.75228) (xy 35.514095 -32.811702) (xy 35.498582 -32.869595)
			(xy 35.475646 -32.924968) (xy 35.445679 -32.976874) (xy 35.409192 -33.024424) (xy 35.366812 -33.066804)
			(xy 35.319262 -33.103291) (xy 35.267356 -33.133258) (xy 35.211983 -33.156194) (xy 35.15409 -33.171707)
			(xy 35.094668 -33.17953) (xy 35.034732 -33.17953) (xy 34.97531 -33.171707) (xy 34.917417 -33.156194)
			(xy 34.862044 -33.133258) (xy 34.810138 -33.103291) (xy 34.762588 -33.066804) (xy 34.720208 -33.024424)
			(xy 34.683721 -32.976874) (xy 34.653754 -32.924968) (xy 34.630818 -32.869595) (xy 34.615305 -32.811702)
			(xy 34.607482 -32.75228) (xy 34.606992 -32.722312) (xy 32.09544 -32.722312) (xy 32.09544 -34.52241)
			(xy 32.752792 -34.52241) (xy 32.752792 -33.65881) (xy 32.753282 -33.628842) (xy 32.761105 -33.56942)
			(xy 32.776618 -33.511527) (xy 32.799554 -33.456154) (xy 32.829521 -33.404248) (xy 32.866008 -33.356698)
			(xy 32.908388 -33.314318) (xy 32.955938 -33.277831) (xy 33.007844 -33.247864) (xy 33.063217 -33.224928)
			(xy 33.12111 -33.209415) (xy 33.180532 -33.201592) (xy 33.240468 -33.201592) (xy 33.29989 -33.209415)
			(xy 33.357783 -33.224928) (xy 33.413156 -33.247864) (xy 33.465062 -33.277831) (xy 33.512612 -33.314318)
			(xy 33.554992 -33.356698) (xy 33.591479 -33.404248) (xy 33.621446 -33.456154) (xy 33.644382 -33.511527)
			(xy 33.659895 -33.56942) (xy 33.667718 -33.628842) (xy 33.668208 -33.65881) (xy 33.668208 -34.520886)
			(xy 47.489364 -34.520886) (xy 47.489364 -33.657286) (xy 47.489854 -33.627302) (xy 47.497682 -33.567846)
			(xy 47.513203 -33.509921) (xy 47.536152 -33.454517) (xy 47.566136 -33.402583) (xy 47.602642 -33.355007)
			(xy 47.645047 -33.312602) (xy 47.692623 -33.276096) (xy 47.744557 -33.246112) (xy 47.799961 -33.223163)
			(xy 47.857886 -33.207642) (xy 47.917342 -33.199814) (xy 47.97731 -33.199814) (xy 48.036766 -33.207642)
			(xy 48.094691 -33.223163) (xy 48.150095 -33.246112) (xy 48.202029 -33.276096) (xy 48.249605 -33.312602)
			(xy 48.29201 -33.355007) (xy 48.328516 -33.402583) (xy 48.3585 -33.454517) (xy 48.381449 -33.509921)
			(xy 48.39697 -33.567846) (xy 48.404798 -33.627302) (xy 48.405288 -33.657286) (xy 48.405288 -34.520886)
			(xy 48.404798 -34.55087) (xy 48.39697 -34.610326) (xy 48.381449 -34.668251) (xy 48.3585 -34.723655)
			(xy 48.328516 -34.775589) (xy 48.29201 -34.823165) (xy 48.249605 -34.86557) (xy 48.202029 -34.902076)
			(xy 48.150095 -34.93206) (xy 48.094691 -34.955009) (xy 48.036766 -34.97053) (xy 47.97731 -34.978358)
			(xy 47.917342 -34.978358) (xy 47.857886 -34.97053) (xy 47.799961 -34.955009) (xy 47.744557 -34.93206)
			(xy 47.692623 -34.902076) (xy 47.645047 -34.86557) (xy 47.602642 -34.823165) (xy 47.566136 -34.775589)
			(xy 47.536152 -34.723655) (xy 47.513203 -34.668251) (xy 47.497682 -34.610326) (xy 47.489854 -34.55087)
			(xy 47.489364 -34.520886) (xy 33.668208 -34.520886) (xy 33.668208 -34.52241) (xy 33.667718 -34.552378)
			(xy 33.659895 -34.6118) (xy 33.644382 -34.669693) (xy 33.621446 -34.725066) (xy 33.591479 -34.776972)
			(xy 33.554992 -34.824522) (xy 33.512612 -34.866902) (xy 33.465062 -34.903389) (xy 33.413156 -34.933356)
			(xy 33.357783 -34.956292) (xy 33.29989 -34.971805) (xy 33.240468 -34.979628) (xy 33.180532 -34.979628)
			(xy 33.12111 -34.971805) (xy 33.063217 -34.956292) (xy 33.007844 -34.933356) (xy 32.955938 -34.903389)
			(xy 32.908388 -34.866902) (xy 32.866008 -34.824522) (xy 32.829521 -34.776972) (xy 32.799554 -34.725066)
			(xy 32.776618 -34.669693) (xy 32.761105 -34.6118) (xy 32.753282 -34.552378) (xy 32.752792 -34.52241)
			(xy 32.09544 -34.52241) (xy 32.09544 -34.72434) (xy 32.096456 -34.733992) (xy 32.098089 -34.741233)
			(xy 32.104941 -34.754392) (xy 32.109918 -34.7599) (xy 33.488884 -36.138866) (xy 33.492744 -36.142593)
			(xy 33.501712 -36.148482) (xy 33.506664 -36.15055) (xy 33.509458 -36.151312) (xy 33.535018 -36.159747)
			(xy 33.583655 -36.182797) (xy 33.628571 -36.212454) (xy 33.668874 -36.248127) (xy 33.703765 -36.289109)
			(xy 33.732551 -36.334587) (xy 33.754661 -36.383659) (xy 33.769657 -36.435351) (xy 33.777241 -36.488637)
			(xy 33.777682 -36.515548) (xy 33.777061 -36.546295) (xy 33.768309 -36.60013) (xy 37.998153 -36.60013)
			(xy 38.002158 -36.512222) (xy 38.014141 -36.425042) (xy 38.034001 -36.339313) (xy 38.061576 -36.255745)
			(xy 38.096635 -36.175031) (xy 38.138888 -36.097839) (xy 38.187986 -36.02481) (xy 38.243522 -35.956548)
			(xy 38.305034 -35.893618) (xy 38.372015 -35.836544) (xy 38.443908 -35.785796) (xy 38.520117 -35.741796)
			(xy 38.600012 -35.704909) (xy 38.682931 -35.67544) (xy 38.768186 -35.653633) (xy 38.85507 -35.639669)
			(xy 38.942864 -35.633663) (xy 39.030841 -35.635667) (xy 39.118271 -35.645662) (xy 39.20443 -35.663566)
			(xy 39.288604 -35.68923) (xy 39.370095 -35.722443) (xy 39.448229 -35.762929) (xy 39.522357 -35.810351)
			(xy 39.591865 -35.864318) (xy 39.605164 -35.876738) (xy 44.717206 -35.876738) (xy 44.721277 -35.821116)
			(xy 44.733403 -35.766679) (xy 44.753326 -35.714588) (xy 44.780622 -35.665953) (xy 44.814708 -35.62181)
			(xy 44.854857 -35.583101) (xy 44.900215 -35.55065) (xy 44.949815 -35.525149) (xy 45.002599 -35.507142)
			(xy 45.057442 -35.497012) (xy 45.113176 -35.494975) (xy 45.168613 -35.501075) (xy 45.22257 -35.515181)
			(xy 45.273899 -35.536993) (xy 45.321505 -35.566047) (xy 45.364373 -35.601722) (xy 45.40159 -35.643259)
			(xy 45.432363 -35.689772) (xy 45.456035 -35.740269) (xy 45.472103 -35.793676) (xy 45.480223 -35.848852)
			(xy 45.480732 -35.876738) (xy 45.480223 -35.904624) (xy 45.472103 -35.9598) (xy 45.456035 -36.013207)
			(xy 45.432363 -36.063704) (xy 45.40159 -36.110217) (xy 45.364373 -36.151754) (xy 45.321505 -36.187429)
			(xy 45.273899 -36.216483) (xy 45.22257 -36.238295) (xy 45.168613 -36.252401) (xy 45.113176 -36.258501)
			(xy 45.057442 -36.256464) (xy 45.002599 -36.246334) (xy 44.949815 -36.228327) (xy 44.900215 -36.202826)
			(xy 44.854857 -36.170375) (xy 44.814708 -36.131666) (xy 44.780622 -36.087523) (xy 44.753326 -36.038888)
			(xy 44.733403 -35.986797) (xy 44.721277 -35.93236) (xy 44.717206 -35.876738) (xy 39.605164 -35.876738)
			(xy 39.656179 -35.924383) (xy 39.714763 -35.990047) (xy 39.767134 -36.060766) (xy 39.812857 -36.135954)
			(xy 39.851554 -36.214989) (xy 39.882903 -36.297215) (xy 39.906645 -36.381951) (xy 39.922583 -36.468495)
			(xy 39.926369 -36.50996) (xy 46.613824 -36.50996) (xy 46.617895 -36.454338) (xy 46.630021 -36.399901)
			(xy 46.649944 -36.34781) (xy 46.67724 -36.299175) (xy 46.711326 -36.255032) (xy 46.751475 -36.216323)
			(xy 46.796833 -36.183872) (xy 46.846433 -36.158371) (xy 46.899217 -36.140364) (xy 46.95406 -36.130234)
			(xy 47.009794 -36.128197) (xy 47.065231 -36.134297) (xy 47.119188 -36.148403) (xy 47.170517 -36.170215)
			(xy 47.218123 -36.199269) (xy 47.260991 -36.234944) (xy 47.298208 -36.276481) (xy 47.328981 -36.322994)
			(xy 47.352653 -36.373491) (xy 47.368721 -36.426898) (xy 47.376841 -36.482074) (xy 47.37735 -36.50996)
			(xy 47.376841 -36.537846) (xy 47.368721 -36.593022) (xy 47.352653 -36.646429) (xy 47.328981 -36.696926)
			(xy 47.298208 -36.743439) (xy 47.260991 -36.784976) (xy 47.218123 -36.820651) (xy 47.170517 -36.849705)
			(xy 47.119188 -36.871517) (xy 47.065231 -36.885623) (xy 47.009794 -36.891723) (xy 46.95406 -36.889686)
			(xy 46.899217 -36.879556) (xy 46.846433 -36.861549) (xy 46.796833 -36.836048) (xy 46.751475 -36.803597)
			(xy 46.711326 -36.764888) (xy 46.67724 -36.720745) (xy 46.649944 -36.67211) (xy 46.630021 -36.620019)
			(xy 46.617895 -36.565582) (xy 46.613824 -36.50996) (xy 39.926369 -36.50996) (xy 39.930585 -36.55613)
			(xy 39.931086 -36.60013) (xy 39.930585 -36.64413) (xy 39.922583 -36.731765) (xy 39.906645 -36.818309)
			(xy 39.882903 -36.903045) (xy 39.851554 -36.985271) (xy 39.812857 -37.064306) (xy 39.767134 -37.139494)
			(xy 39.714763 -37.210213) (xy 39.656179 -37.275877) (xy 39.591865 -37.335942) (xy 39.522357 -37.389909)
			(xy 39.448229 -37.437331) (xy 39.375223 -37.47516) (xy 43.759118 -37.47516) (xy 43.763189 -37.419538)
			(xy 43.775315 -37.365101) (xy 43.795238 -37.31301) (xy 43.822534 -37.264375) (xy 43.85662 -37.220232)
			(xy 43.896769 -37.181523) (xy 43.942127 -37.149072) (xy 43.991727 -37.123571) (xy 44.044511 -37.105564)
			(xy 44.099354 -37.095434) (xy 44.155088 -37.093397) (xy 44.210525 -37.099497) (xy 44.264482 -37.113603)
			(xy 44.315811 -37.135415) (xy 44.363417 -37.164469) (xy 44.406285 -37.200144) (xy 44.443502 -37.241681)
			(xy 44.474275 -37.288194) (xy 44.497947 -37.338691) (xy 44.514015 -37.392098) (xy 44.522135 -37.447274)
			(xy 44.522644 -37.47516) (xy 44.522135 -37.503046) (xy 44.514015 -37.558222) (xy 44.497947 -37.611629)
			(xy 44.474275 -37.662126) (xy 44.474122 -37.662358) (xy 45.948344 -37.662358) (xy 45.952415 -37.606736)
			(xy 45.964541 -37.552299) (xy 45.984464 -37.500208) (xy 46.01176 -37.451573) (xy 46.045846 -37.40743)
			(xy 46.085995 -37.368721) (xy 46.131353 -37.33627) (xy 46.180953 -37.310769) (xy 46.233737 -37.292762)
			(xy 46.28858 -37.282632) (xy 46.344314 -37.280595) (xy 46.399751 -37.286695) (xy 46.453708 -37.300801)
			(xy 46.505037 -37.322613) (xy 46.552643 -37.351667) (xy 46.595511 -37.387342) (xy 46.632728 -37.428879)
			(xy 46.663501 -37.475392) (xy 46.687173 -37.525889) (xy 46.703241 -37.579296) (xy 46.711361 -37.634472)
			(xy 46.71187 -37.662358) (xy 46.711361 -37.690244) (xy 46.703241 -37.74542) (xy 46.687173 -37.798827)
			(xy 46.663501 -37.849324) (xy 46.632728 -37.895837) (xy 46.595511 -37.937374) (xy 46.552643 -37.973049)
			(xy 46.505037 -38.002103) (xy 46.453708 -38.023915) (xy 46.399751 -38.038021) (xy 46.344314 -38.044121)
			(xy 46.28858 -38.042084) (xy 46.233737 -38.031954) (xy 46.180953 -38.013947) (xy 46.131353 -37.988446)
			(xy 46.085995 -37.955995) (xy 46.045846 -37.917286) (xy 46.01176 -37.873143) (xy 45.984464 -37.824508)
			(xy 45.964541 -37.772417) (xy 45.952415 -37.71798) (xy 45.948344 -37.662358) (xy 44.474122 -37.662358)
			(xy 44.443502 -37.708639) (xy 44.406285 -37.750176) (xy 44.363417 -37.785851) (xy 44.315811 -37.814905)
			(xy 44.264482 -37.836717) (xy 44.210525 -37.850823) (xy 44.155088 -37.856923) (xy 44.099354 -37.854886)
			(xy 44.044511 -37.844756) (xy 43.991727 -37.826749) (xy 43.942127 -37.801248) (xy 43.896769 -37.768797)
			(xy 43.85662 -37.730088) (xy 43.822534 -37.685945) (xy 43.795238 -37.63731) (xy 43.775315 -37.585219)
			(xy 43.763189 -37.530782) (xy 43.759118 -37.47516) (xy 39.375223 -37.47516) (xy 39.370095 -37.477817)
			(xy 39.288604 -37.51103) (xy 39.20443 -37.536694) (xy 39.118271 -37.554598) (xy 39.030841 -37.564593)
			(xy 38.942864 -37.566597) (xy 38.85507 -37.560591) (xy 38.768186 -37.546627) (xy 38.682931 -37.52482)
			(xy 38.600012 -37.495351) (xy 38.520117 -37.458464) (xy 38.443908 -37.414464) (xy 38.372015 -37.363716)
			(xy 38.305034 -37.306642) (xy 38.243522 -37.243712) (xy 38.187986 -37.17545) (xy 38.138888 -37.102421)
			(xy 38.096635 -37.025229) (xy 38.061576 -36.944515) (xy 38.034001 -36.860947) (xy 38.014141 -36.775218)
			(xy 38.002158 -36.688038) (xy 37.998153 -36.60013) (xy 33.768309 -36.60013) (xy 33.767194 -36.606992)
			(xy 33.747723 -36.665321) (xy 33.733994 -36.69284) (xy 33.730692 -36.699444) (xy 33.728152 -36.710112)
			(xy 33.728152 -38.317932) (xy 33.729168 -38.327584) (xy 33.730801 -38.334825) (xy 33.737652 -38.347985)
			(xy 33.74263 -38.353492) (xy 34.11909 -38.729952) (xy 49.700897 -38.729952) (xy 49.700897 -38.675448)
			(xy 49.708655 -38.6215) (xy 49.724011 -38.569204) (xy 49.746654 -38.519627) (xy 49.776123 -38.473777)
			(xy 49.811817 -38.432587) (xy 49.85301 -38.396898) (xy 49.898864 -38.367434) (xy 49.948444 -38.344796)
			(xy 50.000741 -38.329446) (xy 50.05469 -38.321694) (xy 50.081942 -38.321234) (xy 50.110245 -38.321753)
			(xy 50.166233 -38.330098) (xy 50.220372 -38.346627) (xy 50.271474 -38.370977) (xy 50.318414 -38.402613)
			(xy 50.360162 -38.440841) (xy 50.395801 -38.48482) (xy 50.410618 -38.50894) (xy 50.418226 -38.520968)
			(xy 50.438843 -38.540569) (xy 50.464072 -38.553712) (xy 50.491951 -38.559372) (xy 50.520309 -38.557109)
			(xy 50.546937 -38.5471) (xy 50.569764 -38.530123) (xy 50.578766 -38.5191) (xy 50.596977 -38.496244)
			(xy 50.639135 -38.455779) (xy 50.686965 -38.422209) (xy 50.739352 -38.396319) (xy 50.795072 -38.378712)
			(xy 50.852824 -38.3698) (xy 50.882042 -38.36924) (xy 50.909295 -38.369633) (xy 50.963245 -38.377395)
			(xy 51.015541 -38.392756) (xy 51.065119 -38.415402) (xy 51.11097 -38.444873) (xy 51.15216 -38.480569)
			(xy 51.187852 -38.521764) (xy 51.217318 -38.567618) (xy 51.239959 -38.617198) (xy 51.255314 -38.669496)
			(xy 51.26307 -38.723447) (xy 51.26307 -38.777953) (xy 51.255314 -38.831904) (xy 51.239959 -38.884202)
			(xy 51.217318 -38.933782) (xy 51.187852 -38.979636) (xy 51.15216 -39.020831) (xy 51.11097 -39.056527)
			(xy 51.065119 -39.085998) (xy 51.015541 -39.108644) (xy 50.963245 -39.124005) (xy 50.909295 -39.131767)
			(xy 50.882042 -39.132256) (xy 50.853738 -39.131754) (xy 50.797749 -39.123407) (xy 50.743609 -39.106876)
			(xy 50.692508 -39.082523) (xy 50.645568 -39.050883) (xy 50.60382 -39.012653) (xy 50.568183 -38.968671)
			(xy 50.553366 -38.94455) (xy 50.545779 -38.932508) (xy 50.525157 -38.912908) (xy 50.499923 -38.899767)
			(xy 50.472041 -38.894109) (xy 50.44368 -38.896374) (xy 50.417049 -38.906386) (xy 50.394221 -38.923366)
			(xy 50.385218 -38.93439) (xy 50.367014 -38.957251) (xy 50.324855 -38.997717) (xy 50.277023 -39.031286)
			(xy 50.224635 -39.057176) (xy 50.168913 -39.074781) (xy 50.11116 -39.083691) (xy 50.081942 -39.08425)
			(xy 50.05469 -39.083706) (xy 50.000741 -39.075954) (xy 49.948444 -39.060604) (xy 49.898864 -39.037966)
			(xy 49.85301 -39.008502) (xy 49.811817 -38.972813) (xy 49.776123 -38.931623) (xy 49.746654 -38.885773)
			(xy 49.724011 -38.836196) (xy 49.708655 -38.7839) (xy 49.700897 -38.729952) (xy 34.11909 -38.729952)
			(xy 36.657889 -41.268751) (xy 41.84395 -41.268751) (xy 41.84395 -41.214249) (xy 41.851706 -41.1603)
			(xy 41.86706 -41.108005) (xy 41.8897 -41.058427) (xy 41.919165 -41.012575) (xy 41.954854 -40.971383)
			(xy 41.996043 -40.935689) (xy 42.041892 -40.906219) (xy 42.091467 -40.883574) (xy 42.143761 -40.868214)
			(xy 42.197709 -40.860453) (xy 42.22496 -40.859964) (xy 42.2537 -40.860461) (xy 42.310528 -40.869091)
			(xy 42.365419 -40.886148) (xy 42.41713 -40.911246) (xy 42.464492 -40.943815) (xy 42.485818 -40.963088)
			(xy 42.492676 -40.969692) (xy 42.51071 -40.976804) (xy 42.59961 -40.976804) (xy 42.617644 -40.969692)
			(xy 42.624502 -40.963088) (xy 42.645853 -40.943845) (xy 42.693207 -40.911273) (xy 42.744913 -40.886174)
			(xy 42.799799 -40.869117) (xy 42.856622 -40.860488) (xy 42.88536 -40.859964) (xy 42.912613 -40.860481)
			(xy 42.966564 -40.868232) (xy 43.018863 -40.883584) (xy 43.068444 -40.906222) (xy 43.114299 -40.935687)
			(xy 43.155494 -40.971378) (xy 43.191189 -41.012569) (xy 43.220658 -41.05842) (xy 43.243302 -41.108)
			(xy 43.258659 -41.160297) (xy 43.266417 -41.214247) (xy 43.266417 -41.268753) (xy 43.258659 -41.322703)
			(xy 43.243302 -41.375) (xy 43.220658 -41.42458) (xy 43.191189 -41.470431) (xy 43.155494 -41.511622)
			(xy 43.114299 -41.547313) (xy 43.068444 -41.576778) (xy 43.018863 -41.599416) (xy 42.966564 -41.614768)
			(xy 42.912613 -41.622519) (xy 42.88536 -41.62298) (xy 42.856621 -41.622459) (xy 42.799795 -41.613833)
			(xy 42.744905 -41.596781) (xy 42.693193 -41.571689) (xy 42.64583 -41.539126) (xy 42.624502 -41.519856)
			(xy 42.617644 -41.513252) (xy 42.59961 -41.50614) (xy 42.51071 -41.50614) (xy 42.492676 -41.513252)
			(xy 42.485818 -41.519856) (xy 42.464506 -41.539145) (xy 42.41714 -41.571709) (xy 42.365425 -41.596798)
			(xy 42.310531 -41.613844) (xy 42.2537 -41.622462) (xy 42.22496 -41.62298) (xy 42.197709 -41.622547)
			(xy 42.143761 -41.614786) (xy 42.091467 -41.599426) (xy 42.041892 -41.576781) (xy 41.996043 -41.547311)
			(xy 41.954854 -41.511617) (xy 41.919165 -41.470425) (xy 41.8897 -41.424573) (xy 41.86706 -41.374995)
			(xy 41.851706 -41.3227) (xy 41.84395 -41.268751) (xy 36.657889 -41.268751) (xy 38.69436 -43.305222)
			(xy 44.307252 -43.305222) (xy 44.307718 -43.277852) (xy 44.315534 -43.223672) (xy 44.331022 -43.171168)
			(xy 44.353864 -43.121422) (xy 44.38359 -43.075455) (xy 44.401232 -43.054524) (xy 44.401486 -43.05427)
			(xy 44.407048 -43.047166) (xy 44.41331 -43.030263) (xy 44.413678 -43.02125) (xy 44.413678 -42.954194)
			(xy 44.413329 -42.945176) (xy 44.407076 -42.928259) (xy 44.401486 -42.921174) (xy 44.401232 -42.921174)
			(xy 44.401232 -42.92092) (xy 44.383594 -42.899987) (xy 44.353881 -42.854015) (xy 44.331044 -42.804268)
			(xy 44.315553 -42.751767) (xy 44.307725 -42.697591) (xy 44.307252 -42.670222) (xy 44.307802 -42.641484)
			(xy 44.31642 -42.584659) (xy 44.333465 -42.529769) (xy 44.35855 -42.478057) (xy 44.391109 -42.430692)
			(xy 44.410376 -42.409364) (xy 44.41698 -42.402506) (xy 44.424092 -42.384472) (xy 44.424092 -42.295572)
			(xy 44.41698 -42.277538) (xy 44.410376 -42.27068) (xy 44.391129 -42.249333) (xy 44.358567 -42.201973)
			(xy 44.333478 -42.150264) (xy 44.316428 -42.095377) (xy 44.307805 -42.038553) (xy 44.307802 -41.981079)
			(xy 44.316421 -41.924255) (xy 44.333466 -41.869366) (xy 44.358551 -41.817655) (xy 44.391109 -41.770292)
			(xy 44.410376 -41.748964) (xy 44.41698 -41.742106) (xy 44.424092 -41.724072) (xy 44.424092 -41.635172)
			(xy 44.41698 -41.617138) (xy 44.410376 -41.61028) (xy 44.391122 -41.588938) (xy 44.358552 -41.541581)
			(xy 44.333456 -41.489873) (xy 44.316401 -41.434985) (xy 44.307775 -41.37816) (xy 44.307252 -41.349422)
			(xy 44.307738 -41.322171) (xy 44.315494 -41.268223) (xy 44.330849 -41.215928) (xy 44.353491 -41.166351)
			(xy 44.382957 -41.120501) (xy 44.418648 -41.07931) (xy 44.459839 -41.043619) (xy 44.505689 -41.014153)
			(xy 44.555266 -40.991511) (xy 44.607561 -40.976156) (xy 44.661509 -40.9684) (xy 44.716011 -40.9684)
			(xy 44.739132 -40.971724) (xy 52.594 -40.971724) (xy 52.598071 -40.916102) (xy 52.610197 -40.861665)
			(xy 52.63012 -40.809574) (xy 52.657416 -40.760939) (xy 52.691502 -40.716796) (xy 52.731651 -40.678087)
			(xy 52.777009 -40.645636) (xy 52.826609 -40.620135) (xy 52.879393 -40.602128) (xy 52.934236 -40.591998)
			(xy 52.98997 -40.589961) (xy 53.045407 -40.596061) (xy 53.099364 -40.610167) (xy 53.150693 -40.631979)
			(xy 53.198299 -40.661033) (xy 53.241167 -40.696708) (xy 53.278384 -40.738245) (xy 53.309157 -40.784758)
			(xy 53.332829 -40.835255) (xy 53.348897 -40.888662) (xy 53.357017 -40.943838) (xy 53.357526 -40.971724)
			(xy 53.357017 -40.99961) (xy 53.348897 -41.054786) (xy 53.332829 -41.108193) (xy 53.309157 -41.15869)
			(xy 53.278384 -41.205203) (xy 53.241167 -41.24674) (xy 53.198299 -41.282415) (xy 53.150693 -41.311469)
			(xy 53.099364 -41.333281) (xy 53.045407 -41.347387) (xy 52.98997 -41.353487) (xy 52.934236 -41.35145)
			(xy 52.879393 -41.34132) (xy 52.826609 -41.323313) (xy 52.777009 -41.297812) (xy 52.731651 -41.265361)
			(xy 52.691502 -41.226652) (xy 52.657416 -41.182509) (xy 52.63012 -41.133874) (xy 52.610197 -41.081783)
			(xy 52.598071 -41.027346) (xy 52.594 -40.971724) (xy 44.739132 -40.971724) (xy 44.769959 -40.976156)
			(xy 44.822254 -40.991511) (xy 44.871831 -41.014153) (xy 44.917681 -41.043619) (xy 44.958872 -41.07931)
			(xy 44.994563 -41.120501) (xy 45.024029 -41.166351) (xy 45.046671 -41.215928) (xy 45.062026 -41.268223)
			(xy 45.069782 -41.322171) (xy 45.070268 -41.349422) (xy 45.069739 -41.37816) (xy 45.061115 -41.434987)
			(xy 45.044065 -41.489877) (xy 45.018975 -41.541589) (xy 44.986413 -41.588952) (xy 44.967144 -41.61028)
			(xy 44.96054 -41.617138) (xy 44.953428 -41.635172) (xy 44.953428 -41.724072) (xy 44.96054 -41.742106)
			(xy 44.967144 -41.748964) (xy 44.986438 -41.770271) (xy 45.019005 -41.817636) (xy 45.044098 -41.869351)
			(xy 45.061148 -41.924245) (xy 45.069769 -41.981076) (xy 45.069767 -42.038556) (xy 45.06114 -42.095386)
			(xy 45.044086 -42.150279) (xy 45.018989 -42.201992) (xy 44.986418 -42.249354) (xy 44.967144 -42.27068)
			(xy 44.96054 -42.277538) (xy 44.953428 -42.295572) (xy 44.953428 -42.384472) (xy 44.96054 -42.402506)
			(xy 44.967144 -42.409364) (xy 44.986422 -42.430685) (xy 45.018988 -42.478048) (xy 45.044079 -42.529761)
			(xy 45.061128 -42.584654) (xy 45.069749 -42.641482) (xy 45.070268 -42.670222) (xy 45.069823 -42.697593)
			(xy 45.062001 -42.751773) (xy 45.046508 -42.804277) (xy 45.025951 -42.849038) (xy 46.891954 -42.849038)
			(xy 46.896025 -42.793416) (xy 46.908151 -42.738979) (xy 46.928074 -42.686888) (xy 46.95537 -42.638253)
			(xy 46.989456 -42.59411) (xy 47.029605 -42.555401) (xy 47.074963 -42.52295) (xy 47.124563 -42.497449)
			(xy 47.177347 -42.479442) (xy 47.23219 -42.469312) (xy 47.287924 -42.467275) (xy 47.343361 -42.473375)
			(xy 47.397318 -42.487481) (xy 47.448647 -42.509293) (xy 47.496253 -42.538347) (xy 47.539121 -42.574022)
			(xy 47.576338 -42.615559) (xy 47.607111 -42.662072) (xy 47.630783 -42.712569) (xy 47.646851 -42.765976)
			(xy 47.654971 -42.821152) (xy 47.655332 -42.84091) (xy 52.93309 -42.84091) (xy 52.937161 -42.785288)
			(xy 52.949287 -42.730851) (xy 52.96921 -42.67876) (xy 52.996506 -42.630125) (xy 53.030592 -42.585982)
			(xy 53.070741 -42.547273) (xy 53.116099 -42.514822) (xy 53.165699 -42.489321) (xy 53.218483 -42.471314)
			(xy 53.273326 -42.461184) (xy 53.32906 -42.459147) (xy 53.384497 -42.465247) (xy 53.438454 -42.479353)
			(xy 53.489783 -42.501165) (xy 53.537389 -42.530219) (xy 53.580257 -42.565894) (xy 53.617474 -42.607431)
			(xy 53.648247 -42.653944) (xy 53.671919 -42.704441) (xy 53.687987 -42.757848) (xy 53.696107 -42.813024)
			(xy 53.696616 -42.84091) (xy 53.696107 -42.868796) (xy 53.687987 -42.923972) (xy 53.671919 -42.977379)
			(xy 53.648247 -43.027876) (xy 53.617474 -43.074389) (xy 53.580257 -43.115926) (xy 53.537389 -43.151601)
			(xy 53.489783 -43.180655) (xy 53.438454 -43.202467) (xy 53.384497 -43.216573) (xy 53.32906 -43.222673)
			(xy 53.273326 -43.220636) (xy 53.218483 -43.210506) (xy 53.165699 -43.192499) (xy 53.116099 -43.166998)
			(xy 53.070741 -43.134547) (xy 53.030592 -43.095838) (xy 52.996506 -43.051695) (xy 52.96921 -43.00306)
			(xy 52.949287 -42.950969) (xy 52.937161 -42.896532) (xy 52.93309 -42.84091) (xy 47.655332 -42.84091)
			(xy 47.65548 -42.849038) (xy 47.654971 -42.876924) (xy 47.646851 -42.9321) (xy 47.630783 -42.985507)
			(xy 47.607111 -43.036004) (xy 47.576338 -43.082517) (xy 47.539121 -43.124054) (xy 47.496253 -43.159729)
			(xy 47.448647 -43.188783) (xy 47.397318 -43.210595) (xy 47.343361 -43.224701) (xy 47.287924 -43.230801)
			(xy 47.23219 -43.228764) (xy 47.177347 -43.218634) (xy 47.124563 -43.200627) (xy 47.074963 -43.175126)
			(xy 47.029605 -43.142675) (xy 46.989456 -43.103966) (xy 46.95537 -43.059823) (xy 46.928074 -43.011188)
			(xy 46.908151 -42.959097) (xy 46.896025 -42.90466) (xy 46.891954 -42.849038) (xy 45.025951 -42.849038)
			(xy 45.023661 -42.854024) (xy 44.993932 -42.899989) (xy 44.976288 -42.92092) (xy 44.976034 -42.921174)
			(xy 44.970444 -42.928258) (xy 44.964201 -42.945177) (xy 44.963842 -42.954194) (xy 44.963842 -43.02125)
			(xy 44.964214 -43.030266) (xy 44.97045 -43.047183) (xy 44.976034 -43.05427) (xy 44.976288 -43.05427)
			(xy 44.976288 -43.054524) (xy 44.993903 -43.075475) (xy 45.023619 -43.121443) (xy 45.04646 -43.171185)
			(xy 45.061956 -43.223682) (xy 45.069791 -43.277854) (xy 45.070268 -43.305222) (xy 45.069782 -43.332473)
			(xy 45.062026 -43.386421) (xy 45.046671 -43.438716) (xy 45.024029 -43.488293) (xy 44.994563 -43.534143)
			(xy 44.958872 -43.575334) (xy 44.917681 -43.611025) (xy 44.871831 -43.640491) (xy 44.822254 -43.663133)
			(xy 44.769959 -43.678488) (xy 44.716011 -43.686244) (xy 44.661509 -43.686244) (xy 44.607561 -43.678488)
			(xy 44.555266 -43.663133) (xy 44.505689 -43.640491) (xy 44.459839 -43.611025) (xy 44.418648 -43.575334)
			(xy 44.382957 -43.534143) (xy 44.353491 -43.488293) (xy 44.330849 -43.438716) (xy 44.315494 -43.386421)
			(xy 44.307738 -43.332473) (xy 44.307252 -43.305222) (xy 38.69436 -43.305222) (xy 39.048436 -43.659298)
			(xy 39.066469 -43.678068) (xy 39.097051 -43.720184) (xy 39.105242 -43.73626) (xy 46.213012 -43.73626)
			(xy 46.217083 -43.680638) (xy 46.229209 -43.626201) (xy 46.249132 -43.57411) (xy 46.276428 -43.525475)
			(xy 46.310514 -43.481332) (xy 46.350663 -43.442623) (xy 46.396021 -43.410172) (xy 46.445621 -43.384671)
			(xy 46.498405 -43.366664) (xy 46.553248 -43.356534) (xy 46.608982 -43.354497) (xy 46.664419 -43.360597)
			(xy 46.718376 -43.374703) (xy 46.769705 -43.396515) (xy 46.817311 -43.425569) (xy 46.860179 -43.461244)
			(xy 46.897396 -43.502781) (xy 46.928169 -43.549294) (xy 46.951841 -43.599791) (xy 46.967909 -43.653198)
			(xy 46.976029 -43.708374) (xy 46.976538 -43.73626) (xy 46.976029 -43.764146) (xy 46.967909 -43.819322)
			(xy 46.9566 -43.85691) (xy 50.719734 -43.85691) (xy 50.723805 -43.801288) (xy 50.735931 -43.746851)
			(xy 50.755854 -43.69476) (xy 50.78315 -43.646125) (xy 50.817236 -43.601982) (xy 50.857385 -43.563273)
			(xy 50.902743 -43.530822) (xy 50.952343 -43.505321) (xy 51.005127 -43.487314) (xy 51.05997 -43.477184)
			(xy 51.115704 -43.475147) (xy 51.171141 -43.481247) (xy 51.225098 -43.495353) (xy 51.276427 -43.517165)
			(xy 51.324033 -43.546219) (xy 51.366901 -43.581894) (xy 51.404118 -43.623431) (xy 51.434891 -43.669944)
			(xy 51.458563 -43.720441) (xy 51.474631 -43.773848) (xy 51.482751 -43.829024) (xy 51.48326 -43.85691)
			(xy 51.482751 -43.884796) (xy 51.474631 -43.939972) (xy 51.458563 -43.993379) (xy 51.434891 -44.043876)
			(xy 51.404118 -44.090389) (xy 51.366901 -44.131926) (xy 51.324033 -44.167601) (xy 51.276427 -44.196655)
			(xy 51.225098 -44.218467) (xy 51.171141 -44.232573) (xy 51.115704 -44.238673) (xy 51.05997 -44.236636)
			(xy 51.005127 -44.226506) (xy 50.952343 -44.208499) (xy 50.902743 -44.182998) (xy 50.857385 -44.150547)
			(xy 50.817236 -44.111838) (xy 50.78315 -44.067695) (xy 50.755854 -44.01906) (xy 50.735931 -43.966969)
			(xy 50.723805 -43.912532) (xy 50.719734 -43.85691) (xy 46.9566 -43.85691) (xy 46.951841 -43.872729)
			(xy 46.928169 -43.923226) (xy 46.897396 -43.969739) (xy 46.860179 -44.011276) (xy 46.817311 -44.046951)
			(xy 46.769705 -44.076005) (xy 46.718376 -44.097817) (xy 46.664419 -44.111923) (xy 46.608982 -44.118023)
			(xy 46.553248 -44.115986) (xy 46.498405 -44.105856) (xy 46.445621 -44.087849) (xy 46.396021 -44.062348)
			(xy 46.350663 -44.029897) (xy 46.310514 -43.991188) (xy 46.276428 -43.947045) (xy 46.249132 -43.89841)
			(xy 46.229209 -43.846319) (xy 46.217083 -43.791882) (xy 46.213012 -43.73626) (xy 39.105242 -43.73626)
			(xy 39.120679 -43.76656) (xy 39.136772 -43.816058) (xy 39.144935 -43.867462) (xy 39.145464 -43.893486)
			(xy 39.145464 -45.114464) (xy 46.065438 -45.114464) (xy 46.069509 -45.058842) (xy 46.081635 -45.004405)
			(xy 46.101558 -44.952314) (xy 46.128854 -44.903679) (xy 46.16294 -44.859536) (xy 46.203089 -44.820827)
			(xy 46.248447 -44.788376) (xy 46.298047 -44.762875) (xy 46.350831 -44.744868) (xy 46.405674 -44.734738)
			(xy 46.461408 -44.732701) (xy 46.516845 -44.738801) (xy 46.570802 -44.752907) (xy 46.622131 -44.774719)
			(xy 46.669737 -44.803773) (xy 46.712605 -44.839448) (xy 46.742587 -44.87291) (xy 52.93309 -44.87291)
			(xy 52.937161 -44.817288) (xy 52.949287 -44.762851) (xy 52.96921 -44.71076) (xy 52.996506 -44.662125)
			(xy 53.030592 -44.617982) (xy 53.070741 -44.579273) (xy 53.116099 -44.546822) (xy 53.165699 -44.521321)
			(xy 53.218483 -44.503314) (xy 53.273326 -44.493184) (xy 53.32906 -44.491147) (xy 53.384497 -44.497247)
			(xy 53.438454 -44.511353) (xy 53.489783 -44.533165) (xy 53.537389 -44.562219) (xy 53.580257 -44.597894)
			(xy 53.617474 -44.639431) (xy 53.648247 -44.685944) (xy 53.671919 -44.736441) (xy 53.687987 -44.789848)
			(xy 53.696107 -44.845024) (xy 53.696616 -44.87291) (xy 53.696107 -44.900796) (xy 53.687987 -44.955972)
			(xy 53.671919 -45.009379) (xy 53.648247 -45.059876) (xy 53.617474 -45.106389) (xy 53.580257 -45.147926)
			(xy 53.537389 -45.183601) (xy 53.489783 -45.212655) (xy 53.438454 -45.234467) (xy 53.384497 -45.248573)
			(xy 53.32906 -45.254673) (xy 53.273326 -45.252636) (xy 53.218483 -45.242506) (xy 53.165699 -45.224499)
			(xy 53.116099 -45.198998) (xy 53.070741 -45.166547) (xy 53.030592 -45.127838) (xy 52.996506 -45.083695)
			(xy 52.96921 -45.03506) (xy 52.949287 -44.982969) (xy 52.937161 -44.928532) (xy 52.93309 -44.87291)
			(xy 46.742587 -44.87291) (xy 46.749822 -44.880985) (xy 46.780595 -44.927498) (xy 46.804267 -44.977995)
			(xy 46.820335 -45.031402) (xy 46.828455 -45.086578) (xy 46.828964 -45.114464) (xy 46.828455 -45.14235)
			(xy 46.820335 -45.197526) (xy 46.804267 -45.250933) (xy 46.780595 -45.30143) (xy 46.749822 -45.347943)
			(xy 46.74418 -45.35424) (xy 50.703732 -45.35424) (xy 50.707803 -45.298618) (xy 50.719929 -45.244181)
			(xy 50.739852 -45.19209) (xy 50.767148 -45.143455) (xy 50.801234 -45.099312) (xy 50.841383 -45.060603)
			(xy 50.886741 -45.028152) (xy 50.936341 -45.002651) (xy 50.989125 -44.984644) (xy 51.043968 -44.974514)
			(xy 51.099702 -44.972477) (xy 51.155139 -44.978577) (xy 51.209096 -44.992683) (xy 51.260425 -45.014495)
			(xy 51.308031 -45.043549) (xy 51.350899 -45.079224) (xy 51.388116 -45.120761) (xy 51.418889 -45.167274)
			(xy 51.442561 -45.217771) (xy 51.458629 -45.271178) (xy 51.466749 -45.326354) (xy 51.467258 -45.35424)
			(xy 51.466749 -45.382126) (xy 51.458629 -45.437302) (xy 51.442561 -45.490709) (xy 51.418889 -45.541206)
			(xy 51.388116 -45.587719) (xy 51.350899 -45.629256) (xy 51.308031 -45.664931) (xy 51.260425 -45.693985)
			(xy 51.209096 -45.715797) (xy 51.155139 -45.729903) (xy 51.099702 -45.736003) (xy 51.043968 -45.733966)
			(xy 50.989125 -45.723836) (xy 50.936341 -45.705829) (xy 50.886741 -45.680328) (xy 50.841383 -45.647877)
			(xy 50.801234 -45.609168) (xy 50.767148 -45.565025) (xy 50.739852 -45.51639) (xy 50.719929 -45.464299)
			(xy 50.707803 -45.409862) (xy 50.703732 -45.35424) (xy 46.74418 -45.35424) (xy 46.712605 -45.38948)
			(xy 46.669737 -45.425155) (xy 46.622131 -45.454209) (xy 46.570802 -45.476021) (xy 46.516845 -45.490127)
			(xy 46.461408 -45.496227) (xy 46.405674 -45.49419) (xy 46.350831 -45.48406) (xy 46.298047 -45.466053)
			(xy 46.248447 -45.440552) (xy 46.203089 -45.408101) (xy 46.16294 -45.369392) (xy 46.128854 -45.325249)
			(xy 46.101558 -45.276614) (xy 46.081635 -45.224523) (xy 46.069509 -45.170086) (xy 46.065438 -45.114464)
			(xy 39.145464 -45.114464) (xy 39.145464 -46.082204) (xy 44.05249 -46.082204) (xy 44.052959 -46.054951)
			(xy 44.060715 -46.001001) (xy 44.076071 -45.948703) (xy 44.098713 -45.899123) (xy 44.12818 -45.85327)
			(xy 44.163873 -45.812077) (xy 44.205065 -45.776384) (xy 44.250918 -45.746916) (xy 44.300497 -45.724273)
			(xy 44.352795 -45.708917) (xy 44.406745 -45.701159) (xy 44.433998 -45.700696) (xy 44.460901 -45.70116)
			(xy 44.51417 -45.708731) (xy 44.565849 -45.72371) (xy 44.61491 -45.7458) (xy 44.660383 -45.774562)
			(xy 44.701364 -45.809427) (xy 44.737042 -45.849702) (xy 44.75226 -45.871892) (xy 44.759372 -45.882814)
			(xy 44.782232 -45.894752) (xy 44.8945 -45.89272) (xy 44.916852 -45.879766) (xy 44.92371 -45.86859)
			(xy 44.938638 -45.844993) (xy 44.974316 -45.802041) (xy 45.015873 -45.764748) (xy 45.062422 -45.73391)
			(xy 45.112969 -45.710186) (xy 45.166433 -45.694082) (xy 45.221674 -45.685943) (xy 45.249592 -45.685456)
			(xy 45.276585 -45.685922) (xy 45.330033 -45.693527) (xy 45.381876 -45.708586) (xy 45.431081 -45.730799)
			(xy 45.476665 -45.759722) (xy 45.497496 -45.776896) (xy 45.505624 -45.784008) (xy 45.526198 -45.790104)
			(xy 45.611542 -45.779182) (xy 45.622082 -45.777389) (xy 45.640367 -45.766348) (xy 45.646848 -45.757846)
			(xy 45.662178 -45.736598) (xy 45.697769 -45.698145) (xy 45.73829 -45.664928) (xy 45.782977 -45.637572)
			(xy 45.830989 -45.616591) (xy 45.881421 -45.602382) (xy 45.933324 -45.595211) (xy 45.959522 -45.594778)
			(xy 45.986771 -45.595294) (xy 46.040714 -45.603053) (xy 46.093005 -45.618409) (xy 46.142577 -45.64105)
			(xy 46.188423 -45.670516) (xy 46.229609 -45.706206) (xy 46.265297 -45.747395) (xy 46.29476 -45.793242)
			(xy 46.317399 -45.842816) (xy 46.332752 -45.895107) (xy 46.340508 -45.949051) (xy 46.340508 -46.003549)
			(xy 46.332752 -46.057493) (xy 46.317399 -46.109784) (xy 46.29476 -46.159358) (xy 46.265297 -46.205205)
			(xy 46.229609 -46.246394) (xy 46.188423 -46.282084) (xy 46.142577 -46.31155) (xy 46.093005 -46.334191)
			(xy 46.040714 -46.349547) (xy 45.986771 -46.357306) (xy 45.959522 -46.357794) (xy 45.93253 -46.357308)
			(xy 45.879083 -46.349706) (xy 45.82724 -46.334651) (xy 45.778035 -46.312443) (xy 45.73245 -46.283525)
			(xy 45.711618 -46.266354) (xy 45.70349 -46.259242) (xy 45.682916 -46.253146) (xy 45.597572 -46.264068)
			(xy 45.587026 -46.265836) (xy 45.568745 -46.276896) (xy 45.562266 -46.285404) (xy 45.544654 -46.309705)
			(xy 45.503058 -46.352964) (xy 45.479462 -46.37151) (xy 45.471588 -46.377352) (xy 45.461174 -46.394878)
			(xy 45.447966 -46.485302) (xy 45.452792 -46.504606) (xy 45.458634 -46.51248) (xy 45.458634 -46.512734)
			(xy 45.476132 -46.537482) (xy 45.503937 -46.591333) (xy 45.522875 -46.648904) (xy 45.530078 -46.693836)
			(xy 50.676302 -46.693836) (xy 50.676788 -46.666585) (xy 50.684544 -46.612637) (xy 50.699899 -46.560342)
			(xy 50.722541 -46.510765) (xy 50.752007 -46.464915) (xy 50.787698 -46.423724) (xy 50.828889 -46.388033)
			(xy 50.874739 -46.358567) (xy 50.924316 -46.335925) (xy 50.976611 -46.32057) (xy 51.030559 -46.312814)
			(xy 51.085061 -46.312814) (xy 51.139009 -46.32057) (xy 51.191304 -46.335925) (xy 51.240881 -46.358567)
			(xy 51.286731 -46.388033) (xy 51.327922 -46.423724) (xy 51.363613 -46.464915) (xy 51.393079 -46.510765)
			(xy 51.415721 -46.560342) (xy 51.431076 -46.612637) (xy 51.438832 -46.666585) (xy 51.439318 -46.693836)
			(xy 51.438843 -46.720263) (xy 51.431534 -46.772611) (xy 51.417061 -46.823446) (xy 51.395702 -46.871793)
			(xy 51.382168 -46.894496) (xy 51.381914 -46.89475) (xy 51.376577 -46.904768) (xy 51.374321 -46.927318)
			(xy 51.377596 -46.938184) (xy 51.403758 -47.01286) (xy 51.408139 -47.023377) (xy 51.42423 -47.039465)
			(xy 51.434746 -47.043848) (xy 51.435 -47.043848) (xy 51.459499 -47.052944) (xy 51.505952 -47.076881)
			(xy 51.548706 -47.106932) (xy 51.586959 -47.142535) (xy 51.619998 -47.183025) (xy 51.647203 -47.227643)
			(xy 51.668066 -47.275556) (xy 51.682197 -47.325868) (xy 51.689331 -47.377637) (xy 51.689762 -47.403766)
			(xy 51.689276 -47.431017) (xy 51.687753 -47.441612) (xy 52.961792 -47.441612) (xy 52.965863 -47.38599)
			(xy 52.977989 -47.331553) (xy 52.997912 -47.279462) (xy 53.025208 -47.230827) (xy 53.059294 -47.186684)
			(xy 53.099443 -47.147975) (xy 53.144801 -47.115524) (xy 53.194401 -47.090023) (xy 53.247185 -47.072016)
			(xy 53.302028 -47.061886) (xy 53.357762 -47.059849) (xy 53.413199 -47.065949) (xy 53.467156 -47.080055)
			(xy 53.518485 -47.101867) (xy 53.566091 -47.130921) (xy 53.608959 -47.166596) (xy 53.646176 -47.208133)
			(xy 53.676949 -47.254646) (xy 53.700621 -47.305143) (xy 53.716689 -47.35855) (xy 53.724809 -47.413726)
			(xy 53.725318 -47.441612) (xy 53.724809 -47.469498) (xy 53.716689 -47.524674) (xy 53.700621 -47.578081)
			(xy 53.676949 -47.628578) (xy 53.646176 -47.675091) (xy 53.608959 -47.716628) (xy 53.566091 -47.752303)
			(xy 53.518485 -47.781357) (xy 53.467156 -47.803169) (xy 53.413199 -47.817275) (xy 53.357762 -47.823375)
			(xy 53.302028 -47.821338) (xy 53.247185 -47.811208) (xy 53.194401 -47.793201) (xy 53.144801 -47.7677)
			(xy 53.099443 -47.735249) (xy 53.059294 -47.69654) (xy 53.025208 -47.652397) (xy 52.997912 -47.603762)
			(xy 52.977989 -47.551671) (xy 52.965863 -47.497234) (xy 52.961792 -47.441612) (xy 51.687753 -47.441612)
			(xy 51.68152 -47.484965) (xy 51.666165 -47.53726) (xy 51.643523 -47.586837) (xy 51.614057 -47.632687)
			(xy 51.578366 -47.673878) (xy 51.537175 -47.709569) (xy 51.491325 -47.739035) (xy 51.441748 -47.761677)
			(xy 51.389453 -47.777032) (xy 51.335505 -47.784788) (xy 51.281003 -47.784788) (xy 51.227055 -47.777032)
			(xy 51.17476 -47.761677) (xy 51.125183 -47.739035) (xy 51.079333 -47.709569) (xy 51.038142 -47.673878)
			(xy 51.002451 -47.632687) (xy 50.972985 -47.586837) (xy 50.950343 -47.53726) (xy 50.934988 -47.484965)
			(xy 50.927232 -47.431017) (xy 50.926746 -47.403766) (xy 50.927213 -47.377338) (xy 50.934523 -47.32499)
			(xy 50.948998 -47.274155) (xy 50.97036 -47.225809) (xy 50.983896 -47.203106) (xy 50.98415 -47.202852)
			(xy 50.989485 -47.192834) (xy 50.991744 -47.170284) (xy 50.988468 -47.159418) (xy 50.962306 -47.084742)
			(xy 50.95794 -47.074217) (xy 50.941839 -47.058132) (xy 50.931318 -47.053754) (xy 50.931064 -47.053754)
			(xy 50.906558 -47.044677) (xy 50.860105 -47.020736) (xy 50.817353 -46.990681) (xy 50.779101 -46.955075)
			(xy 50.746064 -46.914583) (xy 50.71886 -46.869963) (xy 50.697998 -46.822048) (xy 50.683867 -46.771736)
			(xy 50.676733 -46.719966) (xy 50.676302 -46.693836) (xy 45.530078 -46.693836) (xy 45.532468 -46.708745)
			(xy 45.533056 -46.739048) (xy 45.532567 -46.766298) (xy 45.524805 -46.820243) (xy 45.509446 -46.872535)
			(xy 45.486803 -46.922109) (xy 45.457336 -46.967957) (xy 45.421646 -47.009146) (xy 45.380457 -47.044836)
			(xy 45.334609 -47.074303) (xy 45.285035 -47.096946) (xy 45.232743 -47.112305) (xy 45.178798 -47.120067)
			(xy 45.151548 -47.120556) (xy 45.125514 -47.120131) (xy 45.07393 -47.113038) (xy 45.023788 -47.099003)
			(xy 44.976018 -47.078287) (xy 44.931504 -47.051274) (xy 44.91101 -47.035212) (xy 44.903257 -47.029464)
			(xy 44.884843 -47.023727) (xy 44.875196 -47.024036) (xy 44.79544 -47.030386) (xy 44.77766 -47.039022)
			(xy 44.77131 -47.046388) (xy 44.753147 -47.066051) (xy 44.712235 -47.100572) (xy 44.666903 -47.129039)
			(xy 44.618038 -47.150893) (xy 44.566599 -47.165707) (xy 44.513595 -47.173189) (xy 44.48683 -47.173642)
			(xy 44.459581 -47.173094) (xy 44.405637 -47.165342) (xy 44.353346 -47.149993) (xy 44.303771 -47.127358)
			(xy 44.257922 -47.097898) (xy 44.216733 -47.062213) (xy 44.181041 -47.021029) (xy 44.151573 -46.975185)
			(xy 44.12893 -46.925614) (xy 44.113571 -46.873325) (xy 44.105811 -46.819383) (xy 44.105322 -46.792134)
			(xy 44.105841 -46.76336) (xy 44.114492 -46.706465) (xy 44.13159 -46.651514) (xy 44.156745 -46.599754)
			(xy 44.189387 -46.552358) (xy 44.2087 -46.531022) (xy 44.216066 -46.523148) (xy 44.223178 -46.503336)
			(xy 44.215812 -46.40707) (xy 44.205906 -46.388274) (xy 44.197524 -46.38167) (xy 44.17534 -46.363444)
			(xy 44.13613 -46.321509) (xy 44.103644 -46.274174) (xy 44.078615 -46.222506) (xy 44.061609 -46.167672)
			(xy 44.053008 -46.110909) (xy 44.05249 -46.082204) (xy 39.145464 -46.082204) (xy 39.145464 -48.30699)
			(xy 50.553872 -48.30699) (xy 50.557943 -48.251368) (xy 50.570069 -48.196931) (xy 50.589992 -48.14484)
			(xy 50.617288 -48.096205) (xy 50.651374 -48.052062) (xy 50.691523 -48.013353) (xy 50.736881 -47.980902)
			(xy 50.786481 -47.955401) (xy 50.839265 -47.937394) (xy 50.894108 -47.927264) (xy 50.949842 -47.925227)
			(xy 51.005279 -47.931327) (xy 51.059236 -47.945433) (xy 51.110565 -47.967245) (xy 51.158171 -47.996299)
			(xy 51.201039 -48.031974) (xy 51.238256 -48.073511) (xy 51.269029 -48.120024) (xy 51.292701 -48.170521)
			(xy 51.308769 -48.223928) (xy 51.316889 -48.279104) (xy 51.317398 -48.30699) (xy 51.316889 -48.334876)
			(xy 51.308769 -48.390052) (xy 51.292701 -48.443459) (xy 51.269029 -48.493956) (xy 51.238256 -48.540469)
			(xy 51.201039 -48.582006) (xy 51.158171 -48.617681) (xy 51.110565 -48.646735) (xy 51.059236 -48.668547)
			(xy 51.005279 -48.682653) (xy 50.949842 -48.688753) (xy 50.894108 -48.686716) (xy 50.839265 -48.676586)
			(xy 50.786481 -48.658579) (xy 50.736881 -48.633078) (xy 50.691523 -48.600627) (xy 50.651374 -48.561918)
			(xy 50.617288 -48.517775) (xy 50.589992 -48.46914) (xy 50.570069 -48.417049) (xy 50.557943 -48.362612)
			(xy 50.553872 -48.30699) (xy 39.145464 -48.30699) (xy 39.145464 -48.753014) (xy 47.168306 -48.753014)
			(xy 47.172377 -48.697392) (xy 47.184503 -48.642955) (xy 47.204426 -48.590864) (xy 47.231722 -48.542229)
			(xy 47.265808 -48.498086) (xy 47.305957 -48.459377) (xy 47.351315 -48.426926) (xy 47.400915 -48.401425)
			(xy 47.453699 -48.383418) (xy 47.508542 -48.373288) (xy 47.564276 -48.371251) (xy 47.619713 -48.377351)
			(xy 47.67367 -48.391457) (xy 47.724999 -48.413269) (xy 47.772605 -48.442323) (xy 47.815473 -48.477998)
			(xy 47.85269 -48.519535) (xy 47.883463 -48.566048) (xy 47.907135 -48.616545) (xy 47.923203 -48.669952)
			(xy 47.931323 -48.725128) (xy 47.931832 -48.753014) (xy 47.931323 -48.7809) (xy 47.923203 -48.836076)
			(xy 47.907135 -48.889483) (xy 47.905739 -48.89246) (xy 49.214022 -48.89246) (xy 49.218093 -48.836838)
			(xy 49.230219 -48.782401) (xy 49.250142 -48.73031) (xy 49.277438 -48.681675) (xy 49.311524 -48.637532)
			(xy 49.351673 -48.598823) (xy 49.397031 -48.566372) (xy 49.446631 -48.540871) (xy 49.499415 -48.522864)
			(xy 49.554258 -48.512734) (xy 49.609992 -48.510697) (xy 49.665429 -48.516797) (xy 49.719386 -48.530903)
			(xy 49.770715 -48.552715) (xy 49.818321 -48.581769) (xy 49.861189 -48.617444) (xy 49.898406 -48.658981)
			(xy 49.929179 -48.705494) (xy 49.952851 -48.755991) (xy 49.968919 -48.809398) (xy 49.977039 -48.864574)
			(xy 49.977548 -48.89246) (xy 49.977039 -48.920346) (xy 49.974601 -48.93691) (xy 52.93309 -48.93691)
			(xy 52.937161 -48.881288) (xy 52.949287 -48.826851) (xy 52.96921 -48.77476) (xy 52.996506 -48.726125)
			(xy 53.030592 -48.681982) (xy 53.070741 -48.643273) (xy 53.116099 -48.610822) (xy 53.165699 -48.585321)
			(xy 53.218483 -48.567314) (xy 53.273326 -48.557184) (xy 53.32906 -48.555147) (xy 53.384497 -48.561247)
			(xy 53.438454 -48.575353) (xy 53.489783 -48.597165) (xy 53.537389 -48.626219) (xy 53.580257 -48.661894)
			(xy 53.617474 -48.703431) (xy 53.648247 -48.749944) (xy 53.671919 -48.800441) (xy 53.687987 -48.853848)
			(xy 53.696107 -48.909024) (xy 53.696616 -48.93691) (xy 53.696107 -48.964796) (xy 53.687987 -49.019972)
			(xy 53.671919 -49.073379) (xy 53.648247 -49.123876) (xy 53.617474 -49.170389) (xy 53.580257 -49.211926)
			(xy 53.537389 -49.247601) (xy 53.489783 -49.276655) (xy 53.438454 -49.298467) (xy 53.384497 -49.312573)
			(xy 53.32906 -49.318673) (xy 53.273326 -49.316636) (xy 53.218483 -49.306506) (xy 53.165699 -49.288499)
			(xy 53.116099 -49.262998) (xy 53.070741 -49.230547) (xy 53.030592 -49.191838) (xy 52.996506 -49.147695)
			(xy 52.96921 -49.09906) (xy 52.949287 -49.046969) (xy 52.937161 -48.992532) (xy 52.93309 -48.93691)
			(xy 49.974601 -48.93691) (xy 49.968919 -48.975522) (xy 49.952851 -49.028929) (xy 49.929179 -49.079426)
			(xy 49.898406 -49.125939) (xy 49.861189 -49.167476) (xy 49.818321 -49.203151) (xy 49.770715 -49.232205)
			(xy 49.719386 -49.254017) (xy 49.665429 -49.268123) (xy 49.609992 -49.274223) (xy 49.554258 -49.272186)
			(xy 49.499415 -49.262056) (xy 49.446631 -49.244049) (xy 49.397031 -49.218548) (xy 49.351673 -49.186097)
			(xy 49.311524 -49.147388) (xy 49.277438 -49.103245) (xy 49.250142 -49.05461) (xy 49.230219 -49.002519)
			(xy 49.218093 -48.948082) (xy 49.214022 -48.89246) (xy 47.905739 -48.89246) (xy 47.883463 -48.93998)
			(xy 47.85269 -48.986493) (xy 47.815473 -49.02803) (xy 47.772605 -49.063705) (xy 47.724999 -49.092759)
			(xy 47.67367 -49.114571) (xy 47.619713 -49.128677) (xy 47.564276 -49.134777) (xy 47.508542 -49.13274)
			(xy 47.453699 -49.12261) (xy 47.400915 -49.104603) (xy 47.351315 -49.079102) (xy 47.305957 -49.046651)
			(xy 47.265808 -49.007942) (xy 47.231722 -48.963799) (xy 47.204426 -48.915164) (xy 47.184503 -48.863073)
			(xy 47.172377 -48.808636) (xy 47.168306 -48.753014) (xy 39.145464 -48.753014) (xy 39.145464 -49.95291)
			(xy 52.93309 -49.95291) (xy 52.937161 -49.897288) (xy 52.949287 -49.842851) (xy 52.96921 -49.79076)
			(xy 52.996506 -49.742125) (xy 53.030592 -49.697982) (xy 53.070741 -49.659273) (xy 53.116099 -49.626822)
			(xy 53.165699 -49.601321) (xy 53.218483 -49.583314) (xy 53.273326 -49.573184) (xy 53.32906 -49.571147)
			(xy 53.384497 -49.577247) (xy 53.438454 -49.591353) (xy 53.463398 -49.601953) (xy 58.112859 -49.601953)
			(xy 58.112859 -49.547447) (xy 58.120617 -49.493495) (xy 58.135973 -49.441197) (xy 58.158616 -49.391616)
			(xy 58.188085 -49.345763) (xy 58.22378 -49.30457) (xy 58.264974 -49.268877) (xy 58.310829 -49.23941)
			(xy 58.36041 -49.216768) (xy 58.412709 -49.201414) (xy 58.466661 -49.193658) (xy 58.493914 -49.193196)
			(xy 58.521284 -49.193655) (xy 58.575464 -49.201475) (xy 58.627967 -49.216965) (xy 58.677714 -49.239809)
			(xy 58.72368 -49.269534) (xy 58.744612 -49.287176) (xy 58.744866 -49.28743) (xy 58.751956 -49.293012)
			(xy 58.76887 -49.29926) (xy 58.777886 -49.299622) (xy 58.844942 -49.299622) (xy 58.853956 -49.299233)
			(xy 58.870873 -49.293007) (xy 58.877962 -49.28743) (xy 58.877962 -49.287176) (xy 58.878216 -49.287176)
			(xy 58.899149 -49.269535) (xy 58.945117 -49.239811) (xy 58.994863 -49.216965) (xy 59.047365 -49.201469)
			(xy 59.101543 -49.19364) (xy 59.156285 -49.19364) (xy 59.210463 -49.201469) (xy 59.262965 -49.216965)
			(xy 59.312711 -49.239811) (xy 59.358679 -49.269535) (xy 59.379612 -49.287176) (xy 59.379866 -49.28743)
			(xy 59.386956 -49.293012) (xy 59.40387 -49.29926) (xy 59.412886 -49.299622) (xy 59.479942 -49.299622)
			(xy 59.488956 -49.299233) (xy 59.505873 -49.293007) (xy 59.512962 -49.28743) (xy 59.512962 -49.287176)
			(xy 59.513216 -49.287176) (xy 59.534149 -49.269535) (xy 59.580117 -49.239811) (xy 59.629863 -49.216965)
			(xy 59.682365 -49.201469) (xy 59.736543 -49.19364) (xy 59.791285 -49.19364) (xy 59.845463 -49.201469)
			(xy 59.897965 -49.216965) (xy 59.947711 -49.239811) (xy 59.993679 -49.269535) (xy 60.014612 -49.287176)
			(xy 60.014866 -49.28743) (xy 60.021956 -49.293012) (xy 60.03887 -49.29926) (xy 60.047886 -49.299622)
			(xy 60.114942 -49.299622) (xy 60.123956 -49.299233) (xy 60.140873 -49.293007) (xy 60.147962 -49.28743)
			(xy 60.147962 -49.287176) (xy 60.148216 -49.287176) (xy 60.169166 -49.269559) (xy 60.215134 -49.239845)
			(xy 60.264877 -49.217005) (xy 60.317374 -49.201509) (xy 60.371546 -49.193674) (xy 60.398914 -49.193196)
			(xy 60.426165 -49.193675) (xy 60.480112 -49.201433) (xy 60.532405 -49.216789) (xy 60.581981 -49.239432)
			(xy 60.62783 -49.268899) (xy 60.669019 -49.304591) (xy 60.70471 -49.345781) (xy 60.734175 -49.391631)
			(xy 60.756815 -49.441208) (xy 60.77217 -49.493502) (xy 60.779926 -49.547449) (xy 60.779926 -49.601951)
			(xy 60.77217 -49.655898) (xy 60.756815 -49.708192) (xy 60.734175 -49.757769) (xy 60.70471 -49.803619)
			(xy 60.669019 -49.844809) (xy 60.62783 -49.880501) (xy 60.581981 -49.909968) (xy 60.532405 -49.932611)
			(xy 60.480112 -49.947967) (xy 60.426165 -49.955725) (xy 60.398914 -49.956212) (xy 60.371544 -49.955735)
			(xy 60.317366 -49.947919) (xy 60.264863 -49.932433) (xy 60.215116 -49.909593) (xy 60.169148 -49.879872)
			(xy 60.148216 -49.862232) (xy 60.147962 -49.861978) (xy 60.140864 -49.856409) (xy 60.123956 -49.850152)
			(xy 60.114942 -49.849786) (xy 60.047886 -49.849786) (xy 60.038869 -49.85014) (xy 60.021952 -49.85639)
			(xy 60.014866 -49.861978) (xy 60.014612 -49.862232) (xy 59.993679 -49.879873) (xy 59.947711 -49.909597)
			(xy 59.897965 -49.932443) (xy 59.845463 -49.947939) (xy 59.791285 -49.955768) (xy 59.736543 -49.955768)
			(xy 59.682365 -49.947939) (xy 59.629863 -49.932443) (xy 59.580117 -49.909597) (xy 59.534149 -49.879873)
			(xy 59.513216 -49.862232) (xy 59.512962 -49.861978) (xy 59.505864 -49.856409) (xy 59.488956 -49.850152)
			(xy 59.479942 -49.849786) (xy 59.412886 -49.849786) (xy 59.403869 -49.85014) (xy 59.386952 -49.85639)
			(xy 59.379866 -49.861978) (xy 59.379866 -49.862232) (xy 59.379612 -49.862232) (xy 59.358679 -49.879873)
			(xy 59.312711 -49.909597) (xy 59.262965 -49.932443) (xy 59.210463 -49.947939) (xy 59.156285 -49.955768)
			(xy 59.101543 -49.955768) (xy 59.047365 -49.947939) (xy 58.994863 -49.932443) (xy 58.945117 -49.909597)
			(xy 58.899149 -49.879873) (xy 58.878216 -49.862232) (xy 58.877962 -49.861978) (xy 58.870864 -49.856409)
			(xy 58.853956 -49.850152) (xy 58.844942 -49.849786) (xy 58.777886 -49.849786) (xy 58.768869 -49.85014)
			(xy 58.751952 -49.85639) (xy 58.744866 -49.861978) (xy 58.744866 -49.862232) (xy 58.744612 -49.862232)
			(xy 58.72369 -49.879884) (xy 58.677714 -49.909593) (xy 58.627964 -49.932426) (xy 58.575461 -49.947914)
			(xy 58.521284 -49.955739) (xy 58.493914 -49.956212) (xy 58.466661 -49.955742) (xy 58.412709 -49.947986)
			(xy 58.36041 -49.932632) (xy 58.310829 -49.90999) (xy 58.264974 -49.880523) (xy 58.22378 -49.84483)
			(xy 58.188085 -49.803637) (xy 58.158616 -49.757784) (xy 58.135973 -49.708203) (xy 58.120617 -49.655905)
			(xy 58.112859 -49.601953) (xy 53.463398 -49.601953) (xy 53.489783 -49.613165) (xy 53.537389 -49.642219)
			(xy 53.580257 -49.677894) (xy 53.617474 -49.719431) (xy 53.648247 -49.765944) (xy 53.671919 -49.816441)
			(xy 53.687987 -49.869848) (xy 53.696107 -49.925024) (xy 53.696616 -49.95291) (xy 53.696107 -49.980796)
			(xy 53.687987 -50.035972) (xy 53.671919 -50.089379) (xy 53.648247 -50.139876) (xy 53.617474 -50.186389)
			(xy 53.580257 -50.227926) (xy 53.537389 -50.263601) (xy 53.489783 -50.292655) (xy 53.438454 -50.314467)
			(xy 53.384497 -50.328573) (xy 53.32906 -50.334673) (xy 53.273326 -50.332636) (xy 53.218483 -50.322506)
			(xy 53.165699 -50.304499) (xy 53.116099 -50.278998) (xy 53.070741 -50.246547) (xy 53.030592 -50.207838)
			(xy 52.996506 -50.163695) (xy 52.96921 -50.11506) (xy 52.949287 -50.062969) (xy 52.937161 -50.008532)
			(xy 52.93309 -49.95291) (xy 39.145464 -49.95291) (xy 39.145464 -51.019456) (xy 50.749452 -51.019456)
			(xy 50.753523 -50.963834) (xy 50.765649 -50.909397) (xy 50.785572 -50.857306) (xy 50.812868 -50.808671)
			(xy 50.846954 -50.764528) (xy 50.887103 -50.725819) (xy 50.932461 -50.693368) (xy 50.982061 -50.667867)
			(xy 51.034845 -50.64986) (xy 51.089688 -50.63973) (xy 51.145422 -50.637693) (xy 51.200859 -50.643793)
			(xy 51.254816 -50.657899) (xy 51.306145 -50.679711) (xy 51.353751 -50.708765) (xy 51.396619 -50.74444)
			(xy 51.433836 -50.785977) (xy 51.464609 -50.83249) (xy 51.488281 -50.882987) (xy 51.504349 -50.936394)
			(xy 51.512469 -50.99157) (xy 51.512978 -51.019456) (xy 51.512469 -51.047342) (xy 51.504349 -51.102518)
			(xy 51.488281 -51.155925) (xy 51.464609 -51.206422) (xy 51.439753 -51.243992) (xy 59.132978 -51.243992)
			(xy 59.13342 -51.216621) (xy 59.141241 -51.16244) (xy 59.156735 -51.109936) (xy 59.179582 -51.060189)
			(xy 59.209313 -51.014224) (xy 59.226958 -50.993294) (xy 59.227212 -50.99304) (xy 59.232789 -50.985947)
			(xy 59.239041 -50.969035) (xy 59.239404 -50.96002) (xy 59.239404 -50.892964) (xy 59.239063 -50.883946)
			(xy 59.232804 -50.867029) (xy 59.227212 -50.859944) (xy 59.226958 -50.859944) (xy 59.226958 -50.85969)
			(xy 59.209294 -50.838778) (xy 59.179587 -50.792799) (xy 59.156757 -50.743046) (xy 59.141271 -50.690542)
			(xy 59.133449 -50.636362) (xy 59.132978 -50.608992) (xy 59.13347 -50.581741) (xy 59.141228 -50.527794)
			(xy 59.156583 -50.475501) (xy 59.179224 -50.425924) (xy 59.20869 -50.380075) (xy 59.244381 -50.338885)
			(xy 59.28557 -50.303193) (xy 59.331419 -50.273727) (xy 59.380995 -50.251085) (xy 59.433289 -50.235729)
			(xy 59.487235 -50.227971) (xy 59.514486 -50.227484) (xy 59.543404 -50.22798) (xy 59.600578 -50.236709)
			(xy 59.655778 -50.25397) (xy 59.707741 -50.279365) (xy 59.755274 -50.312314) (xy 59.797288 -50.352061)
			(xy 59.815476 -50.37455) (xy 59.823095 -50.383345) (xy 59.843987 -50.393533) (xy 59.855608 -50.394108)
			(xy 59.935364 -50.394108) (xy 59.946998 -50.393588) (xy 59.967907 -50.383385) (xy 59.975496 -50.37455)
			(xy 59.993677 -50.352058) (xy 60.0357 -50.312326) (xy 60.083238 -50.279389) (xy 60.135201 -50.254003)
			(xy 60.190399 -50.236748) (xy 60.24757 -50.228019) (xy 60.276486 -50.227484) (xy 60.303738 -50.227968)
			(xy 60.357688 -50.235723) (xy 60.409985 -50.251077) (xy 60.459564 -50.273717) (xy 60.505417 -50.303183)
			(xy 60.54661 -50.338875) (xy 60.582304 -50.380065) (xy 60.611772 -50.425916) (xy 60.634415 -50.475495)
			(xy 60.649772 -50.527791) (xy 60.65753 -50.58174) (xy 60.657994 -50.608992) (xy 60.657523 -50.635306)
			(xy 60.650289 -50.687434) (xy 60.635971 -50.738077) (xy 60.614839 -50.786276) (xy 60.587294 -50.83112)
			(xy 60.553855 -50.871759) (xy 60.534804 -50.889916) (xy 60.527394 -50.89743) (xy 60.518874 -50.916716)
			(xy 60.518294 -50.927254) (xy 60.518294 -51.00193) (xy 60.518849 -51.012477) (xy 60.527366 -51.031772)
			(xy 60.534804 -51.039268) (xy 60.553886 -51.057397) (xy 60.587341 -51.098032) (xy 60.614896 -51.142878)
			(xy 60.63603 -51.191084) (xy 60.650342 -51.241736) (xy 60.657559 -51.293874) (xy 60.657994 -51.320192)
			(xy 60.657537 -51.347445) (xy 60.649781 -51.401397) (xy 60.634425 -51.453696) (xy 60.611783 -51.503277)
			(xy 60.582314 -51.549131) (xy 60.54662 -51.590324) (xy 60.505426 -51.626018) (xy 60.459572 -51.655486)
			(xy 60.40999 -51.678127) (xy 60.357691 -51.693482) (xy 60.303739 -51.701238) (xy 60.276486 -51.7017)
			(xy 60.248821 -51.701199) (xy 60.194071 -51.693198) (xy 60.141049 -51.677379) (xy 60.090865 -51.654074)
			(xy 60.044569 -51.623771) (xy 60.003131 -51.587105) (xy 59.967419 -51.544842) (xy 59.952382 -51.521614)
			(xy 59.945763 -51.511923) (xy 59.925889 -51.499487) (xy 59.914282 -51.497738) (xy 59.834272 -51.489864)
			(xy 59.822633 -51.489219) (xy 59.800795 -51.497308) (xy 59.792362 -51.505358) (xy 59.792108 -51.505612)
			(xy 59.774008 -51.524174) (xy 59.73368 -51.556754) (xy 59.68931 -51.583569) (xy 59.641715 -51.604125)
			(xy 59.591774 -51.618043) (xy 59.540408 -51.625065) (xy 59.514486 -51.6255) (xy 59.487234 -51.625035)
			(xy 59.433285 -51.617277) (xy 59.38099 -51.601919) (xy 59.331412 -51.579276) (xy 59.285561 -51.549807)
			(xy 59.244371 -51.514114) (xy 59.208679 -51.472921) (xy 59.179214 -51.427069) (xy 59.156573 -51.37749)
			(xy 59.141219 -51.325193) (xy 59.133463 -51.271244) (xy 59.132978 -51.243992) (xy 51.439753 -51.243992)
			(xy 51.433836 -51.252935) (xy 51.396619 -51.294472) (xy 51.353751 -51.330147) (xy 51.306145 -51.359201)
			(xy 51.254816 -51.381013) (xy 51.200859 -51.395119) (xy 51.145422 -51.401219) (xy 51.089688 -51.399182)
			(xy 51.034845 -51.389052) (xy 50.982061 -51.371045) (xy 50.932461 -51.345544) (xy 50.887103 -51.313093)
			(xy 50.846954 -51.274384) (xy 50.812868 -51.230241) (xy 50.785572 -51.181606) (xy 50.765649 -51.129515)
			(xy 50.753523 -51.075078) (xy 50.749452 -51.019456) (xy 39.145464 -51.019456) (xy 39.145464 -52.035456)
			(xy 52.941218 -52.035456) (xy 52.945289 -51.979834) (xy 52.957415 -51.925397) (xy 52.977338 -51.873306)
			(xy 53.004634 -51.824671) (xy 53.03872 -51.780528) (xy 53.078869 -51.741819) (xy 53.124227 -51.709368)
			(xy 53.173827 -51.683867) (xy 53.226611 -51.66586) (xy 53.281454 -51.65573) (xy 53.337188 -51.653693)
			(xy 53.392625 -51.659793) (xy 53.446582 -51.673899) (xy 53.497911 -51.695711) (xy 53.545517 -51.724765)
			(xy 53.588385 -51.76044) (xy 53.625602 -51.801977) (xy 53.656375 -51.84849) (xy 53.680047 -51.898987)
			(xy 53.696115 -51.952394) (xy 53.704235 -52.00757) (xy 53.704744 -52.035456) (xy 53.704235 -52.063342)
			(xy 53.696115 -52.118518) (xy 53.680047 -52.171925) (xy 53.656375 -52.222422) (xy 53.625602 -52.268935)
			(xy 53.588385 -52.310472) (xy 53.545517 -52.346147) (xy 53.497911 -52.375201) (xy 53.446582 -52.397013)
			(xy 53.392625 -52.411119) (xy 53.337188 -52.417219) (xy 53.281454 -52.415182) (xy 53.226611 -52.405052)
			(xy 53.173827 -52.387045) (xy 53.124227 -52.361544) (xy 53.078869 -52.329093) (xy 53.03872 -52.290384)
			(xy 53.004634 -52.246241) (xy 52.977338 -52.197606) (xy 52.957415 -52.145515) (xy 52.945289 -52.091078)
			(xy 52.941218 -52.035456) (xy 39.145464 -52.035456) (xy 39.145464 -54.731412) (xy 39.520622 -54.731412)
			(xy 39.52109 -54.704042) (xy 39.528906 -54.649863) (xy 39.544395 -54.597359) (xy 39.567236 -54.547612)
			(xy 39.596961 -54.501646) (xy 39.614602 -54.480714) (xy 39.614856 -54.48046) (xy 39.62043 -54.473365)
			(xy 39.626683 -54.456455) (xy 39.627048 -54.44744) (xy 39.627048 -54.380384) (xy 39.62671 -54.371365)
			(xy 39.62045 -54.354448) (xy 39.614856 -54.347364) (xy 39.614602 -54.347364) (xy 39.614602 -54.34711)
			(xy 39.596974 -54.326167) (xy 39.567251 -54.280201) (xy 39.544406 -54.230456) (xy 39.52891 -54.177956)
			(xy 39.521081 -54.123779) (xy 39.52108 -54.069039) (xy 39.528906 -54.014862) (xy 39.5444 -53.962361)
			(xy 39.567242 -53.912615) (xy 39.596963 -53.866647) (xy 39.614602 -53.845714) (xy 39.614856 -53.84546)
			(xy 39.62043 -53.838365) (xy 39.626683 -53.821455) (xy 39.627048 -53.81244) (xy 39.627048 -53.745384)
			(xy 39.62671 -53.736365) (xy 39.62045 -53.719448) (xy 39.614856 -53.712364) (xy 39.614602 -53.712364)
			(xy 39.614602 -53.71211) (xy 39.596974 -53.691167) (xy 39.567251 -53.645201) (xy 39.544406 -53.595456)
			(xy 39.52891 -53.542956) (xy 39.521081 -53.488779) (xy 39.52108 -53.434039) (xy 39.528906 -53.379862)
			(xy 39.5444 -53.327361) (xy 39.567242 -53.277615) (xy 39.596963 -53.231647) (xy 39.614602 -53.210714)
			(xy 39.614856 -53.21046) (xy 39.62043 -53.203365) (xy 39.626683 -53.186455) (xy 39.627048 -53.17744)
			(xy 39.627048 -53.110384) (xy 39.62671 -53.101365) (xy 39.62045 -53.084448) (xy 39.614856 -53.077364)
			(xy 39.614602 -53.077364) (xy 39.614602 -53.07711) (xy 39.596954 -53.056185) (xy 39.567244 -53.01021)
			(xy 39.544409 -52.960461) (xy 39.52892 -52.907959) (xy 39.521095 -52.853782) (xy 39.520622 -52.826412)
			(xy 39.521108 -52.799161) (xy 39.528864 -52.745213) (xy 39.544219 -52.692918) (xy 39.566861 -52.643341)
			(xy 39.596327 -52.597491) (xy 39.632018 -52.5563) (xy 39.673209 -52.520609) (xy 39.719059 -52.491143)
			(xy 39.768636 -52.468501) (xy 39.820931 -52.453146) (xy 39.874879 -52.44539) (xy 39.929381 -52.44539)
			(xy 39.983329 -52.453146) (xy 40.035624 -52.468501) (xy 40.085201 -52.491143) (xy 40.131051 -52.520609)
			(xy 40.172242 -52.5563) (xy 40.207933 -52.597491) (xy 40.237399 -52.643341) (xy 40.260041 -52.692918)
			(xy 40.275396 -52.745213) (xy 40.283152 -52.799161) (xy 40.283638 -52.826412) (xy 40.283194 -52.853783)
			(xy 40.275373 -52.907964) (xy 40.25988 -52.960468) (xy 40.237033 -53.010214) (xy 40.207302 -53.05618)
			(xy 40.189658 -53.07711) (xy 40.189404 -53.077364) (xy 40.183827 -53.084457) (xy 40.177574 -53.101369)
			(xy 40.177212 -53.110384) (xy 40.177212 -53.17744) (xy 40.177547 -53.186459) (xy 40.18381 -53.203376)
			(xy 40.189404 -53.21046) (xy 40.189658 -53.21046) (xy 40.189658 -53.210714) (xy 40.207311 -53.231637)
			(xy 40.237037 -53.277606) (xy 40.259882 -53.327354) (xy 40.275378 -53.379858) (xy 40.283206 -53.434038)
			(xy 40.283205 -53.48878) (xy 40.275374 -53.54296) (xy 40.259876 -53.595463) (xy 40.237028 -53.64521)
			(xy 40.2073 -53.691178) (xy 40.189658 -53.71211) (xy 40.189404 -53.712364) (xy 40.183827 -53.719457)
			(xy 40.177574 -53.736369) (xy 40.177212 -53.745384) (xy 40.177212 -53.81244) (xy 40.177547 -53.821459)
			(xy 40.18381 -53.838376) (xy 40.189404 -53.84546) (xy 40.189658 -53.84546) (xy 40.189658 -53.845714)
			(xy 40.207311 -53.866637) (xy 40.237037 -53.912606) (xy 40.259882 -53.962354) (xy 40.275378 -54.014858)
			(xy 40.283206 -54.069038) (xy 40.283205 -54.12378) (xy 40.275374 -54.17796) (xy 40.259876 -54.230463)
			(xy 40.237028 -54.28021) (xy 40.2073 -54.326178) (xy 40.189658 -54.34711) (xy 40.189404 -54.347364)
			(xy 40.183827 -54.354457) (xy 40.177574 -54.371369) (xy 40.177212 -54.380384) (xy 40.177212 -54.44744)
			(xy 40.177547 -54.456459) (xy 40.18381 -54.473376) (xy 40.189404 -54.48046) (xy 40.189658 -54.48046)
			(xy 40.189658 -54.480714) (xy 40.207264 -54.501673) (xy 40.236982 -54.547638) (xy 40.259825 -54.597378)
			(xy 40.275324 -54.649873) (xy 40.28316 -54.704045) (xy 40.283638 -54.731412) (xy 40.283152 -54.758663)
			(xy 40.278488 -54.791102) (xy 42.176446 -54.791102) (xy 42.176902 -54.763731) (xy 42.184721 -54.709551)
			(xy 42.200211 -54.657048) (xy 42.223056 -54.607301) (xy 42.252783 -54.561335) (xy 42.270426 -54.540404)
			(xy 42.27068 -54.54015) (xy 42.276261 -54.53306) (xy 42.282509 -54.516146) (xy 42.282872 -54.50713)
			(xy 42.282872 -54.440074) (xy 42.282534 -54.431055) (xy 42.276274 -54.414138) (xy 42.27068 -54.407054)
			(xy 42.270426 -54.407054) (xy 42.270426 -54.4068) (xy 42.252787 -54.385866) (xy 42.223063 -54.339898)
			(xy 42.200217 -54.290152) (xy 42.184721 -54.23765) (xy 42.176892 -54.183472) (xy 42.176892 -54.128731)
			(xy 42.18472 -54.074553) (xy 42.200216 -54.022051) (xy 42.223061 -53.972305) (xy 42.252785 -53.926337)
			(xy 42.270426 -53.905404) (xy 42.27068 -53.90515) (xy 42.276261 -53.89806) (xy 42.282509 -53.881146)
			(xy 42.282872 -53.87213) (xy 42.282872 -53.805074) (xy 42.282534 -53.796055) (xy 42.276274 -53.779138)
			(xy 42.27068 -53.772054) (xy 42.270426 -53.772054) (xy 42.270426 -53.7718) (xy 42.252787 -53.750866)
			(xy 42.223063 -53.704898) (xy 42.200217 -53.655152) (xy 42.184721 -53.60265) (xy 42.176892 -53.548472)
			(xy 42.176892 -53.493731) (xy 42.18472 -53.439553) (xy 42.200216 -53.387051) (xy 42.223061 -53.337305)
			(xy 42.252785 -53.291337) (xy 42.270426 -53.270404) (xy 42.27068 -53.27015) (xy 42.276261 -53.26306)
			(xy 42.282509 -53.246146) (xy 42.282872 -53.23713) (xy 42.282872 -53.170074) (xy 42.282534 -53.161055)
			(xy 42.276274 -53.144138) (xy 42.27068 -53.137054) (xy 42.270426 -53.137054) (xy 42.270426 -53.1368)
			(xy 42.252777 -53.115875) (xy 42.223066 -53.069901) (xy 42.200232 -53.020152) (xy 42.184743 -52.967649)
			(xy 42.176918 -52.913472) (xy 42.176446 -52.886102) (xy 42.176932 -52.858851) (xy 42.184688 -52.804903)
			(xy 42.200043 -52.752608) (xy 42.222685 -52.703031) (xy 42.252151 -52.657181) (xy 42.287842 -52.61599)
			(xy 42.329033 -52.580299) (xy 42.374883 -52.550833) (xy 42.42446 -52.528191) (xy 42.476755 -52.512836)
			(xy 42.530703 -52.50508) (xy 42.585205 -52.50508) (xy 42.639153 -52.512836) (xy 42.691448 -52.528191)
			(xy 42.730557 -52.546052) (xy 47.679573 -52.546052) (xy 47.679573 -52.491548) (xy 47.68733 -52.437599)
			(xy 47.702686 -52.385303) (xy 47.725328 -52.335724) (xy 47.754796 -52.289873) (xy 47.790489 -52.248682)
			(xy 47.831681 -52.21299) (xy 47.877533 -52.183523) (xy 47.927112 -52.160883) (xy 47.979409 -52.145528)
			(xy 48.033358 -52.137773) (xy 48.06061 -52.13731) (xy 48.087981 -52.137768) (xy 48.14216 -52.145587)
			(xy 48.194663 -52.161078) (xy 48.24441 -52.183922) (xy 48.290377 -52.213648) (xy 48.311308 -52.23129)
			(xy 48.311562 -52.231544) (xy 48.318651 -52.237126) (xy 48.335566 -52.243374) (xy 48.344582 -52.243736)
			(xy 48.411638 -52.243736) (xy 48.420656 -52.243389) (xy 48.437572 -52.237134) (xy 48.444658 -52.231544)
			(xy 48.444658 -52.23129) (xy 48.444912 -52.23129) (xy 48.465845 -52.213649) (xy 48.511813 -52.183925)
			(xy 48.561559 -52.161079) (xy 48.614061 -52.145583) (xy 48.668239 -52.137754) (xy 48.722981 -52.137754)
			(xy 48.777159 -52.145583) (xy 48.829661 -52.161079) (xy 48.879407 -52.183925) (xy 48.925375 -52.213649)
			(xy 48.946308 -52.23129) (xy 48.946562 -52.231544) (xy 48.953651 -52.237126) (xy 48.970566 -52.243374)
			(xy 48.979582 -52.243736) (xy 49.046638 -52.243736) (xy 49.055656 -52.243389) (xy 49.072572 -52.237134)
			(xy 49.079658 -52.231544) (xy 49.079658 -52.23129) (xy 49.079912 -52.23129) (xy 49.100865 -52.213677)
			(xy 49.146832 -52.183962) (xy 49.196574 -52.161121) (xy 49.24907 -52.145624) (xy 49.303242 -52.137788)
			(xy 49.33061 -52.13731) (xy 49.357862 -52.137761) (xy 49.411811 -52.145519) (xy 49.464107 -52.160875)
			(xy 49.513686 -52.183518) (xy 49.559537 -52.212986) (xy 49.600728 -52.248679) (xy 49.63642 -52.289871)
			(xy 49.665887 -52.335723) (xy 49.688528 -52.385302) (xy 49.703884 -52.437599) (xy 49.71164 -52.491548)
			(xy 49.71164 -52.546052) (xy 49.705696 -52.587398) (xy 50.755294 -52.587398) (xy 50.759365 -52.531776)
			(xy 50.771491 -52.477339) (xy 50.791414 -52.425248) (xy 50.81871 -52.376613) (xy 50.852796 -52.33247)
			(xy 50.892945 -52.293761) (xy 50.938303 -52.26131) (xy 50.987903 -52.235809) (xy 51.040687 -52.217802)
			(xy 51.09553 -52.207672) (xy 51.151264 -52.205635) (xy 51.206701 -52.211735) (xy 51.260658 -52.225841)
			(xy 51.311987 -52.247653) (xy 51.359593 -52.276707) (xy 51.402461 -52.312382) (xy 51.439678 -52.353919)
			(xy 51.470451 -52.400432) (xy 51.494123 -52.450929) (xy 51.510191 -52.504336) (xy 51.517787 -52.555953)
			(xy 58.583779 -52.555953) (xy 58.583779 -52.501447) (xy 58.591537 -52.447497) (xy 58.606893 -52.3952)
			(xy 58.629536 -52.345621) (xy 58.659005 -52.29977) (xy 58.6947 -52.258579) (xy 58.735894 -52.222887)
			(xy 58.781748 -52.193422) (xy 58.831329 -52.170783) (xy 58.883627 -52.15543) (xy 58.937577 -52.147677)
			(xy 58.96483 -52.147216) (xy 58.992201 -52.147661) (xy 59.046381 -52.155483) (xy 59.098885 -52.170977)
			(xy 59.148631 -52.193823) (xy 59.194597 -52.223553) (xy 59.215528 -52.241196) (xy 59.215782 -52.24145)
			(xy 59.222865 -52.247041) (xy 59.239785 -52.253284) (xy 59.248802 -52.253642) (xy 59.315858 -52.253642)
			(xy 59.324874 -52.253278) (xy 59.341792 -52.247037) (xy 59.348878 -52.24145) (xy 59.348878 -52.241196)
			(xy 59.349132 -52.241196) (xy 59.370078 -52.223575) (xy 59.416047 -52.19386) (xy 59.465791 -52.171021)
			(xy 59.518289 -52.155526) (xy 59.572462 -52.147693) (xy 59.59983 -52.147216) (xy 59.627082 -52.147656)
			(xy 59.681029 -52.155416) (xy 59.733324 -52.170775) (xy 59.7829 -52.193419) (xy 59.82875 -52.222888)
			(xy 59.869939 -52.258582) (xy 59.90563 -52.299774) (xy 59.935095 -52.345626) (xy 59.957735 -52.395204)
			(xy 59.97309 -52.4475) (xy 59.980846 -52.501448) (xy 59.980846 -52.555952) (xy 59.97309 -52.6099)
			(xy 59.957735 -52.662196) (xy 59.935095 -52.711774) (xy 59.90563 -52.757626) (xy 59.869939 -52.798818)
			(xy 59.82875 -52.834512) (xy 59.7829 -52.863981) (xy 59.733324 -52.886625) (xy 59.681029 -52.901984)
			(xy 59.627082 -52.909744) (xy 59.59983 -52.910232) (xy 59.57246 -52.909765) (xy 59.51828 -52.90195)
			(xy 59.465776 -52.886462) (xy 59.416029 -52.86362) (xy 59.370063 -52.833894) (xy 59.349132 -52.816252)
			(xy 59.348878 -52.815998) (xy 59.341802 -52.810396) (xy 59.324877 -52.804159) (xy 59.315858 -52.803806)
			(xy 59.248802 -52.803806) (xy 59.239785 -52.804163) (xy 59.222868 -52.81041) (xy 59.215782 -52.815998)
			(xy 59.215782 -52.816252) (xy 59.215528 -52.816252) (xy 59.19459 -52.833884) (xy 59.14862 -52.863599)
			(xy 59.098874 -52.886437) (xy 59.046374 -52.901929) (xy 58.992199 -52.909758) (xy 58.96483 -52.910232)
			(xy 58.937577 -52.909723) (xy 58.883627 -52.90197) (xy 58.831329 -52.886617) (xy 58.781748 -52.863978)
			(xy 58.735894 -52.834513) (xy 58.6947 -52.798821) (xy 58.659005 -52.75763) (xy 58.629536 -52.711779)
			(xy 58.606893 -52.6622) (xy 58.591537 -52.609903) (xy 58.583779 -52.555953) (xy 51.517787 -52.555953)
			(xy 51.518311 -52.559512) (xy 51.51882 -52.587398) (xy 51.518311 -52.615284) (xy 51.510191 -52.67046)
			(xy 51.494123 -52.723867) (xy 51.470451 -52.774364) (xy 51.439678 -52.820877) (xy 51.402461 -52.862414)
			(xy 51.359593 -52.898089) (xy 51.311987 -52.927143) (xy 51.260658 -52.948955) (xy 51.206701 -52.963061)
			(xy 51.151264 -52.969161) (xy 51.09553 -52.967124) (xy 51.040687 -52.956994) (xy 50.987903 -52.938987)
			(xy 50.938303 -52.913486) (xy 50.892945 -52.881035) (xy 50.852796 -52.842326) (xy 50.81871 -52.798183)
			(xy 50.791414 -52.749548) (xy 50.771491 -52.697457) (xy 50.759365 -52.64302) (xy 50.755294 -52.587398)
			(xy 49.705696 -52.587398) (xy 49.703884 -52.600001) (xy 49.688528 -52.652298) (xy 49.665887 -52.701877)
			(xy 49.63642 -52.747729) (xy 49.600728 -52.788921) (xy 49.559537 -52.824614) (xy 49.513686 -52.854082)
			(xy 49.464107 -52.876725) (xy 49.411811 -52.892081) (xy 49.357862 -52.899839) (xy 49.33061 -52.900326)
			(xy 49.303239 -52.899872) (xy 49.249059 -52.892054) (xy 49.196555 -52.876563) (xy 49.146808 -52.853718)
			(xy 49.100843 -52.82399) (xy 49.079912 -52.806346) (xy 49.079658 -52.806092) (xy 49.07256 -52.800523)
			(xy 49.055652 -52.794266) (xy 49.046638 -52.7939) (xy 48.979582 -52.7939) (xy 48.970564 -52.794249)
			(xy 48.953647 -52.800502) (xy 48.946562 -52.806092) (xy 48.946308 -52.806346) (xy 48.925375 -52.823987)
			(xy 48.879407 -52.853711) (xy 48.829661 -52.876557) (xy 48.777159 -52.892053) (xy 48.722981 -52.899882)
			(xy 48.668239 -52.899882) (xy 48.614061 -52.892053) (xy 48.561559 -52.876557) (xy 48.511813 -52.853711)
			(xy 48.465845 -52.823987) (xy 48.444912 -52.806346) (xy 48.444658 -52.806092) (xy 48.43756 -52.800523)
			(xy 48.420652 -52.794266) (xy 48.411638 -52.7939) (xy 48.344582 -52.7939) (xy 48.335564 -52.794249)
			(xy 48.318647 -52.800502) (xy 48.311562 -52.806092) (xy 48.311562 -52.806346) (xy 48.311308 -52.806346)
			(xy 48.290377 -52.823986) (xy 48.244405 -52.8537) (xy 48.194657 -52.876536) (xy 48.142156 -52.892027)
			(xy 48.087979 -52.899853) (xy 48.06061 -52.900326) (xy 48.033358 -52.899827) (xy 47.979409 -52.892072)
			(xy 47.927112 -52.876717) (xy 47.877533 -52.854077) (xy 47.831681 -52.82461) (xy 47.790489 -52.788918)
			(xy 47.754796 -52.747727) (xy 47.725328 -52.701876) (xy 47.702686 -52.652297) (xy 47.68733 -52.600001)
			(xy 47.679573 -52.546052) (xy 42.730557 -52.546052) (xy 42.741025 -52.550833) (xy 42.786875 -52.580299)
			(xy 42.828066 -52.61599) (xy 42.863757 -52.657181) (xy 42.893223 -52.703031) (xy 42.915865 -52.752608)
			(xy 42.93122 -52.804903) (xy 42.938976 -52.858851) (xy 42.939462 -52.886102) (xy 42.939006 -52.913473)
			(xy 42.931187 -52.967653) (xy 42.915696 -53.020156) (xy 42.892852 -53.069903) (xy 42.863125 -53.115869)
			(xy 42.845482 -53.1368) (xy 42.845228 -53.137054) (xy 42.839646 -53.144143) (xy 42.833399 -53.161058)
			(xy 42.833036 -53.170074) (xy 42.833036 -53.23713) (xy 42.833371 -53.246149) (xy 42.839633 -53.263067)
			(xy 42.845228 -53.27015) (xy 42.845482 -53.27015) (xy 42.845482 -53.270404) (xy 42.863124 -53.291335)
			(xy 42.892848 -53.337304) (xy 42.915693 -53.38705) (xy 42.931189 -53.439552) (xy 42.939017 -53.493731)
			(xy 42.939017 -53.548472) (xy 42.931188 -53.602651) (xy 42.915692 -53.655153) (xy 42.892847 -53.704899)
			(xy 42.863122 -53.750867) (xy 42.846552 -53.77053) (xy 43.210734 -53.77053) (xy 43.211261 -53.741613)
			(xy 43.219986 -53.684442) (xy 43.237242 -53.629243) (xy 43.262632 -53.577281) (xy 43.295574 -53.529747)
			(xy 43.335315 -53.48773) (xy 43.3578 -53.46954) (xy 43.366579 -53.461906) (xy 43.376778 -53.441026)
			(xy 43.377358 -53.429408) (xy 43.377358 -53.349652) (xy 43.376847 -53.338016) (xy 43.36664 -53.317106)
			(xy 43.3578 -53.30952) (xy 43.335326 -53.291318) (xy 43.29559 -53.2493) (xy 43.26265 -53.201768)
			(xy 43.23726 -53.149809) (xy 43.220002 -53.094613) (xy 43.21127 -53.037445) (xy 43.210734 -53.00853)
			(xy 43.211183 -52.981276) (xy 43.218937 -52.927322) (xy 43.234292 -52.875022) (xy 43.256934 -52.825439)
			(xy 43.286403 -52.779584) (xy 43.322098 -52.738389) (xy 43.363293 -52.702695) (xy 43.409149 -52.673228)
			(xy 43.458733 -52.650587) (xy 43.511034 -52.635235) (xy 43.564988 -52.627482) (xy 43.592242 -52.627022)
			(xy 43.618557 -52.627454) (xy 43.670688 -52.634695) (xy 43.721331 -52.649021) (xy 43.76953 -52.67016)
			(xy 43.814373 -52.697712) (xy 43.855011 -52.731157) (xy 43.873166 -52.750212) (xy 43.880697 -52.757603)
			(xy 43.89997 -52.766133) (xy 43.910504 -52.766722) (xy 43.98518 -52.766722) (xy 43.995729 -52.766189)
			(xy 44.015024 -52.757656) (xy 44.022518 -52.750212) (xy 44.040674 -52.731157) (xy 44.081303 -52.697699)
			(xy 44.126144 -52.67014) (xy 44.174344 -52.649001) (xy 44.224992 -52.634684) (xy 44.277126 -52.62746)
			(xy 44.303442 -52.627022) (xy 44.330696 -52.627439) (xy 44.384647 -52.635202) (xy 44.436945 -52.650564)
			(xy 44.486525 -52.673212) (xy 44.532376 -52.702685) (xy 44.573567 -52.738384) (xy 44.609258 -52.779581)
			(xy 44.638723 -52.825439) (xy 44.661361 -52.875022) (xy 44.676713 -52.927323) (xy 44.684466 -52.981276)
			(xy 44.68495 -53.00853) (xy 44.684484 -53.036197) (xy 44.676479 -53.090949) (xy 44.660656 -53.143973)
			(xy 44.637346 -53.194158) (xy 44.607037 -53.240453) (xy 44.570364 -53.281889) (xy 44.528095 -53.317599)
			(xy 44.504864 -53.332634) (xy 44.495176 -53.339257) (xy 44.482737 -53.359128) (xy 44.480988 -53.370734)
			(xy 44.473114 -53.450744) (xy 44.472473 -53.462382) (xy 44.480561 -53.484219) (xy 44.488608 -53.492654)
			(xy 44.488862 -53.492908) (xy 44.507422 -53.51101) (xy 44.540004 -53.551336) (xy 44.566821 -53.595706)
			(xy 44.587377 -53.643301) (xy 44.601295 -53.693242) (xy 44.608316 -53.744608) (xy 44.60875 -53.77053)
			(xy 44.60825 -53.79778) (xy 44.600491 -53.851725) (xy 44.585134 -53.904017) (xy 44.562492 -53.953592)
			(xy 44.533027 -53.99944) (xy 44.497337 -54.040629) (xy 44.456149 -54.07632) (xy 44.410302 -54.105787)
			(xy 44.360728 -54.12843) (xy 44.308437 -54.143788) (xy 44.254492 -54.151549) (xy 44.227242 -54.152038)
			(xy 44.199872 -54.151562) (xy 44.145693 -54.143749) (xy 44.093189 -54.128263) (xy 44.043442 -54.105423)
			(xy 43.997475 -54.075699) (xy 43.976544 -54.058058) (xy 43.97629 -54.057804) (xy 43.96921 -54.052208)
			(xy 43.952288 -54.045967) (xy 43.94327 -54.045612) (xy 43.876214 -54.045612) (xy 43.867197 -54.045973)
			(xy 43.85028 -54.052217) (xy 43.843194 -54.057804) (xy 43.843194 -54.058058) (xy 43.84294 -54.058058)
			(xy 43.821998 -54.075685) (xy 43.776029 -54.1054) (xy 43.726284 -54.128239) (xy 43.673785 -54.143733)
			(xy 43.619611 -54.151563) (xy 43.592242 -54.152038) (xy 43.564992 -54.151506) (xy 43.511045 -54.143755)
			(xy 43.45875 -54.128406) (xy 43.409172 -54.105771) (xy 43.36332 -54.07631) (xy 43.322128 -54.040623)
			(xy 43.286433 -53.999438) (xy 43.256964 -53.953591) (xy 43.234319 -53.904018) (xy 43.21896 -53.851726)
			(xy 43.211199 -53.79778) (xy 43.210734 -53.77053) (xy 42.846552 -53.77053) (xy 42.845482 -53.7718)
			(xy 42.845228 -53.772054) (xy 42.839646 -53.779143) (xy 42.833399 -53.796058) (xy 42.833036 -53.805074)
			(xy 42.833036 -53.87213) (xy 42.833371 -53.881149) (xy 42.839633 -53.898067) (xy 42.845228 -53.90515)
			(xy 42.845482 -53.90515) (xy 42.845482 -53.905404) (xy 42.863124 -53.926335) (xy 42.892848 -53.972304)
			(xy 42.915693 -54.02205) (xy 42.931189 -54.074552) (xy 42.939017 -54.128731) (xy 42.939017 -54.183472)
			(xy 42.931188 -54.237651) (xy 42.915692 -54.290153) (xy 42.9019 -54.320186) (xy 45.130466 -54.320186)
			(xy 45.130908 -54.292815) (xy 45.138729 -54.238634) (xy 45.154223 -54.18613) (xy 45.17707 -54.136383)
			(xy 45.206801 -54.090418) (xy 45.224446 -54.069488) (xy 45.2247 -54.069234) (xy 45.230278 -54.062142)
			(xy 45.23653 -54.045229) (xy 45.236892 -54.036214) (xy 45.236892 -53.969158) (xy 45.236509 -53.960144)
			(xy 45.23028 -53.943227) (xy 45.2247 -53.936138) (xy 45.224446 -53.936138) (xy 45.224446 -53.935884)
			(xy 45.20684 -53.914925) (xy 45.177122 -53.86896) (xy 45.154279 -53.81922) (xy 45.13878 -53.766725)
			(xy 45.130944 -53.712553) (xy 45.130466 -53.685186) (xy 45.130952 -53.657935) (xy 45.138708 -53.603987)
			(xy 45.154063 -53.551692) (xy 45.176705 -53.502115) (xy 45.206171 -53.456265) (xy 45.241862 -53.415074)
			(xy 45.283053 -53.379383) (xy 45.328903 -53.349917) (xy 45.37848 -53.327275) (xy 45.430775 -53.31192)
			(xy 45.484723 -53.304164) (xy 45.539225 -53.304164) (xy 45.593173 -53.31192) (xy 45.645468 -53.327275)
			(xy 45.695045 -53.349917) (xy 45.740895 -53.379383) (xy 45.782086 -53.415074) (xy 45.817777 -53.456265)
			(xy 45.847243 -53.502115) (xy 45.869885 -53.551692) (xy 45.88524 -53.603987) (xy 45.892996 -53.657935)
			(xy 45.893482 -53.685186) (xy 45.893012 -53.712556) (xy 45.885196 -53.766735) (xy 45.869708 -53.819238)
			(xy 45.846867 -53.868985) (xy 45.817143 -53.914952) (xy 45.799502 -53.935884) (xy 45.799248 -53.936138)
			(xy 45.793675 -53.943234) (xy 45.787421 -53.960144) (xy 45.787056 -53.969158) (xy 45.787056 -54.036214)
			(xy 45.787394 -54.045233) (xy 45.793654 -54.06215) (xy 45.799248 -54.069234) (xy 45.799502 -54.069234)
			(xy 45.799502 -54.069488) (xy 45.817149 -54.090414) (xy 45.84686 -54.136388) (xy 45.869694 -54.186137)
			(xy 45.885183 -54.238639) (xy 45.893009 -54.292816) (xy 45.893482 -54.320186) (xy 45.892996 -54.347437)
			(xy 45.88524 -54.401385) (xy 45.869885 -54.45368) (xy 45.847243 -54.503257) (xy 45.817777 -54.549107)
			(xy 45.782086 -54.590298) (xy 45.740895 -54.625989) (xy 45.695045 -54.655455) (xy 45.645468 -54.678097)
			(xy 45.593173 -54.693452) (xy 45.539225 -54.701208) (xy 45.484723 -54.701208) (xy 45.430775 -54.693452)
			(xy 45.37848 -54.678097) (xy 45.328903 -54.655455) (xy 45.283053 -54.625989) (xy 45.241862 -54.590298)
			(xy 45.206171 -54.549107) (xy 45.176705 -54.503257) (xy 45.154063 -54.45368) (xy 45.138708 -54.401385)
			(xy 45.130952 -54.347437) (xy 45.130466 -54.320186) (xy 42.9019 -54.320186) (xy 42.892847 -54.339899)
			(xy 42.863122 -54.385867) (xy 42.845482 -54.4068) (xy 42.845228 -54.407054) (xy 42.839646 -54.414143)
			(xy 42.833399 -54.431058) (xy 42.833036 -54.440074) (xy 42.833036 -54.50713) (xy 42.833371 -54.516149)
			(xy 42.839633 -54.533067) (xy 42.845228 -54.54015) (xy 42.845482 -54.54015) (xy 42.845482 -54.540404)
			(xy 42.863134 -54.561326) (xy 42.892844 -54.607301) (xy 42.915678 -54.657051) (xy 42.931166 -54.709554)
			(xy 42.93899 -54.763732) (xy 42.939107 -54.770528) (xy 46.071028 -54.770528) (xy 46.071504 -54.743158)
			(xy 46.079318 -54.688979) (xy 46.094805 -54.636476) (xy 46.117644 -54.586729) (xy 46.147367 -54.540762)
			(xy 46.165008 -54.51983) (xy 46.165262 -54.519576) (xy 46.170872 -54.512506) (xy 46.177103 -54.495576)
			(xy 46.177454 -54.486556) (xy 46.177454 -54.4195) (xy 46.177107 -54.410482) (xy 46.170853 -54.393565)
			(xy 46.165262 -54.38648) (xy 46.165008 -54.38648) (xy 46.165008 -54.386226) (xy 46.147369 -54.365294)
			(xy 46.117657 -54.319321) (xy 46.094821 -54.269574) (xy 46.07933 -54.217073) (xy 46.071502 -54.162897)
			(xy 46.071028 -54.135528) (xy 46.071514 -54.108277) (xy 46.07927 -54.054329) (xy 46.094625 -54.002034)
			(xy 46.117267 -53.952457) (xy 46.146733 -53.906607) (xy 46.182424 -53.865416) (xy 46.223615 -53.829725)
			(xy 46.269465 -53.800259) (xy 46.319042 -53.777617) (xy 46.371337 -53.762262) (xy 46.425285 -53.754506)
			(xy 46.479787 -53.754506) (xy 46.533735 -53.762262) (xy 46.58603 -53.777617) (xy 46.635607 -53.800259)
			(xy 46.681457 -53.829725) (xy 46.722648 -53.865416) (xy 46.758339 -53.906607) (xy 46.787805 -53.952457)
			(xy 46.79288 -53.96357) (xy 50.772058 -53.96357) (xy 50.776129 -53.907948) (xy 50.788255 -53.853511)
			(xy 50.808178 -53.80142) (xy 50.835474 -53.752785) (xy 50.86956 -53.708642) (xy 50.909709 -53.669933)
			(xy 50.955067 -53.637482) (xy 51.004667 -53.611981) (xy 51.057451 -53.593974) (xy 51.112294 -53.583844)
			(xy 51.168028 -53.581807) (xy 51.223465 -53.587907) (xy 51.277422 -53.602013) (xy 51.328751 -53.623825)
			(xy 51.376357 -53.652879) (xy 51.419225 -53.688554) (xy 51.456442 -53.730091) (xy 51.487215 -53.776604)
			(xy 51.510887 -53.827101) (xy 51.526955 -53.880508) (xy 51.535075 -53.935684) (xy 51.535584 -53.96357)
			(xy 51.535075 -53.991456) (xy 51.526955 -54.046632) (xy 51.510887 -54.100039) (xy 51.487215 -54.150536)
			(xy 51.456442 -54.197049) (xy 51.419225 -54.238586) (xy 51.376357 -54.274261) (xy 51.328751 -54.303315)
			(xy 51.277422 -54.325127) (xy 51.223465 -54.339233) (xy 51.168028 -54.345333) (xy 51.112294 -54.343296)
			(xy 51.057451 -54.333166) (xy 51.004667 -54.315159) (xy 50.955067 -54.289658) (xy 50.909709 -54.257207)
			(xy 50.86956 -54.218498) (xy 50.835474 -54.174355) (xy 50.808178 -54.12572) (xy 50.788255 -54.073629)
			(xy 50.776129 -54.019192) (xy 50.772058 -53.96357) (xy 46.79288 -53.96357) (xy 46.810447 -54.002034)
			(xy 46.825802 -54.054329) (xy 46.833558 -54.108277) (xy 46.834044 -54.135528) (xy 46.833608 -54.162899)
			(xy 46.825785 -54.21708) (xy 46.81029 -54.269584) (xy 46.787441 -54.319331) (xy 46.757709 -54.365296)
			(xy 46.740064 -54.386226) (xy 46.73981 -54.38648) (xy 46.734227 -54.393569) (xy 46.727978 -54.410484)
			(xy 46.727618 -54.4195) (xy 46.727618 -54.486556) (xy 46.727992 -54.495571) (xy 46.734228 -54.512488)
			(xy 46.73981 -54.519576) (xy 46.740064 -54.519576) (xy 46.740064 -54.51983) (xy 46.757678 -54.540782)
			(xy 46.787395 -54.586749) (xy 46.810236 -54.636491) (xy 46.825733 -54.688988) (xy 46.833567 -54.74316)
			(xy 46.834044 -54.770528) (xy 46.833558 -54.797779) (xy 46.825802 -54.851727) (xy 46.810447 -54.904022)
			(xy 46.787805 -54.953599) (xy 46.758339 -54.999449) (xy 46.722648 -55.04064) (xy 46.681457 -55.076331)
			(xy 46.635607 -55.105797) (xy 46.58603 -55.128439) (xy 46.533735 -55.143794) (xy 46.479787 -55.15155)
			(xy 46.425285 -55.15155) (xy 46.371337 -55.143794) (xy 46.319042 -55.128439) (xy 46.269465 -55.105797)
			(xy 46.223615 -55.076331) (xy 46.182424 -55.04064) (xy 46.146733 -54.999449) (xy 46.117267 -54.953599)
			(xy 46.094625 -54.904022) (xy 46.07927 -54.851727) (xy 46.071514 -54.797779) (xy 46.071028 -54.770528)
			(xy 42.939107 -54.770528) (xy 42.939462 -54.791102) (xy 42.938976 -54.818353) (xy 42.93122 -54.872301)
			(xy 42.915865 -54.924596) (xy 42.893223 -54.974173) (xy 42.863757 -55.020023) (xy 42.828066 -55.061214)
			(xy 42.786875 -55.096905) (xy 42.741025 -55.126371) (xy 42.691448 -55.149013) (xy 42.639153 -55.164368)
			(xy 42.585205 -55.172124) (xy 42.530703 -55.172124) (xy 42.476755 -55.164368) (xy 42.42446 -55.149013)
			(xy 42.374883 -55.126371) (xy 42.329033 -55.096905) (xy 42.287842 -55.061214) (xy 42.252151 -55.020023)
			(xy 42.222685 -54.974173) (xy 42.200043 -54.924596) (xy 42.184688 -54.872301) (xy 42.176932 -54.818353)
			(xy 42.176446 -54.791102) (xy 40.278488 -54.791102) (xy 40.275396 -54.812611) (xy 40.260041 -54.864906)
			(xy 40.237399 -54.914483) (xy 40.207933 -54.960333) (xy 40.172242 -55.001524) (xy 40.131051 -55.037215)
			(xy 40.085201 -55.066681) (xy 40.035624 -55.089323) (xy 39.983329 -55.104678) (xy 39.929381 -55.112434)
			(xy 39.874879 -55.112434) (xy 39.820931 -55.104678) (xy 39.768636 -55.089323) (xy 39.719059 -55.066681)
			(xy 39.673209 -55.037215) (xy 39.632018 -55.001524) (xy 39.596327 -54.960333) (xy 39.566861 -54.914483)
			(xy 39.544219 -54.864906) (xy 39.528864 -54.812611) (xy 39.521108 -54.758663) (xy 39.520622 -54.731412)
			(xy 39.145464 -54.731412) (xy 39.145464 -57.002934) (xy 47.563532 -57.002934) (xy 47.56403 -56.974842)
			(xy 47.572253 -56.919264) (xy 47.588542 -56.865494) (xy 47.612544 -56.814696) (xy 47.643739 -56.767969)
			(xy 47.681452 -56.726324) (xy 47.724867 -56.690663) (xy 47.748698 -56.675782) (xy 47.757588 -56.670448)
			(xy 47.76978 -56.65343) (xy 47.7901 -56.560212) (xy 47.785782 -56.539638) (xy 47.77994 -56.531002)
			(xy 47.763931 -56.506944) (xy 47.738592 -56.45501) (xy 47.721369 -56.39985) (xy 47.712656 -56.342725)
			(xy 47.712122 -56.313832) (xy 47.712585 -56.286579) (xy 47.720339 -56.232626) (xy 47.735692 -56.180326)
			(xy 47.758333 -56.130744) (xy 47.7878 -56.08489) (xy 47.823494 -56.043696) (xy 47.864688 -56.008002)
			(xy 47.910543 -55.978534) (xy 47.960125 -55.955893) (xy 48.012424 -55.940539) (xy 48.066377 -55.932785)
			(xy 48.09363 -55.932324) (xy 48.121001 -55.932767) (xy 48.175181 -55.940589) (xy 48.227685 -55.956083)
			(xy 48.277432 -55.978931) (xy 48.323397 -56.00866) (xy 48.344328 -56.026304) (xy 48.344582 -56.026558)
			(xy 48.351665 -56.03215) (xy 48.368585 -56.038392) (xy 48.377602 -56.03875) (xy 48.444658 -56.03875)
			(xy 48.453674 -56.038384) (xy 48.470592 -56.032144) (xy 48.477678 -56.026558) (xy 48.477678 -56.026304)
			(xy 48.477932 -56.026304) (xy 48.498865 -56.008663) (xy 48.544833 -55.978939) (xy 48.594579 -55.956093)
			(xy 48.647081 -55.940597) (xy 48.701259 -55.932768) (xy 48.756001 -55.932768) (xy 48.810179 -55.940597)
			(xy 48.862681 -55.956093) (xy 48.912427 -55.978939) (xy 48.958395 -56.008663) (xy 48.979328 -56.026304)
			(xy 48.979582 -56.026558) (xy 48.986665 -56.03215) (xy 49.003585 -56.038392) (xy 49.012602 -56.03875)
			(xy 49.079658 -56.03875) (xy 49.088674 -56.038384) (xy 49.105592 -56.032144) (xy 49.112678 -56.026558)
			(xy 49.112678 -56.026304) (xy 49.112932 -56.026304) (xy 49.133879 -56.008684) (xy 49.179848 -55.978969)
			(xy 49.229592 -55.956129) (xy 49.282089 -55.940634) (xy 49.336262 -55.932801) (xy 49.36363 -55.932324)
			(xy 49.390882 -55.932748) (xy 49.444831 -55.940509) (xy 49.497127 -55.955868) (xy 49.546704 -55.978512)
			(xy 49.592555 -56.007982) (xy 49.633745 -56.043676) (xy 49.669436 -56.084869) (xy 49.698902 -56.130722)
			(xy 49.721543 -56.180301) (xy 49.736898 -56.232598) (xy 49.744654 -56.286548) (xy 49.744654 -56.341052)
			(xy 49.736898 -56.395002) (xy 49.721543 -56.447299) (xy 49.698902 -56.496878) (xy 49.669436 -56.542731)
			(xy 49.633745 -56.583924) (xy 49.592555 -56.619618) (xy 49.546704 -56.649088) (xy 49.497127 -56.671732)
			(xy 49.444831 -56.687091) (xy 49.390882 -56.694852) (xy 49.36363 -56.69534) (xy 49.33626 -56.694871)
			(xy 49.28208 -56.687056) (xy 49.229577 -56.671569) (xy 49.17983 -56.648727) (xy 49.133863 -56.619002)
			(xy 49.112932 -56.60136) (xy 49.112678 -56.601106) (xy 49.105601 -56.595505) (xy 49.088677 -56.589267)
			(xy 49.079658 -56.588914) (xy 49.012602 -56.588914) (xy 49.003585 -56.589269) (xy 48.986668 -56.595518)
			(xy 48.979582 -56.601106) (xy 48.979582 -56.60136) (xy 48.979328 -56.60136) (xy 48.958395 -56.619001)
			(xy 48.912427 -56.648725) (xy 48.862681 -56.671571) (xy 48.810179 -56.687067) (xy 48.756001 -56.694896)
			(xy 48.701259 -56.694896) (xy 48.647081 -56.687067) (xy 48.594579 -56.671571) (xy 48.544833 -56.648725)
			(xy 48.498865 -56.619001) (xy 48.477932 -56.60136) (xy 48.477678 -56.601106) (xy 48.470601 -56.595505)
			(xy 48.453677 -56.589267) (xy 48.444658 -56.588914) (xy 48.377602 -56.588914) (xy 48.368585 -56.589269)
			(xy 48.351668 -56.595518) (xy 48.344582 -56.601106) (xy 48.344074 -56.60136) (xy 48.331339 -56.612303)
			(xy 48.304248 -56.632145) (xy 48.289972 -56.640984) (xy 48.281082 -56.646318) (xy 48.26889 -56.663336)
			(xy 48.24857 -56.756554) (xy 48.252888 -56.777128) (xy 48.25873 -56.785764) (xy 48.27472 -56.809834)
			(xy 48.300064 -56.861763) (xy 48.317293 -56.91692) (xy 48.326011 -56.974042) (xy 48.326548 -57.002934)
			(xy 48.326062 -57.030185) (xy 48.318306 -57.084133) (xy 48.302951 -57.136428) (xy 48.280309 -57.186005)
			(xy 48.250843 -57.231855) (xy 48.215152 -57.273046) (xy 48.173961 -57.308737) (xy 48.128111 -57.338203)
			(xy 48.078534 -57.360845) (xy 48.026239 -57.3762) (xy 47.972291 -57.383956) (xy 47.917789 -57.383956)
			(xy 47.863841 -57.3762) (xy 47.811546 -57.360845) (xy 47.761969 -57.338203) (xy 47.716119 -57.308737)
			(xy 47.674928 -57.273046) (xy 47.639237 -57.231855) (xy 47.609771 -57.186005) (xy 47.587129 -57.136428)
			(xy 47.571774 -57.084133) (xy 47.564018 -57.030185) (xy 47.563532 -57.002934) (xy 39.145464 -57.002934)
			(xy 39.145464 -58.679334) (xy 47.995332 -58.679334) (xy 47.995745 -58.653018) (xy 48.00299 -58.600887)
			(xy 48.017319 -58.550243) (xy 48.038461 -58.502044) (xy 48.066017 -58.457202) (xy 48.099466 -58.416565)
			(xy 48.118522 -58.39841) (xy 48.125925 -58.39089) (xy 48.134448 -58.371608) (xy 48.135032 -58.361072)
			(xy 48.135032 -58.286396) (xy 48.134509 -58.275846) (xy 48.125968 -58.256551) (xy 48.118522 -58.249058)
			(xy 48.099457 -58.230912) (xy 48.066 -58.19028) (xy 48.038442 -58.145438) (xy 48.017305 -58.097236)
			(xy 48.00299 -58.046586) (xy 47.995768 -57.994451) (xy 47.995332 -57.968134) (xy 47.995818 -57.940883)
			(xy 48.003574 -57.886935) (xy 48.018929 -57.83464) (xy 48.041571 -57.785063) (xy 48.071037 -57.739213)
			(xy 48.106728 -57.698022) (xy 48.147919 -57.662331) (xy 48.193769 -57.632865) (xy 48.243346 -57.610223)
			(xy 48.295641 -57.594868) (xy 48.349589 -57.587112) (xy 48.404091 -57.587112) (xy 48.458039 -57.594868)
			(xy 48.510334 -57.610223) (xy 48.559911 -57.632865) (xy 48.605761 -57.662331) (xy 48.646952 -57.698022)
			(xy 48.682643 -57.739213) (xy 48.712109 -57.785063) (xy 48.734751 -57.83464) (xy 48.750106 -57.886935)
			(xy 48.757862 -57.940883) (xy 48.758348 -57.968134) (xy 48.75792 -57.994449) (xy 48.750679 -58.04658)
			(xy 48.736354 -58.097225) (xy 48.715214 -58.145424) (xy 48.68766 -58.190266) (xy 48.654213 -58.230903)
			(xy 48.635158 -58.249058) (xy 48.627781 -58.256601) (xy 48.619241 -58.275864) (xy 48.618648 -58.286396)
			(xy 48.618648 -58.361072) (xy 48.619165 -58.371623) (xy 48.627707 -58.39092) (xy 48.635158 -58.39841)
			(xy 48.654222 -58.416556) (xy 48.687677 -58.457189) (xy 48.715233 -58.502032) (xy 48.736369 -58.550234)
			(xy 48.750685 -58.600883) (xy 48.75791 -58.653018) (xy 48.758348 -58.679334) (xy 48.757862 -58.706585)
			(xy 48.750106 -58.760533) (xy 48.734751 -58.812828) (xy 48.712109 -58.862405) (xy 48.682643 -58.908255)
			(xy 48.646952 -58.949446) (xy 48.605761 -58.985137) (xy 48.559911 -59.014603) (xy 48.510334 -59.037245)
			(xy 48.458039 -59.0526) (xy 48.404091 -59.060356) (xy 48.349589 -59.060356) (xy 48.295641 -59.0526)
			(xy 48.243346 -59.037245) (xy 48.193769 -59.014603) (xy 48.147919 -58.985137) (xy 48.106728 -58.949446)
			(xy 48.071037 -58.908255) (xy 48.041571 -58.862405) (xy 48.018929 -58.812828) (xy 48.003574 -58.760533)
			(xy 47.995818 -58.706585) (xy 47.995332 -58.679334) (xy 39.145464 -58.679334) (xy 39.145464 -60.019251)
			(xy 48.135784 -60.019251) (xy 48.135784 -59.964749) (xy 48.14354 -59.910803) (xy 48.158895 -59.85851)
			(xy 48.181535 -59.808934) (xy 48.211 -59.763084) (xy 48.246691 -59.721895) (xy 48.287879 -59.686204)
			(xy 48.333728 -59.656738) (xy 48.383304 -59.634097) (xy 48.435597 -59.618741) (xy 48.489543 -59.610984)
			(xy 48.516794 -59.610498) (xy 48.544164 -59.610968) (xy 48.598343 -59.618785) (xy 48.650846 -59.634273)
			(xy 48.700593 -59.657114) (xy 48.74656 -59.686837) (xy 48.767492 -59.704478) (xy 48.767746 -59.704732)
			(xy 48.774841 -59.710306) (xy 48.791751 -59.716559) (xy 48.800766 -59.716924) (xy 48.867822 -59.716924)
			(xy 48.876839 -59.716573) (xy 48.893756 -59.710321) (xy 48.900842 -59.704732) (xy 48.900842 -59.704478)
			(xy 48.901096 -59.704478) (xy 48.922029 -59.686837) (xy 48.967997 -59.657113) (xy 49.017743 -59.634267)
			(xy 49.070245 -59.618771) (xy 49.124423 -59.610942) (xy 49.179165 -59.610942) (xy 49.233343 -59.618771)
			(xy 49.285845 -59.634267) (xy 49.335591 -59.657113) (xy 49.381559 -59.686837) (xy 49.402492 -59.704478)
			(xy 49.402746 -59.704732) (xy 49.409841 -59.710306) (xy 49.426751 -59.716559) (xy 49.435766 -59.716924)
			(xy 49.502822 -59.716924) (xy 49.511839 -59.716573) (xy 49.528756 -59.710321) (xy 49.535842 -59.704732)
			(xy 49.535842 -59.704478) (xy 49.536096 -59.704478) (xy 49.557016 -59.686824) (xy 49.602992 -59.657115)
			(xy 49.652743 -59.634282) (xy 49.705246 -59.618795) (xy 49.759424 -59.61097) (xy 49.786794 -59.610498)
			(xy 49.814048 -59.610949) (xy 49.868 -59.618705) (xy 49.920299 -59.634061) (xy 49.969881 -59.656704)
			(xy 50.015736 -59.686172) (xy 50.05693 -59.721866) (xy 50.092624 -59.76306) (xy 50.122094 -59.808914)
			(xy 50.144737 -59.858495) (xy 50.160093 -59.910794) (xy 50.167851 -59.964746) (xy 50.167851 -60.019254)
			(xy 50.160093 -60.073206) (xy 50.144737 -60.125505) (xy 50.122094 -60.175086) (xy 50.092624 -60.22094)
			(xy 50.05693 -60.262134) (xy 50.015736 -60.297828) (xy 49.969881 -60.327296) (xy 49.920299 -60.349939)
			(xy 49.868 -60.365295) (xy 49.814048 -60.373051) (xy 49.786794 -60.373514) (xy 49.759424 -60.373048)
			(xy 49.705245 -60.36523) (xy 49.652742 -60.34974) (xy 49.602995 -60.326899) (xy 49.557028 -60.297175)
			(xy 49.536096 -60.279534) (xy 49.535842 -60.27928) (xy 49.528749 -60.273703) (xy 49.511837 -60.267451)
			(xy 49.502822 -60.267088) (xy 49.435766 -60.267088) (xy 49.426748 -60.267431) (xy 49.409831 -60.273688)
			(xy 49.402746 -60.27928) (xy 49.402492 -60.279534) (xy 49.381559 -60.297175) (xy 49.335591 -60.326899)
			(xy 49.285845 -60.349745) (xy 49.233343 -60.365241) (xy 49.179165 -60.37307) (xy 49.124423 -60.37307)
			(xy 49.070245 -60.365241) (xy 49.017743 -60.349745) (xy 48.967997 -60.326899) (xy 48.922029 -60.297175)
			(xy 48.901096 -60.279534) (xy 48.900842 -60.27928) (xy 48.893749 -60.273703) (xy 48.876837 -60.267451)
			(xy 48.867822 -60.267088) (xy 48.800766 -60.267088) (xy 48.791748 -60.267431) (xy 48.774831 -60.273688)
			(xy 48.767746 -60.27928) (xy 48.767746 -60.279534) (xy 48.767492 -60.279534) (xy 48.746578 -60.297196)
			(xy 48.7006 -60.326903) (xy 48.650848 -60.349734) (xy 48.598343 -60.36522) (xy 48.544164 -60.373043)
			(xy 48.516794 -60.373514) (xy 48.489543 -60.373016) (xy 48.435597 -60.365259) (xy 48.383304 -60.349903)
			(xy 48.333728 -60.327262) (xy 48.287879 -60.297796) (xy 48.246691 -60.262105) (xy 48.211 -60.220916)
			(xy 48.181535 -60.175066) (xy 48.158895 -60.12549) (xy 48.14354 -60.073197) (xy 48.135784 -60.019251)
			(xy 39.145464 -60.019251) (xy 39.145464 -67.12895) (xy 40.366698 -67.12895) (xy 40.366698 -67.07445)
			(xy 40.374454 -67.020506) (xy 40.389808 -66.968214) (xy 40.412448 -66.91864) (xy 40.441912 -66.872792)
			(xy 40.477601 -66.831604) (xy 40.518789 -66.795915) (xy 40.564636 -66.76645) (xy 40.614211 -66.74381)
			(xy 40.666502 -66.728455) (xy 40.720446 -66.720699) (xy 40.747696 -66.720212) (xy 40.775066 -66.720677)
			(xy 40.829246 -66.728495) (xy 40.881749 -66.743984) (xy 40.931496 -66.766826) (xy 40.977462 -66.796551)
			(xy 40.998394 -66.814192) (xy 40.998648 -66.814446) (xy 41.005741 -66.820023) (xy 41.022653 -66.826274)
			(xy 41.031668 -66.826638) (xy 41.098724 -66.826638) (xy 41.107741 -66.826284) (xy 41.124658 -66.820034)
			(xy 41.131744 -66.814446) (xy 41.131744 -66.814192) (xy 41.131998 -66.814192) (xy 41.152919 -66.796539)
			(xy 41.198895 -66.76683) (xy 41.248645 -66.743996) (xy 41.301148 -66.728509) (xy 41.355326 -66.720684)
			(xy 41.382696 -66.720212) (xy 41.409951 -66.720635) (xy 41.463905 -66.728392) (xy 41.516206 -66.743748)
			(xy 41.565789 -66.766392) (xy 41.611645 -66.795861) (xy 41.652841 -66.831557) (xy 41.688537 -66.872752)
			(xy 41.718007 -66.918607) (xy 41.740651 -66.96819) (xy 41.756008 -67.020491) (xy 41.763765 -67.074446)
			(xy 41.763765 -67.128954) (xy 41.756008 -67.182909) (xy 41.740651 -67.23521) (xy 41.718007 -67.284793)
			(xy 41.688537 -67.330648) (xy 41.652841 -67.371843) (xy 41.611645 -67.407539) (xy 41.565789 -67.437008)
			(xy 41.516206 -67.459652) (xy 41.463905 -67.475008) (xy 41.409951 -67.482765) (xy 41.382696 -67.483228)
			(xy 41.355325 -67.482782) (xy 41.301144 -67.474962) (xy 41.24864 -67.459469) (xy 41.198894 -67.436623)
			(xy 41.152928 -67.406892) (xy 41.131998 -67.389248) (xy 41.131744 -67.388994) (xy 41.124649 -67.383419)
			(xy 41.107739 -67.377166) (xy 41.098724 -67.376802) (xy 41.031668 -67.376802) (xy 41.02265 -67.377143)
			(xy 41.005733 -67.383402) (xy 40.998648 -67.388994) (xy 40.998648 -67.389248) (xy 40.998394 -67.389248)
			(xy 40.977468 -67.406895) (xy 40.931495 -67.436608) (xy 40.881746 -67.459443) (xy 40.829243 -67.474932)
			(xy 40.775066 -67.482756) (xy 40.747696 -67.483228) (xy 40.720446 -67.482701) (xy 40.666502 -67.474945)
			(xy 40.614211 -67.45959) (xy 40.564636 -67.43695) (xy 40.518789 -67.407485) (xy 40.477601 -67.371796)
			(xy 40.441912 -67.330608) (xy 40.412448 -67.28476) (xy 40.389808 -67.235186) (xy 40.374454 -67.182894)
			(xy 40.366698 -67.12895) (xy 39.145464 -67.12895) (xy 39.145464 -67.488054) (xy 44.779182 -67.488054)
			(xy 44.783253 -67.432432) (xy 44.795379 -67.377995) (xy 44.815302 -67.325904) (xy 44.842598 -67.277269)
			(xy 44.876684 -67.233126) (xy 44.916833 -67.194417) (xy 44.962191 -67.161966) (xy 45.011791 -67.136465)
			(xy 45.064575 -67.118458) (xy 45.119418 -67.108328) (xy 45.175152 -67.106291) (xy 45.230589 -67.112391)
			(xy 45.284546 -67.126497) (xy 45.335875 -67.148309) (xy 45.383481 -67.177363) (xy 45.426349 -67.213038)
			(xy 45.463566 -67.254575) (xy 45.494339 -67.301088) (xy 45.518011 -67.351585) (xy 45.534079 -67.404992)
			(xy 45.542199 -67.460168) (xy 45.542708 -67.488054) (xy 45.542199 -67.51594) (xy 45.539014 -67.537584)
			(xy 46.07128 -67.537584) (xy 46.075351 -67.481962) (xy 46.087477 -67.427525) (xy 46.1074 -67.375434)
			(xy 46.134696 -67.326799) (xy 46.168782 -67.282656) (xy 46.208931 -67.243947) (xy 46.254289 -67.211496)
			(xy 46.303889 -67.185995) (xy 46.356673 -67.167988) (xy 46.411516 -67.157858) (xy 46.46725 -67.155821)
			(xy 46.522687 -67.161921) (xy 46.576644 -67.176027) (xy 46.627973 -67.197839) (xy 46.675579 -67.226893)
			(xy 46.718447 -67.262568) (xy 46.755664 -67.304105) (xy 46.786437 -67.350618) (xy 46.810109 -67.401115)
			(xy 46.826177 -67.454522) (xy 46.834297 -67.509698) (xy 46.834806 -67.537584) (xy 46.834297 -67.56547)
			(xy 46.830252 -67.592956) (xy 47.345344 -67.592956) (xy 47.349415 -67.537334) (xy 47.361541 -67.482897)
			(xy 47.381464 -67.430806) (xy 47.40876 -67.382171) (xy 47.442846 -67.338028) (xy 47.482995 -67.299319)
			(xy 47.528353 -67.266868) (xy 47.577953 -67.241367) (xy 47.630737 -67.22336) (xy 47.68558 -67.21323)
			(xy 47.741314 -67.211193) (xy 47.796751 -67.217293) (xy 47.850708 -67.231399) (xy 47.902037 -67.253211)
			(xy 47.949643 -67.282265) (xy 47.992511 -67.31794) (xy 48.029728 -67.359477) (xy 48.060501 -67.40599)
			(xy 48.084173 -67.456487) (xy 48.100241 -67.509894) (xy 48.108358 -67.565048) (xy 50.446716 -67.565048)
			(xy 50.446716 -67.510552) (xy 50.454472 -67.456611) (xy 50.469824 -67.404323) (xy 50.492462 -67.354751)
			(xy 50.521924 -67.308906) (xy 50.557611 -67.267721) (xy 50.598795 -67.232033) (xy 50.644639 -67.202569)
			(xy 50.69421 -67.179929) (xy 50.746497 -67.164574) (xy 50.800438 -67.156817) (xy 50.827686 -67.15633)
			(xy 50.855056 -67.156797) (xy 50.909236 -67.164613) (xy 50.961739 -67.180102) (xy 51.011486 -67.202944)
			(xy 51.057453 -67.232668) (xy 51.078384 -67.25031) (xy 51.078638 -67.250564) (xy 51.085733 -67.256138)
			(xy 51.102643 -67.262391) (xy 51.111658 -67.262756) (xy 51.178714 -67.262756) (xy 51.187733 -67.262415)
			(xy 51.20465 -67.256158) (xy 51.211734 -67.250564) (xy 51.211734 -67.25031) (xy 51.211988 -67.25031)
			(xy 51.232915 -67.232665) (xy 51.278889 -67.202953) (xy 51.328638 -67.180118) (xy 51.38114 -67.164629)
			(xy 51.435316 -67.156803) (xy 51.462686 -67.15633) (xy 51.489942 -67.156716) (xy 51.5439 -67.164472)
			(xy 51.596205 -67.179828) (xy 51.645792 -67.202472) (xy 51.691651 -67.231943) (xy 51.73285 -67.26764)
			(xy 51.768549 -67.308837) (xy 51.798021 -67.354696) (xy 51.820667 -67.404282) (xy 51.836025 -67.456586)
			(xy 51.843783 -67.510544) (xy 51.843783 -67.565056) (xy 51.836025 -67.619014) (xy 51.820667 -67.671318)
			(xy 51.798021 -67.720904) (xy 51.768549 -67.766763) (xy 51.73285 -67.80796) (xy 51.691651 -67.843657)
			(xy 51.645792 -67.873128) (xy 51.596205 -67.895772) (xy 51.5439 -67.911128) (xy 51.489942 -67.918884)
			(xy 51.462686 -67.919346) (xy 51.435315 -67.918901) (xy 51.381134 -67.91108) (xy 51.32863 -67.895587)
			(xy 51.278884 -67.87274) (xy 51.232918 -67.84301) (xy 51.211988 -67.825366) (xy 51.211734 -67.825112)
			(xy 51.204641 -67.819535) (xy 51.187729 -67.813282) (xy 51.178714 -67.81292) (xy 51.111658 -67.81292)
			(xy 51.102643 -67.813301) (xy 51.085726 -67.819531) (xy 51.078638 -67.825112) (xy 51.078638 -67.825366)
			(xy 51.078384 -67.825366) (xy 51.057427 -67.842974) (xy 51.011461 -67.872692) (xy 50.96172 -67.895534)
			(xy 50.909225 -67.911032) (xy 50.855054 -67.918868) (xy 50.827686 -67.919346) (xy 50.800438 -67.918783)
			(xy 50.746497 -67.911026) (xy 50.69421 -67.895671) (xy 50.644639 -67.873031) (xy 50.598795 -67.843567)
			(xy 50.557611 -67.807879) (xy 50.521924 -67.766694) (xy 50.492462 -67.720849) (xy 50.469824 -67.671277)
			(xy 50.454472 -67.618989) (xy 50.446716 -67.565048) (xy 48.108358 -67.565048) (xy 48.108361 -67.56507)
			(xy 48.10887 -67.592956) (xy 48.108361 -67.620842) (xy 48.100241 -67.676018) (xy 48.084173 -67.729425)
			(xy 48.060501 -67.779922) (xy 48.029728 -67.826435) (xy 47.992511 -67.867972) (xy 47.949643 -67.903647)
			(xy 47.902037 -67.932701) (xy 47.850708 -67.954513) (xy 47.796751 -67.968619) (xy 47.741314 -67.974719)
			(xy 47.68558 -67.972682) (xy 47.630737 -67.962552) (xy 47.577953 -67.944545) (xy 47.528353 -67.919044)
			(xy 47.482995 -67.886593) (xy 47.442846 -67.847884) (xy 47.40876 -67.803741) (xy 47.381464 -67.755106)
			(xy 47.361541 -67.703015) (xy 47.349415 -67.648578) (xy 47.345344 -67.592956) (xy 46.830252 -67.592956)
			(xy 46.826177 -67.620646) (xy 46.810109 -67.674053) (xy 46.786437 -67.72455) (xy 46.755664 -67.771063)
			(xy 46.718447 -67.8126) (xy 46.675579 -67.848275) (xy 46.627973 -67.877329) (xy 46.576644 -67.899141)
			(xy 46.522687 -67.913247) (xy 46.46725 -67.919347) (xy 46.411516 -67.91731) (xy 46.356673 -67.90718)
			(xy 46.303889 -67.889173) (xy 46.254289 -67.863672) (xy 46.208931 -67.831221) (xy 46.168782 -67.792512)
			(xy 46.134696 -67.748369) (xy 46.1074 -67.699734) (xy 46.087477 -67.647643) (xy 46.075351 -67.593206)
			(xy 46.07128 -67.537584) (xy 45.539014 -67.537584) (xy 45.534079 -67.571116) (xy 45.518011 -67.624523)
			(xy 45.494339 -67.67502) (xy 45.463566 -67.721533) (xy 45.426349 -67.76307) (xy 45.383481 -67.798745)
			(xy 45.335875 -67.827799) (xy 45.284546 -67.849611) (xy 45.230589 -67.863717) (xy 45.175152 -67.869817)
			(xy 45.119418 -67.86778) (xy 45.064575 -67.85765) (xy 45.011791 -67.839643) (xy 44.962191 -67.814142)
			(xy 44.916833 -67.781691) (xy 44.876684 -67.742982) (xy 44.842598 -67.698839) (xy 44.815302 -67.650204)
			(xy 44.795379 -67.598113) (xy 44.783253 -67.543676) (xy 44.779182 -67.488054) (xy 39.145464 -67.488054)
			(xy 39.145464 -68.586604) (xy 42.625264 -68.586604) (xy 42.625717 -68.559233) (xy 42.633535 -68.505053)
			(xy 42.649027 -68.452549) (xy 42.671872 -68.402802) (xy 42.701601 -68.356837) (xy 42.719244 -68.335906)
			(xy 42.719498 -68.335652) (xy 42.725069 -68.328555) (xy 42.731325 -68.311646) (xy 42.73169 -68.302632)
			(xy 42.73169 -68.235576) (xy 42.731347 -68.226558) (xy 42.72509 -68.209641) (xy 42.719498 -68.202556)
			(xy 42.719244 -68.202556) (xy 42.719244 -68.202302) (xy 42.701599 -68.181374) (xy 42.671887 -68.135401)
			(xy 42.649051 -68.085652) (xy 42.633562 -68.033151) (xy 42.625736 -67.978974) (xy 42.625264 -67.951604)
			(xy 42.625781 -67.924354) (xy 42.633537 -67.870409) (xy 42.64889 -67.818117) (xy 42.671529 -67.768541)
			(xy 42.700992 -67.722692) (xy 42.73668 -67.681503) (xy 42.777866 -67.645811) (xy 42.823713 -67.616344)
			(xy 42.873287 -67.593701) (xy 42.925578 -67.578343) (xy 42.979522 -67.570584) (xy 43.006772 -67.570096)
			(xy 43.033088 -67.570517) (xy 43.085218 -67.577761) (xy 43.135862 -67.59209) (xy 43.18406 -67.613231)
			(xy 43.228903 -67.640785) (xy 43.269541 -67.674231) (xy 43.287696 -67.693286) (xy 43.295219 -67.700686)
			(xy 43.314498 -67.709212) (xy 43.325034 -67.709796) (xy 43.39971 -67.709796) (xy 43.410262 -67.709287)
			(xy 43.429557 -67.700738) (xy 43.437048 -67.693286) (xy 43.455184 -67.674212) (xy 43.495819 -67.640757)
			(xy 43.540663 -67.6132) (xy 43.588867 -67.592065) (xy 43.639518 -67.577752) (xy 43.691655 -67.570532)
			(xy 43.717972 -67.570096) (xy 43.745342 -67.570579) (xy 43.79952 -67.578393) (xy 43.852023 -67.593878)
			(xy 43.90177 -67.616716) (xy 43.947738 -67.646437) (xy 43.96867 -67.664076) (xy 43.968924 -67.66433)
			(xy 43.975997 -67.669936) (xy 43.992924 -67.67617) (xy 44.001944 -67.676522) (xy 44.069 -67.676522)
			(xy 44.078016 -67.67616) (xy 44.094933 -67.669915) (xy 44.10202 -67.66433) (xy 44.10202 -67.664076)
			(xy 44.102274 -67.664076) (xy 44.123202 -67.646432) (xy 44.169176 -67.616722) (xy 44.218925 -67.593887)
			(xy 44.271426 -67.578397) (xy 44.325603 -67.57057) (xy 44.352972 -67.570096) (xy 44.380224 -67.570581)
			(xy 44.434175 -67.578335) (xy 44.486472 -67.593687) (xy 44.536053 -67.616327) (xy 44.581906 -67.645792)
			(xy 44.623099 -67.681484) (xy 44.658793 -67.722675) (xy 44.688262 -67.768526) (xy 44.710904 -67.818105)
			(xy 44.72626 -67.870402) (xy 44.734017 -67.924352) (xy 44.73448 -67.951604) (xy 44.734021 -67.978975)
			(xy 44.726202 -68.033154) (xy 44.710712 -68.085658) (xy 44.687868 -68.135404) (xy 44.658142 -68.181371)
			(xy 44.6405 -68.202302) (xy 44.640246 -68.202556) (xy 44.634665 -68.209646) (xy 44.628416 -68.22656)
			(xy 44.628054 -68.235576) (xy 44.628054 -68.302632) (xy 44.628384 -68.311652) (xy 44.634649 -68.328569)
			(xy 44.640246 -68.335652) (xy 44.6405 -68.335652) (xy 44.6405 -68.335906) (xy 44.658155 -68.356825)
			(xy 44.687865 -68.402801) (xy 44.710698 -68.452552) (xy 44.726185 -68.505056) (xy 44.734008 -68.559234)
			(xy 44.73448 -68.586604) (xy 44.734048 -68.613858) (xy 44.72629 -68.667812) (xy 44.710932 -68.720112)
			(xy 44.694299 -68.75653) (xy 48.170338 -68.75653) (xy 48.170812 -68.72916) (xy 48.178627 -68.674981)
			(xy 48.194113 -68.622477) (xy 48.216954 -68.57273) (xy 48.246677 -68.526764) (xy 48.264318 -68.505832)
			(xy 48.264572 -68.505578) (xy 48.270182 -68.498508) (xy 48.276413 -68.481578) (xy 48.276764 -68.472558)
			(xy 48.276764 -68.405502) (xy 48.276414 -68.396484) (xy 48.270162 -68.379567) (xy 48.264572 -68.372482)
			(xy 48.264318 -68.372482) (xy 48.264318 -68.372228) (xy 48.246681 -68.351294) (xy 48.216969 -68.305322)
			(xy 48.194132 -68.255575) (xy 48.17864 -68.203075) (xy 48.170812 -68.148899) (xy 48.170338 -68.12153)
			(xy 48.170783 -68.094276) (xy 48.178537 -68.040322) (xy 48.193892 -67.988021) (xy 48.216534 -67.938438)
			(xy 48.246004 -67.892582) (xy 48.281699 -67.851388) (xy 48.322895 -67.815694) (xy 48.368752 -67.786227)
			(xy 48.418336 -67.763586) (xy 48.470637 -67.748234) (xy 48.524592 -67.740482) (xy 48.551846 -67.740022)
			(xy 48.579215 -67.740514) (xy 48.633394 -67.748325) (xy 48.685897 -67.763808) (xy 48.735644 -67.786644)
			(xy 48.781612 -67.816363) (xy 48.802544 -67.834002) (xy 48.802798 -67.834256) (xy 48.809876 -67.839855)
			(xy 48.8268 -67.846093) (xy 48.835818 -67.846448) (xy 48.902874 -67.846448) (xy 48.911891 -67.84609)
			(xy 48.928809 -67.839844) (xy 48.935894 -67.834256) (xy 48.935894 -67.834002) (xy 48.936148 -67.834002)
			(xy 48.957089 -67.816374) (xy 49.003059 -67.786661) (xy 49.052805 -67.763822) (xy 49.105303 -67.748329)
			(xy 49.159477 -67.740498) (xy 49.186846 -67.740022) (xy 49.213161 -67.740452) (xy 49.265292 -67.747693)
			(xy 49.315935 -67.762019) (xy 49.364134 -67.783159) (xy 49.408977 -67.810712) (xy 49.449615 -67.844157)
			(xy 49.46777 -67.863212) (xy 49.475299 -67.870604) (xy 49.494574 -67.879134) (xy 49.505108 -67.879722)
			(xy 49.579784 -67.879722) (xy 49.590333 -67.879191) (xy 49.609628 -67.870657) (xy 49.617122 -67.863212)
			(xy 49.635276 -67.844155) (xy 49.675906 -67.810698) (xy 49.720746 -67.783138) (xy 49.768948 -67.762)
			(xy 49.819595 -67.747683) (xy 49.87173 -67.74046) (xy 49.898046 -67.740022) (xy 49.9253 -67.740435)
			(xy 49.979252 -67.748199) (xy 50.03155 -67.763561) (xy 50.081129 -67.78621) (xy 50.126981 -67.815684)
			(xy 50.168171 -67.851383) (xy 50.203862 -67.89258) (xy 50.233327 -67.938438) (xy 50.255965 -67.988022)
			(xy 50.271318 -68.040323) (xy 50.27907 -68.094276) (xy 50.279554 -68.12153) (xy 50.279117 -68.148901)
			(xy 50.271294 -68.203082) (xy 50.255798 -68.255586) (xy 50.23295 -68.305332) (xy 50.203219 -68.351298)
			(xy 50.185574 -68.372228) (xy 50.18532 -68.372482) (xy 50.179725 -68.379563) (xy 50.173486 -68.396484)
			(xy 50.173128 -68.405502) (xy 50.173128 -68.472558) (xy 50.173499 -68.481574) (xy 50.179736 -68.498491)
			(xy 50.18532 -68.505578) (xy 50.185574 -68.505578) (xy 50.185574 -68.505832) (xy 50.203191 -68.526782)
			(xy 50.232907 -68.57275) (xy 50.255747 -68.622492) (xy 50.271244 -68.674989) (xy 50.279077 -68.729162)
			(xy 50.279554 -68.75653) (xy 50.27905 -68.78378) (xy 50.271291 -68.837725) (xy 50.255934 -68.890016)
			(xy 50.233293 -68.93959) (xy 50.203828 -68.985438) (xy 50.168138 -69.026627) (xy 50.126951 -69.062318)
			(xy 50.081105 -69.091785) (xy 50.031531 -69.114429) (xy 49.97924 -69.129787) (xy 49.925296 -69.137549)
			(xy 49.898046 -69.138038) (xy 49.87173 -69.137626) (xy 49.819598 -69.130383) (xy 49.768954 -69.116054)
			(xy 49.720754 -69.094911) (xy 49.675912 -69.067355) (xy 49.635276 -69.033905) (xy 49.617122 -69.014848)
			(xy 49.609588 -69.007461) (xy 49.590318 -68.998927) (xy 49.579784 -68.998338) (xy 49.505108 -68.998338)
			(xy 49.494556 -68.998847) (xy 49.47526 -69.007395) (xy 49.46777 -69.014848) (xy 49.449631 -69.03392)
			(xy 49.408997 -69.067374) (xy 49.364153 -69.09493) (xy 49.315949 -69.116065) (xy 49.265299 -69.130379)
			(xy 49.213163 -69.137601) (xy 49.186846 -69.138038) (xy 49.159476 -69.13756) (xy 49.105297 -69.129747)
			(xy 49.052793 -69.114262) (xy 49.003046 -69.091422) (xy 48.957079 -69.061699) (xy 48.936148 -69.044058)
			(xy 48.935894 -69.043804) (xy 48.928813 -69.038209) (xy 48.911892 -69.031967) (xy 48.902874 -69.031612)
			(xy 48.835818 -69.031612) (xy 48.826802 -69.031975) (xy 48.809884 -69.038218) (xy 48.802798 -69.043804)
			(xy 48.802798 -69.044058) (xy 48.802544 -69.044058) (xy 48.781601 -69.061683) (xy 48.735632 -69.091399)
			(xy 48.685887 -69.114238) (xy 48.633389 -69.129732) (xy 48.579215 -69.137563) (xy 48.551846 -69.138038)
			(xy 48.524596 -69.137502) (xy 48.470649 -69.129752) (xy 48.418354 -69.114403) (xy 48.368776 -69.091768)
			(xy 48.322924 -69.062308) (xy 48.281732 -69.026622) (xy 48.246038 -68.985437) (xy 48.216568 -68.939591)
			(xy 48.193923 -68.890017) (xy 48.178564 -68.837725) (xy 48.170803 -68.78378) (xy 48.170338 -68.75653)
			(xy 44.694299 -68.75653) (xy 44.688287 -68.769694) (xy 44.658816 -68.815548) (xy 44.623119 -68.856742)
			(xy 44.581923 -68.892435) (xy 44.536066 -68.921902) (xy 44.486482 -68.944543) (xy 44.43418 -68.959897)
			(xy 44.380226 -68.967651) (xy 44.352972 -68.968112) (xy 44.325601 -68.967659) (xy 44.271422 -68.959838)
			(xy 44.218919 -68.944345) (xy 44.169172 -68.921501) (xy 44.123206 -68.891774) (xy 44.102274 -68.874132)
			(xy 44.10202 -68.873878) (xy 44.094934 -68.868291) (xy 44.078017 -68.862045) (xy 44.069 -68.861686)
			(xy 44.001944 -68.861686) (xy 43.99293 -68.862067) (xy 43.976013 -68.868298) (xy 43.968924 -68.873878)
			(xy 43.968924 -68.874132) (xy 43.96867 -68.874132) (xy 43.947726 -68.891757) (xy 43.901756 -68.92147)
			(xy 43.852012 -68.944308) (xy 43.799514 -68.959802) (xy 43.74534 -68.967635) (xy 43.717972 -68.968112)
			(xy 43.691658 -68.967659) (xy 43.639529 -68.960421) (xy 43.588886 -68.946099) (xy 43.540687 -68.924963)
			(xy 43.495844 -68.897415) (xy 43.455204 -68.863974) (xy 43.437048 -68.844922) (xy 43.429545 -68.837499)
			(xy 43.410251 -68.828986) (xy 43.39971 -68.828412) (xy 43.325034 -68.828412) (xy 43.314484 -68.828942)
			(xy 43.295189 -68.837476) (xy 43.287696 -68.844922) (xy 43.26954 -68.863977) (xy 43.22891 -68.897433)
			(xy 43.184069 -68.924992) (xy 43.135869 -68.94613) (xy 43.085222 -68.960448) (xy 43.033088 -68.967673)
			(xy 43.006772 -68.968112) (xy 42.97952 -68.967648) (xy 42.925572 -68.959888) (xy 42.873277 -68.94453)
			(xy 42.8237 -68.921885) (xy 42.77785 -68.892417) (xy 42.73666 -68.856723) (xy 42.700969 -68.815531)
			(xy 42.671503 -68.769679) (xy 42.648862 -68.7201) (xy 42.633507 -68.667805) (xy 42.62575 -68.613856)
			(xy 42.625264 -68.586604) (xy 39.145464 -68.586604) (xy 39.145464 -71.555864) (xy 45.194472 -71.555864)
			(xy 45.198543 -71.500242) (xy 45.210669 -71.445805) (xy 45.230592 -71.393714) (xy 45.257888 -71.345079)
			(xy 45.291974 -71.300936) (xy 45.332123 -71.262227) (xy 45.377481 -71.229776) (xy 45.427081 -71.204275)
			(xy 45.479865 -71.186268) (xy 45.534708 -71.176138) (xy 45.590442 -71.174101) (xy 45.645879 -71.180201)
			(xy 45.699836 -71.194307) (xy 45.751165 -71.216119) (xy 45.798771 -71.245173) (xy 45.841639 -71.280848)
			(xy 45.878856 -71.322385) (xy 45.909629 -71.368898) (xy 45.933301 -71.419395) (xy 45.949369 -71.472802)
			(xy 45.957489 -71.527978) (xy 45.957998 -71.555864) (xy 45.957489 -71.58375) (xy 45.95165 -71.623428)
			(xy 46.703486 -71.623428) (xy 46.707557 -71.567806) (xy 46.719683 -71.513369) (xy 46.739606 -71.461278)
			(xy 46.766902 -71.412643) (xy 46.800988 -71.3685) (xy 46.841137 -71.329791) (xy 46.886495 -71.29734)
			(xy 46.936095 -71.271839) (xy 46.988879 -71.253832) (xy 47.043722 -71.243702) (xy 47.099456 -71.241665)
			(xy 47.154893 -71.247765) (xy 47.20885 -71.261871) (xy 47.260179 -71.283683) (xy 47.307785 -71.312737)
			(xy 47.350653 -71.348412) (xy 47.38787 -71.389949) (xy 47.418643 -71.436462) (xy 47.442315 -71.486959)
			(xy 47.458383 -71.540366) (xy 47.466503 -71.595542) (xy 47.467012 -71.623428) (xy 47.466503 -71.651314)
			(xy 47.458383 -71.70649) (xy 47.442315 -71.759897) (xy 47.418643 -71.810394) (xy 47.38787 -71.856907)
			(xy 47.350653 -71.898444) (xy 47.307785 -71.934119) (xy 47.260179 -71.963173) (xy 47.20885 -71.984985)
			(xy 47.154893 -71.999091) (xy 47.099456 -72.005191) (xy 47.043722 -72.003154) (xy 46.988879 -71.993024)
			(xy 46.936095 -71.975017) (xy 46.886495 -71.949516) (xy 46.841137 -71.917065) (xy 46.800988 -71.878356)
			(xy 46.766902 -71.834213) (xy 46.739606 -71.785578) (xy 46.719683 -71.733487) (xy 46.707557 -71.67905)
			(xy 46.703486 -71.623428) (xy 45.95165 -71.623428) (xy 45.949369 -71.638926) (xy 45.933301 -71.692333)
			(xy 45.909629 -71.74283) (xy 45.878856 -71.789343) (xy 45.841639 -71.83088) (xy 45.798771 -71.866555)
			(xy 45.751165 -71.895609) (xy 45.699836 -71.917421) (xy 45.645879 -71.931527) (xy 45.590442 -71.937627)
			(xy 45.534708 -71.93559) (xy 45.479865 -71.92546) (xy 45.427081 -71.907453) (xy 45.377481 -71.881952)
			(xy 45.332123 -71.849501) (xy 45.291974 -71.810792) (xy 45.257888 -71.766649) (xy 45.230592 -71.718014)
			(xy 45.210669 -71.665923) (xy 45.198543 -71.611486) (xy 45.194472 -71.555864) (xy 39.145464 -71.555864)
			(xy 39.145464 -74.585068) (xy 39.145534 -74.588874) (xy 39.146689 -74.596398) (xy 39.14775 -74.600054)
			(xy 39.149737 -74.605857) (xy 39.156027 -74.616383) (xy 39.160196 -74.620882) (xy 41.803828 -77.264514)
			(xy 43.32732 -78.787752) (xy 43.331181 -78.791477) (xy 43.340151 -78.797362) (xy 43.3451 -78.799436)
			(xy 43.347894 -78.800198) (xy 43.373452 -78.808634) (xy 43.422087 -78.831688) (xy 43.466999 -78.861345)
			(xy 43.5073 -78.897019) (xy 43.542189 -78.938001) (xy 43.570973 -78.983479) (xy 43.593083 -79.032549)
			(xy 43.608079 -79.084239) (xy 43.615664 -79.137523) (xy 43.616118 -79.164434) (xy 43.61563 -79.191684)
			(xy 43.60787 -79.245629) (xy 43.592512 -79.29792) (xy 43.569869 -79.347493) (xy 43.540402 -79.39334)
			(xy 43.50471 -79.434527) (xy 43.463521 -79.470216) (xy 43.417672 -79.49968) (xy 43.368097 -79.52232)
			(xy 43.315805 -79.537675) (xy 43.26186 -79.545432) (xy 43.23461 -79.545942) (xy 43.207709 -79.545482)
			(xy 43.154439 -79.537925) (xy 43.102759 -79.522959) (xy 43.053695 -79.500882) (xy 43.008218 -79.47213)
			(xy 42.967232 -79.437275) (xy 42.931549 -79.397008) (xy 42.901876 -79.352127) (xy 42.878803 -79.303523)
			(xy 42.870374 -79.277972) (xy 42.870374 -79.277718) (xy 42.869612 -79.274924) (xy 42.867527 -79.269982)
			(xy 42.861635 -79.261021) (xy 42.857928 -79.257144) (xy 42.300652 -78.699868) (xy 42.291612 -78.691909)
			(xy 42.268688 -78.684631) (xy 42.25671 -78.685898) (xy 42.170858 -78.70317) (xy 42.159869 -78.706298)
			(xy 42.141929 -78.720399) (xy 42.136314 -78.730348) (xy 42.135044 -78.733396) (xy 42.123886 -78.7593)
			(xy 42.095059 -78.807777) (xy 42.059408 -78.851481) (xy 42.017711 -78.889461) (xy 41.970877 -78.920887)
			(xy 41.919927 -78.945076) (xy 41.865971 -78.9615) (xy 41.810184 -78.969802) (xy 41.781984 -78.970378)
			(xy 41.769246 -78.970299) (xy 41.743825 -78.968645) (xy 41.731184 -78.967076) (xy 41.700964 -78.962416)
			(xy 41.642438 -78.944718) (xy 41.587494 -78.917893) (xy 41.537545 -78.882629) (xy 41.515284 -78.861666)
			(xy 41.493238 -78.83921) (xy 41.45607 -78.788434) (xy 41.427732 -78.732251) (xy 41.417748 -78.702408)
			(xy 41.417748 -78.702154) (xy 41.416986 -78.69936) (xy 41.414903 -78.694417) (xy 41.409013 -78.685454)
			(xy 41.405302 -78.68158) (xy 38.632638 -75.908916) (xy 38.625237 -75.902242) (xy 38.606827 -75.894659)
			(xy 38.586918 -75.89467) (xy 38.57752 -75.897994) (xy 38.571932 -75.90028) (xy 38.563042 -75.903836)
			(xy 38.554406 -75.91679) (xy 38.550537 -75.923118) (xy 38.546267 -75.937317) (xy 38.546024 -75.94473)
			(xy 38.546024 -85.025538) (xy 44.856389 -85.025538) (xy 44.856389 -84.896398) (xy 44.864339 -84.767503)
			(xy 44.880209 -84.639343) (xy 44.903938 -84.512402) (xy 44.935437 -84.387163) (xy 44.974586 -84.2641)
			(xy 45.021237 -84.143681) (xy 45.075212 -84.026362) (xy 45.136307 -83.912588) (xy 45.20429 -83.802791)
			(xy 45.278904 -83.697388) (xy 45.359865 -83.596778) (xy 45.446865 -83.501343) (xy 45.539576 -83.411444)
			(xy 45.637646 -83.327423) (xy 45.740701 -83.249599) (xy 45.848352 -83.178267) (xy 45.960191 -83.113697)
			(xy 46.075792 -83.056135) (xy 46.194717 -83.005798) (xy 46.316516 -82.962878) (xy 46.440726 -82.927537)
			(xy 46.566875 -82.89991) (xy 46.694487 -82.880101) (xy 46.823076 -82.868185) (xy 46.952154 -82.864209)
			(xy 47.081232 -82.868185) (xy 47.209821 -82.880101) (xy 47.337433 -82.89991) (xy 47.463582 -82.927537)
			(xy 47.587792 -82.962878) (xy 47.709591 -83.005798) (xy 47.828516 -83.056135) (xy 47.944117 -83.113697)
			(xy 48.055956 -83.178267) (xy 48.163607 -83.249599) (xy 48.266662 -83.327423) (xy 48.364732 -83.411444)
			(xy 48.457443 -83.501343) (xy 48.544443 -83.596778) (xy 48.625404 -83.697388) (xy 48.700018 -83.802791)
			(xy 48.768001 -83.912588) (xy 48.829096 -84.026362) (xy 48.883071 -84.143681) (xy 48.929722 -84.2641)
			(xy 48.968871 -84.387163) (xy 49.00037 -84.512402) (xy 49.024099 -84.639343) (xy 49.039969 -84.767503)
			(xy 49.047919 -84.896398) (xy 49.048416 -84.960968) (xy 49.047919 -85.025538) (xy 49.039969 -85.154433)
			(xy 49.024099 -85.282593) (xy 49.00037 -85.409534) (xy 48.968871 -85.534773) (xy 48.929722 -85.657836)
			(xy 48.883071 -85.778255) (xy 48.829096 -85.895574) (xy 48.768001 -86.009348) (xy 48.700018 -86.119145)
			(xy 48.625404 -86.224548) (xy 48.544443 -86.325158) (xy 48.457443 -86.420593) (xy 48.364732 -86.510492)
			(xy 48.266662 -86.594513) (xy 48.163607 -86.672337) (xy 48.055956 -86.743669) (xy 47.944117 -86.808239)
			(xy 47.828516 -86.865801) (xy 47.709591 -86.916138) (xy 47.587792 -86.959058) (xy 47.463582 -86.994399)
			(xy 47.337433 -87.022026) (xy 47.209821 -87.041835) (xy 47.081232 -87.053751) (xy 46.952154 -87.057728)
			(xy 46.823076 -87.053751) (xy 46.694487 -87.041835) (xy 46.566875 -87.022026) (xy 46.440726 -86.994399)
			(xy 46.316516 -86.959058) (xy 46.194717 -86.916138) (xy 46.075792 -86.865801) (xy 45.960191 -86.808239)
			(xy 45.848352 -86.743669) (xy 45.740701 -86.672337) (xy 45.637646 -86.594513) (xy 45.539576 -86.510492)
			(xy 45.446865 -86.420593) (xy 45.359865 -86.325158) (xy 45.278904 -86.224548) (xy 45.20429 -86.119145)
			(xy 45.136307 -86.009348) (xy 45.075212 -85.895574) (xy 45.021237 -85.778255) (xy 44.974586 -85.657836)
			(xy 44.935437 -85.534773) (xy 44.903938 -85.409534) (xy 44.880209 -85.282593) (xy 44.864339 -85.154433)
			(xy 44.856389 -85.025538) (xy 38.546024 -85.025538) (xy 38.546024 -89.3699) (xy 38.545564 -89.402754)
			(xy 38.538207 -89.468048) (xy 38.523587 -89.532108) (xy 38.501887 -89.594129) (xy 38.47338 -89.653331)
			(xy 38.438424 -89.708969) (xy 38.397459 -89.760343) (xy 38.374574 -89.78392) (xy 32.943546 -95.214948)
			(xy 47.274239 -95.214948) (xy 47.278194 -95.123111) (xy 47.290029 -95.031954) (xy 47.309656 -94.942151)
			(xy 47.33693 -94.854369) (xy 47.37165 -94.769255) (xy 47.413558 -94.687442) (xy 47.462344 -94.609534)
			(xy 47.517647 -94.536109) (xy 47.579057 -94.467709) (xy 47.646119 -94.404842) (xy 47.718338 -94.347972)
			(xy 47.795178 -94.297521) (xy 47.876071 -94.253862) (xy 47.960417 -94.217319) (xy 48.047593 -94.188162)
			(xy 48.136952 -94.166608) (xy 48.227833 -94.152814) (xy 48.319564 -94.146884) (xy 48.411465 -94.148862)
			(xy 48.502856 -94.158733) (xy 48.59306 -94.176423) (xy 48.681409 -94.201803) (xy 48.767249 -94.234683)
			(xy 48.849945 -94.274821) (xy 48.928885 -94.32192) (xy 49.003483 -94.37563) (xy 49.073189 -94.435554)
			(xy 49.137484 -94.501248) (xy 49.195895 -94.572226) (xy 49.247987 -94.647963) (xy 49.293376 -94.727898)
			(xy 49.331726 -94.811438) (xy 49.362751 -94.897966) (xy 49.386224 -94.986841) (xy 49.40197 -95.077405)
			(xy 49.409872 -95.168987) (xy 49.410366 -95.214948) (xy 49.409872 -95.260909) (xy 49.40197 -95.352491)
			(xy 49.386224 -95.443055) (xy 49.362751 -95.53193) (xy 49.331726 -95.618458) (xy 49.293376 -95.701998)
			(xy 49.247987 -95.781933) (xy 49.195895 -95.85767) (xy 49.137484 -95.928648) (xy 49.073189 -95.994342)
			(xy 49.003483 -96.054266) (xy 48.928885 -96.107976) (xy 48.849945 -96.155075) (xy 48.767249 -96.195213)
			(xy 48.681409 -96.228093) (xy 48.59306 -96.253473) (xy 48.502856 -96.271163) (xy 48.411465 -96.281034)
			(xy 48.319564 -96.283012) (xy 48.227833 -96.277082) (xy 48.136952 -96.263288) (xy 48.047593 -96.241734)
			(xy 47.960417 -96.212577) (xy 47.876071 -96.176034) (xy 47.795178 -96.132375) (xy 47.718338 -96.081924)
			(xy 47.646119 -96.025054) (xy 47.579057 -95.962187) (xy 47.517647 -95.893787) (xy 47.462344 -95.820362)
			(xy 47.413558 -95.742454) (xy 47.37165 -95.660641) (xy 47.33693 -95.575527) (xy 47.309656 -95.487745)
			(xy 47.290029 -95.397942) (xy 47.278194 -95.306785) (xy 47.274239 -95.214948) (xy 32.943546 -95.214948)
			(xy 31.994094 -96.1644) (xy 37.225476 -96.1644) (xy 37.229547 -96.108778) (xy 37.241673 -96.054341)
			(xy 37.261596 -96.00225) (xy 37.288892 -95.953615) (xy 37.322978 -95.909472) (xy 37.363127 -95.870763)
			(xy 37.408485 -95.838312) (xy 37.458085 -95.812811) (xy 37.510869 -95.794804) (xy 37.565712 -95.784674)
			(xy 37.621446 -95.782637) (xy 37.676883 -95.788737) (xy 37.73084 -95.802843) (xy 37.782169 -95.824655)
			(xy 37.829775 -95.853709) (xy 37.872643 -95.889384) (xy 37.90986 -95.930921) (xy 37.940633 -95.977434)
			(xy 37.964305 -96.027931) (xy 37.980373 -96.081338) (xy 37.988493 -96.136514) (xy 37.989002 -96.1644)
			(xy 37.988493 -96.192286) (xy 37.980373 -96.247462) (xy 37.964305 -96.300869) (xy 37.940633 -96.351366)
			(xy 37.90986 -96.397879) (xy 37.872643 -96.439416) (xy 37.829775 -96.475091) (xy 37.782169 -96.504145)
			(xy 37.73084 -96.525957) (xy 37.676883 -96.540063) (xy 37.621446 -96.546163) (xy 37.565712 -96.544126)
			(xy 37.510869 -96.533996) (xy 37.458085 -96.515989) (xy 37.408485 -96.490488) (xy 37.363127 -96.458037)
			(xy 37.322978 -96.419328) (xy 37.288892 -96.375185) (xy 37.261596 -96.32655) (xy 37.241673 -96.274459)
			(xy 37.229547 -96.220022) (xy 37.225476 -96.1644) (xy 31.994094 -96.1644) (xy 30.978094 -97.1804)
			(xy 37.225476 -97.1804) (xy 37.229547 -97.124778) (xy 37.241673 -97.070341) (xy 37.261596 -97.01825)
			(xy 37.288892 -96.969615) (xy 37.322978 -96.925472) (xy 37.363127 -96.886763) (xy 37.408485 -96.854312)
			(xy 37.458085 -96.828811) (xy 37.510869 -96.810804) (xy 37.565712 -96.800674) (xy 37.621446 -96.798637)
			(xy 37.676883 -96.804737) (xy 37.73084 -96.818843) (xy 37.782169 -96.840655) (xy 37.829775 -96.869709)
			(xy 37.872643 -96.905384) (xy 37.90986 -96.946921) (xy 37.940633 -96.993434) (xy 37.964305 -97.043931)
			(xy 37.967842 -97.055686) (xy 51.605432 -97.055686) (xy 51.609503 -97.000064) (xy 51.621629 -96.945627)
			(xy 51.641552 -96.893536) (xy 51.668848 -96.844901) (xy 51.702934 -96.800758) (xy 51.743083 -96.762049)
			(xy 51.788441 -96.729598) (xy 51.838041 -96.704097) (xy 51.890825 -96.68609) (xy 51.945668 -96.67596)
			(xy 52.001402 -96.673923) (xy 52.056839 -96.680023) (xy 52.110796 -96.694129) (xy 52.162125 -96.715941)
			(xy 52.209731 -96.744995) (xy 52.252599 -96.78067) (xy 52.289816 -96.822207) (xy 52.320589 -96.86872)
			(xy 52.344261 -96.919217) (xy 52.360329 -96.972624) (xy 52.368449 -97.0278) (xy 52.368958 -97.055686)
			(xy 52.368449 -97.083572) (xy 52.360329 -97.138748) (xy 52.344261 -97.192155) (xy 52.320589 -97.242652)
			(xy 52.289816 -97.289165) (xy 52.252599 -97.330702) (xy 52.209731 -97.366377) (xy 52.162125 -97.395431)
			(xy 52.110796 -97.417243) (xy 52.056839 -97.431349) (xy 52.001402 -97.437449) (xy 51.945668 -97.435412)
			(xy 51.890825 -97.425282) (xy 51.838041 -97.407275) (xy 51.788441 -97.381774) (xy 51.743083 -97.349323)
			(xy 51.702934 -97.310614) (xy 51.668848 -97.266471) (xy 51.641552 -97.217836) (xy 51.621629 -97.165745)
			(xy 51.609503 -97.111308) (xy 51.605432 -97.055686) (xy 37.967842 -97.055686) (xy 37.980373 -97.097338)
			(xy 37.988493 -97.152514) (xy 37.989002 -97.1804) (xy 37.988493 -97.208286) (xy 37.980373 -97.263462)
			(xy 37.964305 -97.316869) (xy 37.940633 -97.367366) (xy 37.90986 -97.413879) (xy 37.872643 -97.455416)
			(xy 37.829775 -97.491091) (xy 37.782169 -97.520145) (xy 37.73084 -97.541957) (xy 37.676883 -97.556063)
			(xy 37.621446 -97.562163) (xy 37.565712 -97.560126) (xy 37.510869 -97.549996) (xy 37.458085 -97.531989)
			(xy 37.408485 -97.506488) (xy 37.363127 -97.474037) (xy 37.322978 -97.435328) (xy 37.288892 -97.391185)
			(xy 37.261596 -97.34255) (xy 37.241673 -97.290459) (xy 37.229547 -97.236022) (xy 37.225476 -97.1804)
			(xy 30.978094 -97.1804) (xy 30.950916 -97.207578) (xy 30.947614 -97.211642) (xy 30.943478 -97.218152)
			(xy 30.938946 -97.232889) (xy 30.938724 -97.240598) (xy 30.938724 -97.790508) (xy 30.938269 -97.823364)
			(xy 30.930922 -97.888663) (xy 30.91631 -97.952729) (xy 30.894617 -98.014757) (xy 30.866116 -98.073965)
			(xy 30.831165 -98.129611) (xy 30.790204 -98.180993) (xy 30.767274 -98.204528) (xy 28.793948 -100.177854)
			(xy 37.31006 -100.177854) (xy 37.31006 -99.314254) (xy 37.31055 -99.284286) (xy 37.318373 -99.224864)
			(xy 37.333886 -99.166971) (xy 37.356822 -99.111598) (xy 37.386789 -99.059692) (xy 37.423276 -99.012142)
			(xy 37.465656 -98.969762) (xy 37.513206 -98.933275) (xy 37.565112 -98.903308) (xy 37.620485 -98.880372)
			(xy 37.678378 -98.864859) (xy 37.7378 -98.857036) (xy 37.797736 -98.857036) (xy 37.857158 -98.864859)
			(xy 37.915051 -98.880372) (xy 37.970424 -98.903308) (xy 38.02233 -98.933275) (xy 38.06988 -98.969762)
			(xy 38.11226 -99.012142) (xy 38.148747 -99.059692) (xy 38.178714 -99.111598) (xy 38.20165 -99.166971)
			(xy 38.217163 -99.224864) (xy 38.224986 -99.284286) (xy 38.225476 -99.314254) (xy 38.225476 -100.177854)
			(xy 38.224986 -100.207822) (xy 38.217163 -100.267244) (xy 38.20165 -100.325137) (xy 38.178714 -100.38051)
			(xy 38.148747 -100.432416) (xy 38.11226 -100.479966) (xy 38.06988 -100.522346) (xy 38.02233 -100.558833)
			(xy 37.970424 -100.5888) (xy 37.915051 -100.611736) (xy 37.857158 -100.627249) (xy 37.797736 -100.635072)
			(xy 37.7378 -100.635072) (xy 37.678378 -100.627249) (xy 37.620485 -100.611736) (xy 37.565112 -100.5888)
			(xy 37.513206 -100.558833) (xy 37.465656 -100.522346) (xy 37.423276 -100.479966) (xy 37.386789 -100.432416)
			(xy 37.356822 -100.38051) (xy 37.333886 -100.325137) (xy 37.318373 -100.267244) (xy 37.31055 -100.207822)
			(xy 37.31006 -100.177854) (xy 28.793948 -100.177854) (xy 27.537664 -101.434138) (xy 27.534362 -101.438202)
			(xy 27.530231 -101.444713) (xy 27.525712 -101.45945) (xy 27.525472 -101.467158) (xy 27.525472 -101.984302)
			(xy 35.277552 -101.984302) (xy 35.277552 -101.120702) (xy 35.278042 -101.090734) (xy 35.285865 -101.031312)
			(xy 35.301378 -100.973419) (xy 35.324314 -100.918046) (xy 35.354281 -100.86614) (xy 35.390768 -100.81859)
			(xy 35.433148 -100.77621) (xy 35.480698 -100.739723) (xy 35.532604 -100.709756) (xy 35.587977 -100.68682)
			(xy 35.64587 -100.671307) (xy 35.705292 -100.663484) (xy 35.765228 -100.663484) (xy 35.82465 -100.671307)
			(xy 35.882543 -100.68682) (xy 35.937916 -100.709756) (xy 35.989822 -100.739723) (xy 36.037372 -100.77621)
			(xy 36.079752 -100.81859) (xy 36.116239 -100.86614) (xy 36.146206 -100.918046) (xy 36.169142 -100.973419)
			(xy 36.184655 -101.031312) (xy 36.192478 -101.090734) (xy 36.192968 -101.120702) (xy 36.192968 -101.984302)
			(xy 36.192478 -102.01427) (xy 36.184655 -102.073692) (xy 36.169142 -102.131585) (xy 36.146206 -102.186958)
			(xy 36.116239 -102.238864) (xy 36.079752 -102.286414) (xy 36.037372 -102.328794) (xy 35.989822 -102.365281)
			(xy 35.937916 -102.395248) (xy 35.882543 -102.418184) (xy 35.82465 -102.433697) (xy 35.765228 -102.44152)
			(xy 35.705292 -102.44152) (xy 35.64587 -102.433697) (xy 35.587977 -102.418184) (xy 35.532604 -102.395248)
			(xy 35.480698 -102.365281) (xy 35.433148 -102.328794) (xy 35.390768 -102.286414) (xy 35.354281 -102.238864)
			(xy 35.324314 -102.186958) (xy 35.301378 -102.131585) (xy 35.285865 -102.073692) (xy 35.278042 -102.01427)
			(xy 35.277552 -101.984302) (xy 27.525472 -101.984302) (xy 27.525472 -103.777796) (xy 37.31006 -103.777796)
			(xy 37.31006 -102.914196) (xy 37.31055 -102.884228) (xy 37.318373 -102.824806) (xy 37.333886 -102.766913)
			(xy 37.356822 -102.71154) (xy 37.386789 -102.659634) (xy 37.423276 -102.612084) (xy 37.465656 -102.569704)
			(xy 37.513206 -102.533217) (xy 37.565112 -102.50325) (xy 37.620485 -102.480314) (xy 37.678378 -102.464801)
			(xy 37.7378 -102.456978) (xy 37.797736 -102.456978) (xy 37.857158 -102.464801) (xy 37.915051 -102.480314)
			(xy 37.970424 -102.50325) (xy 38.02233 -102.533217) (xy 38.06988 -102.569704) (xy 38.11226 -102.612084)
			(xy 38.148747 -102.659634) (xy 38.178714 -102.71154) (xy 38.20165 -102.766913) (xy 38.217163 -102.824806)
			(xy 38.224986 -102.884228) (xy 38.225476 -102.914196) (xy 38.225476 -103.777796) (xy 38.224986 -103.807764)
			(xy 38.217163 -103.867186) (xy 38.20165 -103.925079) (xy 38.178714 -103.980452) (xy 38.148747 -104.032358)
			(xy 38.11226 -104.079908) (xy 38.06988 -104.122288) (xy 38.02233 -104.158775) (xy 37.970424 -104.188742)
			(xy 37.915051 -104.211678) (xy 37.857158 -104.227191) (xy 37.797736 -104.235014) (xy 37.7378 -104.235014)
			(xy 37.678378 -104.227191) (xy 37.620485 -104.211678) (xy 37.565112 -104.188742) (xy 37.513206 -104.158775)
			(xy 37.465656 -104.122288) (xy 37.423276 -104.079908) (xy 37.386789 -104.032358) (xy 37.356822 -103.980452)
			(xy 37.333886 -103.925079) (xy 37.318373 -103.867186) (xy 37.31055 -103.807764) (xy 37.31006 -103.777796)
			(xy 27.525472 -103.777796) (xy 27.525472 -105.0544) (xy 27.52596 -105.06441) (xy 27.533618 -105.082906)
			(xy 27.54777 -105.097066) (xy 27.566263 -105.104735) (xy 27.576272 -105.1052) (xy 27.99461 -105.1052)
			(xy 28.004616 -105.10569) (xy 28.023105 -105.113351) (xy 28.037254 -105.127504) (xy 28.044912 -105.145994)
			(xy 28.04541 -105.156) (xy 28.04541 -105.584498) (xy 34.667952 -105.584498) (xy 34.667952 -104.720898)
			(xy 34.668442 -104.69093) (xy 34.676265 -104.631508) (xy 34.691778 -104.573615) (xy 34.714714 -104.518242)
			(xy 34.744681 -104.466336) (xy 34.781168 -104.418786) (xy 34.823548 -104.376406) (xy 34.871098 -104.339919)
			(xy 34.923004 -104.309952) (xy 34.978377 -104.287016) (xy 35.03627 -104.271503) (xy 35.095692 -104.26368)
			(xy 35.155628 -104.26368) (xy 35.21505 -104.271503) (xy 35.272943 -104.287016) (xy 35.328316 -104.309952)
			(xy 35.380222 -104.339919) (xy 35.427772 -104.376406) (xy 35.470152 -104.418786) (xy 35.506639 -104.466336)
			(xy 35.536606 -104.518242) (xy 35.559542 -104.573615) (xy 35.575055 -104.631508) (xy 35.582878 -104.69093)
			(xy 35.583368 -104.720898) (xy 35.583368 -105.584498) (xy 35.582878 -105.614466) (xy 35.575055 -105.673888)
			(xy 35.559542 -105.731781) (xy 35.536606 -105.787154) (xy 35.506639 -105.83906) (xy 35.470152 -105.88661)
			(xy 35.427772 -105.92899) (xy 35.380222 -105.965477) (xy 35.328316 -105.995444) (xy 35.272943 -106.01838)
			(xy 35.21505 -106.033893) (xy 35.155628 -106.041716) (xy 35.095692 -106.041716) (xy 35.03627 -106.033893)
			(xy 34.978377 -106.01838) (xy 34.923004 -105.995444) (xy 34.871098 -105.965477) (xy 34.823548 -105.92899)
			(xy 34.781168 -105.88661) (xy 34.744681 -105.83906) (xy 34.714714 -105.787154) (xy 34.691778 -105.731781)
			(xy 34.676265 -105.673888) (xy 34.668442 -105.614466) (xy 34.667952 -105.584498) (xy 28.04541 -105.584498)
			(xy 28.04541 -108.90758) (xy 28.046426 -108.916978) (xy 28.046426 -108.917486) (xy 28.048132 -108.924644)
			(xy 28.054967 -108.937668) (xy 28.059888 -108.94314) (xy 30.192726 -111.075978) (xy 30.198408 -111.081164)
			(xy 30.212116 -111.08813) (xy 30.21965 -111.089694) (xy 30.220158 -111.089694) (xy 30.228286 -111.090456)
			(xy 32.754316 -111.090456) (xy 32.762422 -111.090153) (xy 32.777826 -111.085099) (xy 32.784542 -111.08055)
			(xy 32.787336 -111.078264) (xy 32.810196 -111.008668) (xy 32.874204 -110.81385) (xy 32.888897 -110.770808)
			(xy 32.925069 -110.687355) (xy 32.968682 -110.607537) (xy 33.019375 -110.532018) (xy 33.076728 -110.461424)
			(xy 33.108138 -110.428532) (xy 33.581594 -109.9439) (xy 33.621103 -109.90459) (xy 33.707412 -109.834068)
			(xy 33.753806 -109.803184) (xy 33.793376 -109.7783) (xy 33.876316 -109.735175) (xy 33.919414 -109.717078)
			(xy 34.627566 -109.429042) (xy 34.7091 -109.395768) (xy 34.709608 -109.383068) (xy 34.7091 -109.377226)
			(xy 34.69767 -109.347254) (xy 34.69767 -109.346746) (xy 34.692082 -109.332014) (xy 34.692082 -109.331506)
			(xy 34.688526 -109.320838) (xy 34.688526 -109.32033) (xy 34.685986 -109.312202) (xy 34.6837 -109.304582)
			(xy 34.681922 -109.297724) (xy 34.680398 -109.291374) (xy 34.680398 -109.290866) (xy 34.674561 -109.264648)
			(xy 34.668327 -109.211297) (xy 34.667952 -109.18444) (xy 34.667952 -108.32084) (xy 34.668442 -108.290872)
			(xy 34.676265 -108.23145) (xy 34.691778 -108.173557) (xy 34.714714 -108.118184) (xy 34.744681 -108.066278)
			(xy 34.781168 -108.018728) (xy 34.823548 -107.976348) (xy 34.871098 -107.939861) (xy 34.923004 -107.909894)
			(xy 34.978377 -107.886958) (xy 35.03627 -107.871445) (xy 35.095692 -107.863622) (xy 35.155628 -107.863622)
			(xy 35.21505 -107.871445) (xy 35.272943 -107.886958) (xy 35.328316 -107.909894) (xy 35.380222 -107.939861)
			(xy 35.427772 -107.976348) (xy 35.470152 -108.018728) (xy 35.506639 -108.066278) (xy 35.536606 -108.118184)
			(xy 35.559542 -108.173557) (xy 35.575055 -108.23145) (xy 35.582878 -108.290872) (xy 35.583368 -108.32084)
			(xy 35.583368 -108.81868) (xy 35.583909 -108.82863) (xy 35.591577 -108.847001) (xy 35.605625 -108.861106)
			(xy 35.61461 -108.865416) (xy 35.638232 -108.865416) (xy 35.64636 -108.864654) (xy 35.646868 -108.864654)
			(xy 35.654385 -108.863051) (xy 35.668072 -108.856073) (xy 35.673792 -108.850938) (xy 35.793426 -108.731304)
			(xy 35.82816 -108.697324) (xy 35.903226 -108.635614) (xy 35.943286 -108.608114) (xy 36.586414 -108.1786)
			(xy 37.351462 -107.667298) (xy 37.358928 -107.661869) (xy 37.369681 -107.646883) (xy 37.374407 -107.629054)
			(xy 37.37249 -107.610709) (xy 37.368734 -107.602274) (xy 37.367972 -107.60075) (xy 37.367464 -107.599988)
			(xy 37.353975 -107.574764) (xy 37.332678 -107.521675) (xy 37.318168 -107.466345) (xy 37.31067 -107.409637)
			(xy 37.31006 -107.38104) (xy 37.31006 -106.514138) (xy 37.31055 -106.48417) (xy 37.318373 -106.424748)
			(xy 37.333886 -106.366855) (xy 37.356822 -106.311482) (xy 37.386789 -106.259576) (xy 37.423276 -106.212026)
			(xy 37.465656 -106.169646) (xy 37.513206 -106.133159) (xy 37.565112 -106.103192) (xy 37.620485 -106.080256)
			(xy 37.678378 -106.064743) (xy 37.7378 -106.05692) (xy 37.797736 -106.05692) (xy 37.857158 -106.064743)
			(xy 37.915051 -106.080256) (xy 37.970424 -106.103192) (xy 38.02233 -106.133159) (xy 38.06988 -106.169646)
			(xy 38.11226 -106.212026) (xy 38.148747 -106.259576) (xy 38.178714 -106.311482) (xy 38.20165 -106.366855)
			(xy 38.217163 -106.424748) (xy 38.224986 -106.48417) (xy 38.225476 -106.514138) (xy 38.225476 -106.988356)
			(xy 38.225628 -106.994224) (xy 38.228326 -107.005644) (xy 38.23081 -107.010962) (xy 38.23081 -107.011216)
			(xy 38.234138 -107.017352) (xy 38.243547 -107.027658) (xy 38.249352 -107.031536) (xy 38.2524 -107.03306)
			(xy 38.25494 -107.034584) (xy 38.263322 -107.037632) (xy 38.273736 -107.040426) (xy 38.284404 -107.038648)
			(xy 38.289684 -107.037627) (xy 38.299675 -107.033655) (xy 38.304216 -107.030774) (xy 38.41877 -106.954828)
			(xy 38.420802 -106.953558) (xy 38.73119 -106.706162) (xy 38.883336 -106.58475) (xy 39.301166 -106.251756)
			(xy 39.301674 -106.251756) (xy 39.314374 -106.241596) (xy 39.318692 -106.237786) (xy 44.69003 -100.866448)
			(xy 44.693431 -100.862877) (xy 44.698928 -100.854689) (xy 44.700952 -100.850192) (xy 44.705016 -100.84054)
			(xy 44.705016 -100.804726) (xy 44.700952 -100.795328) (xy 44.691229 -100.771554) (xy 44.677543 -100.722047)
			(xy 44.670639 -100.67115) (xy 44.670218 -100.645468) (xy 44.670218 -100.64496) (xy 44.670682 -100.618052)
			(xy 44.678247 -100.564771) (xy 44.693221 -100.51308) (xy 44.715308 -100.464005) (xy 44.744069 -100.41852)
			(xy 44.778934 -100.377525) (xy 44.819212 -100.341834) (xy 44.864104 -100.312155) (xy 44.912719 -100.289075)
			(xy 44.964095 -100.273054) (xy 45.017212 -100.264408) (xy 45.044106 -100.263452) (xy 45.051218 -100.263452)
			(xy 45.076404 -100.263786) (xy 45.126354 -100.270279) (xy 45.150786 -100.276406) (xy 45.171106 -100.282502)
			(xy 45.181265 -100.285942) (xy 45.201215 -100.293822) (xy 45.210984 -100.29825) (xy 45.217334 -100.301298)
			(xy 45.224446 -100.302314) (xy 45.236457 -100.303587) (xy 45.259403 -100.296162) (xy 45.268388 -100.28809)
			(xy 46.197012 -99.359466) (xy 46.204408 -99.352614) (xy 46.223007 -99.344874) (xy 46.23308 -99.34448)
			(xy 50.171858 -99.34448) (xy 50.182272 -99.34321) (xy 51.23561 -98.816668) (xy 51.239693 -98.813982)
			(xy 51.246854 -98.807333) (xy 51.249834 -98.80346) (xy 51.254152 -98.797364) (xy 51.256184 -98.785172)
			(xy 51.260882 -98.758612) (xy 51.276772 -98.70707) (xy 51.299755 -98.658277) (xy 51.329376 -98.613203)
			(xy 51.365045 -98.572745) (xy 51.406052 -98.537709) (xy 51.451581 -98.508792) (xy 51.500725 -98.486569)
			(xy 51.552508 -98.471482) (xy 51.605899 -98.463832) (xy 51.632866 -98.463354) (xy 51.633374 -98.463354)
			(xy 51.66741 -98.465132) (xy 51.678078 -98.466148) (xy 51.705775 -98.469911) (xy 51.759734 -98.484494)
			(xy 51.81099 -98.506791) (xy 51.858445 -98.536325) (xy 51.901086 -98.572464) (xy 51.919886 -98.593148)
			(xy 51.923527 -98.597073) (xy 51.932101 -98.603483) (xy 51.936904 -98.605848) (xy 51.93792 -98.606356)
			(xy 53.183028 -98.606356) (xy 53.190394 -98.603308) (xy 53.197252 -98.596196) (xy 53.202586 -98.590862)
			(xy 53.220734 -98.571234) (xy 53.261568 -98.536736) (xy 53.306809 -98.508263) (xy 53.355576 -98.486369)
			(xy 53.406917 -98.471482) (xy 53.459831 -98.463891) (xy 53.486558 -98.463354) (xy 53.487574 -98.463354)
			(xy 53.505009 -98.463551) (xy 53.539734 -98.466736) (xy 53.556916 -98.469704) (xy 53.563774 -98.469704)
			(xy 53.604303 -98.444728) (xy 53.689253 -98.401739) (xy 53.777911 -98.367036) (xy 53.869471 -98.340936)
			(xy 53.963101 -98.323675) (xy 54.057949 -98.31541) (xy 54.105556 -98.315272) (xy 54.10581 -98.315272)
			(xy 54.149468 -98.316125) (xy 54.23639 -98.324529) (xy 54.322244 -98.340501) (xy 54.406372 -98.36392)
			(xy 54.488131 -98.394604) (xy 54.527704 -98.413062) (xy 54.539896 -98.418904) (xy 54.546269 -98.421046)
			(xy 54.559648 -98.422337) (xy 54.566312 -98.421444) (xy 54.567582 -98.42119) (xy 56.230774 -96.757998)
			(xy 56.235754 -96.752567) (xy 56.242601 -96.739528) (xy 56.244236 -96.732344) (xy 56.244236 -96.731836)
			(xy 56.245252 -96.722438) (xy 56.245252 -96.632268) (xy 56.245086 -96.62675) (xy 56.242648 -96.615985)
			(xy 56.240426 -96.610932) (xy 56.240426 -96.610678) (xy 56.230401 -96.588455) (xy 56.21626 -96.5418)
			(xy 56.20912 -96.493576) (xy 56.208676 -96.4692) (xy 56.208676 -67.381374) (xy 56.208248 -67.371306)
			(xy 56.200524 -67.352711) (xy 56.19369 -67.345306) (xy 55.828184 -66.979546) (xy 55.468266 -66.619628)
			(xy 55.465685 -66.617179) (xy 55.459947 -66.612973) (xy 55.456836 -66.611246) (xy 55.445406 -66.606928)
			(xy 55.433214 -66.605404) (xy 53.89499 -66.605404) (xy 53.884921 -66.604979) (xy 53.866318 -66.597263)
			(xy 53.858922 -66.590418) (xy 53.734716 -66.466212) (xy 53.731668 -66.463926) (xy 53.723286 -66.457576)
			(xy 53.715654 -66.451481) (xy 53.70104 -66.438517) (xy 53.694076 -66.431668) (xy 52.830984 -65.568576)
			(xy 52.826519 -65.566954) (xy 52.81719 -65.565175) (xy 52.812442 -65.56502) (xy 48.376332 -65.56502)
			(xy 48.372726 -65.565081) (xy 48.365585 -65.566095) (xy 48.362108 -65.567052) (xy 48.357536 -65.568576)
			(xy 48.348392 -65.572386) (xy 47.971202 -65.949576) (xy 47.963805 -65.956425) (xy 47.945207 -65.964164)
			(xy 47.935134 -65.964562) (xy 47.817024 -65.964562) (xy 47.810928 -65.966086) (xy 47.800514 -65.968372)
			(xy 47.800006 -65.968372) (xy 47.783058 -65.971712) (xy 47.748698 -65.975274) (xy 47.731426 -65.975484)
			(xy 47.05731 -65.975484) (xy 47.040038 -65.975273) (xy 47.005679 -65.971707) (xy 46.98873 -65.968372)
			(xy 46.988222 -65.968372) (xy 46.977808 -65.966086) (xy 46.971712 -65.964562) (xy 46.944026 -65.964562)
			(xy 46.933963 -65.964125) (xy 46.915381 -65.956387) (xy 46.907958 -65.949576) (xy 46.88713 -65.928748)
			(xy 46.88205 -65.9257) (xy 46.866346 -65.915602) (xy 46.837068 -65.892433) (xy 46.82363 -65.879472)
			(xy 46.821852 -65.877694) (xy 46.413166 -65.469008) (xy 46.406562 -65.466976) (xy 46.378607 -65.458178)
			(xy 46.325592 -65.433202) (xy 46.277025 -65.400404) (xy 46.255178 -65.38087) (xy 46.236293 -65.362772)
			(xy 46.203153 -65.322303) (xy 46.175848 -65.277689) (xy 46.154888 -65.229765) (xy 46.140666 -65.179429)
			(xy 46.133449 -65.127623) (xy 46.133004 -65.10147) (xy 46.133004 -65.1002) (xy 46.134782 -65.063116)
			(xy 46.135036 -65.060576) (xy 46.134528 -65.050924) (xy 46.133478 -65.042775) (xy 46.126865 -65.027746)
			(xy 46.121574 -65.02146) (xy 46.078648 -64.9732) (xy 46.07052 -64.964056) (xy 46.065822 -64.959719)
			(xy 46.054766 -64.953307) (xy 46.048676 -64.951356) (xy 46.048168 -64.951102) (xy 46.040294 -64.948816)
			(xy 45.51553 -64.948816) (xy 45.51064 -64.948954) (xy 45.501049 -64.950876) (xy 45.49648 -64.952626)
			(xy 45.486828 -64.956436) (xy 45.479716 -64.963802) (xy 44.466256 -65.977262) (xy 44.465494 -65.978278)
			(xy 44.4466 -65.997092) (xy 44.403797 -66.028878) (xy 44.356351 -66.053197) (xy 44.331128 -66.061844)
			(xy 44.330112 -66.062352) (xy 44.321984 -66.0654) (xy 44.318936 -66.066162) (xy 44.316904 -66.06667)
			(xy 44.313094 -66.067432) (xy 44.300936 -66.070426) (xy 44.27627 -66.074751) (xy 44.263818 -66.076068)
			(xy 44.258484 -66.077084) (xy 44.256452 -66.077592) (xy 44.23664 -66.082168) (xy 44.196266 -66.087011)
			(xy 44.175934 -66.087244) (xy 40.917368 -66.087244) (xy 40.913558 -66.089276) (xy 40.885067 -66.104272)
			(xy 40.824304 -66.125547) (xy 40.760836 -66.136341) (xy 40.728646 -66.137028) (xy 40.70139 -66.136568)
			(xy 40.647431 -66.128816) (xy 40.595125 -66.113463) (xy 40.545536 -66.090822) (xy 40.499675 -66.061354)
			(xy 40.458474 -66.025658) (xy 40.422774 -65.984462) (xy 40.3933 -65.938604) (xy 40.370653 -65.889019)
			(xy 40.355294 -65.836714) (xy 40.347535 -65.782756) (xy 40.347535 -65.728244) (xy 40.355294 -65.674286)
			(xy 40.370653 -65.621981) (xy 40.3933 -65.572396) (xy 40.422774 -65.526538) (xy 40.458474 -65.485342)
			(xy 40.499675 -65.449646) (xy 40.545536 -65.420178) (xy 40.595125 -65.397537) (xy 40.647431 -65.382184)
			(xy 40.70139 -65.374432) (xy 40.728646 -65.374012) (xy 40.760838 -65.374675) (xy 40.824311 -65.385465)
			(xy 40.885075 -65.406749) (xy 40.913558 -65.421764) (xy 40.917368 -65.423796) (xy 44.017438 -65.423796)
			(xy 44.026582 -65.423034) (xy 44.034074 -65.421407) (xy 44.047653 -65.414301) (xy 44.053252 -65.409064)
			(xy 45.079666 -64.382396) (xy 45.100423 -64.362545) (xy 45.147448 -64.329578) (xy 45.19944 -64.305185)
			(xy 45.226986 -64.297052) (xy 45.23359 -64.295274) (xy 45.23867 -64.292226) (xy 45.249084 -64.284352)
			(xy 45.796708 -63.736474) (xy 45.79747 -63.735458) (xy 45.817629 -63.715279) (xy 45.863703 -63.681662)
			(xy 45.914976 -63.656683) (xy 45.94225 -63.648336) (xy 45.945044 -63.647828) (xy 45.947838 -63.647066)
			(xy 45.967916 -63.64205) (xy 46.008936 -63.636566) (xy 46.029626 -63.636144) (xy 48.169322 -63.636144)
			(xy 48.178528 -63.63543) (xy 48.195543 -63.628298) (xy 48.208918 -63.615588) (xy 48.213264 -63.607442)
			(xy 48.238156 -63.545466) (xy 48.238156 -63.544958) (xy 48.248062 -63.521082) (xy 48.249735 -63.51507)
			(xy 48.250493 -63.502619) (xy 48.249586 -63.496444) (xy 48.248824 -63.492888) (xy 48.247101 -63.486922)
			(xy 48.241187 -63.476008) (xy 48.23714 -63.471298) (xy 48.2346 -63.468758) (xy 48.215743 -63.450334)
			(xy 48.182672 -63.409276) (xy 48.155458 -63.364122) (xy 48.1346 -63.315703) (xy 48.120483 -63.264908)
			(xy 48.113365 -63.21267) (xy 48.112934 -63.18631) (xy 48.113405 -63.158531) (xy 48.121311 -63.103537)
			(xy 48.136963 -63.050229) (xy 48.160042 -62.999691) (xy 48.190079 -62.952952) (xy 48.226462 -62.910963)
			(xy 48.26845 -62.87458) (xy 48.315189 -62.844543) (xy 48.365727 -62.821464) (xy 48.419035 -62.805812)
			(xy 48.474029 -62.797906) (xy 48.501808 -62.797436) (xy 48.528765 -62.797895) (xy 48.582163 -62.805341)
			(xy 48.634021 -62.820087) (xy 48.683347 -62.841853) (xy 48.729195 -62.870221) (xy 48.75022 -62.887098)
			(xy 48.757078 -62.892686) (xy 48.76546 -62.895734) (xy 48.769639 -62.897143) (xy 48.778323 -62.898673)
			(xy 48.782732 -62.898782) (xy 48.792638 -62.898782) (xy 48.796243 -62.898848) (xy 48.803381 -62.899872)
			(xy 48.806862 -62.900814) (xy 48.810418 -62.901576) (xy 48.864266 -62.901576) (xy 48.872869 -62.90124)
			(xy 48.889098 -62.895526) (xy 48.896016 -62.8904) (xy 48.89627 -62.890146) (xy 48.897032 -62.889638)
			(xy 48.901604 -62.886082) (xy 48.904144 -62.88405) (xy 48.904906 -62.883288) (xy 48.927004 -62.86754)
			(xy 48.92802 -62.867032) (xy 48.935894 -62.861698) (xy 48.93945 -62.859666) (xy 48.956087 -62.84989)
			(xy 48.99095 -62.833345) (xy 49.009046 -62.826646) (xy 49.009808 -62.826392) (xy 49.010824 -62.826138)
			(xy 49.012094 -62.82563) (xy 49.013618 -62.825122) (xy 49.038642 -62.81707) (xy 49.090263 -62.807131)
			(xy 49.116488 -62.80531) (xy 49.136046 -62.804802) (xy 49.136808 -62.804802) (xy 49.15281 -62.805056)
			(xy 49.157128 -62.80531) (xy 49.186536 -62.807454) (xy 49.244221 -62.819657) (xy 49.299348 -62.840576)
			(xy 49.350607 -62.869713) (xy 49.374044 -62.887606) (xy 49.374298 -62.88786) (xy 49.377346 -62.8904)
			(xy 49.383455 -62.894136) (xy 49.39712 -62.898397) (xy 49.40427 -62.898782) (xy 49.427638 -62.898782)
			(xy 49.433077 -62.898925) (xy 49.443709 -62.901233) (xy 49.44872 -62.903354) (xy 49.462436 -62.909704)
			(xy 49.46714 -62.911773) (xy 49.47712 -62.914213) (xy 49.482248 -62.91453) (xy 49.490884 -62.914022)
			(xy 49.49817 -62.912739) (xy 49.511595 -62.90654) (xy 49.5173 -62.90183) (xy 49.517554 -62.901576)
			(xy 49.538623 -62.883466) (xy 49.585016 -62.852902) (xy 49.635349 -62.829383) (xy 49.688559 -62.813408)
			(xy 49.743522 -62.805313) (xy 49.7713 -62.804802) (xy 49.771808 -62.804802) (xy 49.79906 -62.805266)
			(xy 49.85301 -62.813024) (xy 49.905306 -62.828381) (xy 49.954885 -62.851024) (xy 50.000736 -62.880492)
			(xy 50.041927 -62.916186) (xy 50.077619 -62.957378) (xy 50.107085 -63.003231) (xy 50.129726 -63.052811)
			(xy 50.14508 -63.105108) (xy 50.152835 -63.159058) (xy 50.153316 -63.18631) (xy 50.152746 -63.216037)
			(xy 50.14352 -63.274771) (xy 50.125291 -63.331361) (xy 50.098503 -63.384438) (xy 50.063804 -63.432715)
			(xy 50.043334 -63.45428) (xy 50.04308 -63.454534) (xy 50.036984 -63.460884) (xy 50.030126 -63.475616)
			(xy 50.02911 -63.478156) (xy 50.025046 -63.488316) (xy 50.02296 -63.495998) (xy 50.023102 -63.511906)
			(xy 50.0253 -63.519558) (xy 50.041302 -63.559944) (xy 50.043334 -63.565024) (xy 50.043334 -63.565532)
			(xy 50.060098 -63.606172) (xy 50.06086 -63.60795) (xy 50.065186 -63.615746) (xy 50.0781 -63.62802)
			(xy 50.094415 -63.635178) (xy 50.103278 -63.636144) (xy 51.295046 -63.636144) (xy 51.303174 -63.635382)
			(xy 51.303682 -63.635382) (xy 51.311204 -63.633787) (xy 51.3249 -63.626818) (xy 51.330606 -63.621666)
			(xy 51.407568 -63.544704) (xy 51.41214 -63.53937) (xy 51.41214 -58.161682) (xy 51.41087 -58.159904)
			(xy 51.408584 -58.15711) (xy 51.075082 -57.823608) (xy 51.059919 -57.807942) (xy 51.033532 -57.773236)
			(xy 51.012084 -57.735279) (xy 51.003708 -57.71515) (xy 51.001168 -57.709562) (xy 50.99685 -57.701688)
			(xy 50.981022 -57.679953) (xy 50.955877 -57.632432) (xy 50.938736 -57.581475) (xy 50.930048 -57.528418)
			(xy 50.92954 -57.501536) (xy 50.92954 -56.577992) (xy 50.924927 -56.572298) (xy 50.913192 -56.563533)
			(xy 50.906426 -56.56072) (xy 50.862992 -56.544718) (xy 50.816764 -56.5277) (xy 50.809144 -56.525668)
			(xy 50.803385 -56.524686) (xy 50.791711 -56.525066) (xy 50.78603 -56.52643) (xy 50.778664 -56.528462)
			(xy 50.765456 -56.536844) (xy 50.760376 -56.54294) (xy 50.742143 -56.563795) (xy 50.700687 -56.600535)
			(xy 50.654356 -56.630897) (xy 50.604121 -56.654241) (xy 50.55104 -56.670079) (xy 50.496227 -56.678077)
			(xy 50.46853 -56.678576) (xy 50.441277 -56.678115) (xy 50.387324 -56.670361) (xy 50.335025 -56.655007)
			(xy 50.285443 -56.632366) (xy 50.239588 -56.602898) (xy 50.198394 -56.567204) (xy 50.1627 -56.52601)
			(xy 50.133233 -56.480156) (xy 50.110592 -56.430574) (xy 50.095239 -56.378274) (xy 50.087485 -56.324321)
			(xy 50.087022 -56.297068) (xy 50.087522 -56.269329) (xy 50.095558 -56.214436) (xy 50.111457 -56.161286)
			(xy 50.134883 -56.110996) (xy 50.165344 -56.064629) (xy 50.202196 -56.023159) (xy 50.244663 -55.987462)
			(xy 50.291852 -55.958289) (xy 50.342766 -55.936256) (xy 50.396334 -55.921825) (xy 50.423826 -55.9181)
			(xy 50.438558 -55.916576) (xy 50.46853 -55.915306) (xy 50.495934 -55.915807) (xy 50.550174 -55.923694)
			(xy 50.602732 -55.939243) (xy 50.652531 -55.962138) (xy 50.698551 -55.991908) (xy 50.73985 -56.027943)
			(xy 50.75809 -56.048402) (xy 50.75936 -56.049926) (xy 50.763678 -56.054244) (xy 50.770241 -56.06037)
			(xy 50.786512 -56.067927) (xy 50.795428 -56.068976) (xy 50.800922 -56.069238) (xy 50.81181 -56.067698)
			(xy 50.817018 -56.065928) (xy 50.827686 -56.062118) (xy 50.906172 -56.033416) (xy 50.91684 -56.028082)
			(xy 50.920445 -56.025591) (xy 50.926823 -56.019583) (xy 50.92954 -56.016144) (xy 50.92954 -55.11292)
			(xy 50.93007 -55.086897) (xy 50.93824 -55.035496) (xy 50.954338 -54.986001) (xy 50.977966 -54.939628)
			(xy 51.008546 -54.897513) (xy 51.026568 -54.878732) (xy 52.950618 -52.954682) (xy 52.956968 -52.944014)
			(xy 52.958746 -52.938172) (xy 52.967181 -52.912592) (xy 52.990239 -52.863915) (xy 53.019911 -52.818964)
			(xy 53.055608 -52.77863) (xy 53.096621 -52.743716) (xy 53.142135 -52.714913) (xy 53.191246 -52.692796)
			(xy 53.242978 -52.677802) (xy 53.296305 -52.67023) (xy 53.350167 -52.67023) (xy 53.403494 -52.677802)
			(xy 53.455226 -52.692796) (xy 53.504337 -52.714913) (xy 53.549851 -52.743716) (xy 53.590864 -52.77863)
			(xy 53.626561 -52.818964) (xy 53.656233 -52.863915) (xy 53.679291 -52.912592) (xy 53.687726 -52.938172)
			(xy 53.689504 -52.944014) (xy 53.695854 -52.954682) (xy 54.237724 -53.496552) (xy 58.133464 -53.496552)
			(xy 58.133464 -53.442048) (xy 58.14122 -53.3881) (xy 58.156575 -53.335804) (xy 58.179216 -53.286226)
			(xy 58.208683 -53.240374) (xy 58.244374 -53.199183) (xy 58.285565 -53.16349) (xy 58.331415 -53.134022)
			(xy 58.380993 -53.11138) (xy 58.433288 -53.096023) (xy 58.487236 -53.088265) (xy 58.514488 -53.087778)
			(xy 58.541859 -53.088232) (xy 58.596039 -53.09605) (xy 58.648543 -53.111541) (xy 58.69829 -53.134386)
			(xy 58.744256 -53.164114) (xy 58.765186 -53.181758) (xy 58.76544 -53.182012) (xy 58.772539 -53.187581)
			(xy 58.789446 -53.193838) (xy 58.79846 -53.194204) (xy 58.865516 -53.194204) (xy 58.874534 -53.193854)
			(xy 58.89145 -53.187601) (xy 58.898536 -53.182012) (xy 58.898536 -53.181758) (xy 58.89879 -53.181758)
			(xy 58.919709 -53.164103) (xy 58.965686 -53.134395) (xy 59.015437 -53.111563) (xy 59.06794 -53.096075)
			(xy 59.122118 -53.08825) (xy 59.149488 -53.087778) (xy 59.17674 -53.088268) (xy 59.230691 -53.096024)
			(xy 59.282988 -53.111378) (xy 59.332568 -53.134019) (xy 59.378421 -53.163486) (xy 59.419613 -53.199178)
			(xy 59.455307 -53.24037) (xy 59.484775 -53.286222) (xy 59.507418 -53.335801) (xy 59.522774 -53.388098)
			(xy 59.530531 -53.442048) (xy 59.530531 -53.496552) (xy 59.522774 -53.550502) (xy 59.507418 -53.602799)
			(xy 59.484775 -53.652378) (xy 59.455307 -53.69823) (xy 59.419613 -53.739422) (xy 59.378421 -53.775114)
			(xy 59.332568 -53.804581) (xy 59.282988 -53.827222) (xy 59.230691 -53.842576) (xy 59.17674 -53.850332)
			(xy 59.149488 -53.850794) (xy 59.122117 -53.850336) (xy 59.067938 -53.842517) (xy 59.015435 -53.827026)
			(xy 58.965688 -53.804182) (xy 58.919721 -53.774456) (xy 58.89879 -53.756814) (xy 58.898536 -53.75656)
			(xy 58.891447 -53.750977) (xy 58.874532 -53.744729) (xy 58.865516 -53.744368) (xy 58.79846 -53.744368)
			(xy 58.789442 -53.744713) (xy 58.772525 -53.75097) (xy 58.76544 -53.75656) (xy 58.76544 -53.756814)
			(xy 58.765186 -53.756814) (xy 58.744234 -53.774428) (xy 58.698267 -53.804143) (xy 58.648524 -53.826984)
			(xy 58.596028 -53.842481) (xy 58.541856 -53.850316) (xy 58.514488 -53.850794) (xy 58.487236 -53.850335)
			(xy 58.433288 -53.842577) (xy 58.380993 -53.82722) (xy 58.331415 -53.804578) (xy 58.285565 -53.77511)
			(xy 58.244374 -53.739417) (xy 58.208683 -53.698226) (xy 58.179216 -53.652374) (xy 58.156575 -53.602796)
			(xy 58.14122 -53.5505) (xy 58.133464 -53.496552) (xy 54.237724 -53.496552) (xy 54.366668 -53.625496)
			(xy 54.3847 -53.644267) (xy 54.415279 -53.686384) (xy 54.438904 -53.73276) (xy 54.454996 -53.782257)
			(xy 54.463159 -53.833661) (xy 54.463696 -53.859684) (xy 54.463696 -54.943502) (xy 54.470554 -54.951122)
			(xy 54.513104 -54.989051) (xy 55.901068 -54.989051) (xy 55.901068 -54.934549) (xy 55.908824 -54.880601)
			(xy 55.924179 -54.828307) (xy 55.946819 -54.778729) (xy 55.976284 -54.732879) (xy 56.011975 -54.691688)
			(xy 56.053164 -54.655995) (xy 56.099013 -54.626528) (xy 56.14859 -54.603885) (xy 56.200884 -54.588528)
			(xy 56.254831 -54.580769) (xy 56.282082 -54.580282) (xy 56.310173 -54.580791) (xy 56.36575 -54.589016)
			(xy 56.419518 -54.605304) (xy 56.470316 -54.629305) (xy 56.517043 -54.660497) (xy 56.558688 -54.698207)
			(xy 56.594351 -54.741619) (xy 56.609234 -54.765448) (xy 56.614568 -54.774338) (xy 56.631586 -54.78653)
			(xy 56.724804 -54.80685) (xy 56.745378 -54.802532) (xy 56.754014 -54.79669) (xy 56.778072 -54.780681)
			(xy 56.830006 -54.75534) (xy 56.885165 -54.738117) (xy 56.942291 -54.729405) (xy 56.971184 -54.728872)
			(xy 56.998434 -54.729393) (xy 57.052379 -54.737147) (xy 57.104672 -54.752499) (xy 57.154248 -54.775137)
			(xy 57.200097 -54.804599) (xy 57.241287 -54.840287) (xy 57.276979 -54.881474) (xy 57.306446 -54.92732)
			(xy 57.329088 -54.976894) (xy 57.344445 -55.029185) (xy 57.352204 -55.08313) (xy 57.352692 -55.11038)
			(xy 57.352216 -55.13775) (xy 57.344401 -55.191929) (xy 57.328914 -55.244432) (xy 57.306075 -55.294179)
			(xy 57.276352 -55.340146) (xy 57.258712 -55.361078) (xy 57.258458 -55.361332) (xy 57.252889 -55.36843)
			(xy 57.246633 -55.385338) (xy 57.246266 -55.394352) (xy 57.246266 -55.461408) (xy 57.246626 -55.470424)
			(xy 57.252872 -55.487341) (xy 57.258458 -55.494428) (xy 57.258712 -55.494428) (xy 57.258712 -55.494682)
			(xy 57.276331 -55.515631) (xy 57.306054 -55.561597) (xy 57.328898 -55.611341) (xy 57.344394 -55.66384)
			(xy 57.352224 -55.718016) (xy 57.352226 -55.772754) (xy 57.344401 -55.82693) (xy 57.328909 -55.879431)
			(xy 57.306069 -55.929176) (xy 57.27635 -55.975145) (xy 57.258712 -55.996078) (xy 57.258458 -55.996332)
			(xy 57.252889 -56.00343) (xy 57.246633 -56.020338) (xy 57.246266 -56.029352) (xy 57.246266 -56.096408)
			(xy 57.246626 -56.105424) (xy 57.252872 -56.122341) (xy 57.258458 -56.129428) (xy 57.258712 -56.129428)
			(xy 57.258712 -56.129682) (xy 57.276358 -56.150608) (xy 57.306068 -56.196583) (xy 57.328903 -56.246332)
			(xy 57.344392 -56.298834) (xy 57.352219 -56.35301) (xy 57.352692 -56.38038) (xy 57.352206 -56.407631)
			(xy 57.34445 -56.461579) (xy 57.329095 -56.513874) (xy 57.306453 -56.563451) (xy 57.276987 -56.609301)
			(xy 57.241296 -56.650492) (xy 57.200105 -56.686183) (xy 57.154255 -56.715649) (xy 57.104678 -56.738291)
			(xy 57.052383 -56.753646) (xy 56.998435 -56.761402) (xy 56.943933 -56.761402) (xy 56.889985 -56.753646)
			(xy 56.83769 -56.738291) (xy 56.788113 -56.715649) (xy 56.742263 -56.686183) (xy 56.701072 -56.650492)
			(xy 56.665381 -56.609301) (xy 56.635915 -56.563451) (xy 56.613273 -56.513874) (xy 56.597918 -56.461579)
			(xy 56.590162 -56.407631) (xy 56.589676 -56.38038) (xy 56.590112 -56.353008) (xy 56.597934 -56.298827)
			(xy 56.613429 -56.246323) (xy 56.636278 -56.196577) (xy 56.666011 -56.150612) (xy 56.683656 -56.129682)
			(xy 56.68391 -56.129428) (xy 56.689492 -56.122338) (xy 56.695741 -56.105424) (xy 56.696102 -56.096408)
			(xy 56.696102 -56.029352) (xy 56.695719 -56.020338) (xy 56.689489 -56.003421) (xy 56.68391 -55.996332)
			(xy 56.683656 -55.996332) (xy 56.683656 -55.996078) (xy 56.665995 -55.975162) (xy 56.636268 -55.929192)
			(xy 56.613422 -55.879443) (xy 56.597926 -55.826938) (xy 56.590099 -55.772757) (xy 56.590101 -55.718013)
			(xy 56.597933 -55.663832) (xy 56.613433 -55.611329) (xy 56.636283 -55.561582) (xy 56.666013 -55.515614)
			(xy 56.683656 -55.494682) (xy 56.68391 -55.494428) (xy 56.689492 -55.487338) (xy 56.695741 -55.470424)
			(xy 56.696102 -55.461408) (xy 56.696102 -55.394352) (xy 56.695719 -55.385338) (xy 56.689489 -55.368421)
			(xy 56.68391 -55.361332) (xy 56.683656 -55.360824) (xy 56.67271 -55.348091) (xy 56.65287 -55.320999)
			(xy 56.644032 -55.306722) (xy 56.638698 -55.297832) (xy 56.62168 -55.28564) (xy 56.528462 -55.26532)
			(xy 56.507888 -55.269638) (xy 56.499252 -55.27548) (xy 56.475174 -55.291458) (xy 56.423248 -55.316806)
			(xy 56.368094 -55.334038) (xy 56.310973 -55.34276) (xy 56.282082 -55.343298) (xy 56.254831 -55.342831)
			(xy 56.200884 -55.335072) (xy 56.14859 -55.319715) (xy 56.099013 -55.297072) (xy 56.053164 -55.267605)
			(xy 56.011975 -55.231912) (xy 55.976284 -55.190721) (xy 55.946819 -55.144871) (xy 55.924179 -55.095293)
			(xy 55.908824 -55.042999) (xy 55.901068 -54.989051) (xy 54.513104 -54.989051) (xy 54.526688 -55.00116)
			(xy 54.533876 -55.007039) (xy 54.551194 -55.013703) (xy 54.56047 -55.014114) (xy 54.56555 -55.014114)
			(xy 54.567836 -55.01386) (xy 54.60492 -55.012082) (xy 54.605428 -55.012082) (xy 54.605682 -55.012082)
			(xy 54.61842 -55.01216) (xy 54.643841 -55.013812) (xy 54.656482 -55.015384) (xy 54.681699 -55.019174)
			(xy 54.730888 -55.032626) (xy 54.777843 -55.052519) (xy 54.821724 -55.078498) (xy 54.861748 -55.110098)
			(xy 54.879748 -55.12816) (xy 54.88686 -55.135526) (xy 54.91607 -55.148226) (xy 54.920223 -55.149787)
			(xy 54.92891 -55.151584) (xy 54.933342 -55.151782) (xy 54.988714 -55.151782) (xy 55.00116 -55.149242)
			(xy 55.007002 -55.148226) (xy 55.035704 -55.135526) (xy 55.042562 -55.128414) (xy 55.06059 -55.110344)
			(xy 55.100638 -55.078697) (xy 55.144551 -55.052674) (xy 55.191541 -55.032742) (xy 55.240771 -55.019256)
			(xy 55.29136 -55.012458) (xy 55.316882 -55.012082) (xy 55.344136 -55.012544) (xy 55.398091 -55.020299)
			(xy 55.450392 -55.035654) (xy 55.499976 -55.058296) (xy 55.545833 -55.087764) (xy 55.587029 -55.123459)
			(xy 55.622725 -55.164653) (xy 55.652196 -55.210508) (xy 55.67484 -55.260091) (xy 55.690197 -55.312392)
			(xy 55.697955 -55.366346) (xy 55.697955 -55.420854) (xy 55.690197 -55.474808) (xy 55.67484 -55.527109)
			(xy 55.652196 -55.576692) (xy 55.622725 -55.622547) (xy 55.587029 -55.663741) (xy 55.545833 -55.699436)
			(xy 55.499976 -55.728904) (xy 55.450392 -55.751546) (xy 55.398091 -55.766901) (xy 55.344136 -55.774656)
			(xy 55.316882 -55.775098) (xy 55.291394 -55.774673) (xy 55.240871 -55.767883) (xy 55.191703 -55.754428)
			(xy 55.144763 -55.734546) (xy 55.100889 -55.708591) (xy 55.060861 -55.677026) (xy 55.042816 -55.65902)
			(xy 55.035704 -55.651654) (xy 55.006494 -55.638954) (xy 55.00234 -55.637397) (xy 54.993653 -55.635607)
			(xy 54.989222 -55.635398) (xy 54.9402 -55.635398) (xy 54.93004 -55.636414) (xy 54.919118 -55.6387)
			(xy 54.91353 -55.639716) (xy 54.88686 -55.651654) (xy 54.880002 -55.65902) (xy 54.8587 -55.680128)
			(xy 54.810727 -55.716108) (xy 54.784498 -55.730648) (xy 54.761384 -55.741824) (xy 54.75478 -55.745126)
			(xy 54.751542 -55.746836) (xy 54.74555 -55.751044) (xy 54.742842 -55.753508) (xy 54.737508 -55.758334)
			(xy 54.733698 -55.764938) (xy 54.722268 -55.784496) (xy 54.722268 -55.785004) (xy 54.708298 -55.807102)
			(xy 54.707028 -55.80888) (xy 54.706012 -55.810658) (xy 54.701253 -55.821126) (xy 54.700478 -55.844075)
			(xy 54.704488 -55.854854) (xy 54.705758 -55.857902) (xy 54.486048 -56.077612) (xy 54.478651 -56.08446)
			(xy 54.460052 -56.092189) (xy 54.44998 -56.092598) (xy 53.553614 -56.092598) (xy 53.539644 -56.09463)
			(xy 53.520086 -56.100218) (xy 53.514498 -56.10352) (xy 53.501566 -56.110993) (xy 53.4746 -56.123839)
			(xy 53.46065 -56.129174) (xy 53.432737 -56.138816) (xy 53.374605 -56.149172) (xy 53.34508 -56.149748)
			(xy 53.289962 -56.149748) (xy 53.286152 -56.150002) (xy 53.27729 -56.150974) (xy 53.261034 -56.158267)
			(xy 53.254402 -56.164226) (xy 53.151532 -56.26735) (xy 53.100986 -56.317896) (xy 53.100478 -56.325008)
			(xy 53.100478 -57.253378) (xy 53.100986 -57.25922) (xy 53.100986 -57.259728) (xy 53.102212 -57.267205)
			(xy 53.108402 -57.281025) (xy 53.113178 -57.286906) (xy 53.20284 -57.376314) (xy 53.220297 -57.3945)
			(xy 53.249902 -57.435298) (xy 53.27278 -57.480215) (xy 53.274427 -57.48528) (xy 56.60593 -57.48528)
			(xy 56.610001 -57.429658) (xy 56.622127 -57.375221) (xy 56.64205 -57.32313) (xy 56.669346 -57.274495)
			(xy 56.703432 -57.230352) (xy 56.743581 -57.191643) (xy 56.788939 -57.159192) (xy 56.838539 -57.133691)
			(xy 56.891323 -57.115684) (xy 56.946166 -57.105554) (xy 57.0019 -57.103517) (xy 57.057337 -57.109617)
			(xy 57.111294 -57.123723) (xy 57.162623 -57.145535) (xy 57.210229 -57.174589) (xy 57.253097 -57.210264)
			(xy 57.290314 -57.251801) (xy 57.321087 -57.298314) (xy 57.344759 -57.348811) (xy 57.360827 -57.402218)
			(xy 57.368947 -57.457394) (xy 57.369456 -57.48528) (xy 57.368947 -57.513166) (xy 57.360827 -57.568342)
			(xy 57.344759 -57.621749) (xy 57.321087 -57.672246) (xy 57.290314 -57.718759) (xy 57.253097 -57.760296)
			(xy 57.210229 -57.795971) (xy 57.162623 -57.825025) (xy 57.111294 -57.846837) (xy 57.057337 -57.860943)
			(xy 57.0019 -57.867043) (xy 56.946166 -57.865006) (xy 56.891323 -57.854876) (xy 56.838539 -57.836869)
			(xy 56.788939 -57.811368) (xy 56.743581 -57.778917) (xy 56.703432 -57.740208) (xy 56.669346 -57.696065)
			(xy 56.64205 -57.64743) (xy 56.622127 -57.595339) (xy 56.610001 -57.540902) (xy 56.60593 -57.48528)
			(xy 53.274427 -57.48528) (xy 53.288371 -57.528151) (xy 53.296291 -57.577933) (xy 53.29682 -57.603136)
			(xy 53.29682 -57.872376) (xy 53.300376 -57.881266) (xy 53.311494 -57.910842) (xy 53.323506 -57.972868)
			(xy 53.324252 -58.004456) (xy 53.324252 -58.335164) (xy 53.325268 -58.344816) (xy 53.326893 -58.352061)
			(xy 53.333731 -58.365234) (xy 53.33873 -58.370724) (xy 53.492908 -58.524902) (xy 53.510367 -58.543087)
			(xy 53.523531 -58.561224) (xy 58.562238 -58.561224) (xy 58.566309 -58.505602) (xy 58.578435 -58.451165)
			(xy 58.598358 -58.399074) (xy 58.625654 -58.350439) (xy 58.65974 -58.306296) (xy 58.699889 -58.267587)
			(xy 58.745247 -58.235136) (xy 58.794847 -58.209635) (xy 58.847631 -58.191628) (xy 58.902474 -58.181498)
			(xy 58.958208 -58.179461) (xy 59.013645 -58.185561) (xy 59.067602 -58.199667) (xy 59.118931 -58.221479)
			(xy 59.166537 -58.250533) (xy 59.209405 -58.286208) (xy 59.246622 -58.327745) (xy 59.277395 -58.374258)
			(xy 59.301067 -58.424755) (xy 59.317135 -58.478162) (xy 59.325255 -58.533338) (xy 59.325764 -58.561224)
			(xy 59.325255 -58.58911) (xy 59.317135 -58.644286) (xy 59.301067 -58.697693) (xy 59.277395 -58.74819)
			(xy 59.246622 -58.794703) (xy 59.209405 -58.83624) (xy 59.166537 -58.871915) (xy 59.118931 -58.900969)
			(xy 59.067602 -58.922781) (xy 59.013645 -58.936887) (xy 58.958208 -58.942987) (xy 58.902474 -58.94095)
			(xy 58.847631 -58.93082) (xy 58.794847 -58.912813) (xy 58.745247 -58.887312) (xy 58.699889 -58.854861)
			(xy 58.65974 -58.816152) (xy 58.625654 -58.772009) (xy 58.598358 -58.723374) (xy 58.578435 -58.671283)
			(xy 58.566309 -58.616846) (xy 58.562238 -58.561224) (xy 53.523531 -58.561224) (xy 53.539977 -58.583884)
			(xy 53.562859 -58.6288) (xy 53.578453 -58.676737) (xy 53.586376 -58.72652) (xy 53.586888 -58.751724)
			(xy 53.586888 -59.174634) (xy 57.093102 -59.174634) (xy 57.097173 -59.119012) (xy 57.109299 -59.064575)
			(xy 57.129222 -59.012484) (xy 57.156518 -58.963849) (xy 57.190604 -58.919706) (xy 57.230753 -58.880997)
			(xy 57.276111 -58.848546) (xy 57.325711 -58.823045) (xy 57.378495 -58.805038) (xy 57.433338 -58.794908)
			(xy 57.489072 -58.792871) (xy 57.544509 -58.798971) (xy 57.598466 -58.813077) (xy 57.649795 -58.834889)
			(xy 57.697401 -58.863943) (xy 57.740269 -58.899618) (xy 57.777486 -58.941155) (xy 57.808259 -58.987668)
			(xy 57.831931 -59.038165) (xy 57.847999 -59.091572) (xy 57.856119 -59.146748) (xy 57.856628 -59.174634)
			(xy 57.856119 -59.20252) (xy 57.847999 -59.257696) (xy 57.831931 -59.311103) (xy 57.808259 -59.3616)
			(xy 57.777486 -59.408113) (xy 57.740269 -59.44965) (xy 57.697401 -59.485325) (xy 57.649795 -59.514379)
			(xy 57.598466 -59.536191) (xy 57.544509 -59.550297) (xy 57.489072 -59.556397) (xy 57.433338 -59.55436)
			(xy 57.378495 -59.54423) (xy 57.325711 -59.526223) (xy 57.276111 -59.500722) (xy 57.230753 -59.468271)
			(xy 57.190604 -59.429562) (xy 57.156518 -59.385419) (xy 57.129222 -59.336784) (xy 57.109299 -59.284693)
			(xy 57.097173 -59.230256) (xy 57.093102 -59.174634) (xy 53.586888 -59.174634) (xy 53.586888 -60.633356)
			(xy 59.796932 -60.633356) (xy 59.801003 -60.577734) (xy 59.813129 -60.523297) (xy 59.833052 -60.471206)
			(xy 59.860348 -60.422571) (xy 59.894434 -60.378428) (xy 59.934583 -60.339719) (xy 59.979941 -60.307268)
			(xy 60.029541 -60.281767) (xy 60.082325 -60.26376) (xy 60.137168 -60.25363) (xy 60.192902 -60.251593)
			(xy 60.248339 -60.257693) (xy 60.302296 -60.271799) (xy 60.353625 -60.293611) (xy 60.401231 -60.322665)
			(xy 60.444099 -60.35834) (xy 60.481316 -60.399877) (xy 60.512089 -60.44639) (xy 60.535761 -60.496887)
			(xy 60.551829 -60.550294) (xy 60.559949 -60.60547) (xy 60.560458 -60.633356) (xy 60.559949 -60.661242)
			(xy 60.551829 -60.716418) (xy 60.535761 -60.769825) (xy 60.512089 -60.820322) (xy 60.481316 -60.866835)
			(xy 60.444099 -60.908372) (xy 60.401231 -60.944047) (xy 60.353625 -60.973101) (xy 60.302296 -60.994913)
			(xy 60.248339 -61.009019) (xy 60.192902 -61.015119) (xy 60.137168 -61.013082) (xy 60.082325 -61.002952)
			(xy 60.029541 -60.984945) (xy 59.979941 -60.959444) (xy 59.934583 -60.926993) (xy 59.894434 -60.888284)
			(xy 59.860348 -60.844141) (xy 59.833052 -60.795506) (xy 59.813129 -60.743415) (xy 59.801003 -60.688978)
			(xy 59.796932 -60.633356) (xy 53.586888 -60.633356) (xy 53.586888 -61.487812) (xy 58.304428 -61.487812)
			(xy 58.308499 -61.43219) (xy 58.320625 -61.377753) (xy 58.340548 -61.325662) (xy 58.367844 -61.277027)
			(xy 58.40193 -61.232884) (xy 58.442079 -61.194175) (xy 58.487437 -61.161724) (xy 58.537037 -61.136223)
			(xy 58.589821 -61.118216) (xy 58.644664 -61.108086) (xy 58.700398 -61.106049) (xy 58.755835 -61.112149)
			(xy 58.809792 -61.126255) (xy 58.861121 -61.148067) (xy 58.908727 -61.177121) (xy 58.951595 -61.212796)
			(xy 58.988812 -61.254333) (xy 59.019585 -61.300846) (xy 59.043257 -61.351343) (xy 59.059325 -61.40475)
			(xy 59.067445 -61.459926) (xy 59.067954 -61.487812) (xy 59.067445 -61.515698) (xy 59.059325 -61.570874)
			(xy 59.043257 -61.624281) (xy 59.019585 -61.674778) (xy 58.988812 -61.721291) (xy 58.951595 -61.762828)
			(xy 58.908727 -61.798503) (xy 58.861121 -61.827557) (xy 58.809792 -61.849369) (xy 58.755835 -61.863475)
			(xy 58.700398 -61.869575) (xy 58.644664 -61.867538) (xy 58.589821 -61.857408) (xy 58.537037 -61.839401)
			(xy 58.487437 -61.8139) (xy 58.442079 -61.781449) (xy 58.40193 -61.74274) (xy 58.367844 -61.698597)
			(xy 58.340548 -61.649962) (xy 58.320625 -61.597871) (xy 58.308499 -61.543434) (xy 58.304428 -61.487812)
			(xy 53.586888 -61.487812) (xy 53.586888 -62.121034) (xy 56.242202 -62.121034) (xy 56.246273 -62.065412)
			(xy 56.258399 -62.010975) (xy 56.278322 -61.958884) (xy 56.305618 -61.910249) (xy 56.339704 -61.866106)
			(xy 56.379853 -61.827397) (xy 56.425211 -61.794946) (xy 56.474811 -61.769445) (xy 56.527595 -61.751438)
			(xy 56.582438 -61.741308) (xy 56.638172 -61.739271) (xy 56.693609 -61.745371) (xy 56.747566 -61.759477)
			(xy 56.798895 -61.781289) (xy 56.846501 -61.810343) (xy 56.889369 -61.846018) (xy 56.926586 -61.887555)
			(xy 56.957359 -61.934068) (xy 56.981031 -61.984565) (xy 56.997099 -62.037972) (xy 57.005219 -62.093148)
			(xy 57.005728 -62.121034) (xy 57.005219 -62.14892) (xy 56.997099 -62.204096) (xy 56.981031 -62.257503)
			(xy 56.957359 -62.308) (xy 56.926586 -62.354513) (xy 56.889369 -62.39605) (xy 56.846501 -62.431725)
			(xy 56.798895 -62.460779) (xy 56.747566 -62.482591) (xy 56.693609 -62.496697) (xy 56.638172 -62.502797)
			(xy 56.582438 -62.50076) (xy 56.527595 -62.49063) (xy 56.474811 -62.472623) (xy 56.425211 -62.447122)
			(xy 56.379853 -62.414671) (xy 56.339704 -62.375962) (xy 56.305618 -62.331819) (xy 56.278322 -62.283184)
			(xy 56.258399 -62.231093) (xy 56.246273 -62.176656) (xy 56.242202 -62.121034) (xy 53.586888 -62.121034)
			(xy 53.586888 -62.604142) (xy 53.587904 -62.614048) (xy 53.589682 -62.62243) (xy 53.591259 -62.628796)
			(xy 53.597185 -62.64049) (xy 53.601366 -62.645544) (xy 53.606954 -62.650878) (xy 53.664866 -62.698884)
			(xy 53.668912 -62.702078) (xy 53.677998 -62.706943) (xy 53.6829 -62.708536) (xy 53.694838 -62.712092)
			(xy 53.706014 -62.71006) (xy 53.721394 -62.707625) (xy 53.75242 -62.704954) (xy 53.76799 -62.704726)
			(xy 53.769514 -62.704726) (xy 53.796765 -62.70519) (xy 53.850713 -62.712949) (xy 53.903007 -62.728307)
			(xy 53.952583 -62.75095) (xy 53.998432 -62.780419) (xy 54.03962 -62.816114) (xy 54.075309 -62.857306)
			(xy 54.104773 -62.903159) (xy 54.12741 -62.952738) (xy 54.142761 -63.005034) (xy 54.150513 -63.058983)
			(xy 54.151022 -63.086234) (xy 54.150536 -63.113461) (xy 54.142788 -63.167361) (xy 54.127456 -63.219612)
			(xy 54.10485 -63.269152) (xy 54.102102 -63.273432) (xy 55.576722 -63.273432) (xy 55.580793 -63.21781)
			(xy 55.592919 -63.163373) (xy 55.612842 -63.111282) (xy 55.640138 -63.062647) (xy 55.674224 -63.018504)
			(xy 55.714373 -62.979795) (xy 55.759731 -62.947344) (xy 55.809331 -62.921843) (xy 55.862115 -62.903836)
			(xy 55.916958 -62.893706) (xy 55.972692 -62.891669) (xy 56.028129 -62.897769) (xy 56.082086 -62.911875)
			(xy 56.133415 -62.933687) (xy 56.181021 -62.962741) (xy 56.223889 -62.998416) (xy 56.261106 -63.039953)
			(xy 56.291879 -63.086466) (xy 56.315551 -63.136963) (xy 56.331619 -63.19037) (xy 56.339739 -63.245546)
			(xy 56.340248 -63.273432) (xy 56.339739 -63.301318) (xy 56.331619 -63.356494) (xy 56.315551 -63.409901)
			(xy 56.291879 -63.460398) (xy 56.261106 -63.506911) (xy 56.223889 -63.548448) (xy 56.181021 -63.584123)
			(xy 56.133415 -63.613177) (xy 56.082086 -63.634989) (xy 56.028129 -63.649095) (xy 55.972692 -63.655195)
			(xy 55.916958 -63.653158) (xy 55.862115 -63.643028) (xy 55.809331 -63.625021) (xy 55.759731 -63.59952)
			(xy 55.714373 -63.567069) (xy 55.674224 -63.52836) (xy 55.640138 -63.484217) (xy 55.612842 -63.435582)
			(xy 55.592919 -63.383491) (xy 55.580793 -63.329054) (xy 55.576722 -63.273432) (xy 54.102102 -63.273432)
			(xy 54.07543 -63.314975) (xy 54.039794 -63.356149) (xy 53.998666 -63.391838) (xy 53.952881 -63.421316)
			(xy 53.90337 -63.443985) (xy 53.851138 -63.459384) (xy 53.797248 -63.4672) (xy 53.770022 -63.467742)
			(xy 53.768752 -63.467742) (xy 53.752991 -63.467554) (xy 53.72158 -63.464887) (xy 53.706014 -63.462408)
			(xy 53.695092 -63.46063) (xy 53.683916 -63.463678) (xy 53.678661 -63.465214) (xy 53.668921 -63.470207)
			(xy 53.664612 -63.473584) (xy 53.60543 -63.523114) (xy 53.604922 -63.523622) (xy 53.600912 -63.527231)
			(xy 53.594377 -63.535813) (xy 53.591968 -63.54064) (xy 53.591714 -63.54064) (xy 53.587904 -63.551562)
			(xy 53.586888 -63.56223) (xy 53.586888 -64.556894) (xy 53.58765 -64.565022) (xy 53.58765 -64.56553)
			(xy 53.589249 -64.57305) (xy 53.59622 -64.586743) (xy 53.601366 -64.592454) (xy 53.876448 -64.867536)
			(xy 53.881879 -64.872514) (xy 53.89492 -64.879355) (xy 53.902102 -64.880998) (xy 53.90261 -64.880998)
			(xy 53.912008 -64.882014) (xy 59.235594 -64.882014) (xy 59.23994 -64.881904) (xy 59.248498 -64.880371)
			(xy 59.252612 -64.878966) (xy 59.283346 -64.848232) (xy 59.287918 -64.838072) (xy 59.285632 -64.82334)
			(xy 59.285378 -64.822578) (xy 59.284715 -64.818885) (xy 59.28242 -64.811741) (xy 59.280806 -64.808354)
			(xy 59.273186 -64.797178) (xy 59.253882 -64.775588) (xy 59.2455 -64.77127) (xy 59.237372 -64.766952)
			(xy 59.20724 -64.763104) (xy 59.148286 -64.748463) (xy 59.091788 -64.726148) (xy 59.03874 -64.696552)
			(xy 58.990076 -64.660196) (xy 58.946652 -64.617718) (xy 58.909232 -64.569868) (xy 58.878474 -64.517485)
			(xy 58.85492 -64.461493) (xy 58.838983 -64.402875) (xy 58.830945 -64.342665) (xy 58.830464 -64.312292)
			(xy 58.830933 -64.28234) (xy 58.838753 -64.22295) (xy 58.854258 -64.165088) (xy 58.877184 -64.109745)
			(xy 58.907137 -64.057868) (xy 58.943605 -64.010344) (xy 58.985964 -63.967988) (xy 59.03349 -63.931522)
			(xy 59.085368 -63.901572) (xy 59.140713 -63.87865) (xy 59.198575 -63.863148) (xy 59.257966 -63.855331)
			(xy 59.287918 -63.854838) (xy 59.317609 -63.855306) (xy 59.376491 -63.86298) (xy 59.433886 -63.878211)
			(xy 59.488826 -63.900742) (xy 59.540389 -63.930194) (xy 59.587706 -63.966071) (xy 59.629982 -64.007771)
			(xy 59.666505 -64.054591) (xy 59.696662 -64.105744) (xy 59.719945 -64.16037) (xy 59.728354 -64.188848)
			(xy 59.730894 -64.198246) (xy 59.731148 -64.198754) (xy 59.731656 -64.20104) (xy 59.73191 -64.202056)
			(xy 59.741816 -64.211708) (xy 59.746561 -64.216081) (xy 59.757749 -64.222502) (xy 59.763914 -64.224408)
			(xy 59.7662 -64.224916) (xy 59.849258 -64.24676) (xy 59.854084 -64.247776) (xy 59.865574 -64.24901)
			(xy 59.887647 -64.24225) (xy 59.896502 -64.234822) (xy 59.898026 -64.233552) (xy 60.01893 -64.112648)
			(xy 60.264802 -63.86703) (xy 60.27054 -63.860704) (xy 60.277804 -63.845257) (xy 60.279026 -63.836804)
			(xy 60.27928 -63.83147) (xy 60.27928 -63.136272) (xy 60.278772 -63.135002) (xy 60.268866 -63.127636)
			(xy 60.268612 -63.127636) (xy 60.221368 -63.092076) (xy 60.202826 -63.078106) (xy 60.201302 -63.07709)
			(xy 60.195714 -63.074042) (xy 60.189672 -63.071327) (xy 60.176681 -63.068759) (xy 60.17006 -63.068962)
			(xy 60.162694 -63.069978) (xy 60.158122 -63.071248) (xy 60.131139 -63.078871) (xy 60.075667 -63.087025)
			(xy 60.047632 -63.087504) (xy 60.047124 -63.087504) (xy 60.01987 -63.087042) (xy 59.965917 -63.079288)
			(xy 59.913616 -63.063934) (xy 59.864033 -63.041293) (xy 59.818178 -63.011825) (xy 59.776982 -62.976132)
			(xy 59.741287 -62.934938) (xy 59.711817 -62.889084) (xy 59.689173 -62.839502) (xy 59.673816 -62.787203)
			(xy 59.666059 -62.73325) (xy 59.665616 -62.705996) (xy 59.666097 -62.678826) (xy 59.673808 -62.625037)
			(xy 59.689074 -62.572886) (xy 59.711586 -62.523429) (xy 59.740888 -62.477667) (xy 59.776387 -62.436526)
			(xy 59.817365 -62.400838) (xy 59.862992 -62.371327) (xy 59.912345 -62.348589) (xy 59.964425 -62.333083)
			(xy 60.018179 -62.325125) (xy 60.045346 -62.324488) (xy 60.047886 -62.324488) (xy 60.075288 -62.324996)
			(xy 60.129521 -62.332903) (xy 60.182065 -62.348486) (xy 60.207144 -62.35954) (xy 60.214256 -62.362842)
			(xy 60.215526 -62.36335) (xy 60.21578 -62.363604) (xy 60.219336 -62.364366) (xy 60.228226 -62.364366)
			(xy 60.235494 -62.36413) (xy 60.249428 -62.35999) (xy 60.255658 -62.356238) (xy 60.277248 -62.342522)
			(xy 60.27928 -62.338458) (xy 60.27928 -62.240414) (xy 60.27801 -62.237874) (xy 60.266475 -62.216459)
			(xy 60.248327 -62.17133) (xy 60.236063 -62.12426) (xy 60.229881 -62.076013) (xy 60.229496 -62.051692)
			(xy 60.229496 -62.051438) (xy 60.229957 -62.024183) (xy 60.237709 -61.970229) (xy 60.253062 -61.917926)
			(xy 60.275703 -61.868342) (xy 60.30517 -61.822484) (xy 60.340863 -61.781287) (xy 60.382057 -61.74559)
			(xy 60.427912 -61.716119) (xy 60.477495 -61.693474) (xy 60.529795 -61.678117) (xy 60.58375 -61.670359)
			(xy 60.611004 -61.66993) (xy 60.611766 -61.66993) (xy 60.642948 -61.670568) (xy 60.704478 -61.680734)
			(xy 60.763543 -61.700753) (xy 60.791344 -61.714888) (xy 60.794646 -61.716412) (xy 60.800488 -61.71946)
			(xy 61.508386 -61.71946) (xy 61.517568 -61.711896) (xy 61.5283 -61.690698) (xy 61.52896 -61.67882)
			(xy 61.52896 -58.87085) (xy 61.528749 -58.864764) (xy 61.525791 -58.852954) (xy 61.523118 -58.847482)
			(xy 61.5188 -58.839862) (xy 61.50991 -58.830718) (xy 61.505084 -58.827924) (xy 61.503814 -58.827162)
			(xy 61.458856 -58.800746) (xy 61.430154 -58.783982) (xy 61.42548 -58.781462) (xy 61.415361 -58.778251)
			(xy 61.410088 -58.777632) (xy 61.399928 -58.777124) (xy 61.378846 -58.782204) (xy 61.37275 -58.785506)
			(xy 61.344782 -58.799851) (xy 61.285319 -58.820206) (xy 61.223327 -58.830556) (xy 61.191902 -58.831226)
			(xy 61.190886 -58.831226) (xy 61.163634 -58.830739) (xy 61.109685 -58.822981) (xy 61.05739 -58.807624)
			(xy 61.007812 -58.784981) (xy 60.961961 -58.755513) (xy 60.920771 -58.719819) (xy 60.885079 -58.678628)
			(xy 60.855613 -58.632776) (xy 60.832971 -58.583197) (xy 60.817616 -58.530901) (xy 60.80986 -58.476952)
			(xy 60.80986 -58.422448) (xy 60.817616 -58.368499) (xy 60.832971 -58.316203) (xy 60.855613 -58.266624)
			(xy 60.885079 -58.220772) (xy 60.920771 -58.179581) (xy 60.961961 -58.143887) (xy 61.007812 -58.114419)
			(xy 61.05739 -58.091776) (xy 61.109685 -58.076419) (xy 61.163634 -58.068661) (xy 61.190886 -58.06821)
			(xy 61.191648 -58.06821) (xy 61.223074 -58.06887) (xy 61.285071 -58.079211) (xy 61.344535 -58.099571)
			(xy 61.372496 -58.11393) (xy 61.378084 -58.116978) (xy 61.396626 -58.121804) (xy 61.408269 -58.124169)
			(xy 61.431454 -58.119124) (xy 61.441076 -58.112152) (xy 61.453268 -58.1025) (xy 61.458856 -58.09869)
			(xy 61.504068 -58.071766) (xy 61.505338 -58.071004) (xy 61.5061 -58.070496) (xy 61.513741 -58.064939)
			(xy 61.524691 -58.049564) (xy 61.527436 -58.040524) (xy 61.52896 -58.028078) (xy 61.52896 -54.862984)
			(xy 61.528666 -54.857851) (xy 61.52624 -54.847862) (xy 61.524134 -54.843172) (xy 61.518546 -54.840886)
			(xy 61.497718 -54.83225) (xy 61.488331 -54.828707) (xy 61.468285 -54.828543) (xy 61.449725 -54.836123)
			(xy 61.442346 -54.842918) (xy 58.418199 -57.867296) (xy 59.643008 -57.867296) (xy 59.647079 -57.811674)
			(xy 59.659205 -57.757237) (xy 59.679128 -57.705146) (xy 59.706424 -57.656511) (xy 59.74051 -57.612368)
			(xy 59.780659 -57.573659) (xy 59.826017 -57.541208) (xy 59.875617 -57.515707) (xy 59.928401 -57.4977)
			(xy 59.983244 -57.48757) (xy 60.038978 -57.485533) (xy 60.094415 -57.491633) (xy 60.148372 -57.505739)
			(xy 60.199701 -57.527551) (xy 60.247307 -57.556605) (xy 60.290175 -57.59228) (xy 60.327392 -57.633817)
			(xy 60.358165 -57.68033) (xy 60.381837 -57.730827) (xy 60.397905 -57.784234) (xy 60.406025 -57.83941)
			(xy 60.406534 -57.867296) (xy 60.406025 -57.895182) (xy 60.397905 -57.950358) (xy 60.381837 -58.003765)
			(xy 60.358165 -58.054262) (xy 60.327392 -58.100775) (xy 60.290175 -58.142312) (xy 60.247307 -58.177987)
			(xy 60.199701 -58.207041) (xy 60.148372 -58.228853) (xy 60.094415 -58.242959) (xy 60.038978 -58.249059)
			(xy 59.983244 -58.247022) (xy 59.928401 -58.236892) (xy 59.875617 -58.218885) (xy 59.826017 -58.193384)
			(xy 59.780659 -58.160933) (xy 59.74051 -58.122224) (xy 59.706424 -58.078081) (xy 59.679128 -58.029446)
			(xy 59.659205 -57.977355) (xy 59.647079 -57.922918) (xy 59.643008 -57.867296) (xy 58.418199 -57.867296)
			(xy 58.11266 -58.172858) (xy 58.10631 -58.183526) (xy 58.104532 -58.189368) (xy 58.096083 -58.214935)
			(xy 58.073003 -58.263584) (xy 58.043317 -58.308507) (xy 58.007614 -58.348814) (xy 57.966602 -58.383705)
			(xy 57.921094 -58.412488) (xy 57.871994 -58.434591) (xy 57.820276 -58.449577) (xy 57.766965 -58.457148)
			(xy 57.740042 -58.457592) (xy 57.712788 -58.457132) (xy 57.658833 -58.449379) (xy 57.606531 -58.434027)
			(xy 57.556947 -58.411386) (xy 57.511089 -58.381919) (xy 57.469893 -58.346225) (xy 57.434196 -58.305031)
			(xy 57.404726 -58.259176) (xy 57.382082 -58.209593) (xy 57.366726 -58.157292) (xy 57.35897 -58.103338)
			(xy 57.358534 -58.076084) (xy 57.35828 -58.076084) (xy 57.358737 -58.049147) (xy 57.366302 -57.995807)
			(xy 57.381294 -57.944062) (xy 57.403414 -57.894939) (xy 57.432223 -57.849415) (xy 57.467148 -57.808395)
			(xy 57.507495 -57.772695) (xy 57.552461 -57.743024) (xy 57.601154 -57.719972) (xy 57.626758 -57.711594)
			(xy 57.627012 -57.711594) (xy 57.632845 -57.70958) (xy 57.643377 -57.703156) (xy 57.64784 -57.698894)
			(xy 61.190632 -54.156102) (xy 61.19114 -54.148736) (xy 61.19114 -46.159166) (xy 61.191075 -46.155561)
			(xy 61.190051 -46.148423) (xy 61.189108 -46.144942) (xy 61.187584 -46.14037) (xy 61.183774 -46.131226)
			(xy 55.361332 -40.30853) (xy 55.355744 -40.303704) (xy 52.466494 -40.303704) (xy 52.462684 -40.305736)
			(xy 52.434193 -40.320732) (xy 52.37343 -40.342007) (xy 52.309962 -40.352804) (xy 52.277772 -40.353488)
			(xy 52.250523 -40.353) (xy 52.196579 -40.34524) (xy 52.144289 -40.329882) (xy 52.094716 -40.307239)
			(xy 52.048871 -40.277772) (xy 52.007686 -40.24208) (xy 51.971999 -40.20089) (xy 51.942538 -40.155041)
			(xy 51.919901 -40.105466) (xy 51.90455 -40.053174) (xy 51.896797 -39.999229) (xy 51.896264 -39.97198)
			(xy 51.896745 -39.944821) (xy 51.904451 -39.891053) (xy 51.919705 -39.838921) (xy 51.942198 -39.78948)
			(xy 51.971477 -39.743728) (xy 52.006947 -39.702592) (xy 52.047894 -39.666901) (xy 52.093488 -39.637379)
			(xy 52.142809 -39.614622) (xy 52.194858 -39.599089) (xy 52.248584 -39.591095) (xy 52.27574 -39.590472)
			(xy 52.278534 -39.590472) (xy 52.310597 -39.591195) (xy 52.373804 -39.602033) (xy 52.434316 -39.623264)
			(xy 52.462684 -39.638224) (xy 52.466494 -39.640256) (xy 55.048404 -39.640256) (xy 55.058447 -39.63983)
			(xy 55.076995 -39.632119) (xy 55.091163 -39.61788) (xy 55.095394 -39.60876) (xy 55.106824 -39.581074)
			(xy 55.105554 -39.574724) (xy 54.942486 -39.41191) (xy 51.743864 -36.213288) (xy 51.73853 -36.208716)
			(xy 50.738532 -36.208716) (xy 50.729642 -36.216844) (xy 50.69713 -36.261802) (xy 50.68062 -36.284916)
			(xy 50.676879 -36.291024) (xy 50.672608 -36.304688) (xy 50.672238 -36.31184) (xy 50.672238 -36.331906)
			(xy 50.674524 -36.339526) (xy 50.682688 -36.367329) (xy 50.691483 -36.424601) (xy 50.69205 -36.453572)
			(xy 50.691566 -36.480826) (xy 50.683813 -36.534779) (xy 50.668461 -36.587079) (xy 50.645822 -36.636663)
			(xy 50.616357 -36.68252) (xy 50.580666 -36.723717) (xy 50.539476 -36.759415) (xy 50.493624 -36.788888)
			(xy 50.444045 -36.811536) (xy 50.391747 -36.826898) (xy 50.337796 -36.834661) (xy 50.310542 -36.83508)
			(xy 50.283416 -36.834606) (xy 50.229712 -36.826926) (xy 50.177637 -36.811715) (xy 50.128242 -36.78928)
			(xy 50.082524 -36.760073) (xy 50.041404 -36.724684) (xy 50.005714 -36.683826) (xy 49.976171 -36.638324)
			(xy 49.953373 -36.589096) (xy 49.937779 -36.537134) (xy 49.929704 -36.483487) (xy 49.929034 -36.456366)
			(xy 49.929034 -36.45281) (xy 49.929595 -36.423839) (xy 49.938401 -36.366569) (xy 49.94656 -36.338764)
			(xy 49.947322 -36.336224) (xy 49.948846 -36.331398) (xy 49.950116 -36.320984) (xy 49.95037 -36.31057)
			(xy 49.949354 -36.2966) (xy 49.893728 -36.219638) (xy 49.89142 -36.216578) (xy 49.886065 -36.211095)
			(xy 49.88306 -36.208716) (xy 49.360328 -36.208716) (xy 49.354486 -36.211764) (xy 49.351184 -36.213288)
			(xy 49.323383 -36.227427) (xy 49.264322 -36.247463) (xy 49.202789 -36.257634) (xy 49.171606 -36.258246)
			(xy 49.170844 -36.258246) (xy 49.143586 -36.257786) (xy 49.089625 -36.250033) (xy 49.037317 -36.23468)
			(xy 48.987726 -36.212037) (xy 48.941863 -36.182568) (xy 48.900661 -36.14687) (xy 48.864959 -36.105672)
			(xy 48.835484 -36.059812) (xy 48.812836 -36.010224) (xy 48.797476 -35.957918) (xy 48.789717 -35.903958)
			(xy 48.789717 -35.849442) (xy 48.797476 -35.795482) (xy 48.812836 -35.743176) (xy 48.835484 -35.693587)
			(xy 48.864959 -35.647728) (xy 48.900661 -35.60653) (xy 48.941863 -35.570832) (xy 48.987726 -35.541363)
			(xy 49.037317 -35.51872) (xy 49.089625 -35.503367) (xy 49.143586 -35.495614) (xy 49.170844 -35.49523)
			(xy 49.171606 -35.49523) (xy 49.202787 -35.495872) (xy 49.264315 -35.506044) (xy 49.323376 -35.526068)
			(xy 49.351184 -35.540188) (xy 49.354486 -35.541712) (xy 49.360328 -35.54476) (xy 51.574954 -35.54476)
			(xy 51.584202 -35.544303) (xy 51.60147 -35.537657) (xy 51.615283 -35.525347) (xy 51.619912 -35.517328)
			(xy 51.630326 -35.492436) (xy 51.630326 -35.48888) (xy 51.62677 -35.480244) (xy 51.624768 -35.475518)
			(xy 51.619141 -35.466936) (xy 51.615594 -35.463226) (xy 51.44643 -35.294316) (xy 49.906936 -33.754822)
			(xy 49.887628 -33.734644) (xy 49.855573 -33.688918) (xy 49.843182 -33.66389) (xy 49.831244 -33.634934)
			(xy 49.827942 -33.625028) (xy 49.825656 -33.618932) (xy 49.824132 -33.613344) (xy 49.823878 -33.611566)
			(xy 49.823116 -33.608772) (xy 49.818798 -33.589214) (xy 49.818798 -33.587944) (xy 49.817782 -33.583118)
			(xy 49.813718 -33.555432) (xy 49.813718 -33.553908) (xy 49.812956 -33.530032) (xy 49.812956 -28.695142)
			(xy 49.811178 -28.681934) (xy 49.805844 -28.662884) (xy 49.802796 -28.65755) (xy 49.793696 -28.641035)
			(xy 49.778429 -28.606554) (xy 49.772316 -28.588716) (xy 49.772316 -28.588208) (xy 49.770284 -28.582366)
			(xy 49.770284 -28.582112) (xy 49.768237 -28.576451) (xy 49.761949 -28.56619) (xy 49.757838 -28.561792)
			(xy 49.599342 -28.403296) (xy 49.59223 -28.402788) (xy 46.6852 -28.402788) (xy 46.659909 -28.402293)
			(xy 46.60995 -28.394386) (xy 46.56184 -28.378767) (xy 46.516763 -28.35582) (xy 46.475828 -28.326108)
			(xy 46.457616 -28.308554) (xy 45.928026 -27.77871) (xy 45.921952 -27.77301) (xy 45.907029 -27.765631)
			(xy 45.898816 -27.764232) (xy 45.891958 -27.763724) (xy 45.710602 -27.763724) (xy 45.700939 -27.764202)
			(xy 45.683024 -27.771465) (xy 45.669071 -27.784845) (xy 45.664628 -27.793442) (xy 45.65269 -27.821128)
			(xy 45.62729 -27.88031) (xy 45.625384 -27.885171) (xy 45.62334 -27.895409) (xy 45.623226 -27.90063)
			(xy 45.636942 -27.93492) (xy 45.643292 -27.941778) (xy 45.662029 -27.962909) (xy 45.694706 -28.008973)
			(xy 45.721474 -28.058704) (xy 45.741926 -28.111348) (xy 45.755753 -28.166107) (xy 45.762745 -28.22215)
			(xy 45.76318 -28.250388) (xy 45.76318 -29.114242) (xy 45.76269 -29.144226) (xy 45.754862 -29.203682)
			(xy 45.739341 -29.261607) (xy 45.716392 -29.317011) (xy 45.686408 -29.368945) (xy 45.649902 -29.416521)
			(xy 45.607497 -29.458926) (xy 45.559921 -29.495432) (xy 45.507987 -29.525416) (xy 45.452583 -29.548365)
			(xy 45.394658 -29.563886) (xy 45.335202 -29.571714) (xy 45.275234 -29.571714) (xy 45.215778 -29.563886)
			(xy 45.157853 -29.548365) (xy 45.102449 -29.525416) (xy 45.050515 -29.495432) (xy 45.002939 -29.458926)
			(xy 44.960534 -29.416521) (xy 44.924028 -29.368945) (xy 44.894044 -29.317011) (xy 44.871095 -29.261607)
			(xy 44.855574 -29.203682) (xy 44.847746 -29.144226) (xy 44.847256 -29.114242) (xy 44.847256 -28.250388)
			(xy 44.847688 -28.222149) (xy 44.854664 -28.166102) (xy 44.868484 -28.11134) (xy 44.888938 -28.058694)
			(xy 44.915714 -28.008966) (xy 44.948407 -27.962911) (xy 44.967144 -27.941778) (xy 44.973494 -27.93492)
			(xy 44.98721 -27.90063) (xy 44.987149 -27.895404) (xy 44.985105 -27.885155) (xy 44.983146 -27.88031)
			(xy 44.957746 -27.821128) (xy 44.945808 -27.793442) (xy 44.941412 -27.784816) (xy 44.927439 -27.771438)
			(xy 44.909504 -27.764188) (xy 44.899834 -27.763724) (xy 44.834048 -27.763724) (xy 44.808025 -27.763196)
			(xy 44.756622 -27.755029) (xy 44.707126 -27.738933) (xy 44.66075 -27.715305) (xy 44.618634 -27.684725)
			(xy 44.59986 -27.666696) (xy 43.525948 -26.592784) (xy 43.518525 -26.594016) (xy 43.504115 -26.598348)
			(xy 43.497246 -26.60142) (xy 43.496738 -26.60142) (xy 43.484041 -26.608035) (xy 43.462676 -26.627073)
			(xy 43.447446 -26.651299) (xy 43.439549 -26.678805) (xy 43.43908 -26.693114) (xy 43.43908 -27.342846)
			(xy 43.43859 -27.372814) (xy 43.430767 -27.432236) (xy 43.415254 -27.490129) (xy 43.392318 -27.545502)
			(xy 43.362351 -27.597408) (xy 43.325864 -27.644958) (xy 43.283484 -27.687338) (xy 43.235934 -27.723825)
			(xy 43.184028 -27.753792) (xy 43.128655 -27.776728) (xy 43.070762 -27.792241) (xy 43.01134 -27.800064)
			(xy 42.951404 -27.800064) (xy 42.891982 -27.792241) (xy 42.834089 -27.776728) (xy 42.778716 -27.753792)
			(xy 42.72681 -27.723825) (xy 42.67926 -27.687338) (xy 42.63688 -27.644958) (xy 42.600393 -27.597408)
			(xy 42.570426 -27.545502) (xy 42.54749 -27.490129) (xy 42.531977 -27.432236) (xy 42.524154 -27.372814)
			(xy 42.523664 -27.342846) (xy 42.523664 -26.734008) (xy 42.52341 -26.479246) (xy 42.523909 -26.448419)
			(xy 42.532172 -26.387322) (xy 42.548556 -26.327885) (xy 42.572763 -26.271183) (xy 42.604357 -26.21824)
			(xy 42.642766 -26.170013) (xy 42.687297 -26.127374) (xy 42.737145 -26.091092) (xy 42.791409 -26.061825)
			(xy 42.820082 -26.050494) (xy 42.825924 -26.048208) (xy 42.83075 -26.044906) (xy 42.83964 -26.037286)
			(xy 42.855388 -26.020014) (xy 42.85933 -26.015406) (xy 42.865118 -26.004753) (xy 42.866818 -25.998932)
			(xy 42.87266 -25.973278) (xy 42.874273 -25.96485) (xy 42.872416 -25.947801) (xy 42.865039 -25.932318)
			(xy 42.859198 -25.926034) (xy 42.669968 -25.736804) (xy 42.667115 -25.734101) (xy 42.660734 -25.729514)
			(xy 42.657268 -25.72766) (xy 42.651842 -25.725073) (xy 42.640162 -25.722243) (xy 42.634154 -25.722072)
			(xy 40.379904 -25.722072) (xy 40.374062 -25.72512) (xy 40.368474 -25.727914) (xy 40.340974 -25.741688)
			(xy 40.282638 -25.761165) (xy 40.221933 -25.77103) (xy 40.191182 -25.771602) (xy 40.163932 -25.771115)
			(xy 40.109986 -25.763356) (xy 40.057694 -25.748) (xy 40.008119 -25.725357) (xy 39.962272 -25.69589)
			(xy 39.921084 -25.660199) (xy 39.885395 -25.619009) (xy 39.855931 -25.573159) (xy 39.833292 -25.523583)
			(xy 39.817939 -25.47129) (xy 39.810183 -25.417344) (xy 39.809674 -25.390094) (xy 39.810162 -25.362164)
			(xy 39.818308 -25.306901) (xy 39.834425 -25.253417) (xy 39.858169 -25.202854) (xy 39.889032 -25.156294)
			(xy 39.926355 -25.114732) (xy 39.969338 -25.079057) (xy 40.017065 -25.05003) (xy 40.068514 -25.028273)
			(xy 40.095424 -25.020778) (xy 40.102282 -25.019) (xy 40.108886 -25.01519) (xy 40.119046 -25.007316)
			(xy 40.127174 -24.999188) (xy 40.13508 -24.990339) (xy 40.142485 -24.967826) (xy 40.141398 -24.956008)
			(xy 39.789608 -24.604218) (xy 39.764426 -24.578275) (xy 39.719983 -24.521245) (xy 39.682891 -24.459182)
			(xy 39.653715 -24.393028) (xy 39.632897 -24.323788) (xy 39.626286 -24.288242) (xy 39.621968 -24.263604)
			(xy 39.617884 -24.259839) (xy 39.608392 -24.254074) (xy 39.603172 -24.252174) (xy 39.594028 -24.249126)
			(xy 39.525448 -24.22779) (xy 39.515796 -24.224742) (xy 39.51046 -24.223302) (xy 39.499437 -24.222537)
			(xy 39.493952 -24.223218) (xy 39.29253 -24.42464) (xy 39.27376 -24.442675) (xy 39.231645 -24.47326)
			(xy 39.185269 -24.496891) (xy 39.135771 -24.512988) (xy 39.084366 -24.521156) (xy 39.058342 -24.521668)
			(xy 37.869622 -24.521668) (xy 37.865812 -24.5237) (xy 37.837321 -24.538699) (xy 37.776559 -24.559981)
			(xy 37.713091 -24.570783) (xy 37.6809 -24.571452) (xy 37.653648 -24.570966) (xy 37.599698 -24.56321)
			(xy 37.5474 -24.547855) (xy 37.49782 -24.525215) (xy 37.451967 -24.495749) (xy 37.410773 -24.460058)
			(xy 37.375077 -24.418869) (xy 37.345606 -24.373018) (xy 37.32296 -24.323441) (xy 37.307599 -24.271146)
			(xy 37.299837 -24.217196) (xy 37.299392 -24.189944) (xy 37.299868 -24.162783) (xy 37.307567 -24.109009)
			(xy 37.322816 -24.056872) (xy 37.345306 -24.007424) (xy 37.374583 -23.961666) (xy 37.410054 -23.920524)
			(xy 37.451003 -23.88483) (xy 37.4966 -23.855304) (xy 37.545925 -23.832545) (xy 37.597979 -23.817013)
			(xy 37.65171 -23.809021) (xy 37.678868 -23.808436) (xy 37.681662 -23.808436) (xy 37.713724 -23.809162)
			(xy 37.776928 -23.820005) (xy 37.837437 -23.841243) (xy 37.865812 -23.856188) (xy 37.869622 -23.85822)
			(xy 38.899338 -23.85822) (xy 38.90264 -23.85822) (xy 38.911662 -23.857275) (xy 38.928201 -23.84986)
			(xy 38.934898 -23.843742) (xy 39.014654 -23.763732) (xy 39.05377 -23.724616) (xy 39.054321 -23.720241)
			(xy 39.054063 -23.711427) (xy 39.053262 -23.70709) (xy 39.048182 -23.69058) (xy 39.048182 -23.690072)
			(xy 39.025068 -23.616412) (xy 39.023199 -23.611065) (xy 39.017425 -23.601321) (xy 39.013638 -23.597108)
			(xy 39.01059 -23.5966) (xy 38.989 -23.59279) (xy 38.956185 -23.586357) (xy 38.892171 -23.56701) (xy 38.83078 -23.540493)
			(xy 38.772811 -23.507153) (xy 38.719019 -23.467424) (xy 38.670104 -23.421824) (xy 38.626705 -23.370946)
			(xy 38.589387 -23.315454) (xy 38.558636 -23.256071) (xy 38.546278 -23.224998) (xy 38.537388 -23.201884)
			(xy 38.533578 -23.198582) (xy 38.438328 -23.178516) (xy 38.433248 -23.1775) (xy 38.425374 -23.175722)
			(xy 38.421056 -23.176992) (xy 38.158674 -23.439374) (xy 38.13511 -23.462272) (xy 38.083726 -23.503226)
			(xy 38.028083 -23.538174) (xy 37.96888 -23.566678) (xy 37.90686 -23.588379) (xy 37.842801 -23.603006)
			(xy 37.777508 -23.610374) (xy 37.744654 -23.610824) (xy 37.7444 -23.610824) (xy 37.709003 -23.61029)
			(xy 37.638724 -23.601757) (xy 37.569986 -23.584814) (xy 37.503792 -23.55971) (xy 37.441106 -23.52681)
			(xy 37.382843 -23.486594) (xy 37.329852 -23.439648) (xy 37.282906 -23.386657) (xy 37.24269 -23.328394)
			(xy 37.20979 -23.265708) (xy 37.184686 -23.199514) (xy 37.167743 -23.130776) (xy 37.15921 -23.060497)
			(xy 37.158676 -23.0251) (xy 37.158676 -23.024846) (xy 37.159134 -22.991991) (xy 37.166485 -22.926694)
			(xy 37.181101 -22.862631) (xy 37.202798 -22.800607) (xy 37.231302 -22.741402) (xy 37.266255 -22.68576)
			(xy 37.307219 -22.634382) (xy 37.330126 -22.610826) (xy 37.952426 -21.988526) (xy 37.97599 -21.965628)
			(xy 38.027374 -21.924674) (xy 38.083017 -21.889726) (xy 38.14222 -21.861222) (xy 38.20424 -21.839521)
			(xy 38.268299 -21.824894) (xy 38.333592 -21.817526) (xy 38.366446 -21.817076) (xy 41.978326 -21.817076)
			(xy 41.97858 -21.817076) (xy 41.988763 -21.816576) (xy 42.007506 -21.808597) (xy 42.014902 -21.801582)
			(xy 42.016934 -21.799296) (xy 42.067226 -21.740114) (xy 42.070704 -21.735883) (xy 42.075959 -21.726276)
			(xy 42.07764 -21.721064) (xy 42.080434 -21.710904) (xy 42.079672 -21.70557) (xy 42.076969 -21.689321)
			(xy 42.074042 -21.656509) (xy 42.07383 -21.640038) (xy 42.07383 -21.63572) (xy 42.074598 -21.607317)
			(xy 42.08351 -21.551205) (xy 42.100647 -21.497035) (xy 42.125632 -21.446007) (xy 42.15791 -21.39925)
			(xy 42.176954 -21.378164) (xy 42.183812 -21.371052) (xy 42.187368 -21.362162) (xy 42.189908 -21.353018)
			(xy 42.19067 -21.344128) (xy 42.19067 -21.27377) (xy 42.190606 -21.269636) (xy 42.189336 -21.261468)
			(xy 42.18813 -21.257514) (xy 42.187368 -21.255736) (xy 42.184066 -21.2471) (xy 42.176954 -21.23948)
			(xy 42.15768 -21.218154) (xy 42.125109 -21.170792) (xy 42.100012 -21.119079) (xy 42.082958 -21.064186)
			(xy 42.074332 -21.007356) (xy 42.07433 -20.949876) (xy 42.082951 -20.893045) (xy 42.100001 -20.838151)
			(xy 42.125093 -20.786436) (xy 42.15766 -20.739071) (xy 42.176954 -20.717764) (xy 42.184066 -20.710144)
			(xy 42.187368 -20.701508) (xy 42.18813 -20.69973) (xy 42.189362 -20.695781) (xy 42.190639 -20.68761)
			(xy 42.19067 -20.683474) (xy 42.19067 -20.61337) (xy 42.190606 -20.609236) (xy 42.189336 -20.601068)
			(xy 42.18813 -20.597114) (xy 42.187368 -20.595336) (xy 42.184066 -20.5867) (xy 42.176954 -20.57908)
			(xy 42.15768 -20.557754) (xy 42.125109 -20.510392) (xy 42.100012 -20.458679) (xy 42.082958 -20.403786)
			(xy 42.074332 -20.346956) (xy 42.07433 -20.289476) (xy 42.082951 -20.232645) (xy 42.100001 -20.177751)
			(xy 42.125093 -20.126036) (xy 42.15766 -20.078671) (xy 42.176954 -20.057364) (xy 42.184066 -20.049744)
			(xy 42.187368 -20.041108) (xy 42.18813 -20.03933) (xy 42.189362 -20.035381) (xy 42.190639 -20.02721)
			(xy 42.19067 -20.023074) (xy 42.19067 -19.95297) (xy 42.190606 -19.948836) (xy 42.189336 -19.940668)
			(xy 42.18813 -19.936714) (xy 42.187368 -19.934936) (xy 42.184066 -19.9263) (xy 42.176954 -19.91868)
			(xy 42.15768 -19.897354) (xy 42.125109 -19.849992) (xy 42.100012 -19.798279) (xy 42.082958 -19.743386)
			(xy 42.074332 -19.686556) (xy 42.07433 -19.629076) (xy 42.082951 -19.572245) (xy 42.100001 -19.517351)
			(xy 42.125093 -19.465636) (xy 42.15766 -19.418271) (xy 42.176954 -19.396964) (xy 42.184066 -19.389344)
			(xy 42.187368 -19.380708) (xy 42.18813 -19.37893) (xy 42.189362 -19.374981) (xy 42.190639 -19.36681)
			(xy 42.19067 -19.362674) (xy 42.19067 -19.29257) (xy 42.190606 -19.288436) (xy 42.189336 -19.280268)
			(xy 42.18813 -19.276314) (xy 42.187368 -19.274536) (xy 42.184066 -19.2659) (xy 42.176954 -19.25828)
			(xy 42.157685 -19.236952) (xy 42.125123 -19.189588) (xy 42.100033 -19.137877) (xy 42.082983 -19.082987)
			(xy 42.074359 -19.02616) (xy 42.07383 -18.997422) (xy 42.074316 -18.970171) (xy 42.082072 -18.916223)
			(xy 42.097427 -18.863928) (xy 42.120069 -18.814351) (xy 42.149535 -18.768501) (xy 42.185226 -18.72731)
			(xy 42.226417 -18.691619) (xy 42.272267 -18.662153) (xy 42.321844 -18.639511) (xy 42.374139 -18.624156)
			(xy 42.428087 -18.6164) (xy 42.482589 -18.6164) (xy 42.536537 -18.624156) (xy 42.588832 -18.639511)
			(xy 42.638409 -18.662153) (xy 42.684259 -18.691619) (xy 42.72545 -18.72731) (xy 42.761141 -18.768501)
			(xy 42.790607 -18.814351) (xy 42.813249 -18.863928) (xy 42.828604 -18.916223) (xy 42.83636 -18.970171)
			(xy 42.836846 -18.997422) (xy 42.836323 -19.02616) (xy 42.827697 -19.082985) (xy 42.810642 -19.137873)
			(xy 42.785546 -19.189581) (xy 42.752976 -19.236938) (xy 42.733722 -19.25828) (xy 42.72661 -19.2659)
			(xy 42.723308 -19.274536) (xy 42.722546 -19.276314) (xy 42.721316 -19.280263) (xy 42.720044 -19.288434)
			(xy 42.720006 -19.29257) (xy 42.720006 -19.362674) (xy 42.720073 -19.366807) (xy 42.721349 -19.374974)
			(xy 42.722546 -19.37893) (xy 42.723308 -19.380708) (xy 42.72661 -19.389344) (xy 42.733722 -19.396964)
			(xy 42.752989 -19.418292) (xy 42.785547 -19.465655) (xy 42.810633 -19.517366) (xy 42.827677 -19.572254)
			(xy 42.836296 -19.629079) (xy 42.836294 -19.686553) (xy 42.82767 -19.743377) (xy 42.810621 -19.798264)
			(xy 42.785531 -19.849973) (xy 42.752969 -19.897333) (xy 42.733722 -19.91868) (xy 42.72661 -19.9263)
			(xy 42.723308 -19.934936) (xy 42.722546 -19.936714) (xy 42.721316 -19.940663) (xy 42.720044 -19.948834)
			(xy 42.720006 -19.95297) (xy 42.720006 -20.023074) (xy 42.720073 -20.027207) (xy 42.721349 -20.035374)
			(xy 42.722546 -20.03933) (xy 42.723308 -20.041108) (xy 42.72661 -20.049744) (xy 42.733722 -20.057364)
			(xy 42.752989 -20.078692) (xy 42.785547 -20.126055) (xy 42.810633 -20.177766) (xy 42.827677 -20.232654)
			(xy 42.836296 -20.289479) (xy 42.836294 -20.346953) (xy 42.82767 -20.403777) (xy 42.810621 -20.458664)
			(xy 42.785531 -20.510373) (xy 42.752969 -20.557733) (xy 42.733722 -20.57908) (xy 42.72661 -20.5867)
			(xy 42.723308 -20.595336) (xy 42.722546 -20.597114) (xy 42.721316 -20.601063) (xy 42.720044 -20.609234)
			(xy 42.720006 -20.61337) (xy 42.720006 -20.683474) (xy 42.720073 -20.687607) (xy 42.721349 -20.695774)
			(xy 42.722546 -20.69973) (xy 42.723308 -20.701508) (xy 42.72661 -20.710144) (xy 42.733722 -20.717764)
			(xy 42.752989 -20.739092) (xy 42.785547 -20.786455) (xy 42.810633 -20.838166) (xy 42.827677 -20.893054)
			(xy 42.836296 -20.949879) (xy 42.836294 -21.007353) (xy 42.82767 -21.064177) (xy 42.810621 -21.119064)
			(xy 42.785531 -21.170773) (xy 42.752969 -21.218133) (xy 42.733722 -21.23948) (xy 42.72661 -21.2471)
			(xy 42.723308 -21.255736) (xy 42.722546 -21.257514) (xy 42.721316 -21.261463) (xy 42.720044 -21.269634)
			(xy 42.720006 -21.27377) (xy 42.720006 -21.344128) (xy 42.720768 -21.353018) (xy 42.723308 -21.362162)
			(xy 42.726864 -21.371052) (xy 42.73423 -21.378672) (xy 42.753154 -21.399701) (xy 42.785223 -21.446304)
			(xy 42.81006 -21.497131) (xy 42.827119 -21.551068) (xy 42.836027 -21.606933) (xy 42.836846 -21.635212)
			(xy 42.836846 -21.63953) (xy 42.836673 -21.654968) (xy 42.83413 -21.685741) (xy 42.831766 -21.700998)
			(xy 42.831004 -21.706078) (xy 42.831004 -21.706586) (xy 42.830496 -21.710142) (xy 42.830242 -21.710904)
			(xy 42.833036 -21.72081) (xy 42.834633 -21.72602) (xy 42.839752 -21.735638) (xy 42.843196 -21.73986)
			(xy 42.868088 -21.769324) (xy 42.893742 -21.799296) (xy 42.901265 -21.807275) (xy 42.921145 -21.816476)
			(xy 42.932096 -21.817076) (xy 47.382176 -21.817076) (xy 47.389884 -21.816842) (xy 47.404616 -21.81231)
			(xy 47.411132 -21.808186) (xy 47.415196 -21.804884) (xy 47.62881 -21.59127) (xy 47.629318 -21.583904)
			(xy 47.629318 -21.567902) (xy 47.62627 -21.556218) (xy 47.621952 -21.547836) (xy 47.60842 -21.520574)
			(xy 47.589226 -21.462819) (xy 47.57944 -21.402751) (xy 47.578772 -21.372322) (xy 47.578772 -21.36394)
			(xy 47.579767 -21.337046) (xy 47.588387 -21.283923) (xy 47.604389 -21.23254) (xy 47.627456 -21.183916)
			(xy 47.657128 -21.139018) (xy 47.692817 -21.098737) (xy 47.733814 -21.063872) (xy 47.779306 -21.035117)
			(xy 47.828387 -21.013043) (xy 47.880085 -20.998087) (xy 47.933371 -20.990547) (xy 47.96028 -20.990052)
			(xy 47.963836 -20.990052) (xy 47.972726 -20.990306) (xy 47.97806 -20.99056) (xy 47.98949 -20.988274)
			(xy 47.996202 -20.98686) (xy 48.00857 -20.98094) (xy 48.013874 -20.97659) (xy 48.06696 -20.925536)
			(xy 48.072548 -20.919186) (xy 48.072548 -20.003008) (xy 48.072294 -19.453098) (xy 48.072827 -19.417376)
			(xy 48.081514 -19.346462) (xy 48.09876 -19.277131) (xy 48.124308 -19.210411) (xy 48.15778 -19.147293)
			(xy 48.198678 -19.088713) (xy 48.246395 -19.035541) (xy 48.272954 -19.011646) (xy 48.289718 -18.997168)
			(xy 48.290226 -18.991326) (xy 48.290734 -18.971514) (xy 48.292004 -18.922238) (xy 48.292004 -18.92046)
			(xy 48.292512 -18.906744) (xy 48.243998 -18.858484) (xy 48.221089 -18.834906) (xy 48.180116 -18.783491)
			(xy 48.145156 -18.727813) (xy 48.116648 -18.668572) (xy 48.09495 -18.606512) (xy 48.080335 -18.542414)
			(xy 48.072986 -18.477082) (xy 48.072548 -18.44421) (xy 48.072294 -18.432018) (xy 48.073549 -18.397094)
			(xy 48.083343 -18.327899) (xy 48.101293 -18.260359) (xy 48.127144 -18.195431) (xy 48.160529 -18.134036)
			(xy 48.200976 -18.077045) (xy 48.24791 -18.025266) (xy 48.300667 -17.979433) (xy 48.358497 -17.940196)
			(xy 48.420582 -17.908112) (xy 48.48604 -17.883635) (xy 48.553944 -17.867112) (xy 48.62333 -17.858778)
			(xy 48.658272 -17.858232) (xy 48.667416 -17.858232) (xy 48.704713 -17.859411) (xy 48.778571 -17.870067)
			(xy 48.850477 -17.890018) (xy 48.885094 -17.903952) (xy 48.919837 -17.919178) (xy 48.985418 -17.957301)
			(xy 49.045538 -18.003559) (xy 49.0728 -18.029936) (xy 49.641252 -18.598388) (xy 49.664197 -18.621943)
			(xy 49.705217 -18.673342) (xy 49.740219 -18.729013) (xy 49.768764 -18.788256) (xy 49.790491 -18.850323)
			(xy 49.805127 -18.914434) (xy 49.812488 -18.979782) (xy 49.812956 -19.012662) (xy 49.812956 -21.475192)
			(xy 49.816636 -21.479838) (xy 49.825748 -21.487412) (xy 49.83099 -21.490178) (xy 49.902618 -21.520404)
			(xy 49.903126 -21.520404) (xy 49.920398 -21.527516) (xy 49.927764 -21.530056) (xy 49.936112 -21.531711)
			(xy 49.953036 -21.529999) (xy 49.968461 -21.522829) (xy 49.974754 -21.517102) (xy 49.975516 -21.516594)
			(xy 50.282094 -21.21027) (xy 50.522632 -20.969732) (xy 50.530755 -20.960701) (xy 50.538175 -20.937612)
			(xy 50.536856 -20.925536) (xy 50.535078 -20.914868) (xy 50.523394 -20.842732) (xy 50.52213 -20.837401)
			(xy 50.517643 -20.82741) (xy 50.514504 -20.82292) (xy 50.511202 -20.818348) (xy 50.502566 -20.810982)
			(xy 50.496724 -20.807934) (xy 50.49647 -20.807934) (xy 50.473269 -20.795621) (xy 50.43018 -20.765587)
			(xy 50.391612 -20.729931) (xy 50.358293 -20.689327) (xy 50.330852 -20.644542) (xy 50.309806 -20.596418)
			(xy 50.295552 -20.545865) (xy 50.288359 -20.493836) (xy 50.287936 -20.467574) (xy 50.288401 -20.440324)
			(xy 50.296161 -20.386378) (xy 50.31152 -20.334086) (xy 50.334165 -20.284511) (xy 50.363634 -20.238665)
			(xy 50.399328 -20.197479) (xy 50.440521 -20.161792) (xy 50.486373 -20.132331) (xy 50.535951 -20.109696)
			(xy 50.588246 -20.094346) (xy 50.642193 -20.086596) (xy 50.669444 -20.086066) (xy 50.696636 -20.086551)
			(xy 50.750469 -20.094279) (xy 50.802658 -20.109574) (xy 50.852147 -20.132124) (xy 50.897933 -20.161474)
			(xy 50.939086 -20.197027) (xy 50.974775 -20.238064) (xy 51.004274 -20.283753) (xy 51.026987 -20.333168)
			(xy 51.042453 -20.385307) (xy 51.050358 -20.439114) (xy 51.050952 -20.466304) (xy 51.050952 -20.467828)
			(xy 51.050336 -20.498268) (xy 51.040637 -20.558373) (xy 51.031648 -20.587462) (xy 51.031394 -20.588224)
			(xy 51.030124 -20.592288) (xy 51.0286 -20.603464) (xy 51.028173 -20.607661) (xy 51.028551 -20.616088)
			(xy 51.029362 -20.620228) (xy 51.031648 -20.62988) (xy 51.03749 -20.638262) (xy 51.086766 -20.70735)
			(xy 51.093598 -20.715104) (xy 51.111825 -20.724801) (xy 51.122072 -20.726146) (xy 51.12258 -20.726146)
			(xy 51.12639 -20.7264) (xy 51.35626 -20.7264) (xy 51.360799 -20.726351) (xy 51.369743 -20.724814)
			(xy 51.37404 -20.723352) (xy 51.390042 -20.717256) (xy 51.394095 -20.715677) (xy 51.401634 -20.71134)
			(xy 51.405028 -20.70862) (xy 51.431398 -20.687236) (xy 51.488195 -20.650037) (xy 51.548911 -20.619654)
			(xy 51.612733 -20.596493) (xy 51.678804 -20.580865) (xy 51.746239 -20.57298) (xy 51.780186 -20.572476)
			(xy 52.52339 -20.572476) (xy 52.556244 -20.572936) (xy 52.621539 -20.580291) (xy 52.6856 -20.59491)
			(xy 52.747621 -20.616609) (xy 52.806824 -20.645116) (xy 52.862462 -20.680071) (xy 52.912601 -20.72005)
			(xy 57.185318 -20.72005) (xy 57.189288 -20.589916) (xy 57.201184 -20.460266) (xy 57.220963 -20.331583)
			(xy 57.248549 -20.204344) (xy 57.283842 -20.079025) (xy 57.326708 -19.956089) (xy 57.37699 -19.835996)
			(xy 57.434499 -19.719192) (xy 57.499023 -19.60611) (xy 57.57032 -19.497173) (xy 57.648125 -19.392785)
			(xy 57.73215 -19.293334) (xy 57.822082 -19.199191) (xy 57.917586 -19.110706) (xy 58.018306 -19.028207)
			(xy 58.123868 -18.952002) (xy 58.23388 -18.882375) (xy 58.347932 -18.819584) (xy 58.4656 -18.763862)
			(xy 58.586446 -18.715418) (xy 58.710021 -18.674431) (xy 58.835864 -18.641054) (xy 58.963509 -18.615411)
			(xy 59.092479 -18.597597) (xy 59.222295 -18.587679) (xy 59.352474 -18.585694) (xy 59.482533 -18.591648)
			(xy 59.611986 -18.605521) (xy 59.740353 -18.627259) (xy 59.867156 -18.656783) (xy 59.991923 -18.693982)
			(xy 60.11419 -18.738718) (xy 60.233503 -18.790826) (xy 60.349416 -18.850109) (xy 60.461501 -18.91635)
			(xy 60.569338 -18.9893) (xy 60.672527 -19.068688) (xy 60.770685 -19.15422) (xy 60.863446 -19.245577)
			(xy 60.950465 -19.342419) (xy 61.031418 -19.444386) (xy 61.106004 -19.551098) (xy 61.173945 -19.662159)
			(xy 61.23499 -19.777155) (xy 61.288911 -19.895659) (xy 61.335506 -20.01723) (xy 61.374604 -20.141415)
			(xy 61.406058 -20.267753) (xy 61.429752 -20.395774) (xy 61.445596 -20.525) (xy 61.453534 -20.654953)
			(xy 61.45403 -20.72005) (xy 61.453534 -20.785147) (xy 61.445596 -20.9151) (xy 61.429752 -21.044326)
			(xy 61.406058 -21.172347) (xy 61.374604 -21.298685) (xy 61.335506 -21.42287) (xy 61.288911 -21.544441)
			(xy 61.23499 -21.662945) (xy 61.173945 -21.777941) (xy 61.106004 -21.889002) (xy 61.031418 -21.995714)
			(xy 60.950465 -22.097681) (xy 60.863446 -22.194523) (xy 60.770685 -22.28588) (xy 60.672527 -22.371412)
			(xy 60.569338 -22.4508) (xy 60.461501 -22.52375) (xy 60.349416 -22.589991) (xy 60.233503 -22.649274)
			(xy 60.11419 -22.701382) (xy 59.991923 -22.746118) (xy 59.867156 -22.783317) (xy 59.740353 -22.812841)
			(xy 59.611986 -22.834579) (xy 59.482533 -22.848452) (xy 59.352474 -22.854406) (xy 59.222295 -22.852421)
			(xy 59.092479 -22.842503) (xy 58.963509 -22.824689) (xy 58.835864 -22.799046) (xy 58.710021 -22.765669)
			(xy 58.586446 -22.724682) (xy 58.4656 -22.676238) (xy 58.347932 -22.620516) (xy 58.23388 -22.557725)
			(xy 58.123868 -22.488098) (xy 58.018306 -22.411893) (xy 57.917586 -22.329394) (xy 57.822082 -22.240909)
			(xy 57.73215 -22.146766) (xy 57.648125 -22.047315) (xy 57.57032 -21.942927) (xy 57.499023 -21.83399)
			(xy 57.434499 -21.720908) (xy 57.37699 -21.604104) (xy 57.326708 -21.484011) (xy 57.283842 -21.361075)
			(xy 57.248549 -21.235756) (xy 57.220963 -21.108517) (xy 57.201184 -20.979834) (xy 57.189288 -20.850184)
			(xy 57.185318 -20.72005) (xy 52.912601 -20.72005) (xy 52.913838 -20.721036) (xy 52.93741 -20.743926)
			(xy 53.634894 -21.44141) (xy 53.657787 -21.464976) (xy 53.698733 -21.516362) (xy 53.733672 -21.572006)
			(xy 53.762166 -21.63121) (xy 53.783858 -21.69323) (xy 53.798475 -21.757287) (xy 53.805834 -21.822578)
			(xy 53.806214 -21.847048) (xy 54.072788 -21.847048) (xy 54.076859 -21.791426) (xy 54.088985 -21.736989)
			(xy 54.108908 -21.684898) (xy 54.136204 -21.636263) (xy 54.17029 -21.59212) (xy 54.210439 -21.553411)
			(xy 54.255797 -21.52096) (xy 54.305397 -21.495459) (xy 54.358181 -21.477452) (xy 54.413024 -21.467322)
			(xy 54.468758 -21.465285) (xy 54.524195 -21.471385) (xy 54.578152 -21.485491) (xy 54.629481 -21.507303)
			(xy 54.677087 -21.536357) (xy 54.719955 -21.572032) (xy 54.757172 -21.613569) (xy 54.787945 -21.660082)
			(xy 54.811617 -21.710579) (xy 54.827685 -21.763986) (xy 54.835805 -21.819162) (xy 54.836314 -21.847048)
			(xy 54.835805 -21.874934) (xy 54.827685 -21.93011) (xy 54.811617 -21.983517) (xy 54.787945 -22.034014)
			(xy 54.757172 -22.080527) (xy 54.719955 -22.122064) (xy 54.677087 -22.157739) (xy 54.629481 -22.186793)
			(xy 54.578152 -22.208605) (xy 54.524195 -22.222711) (xy 54.468758 -22.228811) (xy 54.413024 -22.226774)
			(xy 54.358181 -22.216644) (xy 54.305397 -22.198637) (xy 54.255797 -22.173136) (xy 54.210439 -22.140685)
			(xy 54.17029 -22.101976) (xy 54.136204 -22.057833) (xy 54.108908 -22.009198) (xy 54.088985 -21.957107)
			(xy 54.076859 -21.90267) (xy 54.072788 -21.847048) (xy 53.806214 -21.847048) (xy 53.806344 -21.85543)
			(xy 53.806344 -21.855684) (xy 53.805811 -21.891083) (xy 53.797279 -21.961364) (xy 53.780338 -22.030104)
			(xy 53.755235 -22.096301) (xy 53.722336 -22.15899) (xy 53.68212 -22.217256) (xy 53.635175 -22.270249)
			(xy 53.582184 -22.317198) (xy 53.523921 -22.357417) (xy 53.461234 -22.39032) (xy 53.395038 -22.415428)
			(xy 53.326299 -22.432373) (xy 53.256019 -22.440909) (xy 53.22062 -22.441408) (xy 53.220366 -22.441408)
			(xy 53.187511 -22.440951) (xy 53.122213 -22.433602) (xy 53.058149 -22.418987) (xy 52.996124 -22.397292)
			(xy 52.936918 -22.368789) (xy 52.881275 -22.333835) (xy 52.829896 -22.292872) (xy 52.806346 -22.269958)
			(xy 52.747672 -22.211284) (xy 52.74183 -22.210776) (xy 52.729384 -22.210776) (xy 52.723803 -22.210925)
			(xy 52.712911 -22.213367) (xy 52.707794 -22.215602) (xy 52.696618 -22.222714) (xy 52.696364 -22.222968)
			(xy 52.69484 -22.224238) (xy 52.668404 -22.245838) (xy 52.611397 -22.283398) (xy 52.550409 -22.314077)
			(xy 52.486268 -22.337458) (xy 52.419845 -22.353223) (xy 52.352039 -22.36116) (xy 52.317904 -22.361652)
			(xy 52.160932 -22.361652) (xy 52.152296 -22.369272) (xy 52.132484 -22.393656) (xy 52.099464 -22.43455)
			(xy 52.096924 -22.438614) (xy 52.092352 -22.450552) (xy 52.08905 -22.463252) (xy 52.089558 -22.46503)
			(xy 52.09159 -22.47519) (xy 52.095424 -22.494395) (xy 52.099619 -22.533333) (xy 52.099972 -22.552914)
			(xy 52.099972 -22.553422) (xy 52.099972 -22.559264) (xy 52.099231 -22.586339) (xy 52.091042 -22.639878)
			(xy 52.075363 -22.69172) (xy 52.052509 -22.740824) (xy 52.02294 -22.786201) (xy 51.98725 -22.826941)
			(xy 51.946157 -22.862223) (xy 51.900487 -22.891338) (xy 51.851158 -22.913702) (xy 51.799162 -22.928864)
			(xy 51.745545 -22.936519) (xy 51.718464 -22.936962) (xy 51.717956 -22.936962) (xy 51.691859 -22.936518)
			(xy 51.640155 -22.929369) (xy 51.58991 -22.915236) (xy 51.56581 -22.905212) (xy 51.560984 -22.90318)
			(xy 51.539902 -22.898608) (xy 51.530776 -22.899034) (xy 51.513723 -22.905551) (xy 51.506628 -22.911308)
			(xy 51.337972 -23.079964) (xy 51.33467 -23.084028) (xy 51.330528 -23.090537) (xy 51.325987 -23.105273)
			(xy 51.32578 -23.112984) (xy 51.32578 -23.965154) (xy 52.077364 -23.965154) (xy 52.081435 -23.909532)
			(xy 52.093561 -23.855095) (xy 52.113484 -23.803004) (xy 52.14078 -23.754369) (xy 52.174866 -23.710226)
			(xy 52.215015 -23.671517) (xy 52.260373 -23.639066) (xy 52.309973 -23.613565) (xy 52.362757 -23.595558)
			(xy 52.4176 -23.585428) (xy 52.473334 -23.583391) (xy 52.528771 -23.589491) (xy 52.582728 -23.603597)
			(xy 52.634057 -23.625409) (xy 52.681663 -23.654463) (xy 52.724531 -23.690138) (xy 52.761748 -23.731675)
			(xy 52.792521 -23.778188) (xy 52.816193 -23.828685) (xy 52.832261 -23.882092) (xy 52.840381 -23.937268)
			(xy 52.840556 -23.946866) (xy 53.08041 -23.946866) (xy 53.084481 -23.891244) (xy 53.096607 -23.836807)
			(xy 53.11653 -23.784716) (xy 53.143826 -23.736081) (xy 53.177912 -23.691938) (xy 53.218061 -23.653229)
			(xy 53.263419 -23.620778) (xy 53.313019 -23.595277) (xy 53.365803 -23.57727) (xy 53.420646 -23.56714)
			(xy 53.47638 -23.565103) (xy 53.531817 -23.571203) (xy 53.585774 -23.585309) (xy 53.637103 -23.607121)
			(xy 53.684709 -23.636175) (xy 53.727577 -23.67185) (xy 53.764794 -23.713387) (xy 53.795567 -23.7599)
			(xy 53.819239 -23.810397) (xy 53.835307 -23.863804) (xy 53.843427 -23.91898) (xy 53.843936 -23.946866)
			(xy 53.843496 -23.970996) (xy 54.072788 -23.970996) (xy 54.076859 -23.915374) (xy 54.088985 -23.860937)
			(xy 54.108908 -23.808846) (xy 54.136204 -23.760211) (xy 54.17029 -23.716068) (xy 54.210439 -23.677359)
			(xy 54.255797 -23.644908) (xy 54.305397 -23.619407) (xy 54.358181 -23.6014) (xy 54.413024 -23.59127)
			(xy 54.468758 -23.589233) (xy 54.524195 -23.595333) (xy 54.578152 -23.609439) (xy 54.629481 -23.631251)
			(xy 54.677087 -23.660305) (xy 54.719955 -23.69598) (xy 54.757172 -23.737517) (xy 54.787945 -23.78403)
			(xy 54.811617 -23.834527) (xy 54.827685 -23.887934) (xy 54.835805 -23.94311) (xy 54.836314 -23.970996)
			(xy 54.835805 -23.998882) (xy 54.827685 -24.054058) (xy 54.811617 -24.107465) (xy 54.787945 -24.157962)
			(xy 54.757172 -24.204475) (xy 54.719955 -24.246012) (xy 54.677087 -24.281687) (xy 54.629481 -24.310741)
			(xy 54.578152 -24.332553) (xy 54.524195 -24.346659) (xy 54.468758 -24.352759) (xy 54.413024 -24.350722)
			(xy 54.358181 -24.340592) (xy 54.305397 -24.322585) (xy 54.255797 -24.297084) (xy 54.210439 -24.264633)
			(xy 54.17029 -24.225924) (xy 54.136204 -24.181781) (xy 54.108908 -24.133146) (xy 54.088985 -24.081055)
			(xy 54.076859 -24.026618) (xy 54.072788 -23.970996) (xy 53.843496 -23.970996) (xy 53.843427 -23.974752)
			(xy 53.835307 -24.029928) (xy 53.819239 -24.083335) (xy 53.795567 -24.133832) (xy 53.764794 -24.180345)
			(xy 53.727577 -24.221882) (xy 53.684709 -24.257557) (xy 53.637103 -24.286611) (xy 53.585774 -24.308423)
			(xy 53.531817 -24.322529) (xy 53.47638 -24.328629) (xy 53.420646 -24.326592) (xy 53.365803 -24.316462)
			(xy 53.313019 -24.298455) (xy 53.263419 -24.272954) (xy 53.218061 -24.240503) (xy 53.177912 -24.201794)
			(xy 53.143826 -24.157651) (xy 53.11653 -24.109016) (xy 53.096607 -24.056925) (xy 53.084481 -24.002488)
			(xy 53.08041 -23.946866) (xy 52.840556 -23.946866) (xy 52.84089 -23.965154) (xy 52.840381 -23.99304)
			(xy 52.832261 -24.048216) (xy 52.816193 -24.101623) (xy 52.792521 -24.15212) (xy 52.761748 -24.198633)
			(xy 52.724531 -24.24017) (xy 52.681663 -24.275845) (xy 52.634057 -24.304899) (xy 52.582728 -24.326711)
			(xy 52.528771 -24.340817) (xy 52.473334 -24.346917) (xy 52.4176 -24.34488) (xy 52.362757 -24.33475)
			(xy 52.309973 -24.316743) (xy 52.260373 -24.291242) (xy 52.215015 -24.258791) (xy 52.174866 -24.220082)
			(xy 52.14078 -24.175939) (xy 52.113484 -24.127304) (xy 52.093561 -24.075213) (xy 52.081435 -24.020776)
			(xy 52.077364 -23.965154) (xy 51.32578 -23.965154) (xy 51.32578 -24.807418) (xy 58.37123 -24.807418)
			(xy 58.375301 -24.751796) (xy 58.387427 -24.697359) (xy 58.40735 -24.645268) (xy 58.434646 -24.596633)
			(xy 58.468732 -24.55249) (xy 58.508881 -24.513781) (xy 58.554239 -24.48133) (xy 58.603839 -24.455829)
			(xy 58.656623 -24.437822) (xy 58.711466 -24.427692) (xy 58.7672 -24.425655) (xy 58.822637 -24.431755)
			(xy 58.876594 -24.445861) (xy 58.927923 -24.467673) (xy 58.975529 -24.496727) (xy 59.018397 -24.532402)
			(xy 59.055614 -24.573939) (xy 59.086387 -24.620452) (xy 59.110059 -24.670949) (xy 59.126127 -24.724356)
			(xy 59.134247 -24.779532) (xy 59.134756 -24.807418) (xy 59.134247 -24.835304) (xy 59.126127 -24.89048)
			(xy 59.110059 -24.943887) (xy 59.086387 -24.994384) (xy 59.055614 -25.040897) (xy 59.018397 -25.082434)
			(xy 58.975529 -25.118109) (xy 58.927923 -25.147163) (xy 58.876594 -25.168975) (xy 58.822637 -25.183081)
			(xy 58.7672 -25.189181) (xy 58.711466 -25.187144) (xy 58.656623 -25.177014) (xy 58.603839 -25.159007)
			(xy 58.554239 -25.133506) (xy 58.508881 -25.101055) (xy 58.468732 -25.062346) (xy 58.434646 -25.018203)
			(xy 58.40735 -24.969568) (xy 58.387427 -24.917477) (xy 58.375301 -24.86304) (xy 58.37123 -24.807418)
			(xy 51.32578 -24.807418) (xy 51.32578 -25.91562) (xy 51.326043 -25.923263) (xy 51.330575 -25.937862)
			(xy 51.33467 -25.944322) (xy 51.338734 -25.950418) (xy 51.350926 -25.959816) (xy 51.3588 -25.962864)
			(xy 51.387756 -25.97531) (xy 51.415524 -25.989127) (xy 51.466552 -26.024378) (xy 51.476258 -26.03373)
			(xy 57.267854 -26.03373) (xy 57.271925 -25.978108) (xy 57.284051 -25.923671) (xy 57.303974 -25.87158)
			(xy 57.33127 -25.822945) (xy 57.365356 -25.778802) (xy 57.405505 -25.740093) (xy 57.450863 -25.707642)
			(xy 57.500463 -25.682141) (xy 57.553247 -25.664134) (xy 57.60809 -25.654004) (xy 57.663824 -25.651967)
			(xy 57.719261 -25.658067) (xy 57.773218 -25.672173) (xy 57.824547 -25.693985) (xy 57.872153 -25.723039)
			(xy 57.915021 -25.758714) (xy 57.952238 -25.800251) (xy 57.983011 -25.846764) (xy 58.006683 -25.897261)
			(xy 58.022751 -25.950668) (xy 58.030871 -26.005844) (xy 58.03138 -26.03373) (xy 58.030871 -26.061616)
			(xy 58.022751 -26.116792) (xy 58.006683 -26.170199) (xy 57.983011 -26.220696) (xy 57.952238 -26.267209)
			(xy 57.915021 -26.308746) (xy 57.872153 -26.344421) (xy 57.824547 -26.373475) (xy 57.773218 -26.395287)
			(xy 57.719261 -26.409393) (xy 57.663824 -26.415493) (xy 57.60809 -26.413456) (xy 57.553247 -26.403326)
			(xy 57.500463 -26.385319) (xy 57.450863 -26.359818) (xy 57.405505 -26.327367) (xy 57.365356 -26.288658)
			(xy 57.33127 -26.244515) (xy 57.303974 -26.19588) (xy 57.284051 -26.143789) (xy 57.271925 -26.089352)
			(xy 57.267854 -26.03373) (xy 51.476258 -26.03373) (xy 51.511214 -26.06741) (xy 51.53025 -26.091896)
			(xy 51.53025 -26.092404) (xy 51.534822 -26.0985) (xy 51.539394 -26.105104) (xy 51.554887 -26.128745)
			(xy 51.579496 -26.179629) (xy 51.588416 -26.20645) (xy 51.589178 -26.208736) (xy 51.589178 -26.20899)
			(xy 51.589686 -26.210006) (xy 51.591677 -26.214794) (xy 51.597315 -26.223495) (xy 51.600862 -26.227278)
			(xy 53.02123 -27.647646) (xy 53.039341 -27.666427) (xy 53.070023 -27.708625) (xy 53.09372 -27.755106)
			(xy 53.109848 -27.804724) (xy 53.11801 -27.856255) (xy 53.118512 -27.882342) (xy 53.118512 -28.139136)
			(xy 54.397908 -28.139136) (xy 54.401979 -28.083514) (xy 54.414105 -28.029077) (xy 54.434028 -27.976986)
			(xy 54.461324 -27.928351) (xy 54.49541 -27.884208) (xy 54.535559 -27.845499) (xy 54.580917 -27.813048)
			(xy 54.630517 -27.787547) (xy 54.683301 -27.76954) (xy 54.738144 -27.75941) (xy 54.793878 -27.757373)
			(xy 54.849315 -27.763473) (xy 54.903272 -27.777579) (xy 54.954601 -27.799391) (xy 55.002207 -27.828445)
			(xy 55.045075 -27.86412) (xy 55.082292 -27.905657) (xy 55.113065 -27.95217) (xy 55.136737 -28.002667)
			(xy 55.152805 -28.056074) (xy 55.160925 -28.11125) (xy 55.161434 -28.139136) (xy 55.667908 -28.139136)
			(xy 55.671979 -28.083514) (xy 55.684105 -28.029077) (xy 55.704028 -27.976986) (xy 55.731324 -27.928351)
			(xy 55.76541 -27.884208) (xy 55.805559 -27.845499) (xy 55.850917 -27.813048) (xy 55.900517 -27.787547)
			(xy 55.953301 -27.76954) (xy 56.008144 -27.75941) (xy 56.063878 -27.757373) (xy 56.119315 -27.763473)
			(xy 56.173272 -27.777579) (xy 56.224601 -27.799391) (xy 56.272207 -27.828445) (xy 56.315075 -27.86412)
			(xy 56.352292 -27.905657) (xy 56.383065 -27.95217) (xy 56.406737 -28.002667) (xy 56.422805 -28.056074)
			(xy 56.430925 -28.11125) (xy 56.431434 -28.139136) (xy 56.430925 -28.167022) (xy 56.422805 -28.222198)
			(xy 56.406737 -28.275605) (xy 56.383065 -28.326102) (xy 56.352292 -28.372615) (xy 56.315075 -28.414152)
			(xy 56.272207 -28.449827) (xy 56.224601 -28.478881) (xy 56.173272 -28.500693) (xy 56.119315 -28.514799)
			(xy 56.063878 -28.520899) (xy 56.008144 -28.518862) (xy 55.953301 -28.508732) (xy 55.900517 -28.490725)
			(xy 55.850917 -28.465224) (xy 55.805559 -28.432773) (xy 55.76541 -28.394064) (xy 55.731324 -28.349921)
			(xy 55.704028 -28.301286) (xy 55.684105 -28.249195) (xy 55.671979 -28.194758) (xy 55.667908 -28.139136)
			(xy 55.161434 -28.139136) (xy 55.160925 -28.167022) (xy 55.152805 -28.222198) (xy 55.136737 -28.275605)
			(xy 55.113065 -28.326102) (xy 55.082292 -28.372615) (xy 55.045075 -28.414152) (xy 55.002207 -28.449827)
			(xy 54.954601 -28.478881) (xy 54.903272 -28.500693) (xy 54.849315 -28.514799) (xy 54.793878 -28.520899)
			(xy 54.738144 -28.518862) (xy 54.683301 -28.508732) (xy 54.630517 -28.490725) (xy 54.580917 -28.465224)
			(xy 54.535559 -28.432773) (xy 54.49541 -28.394064) (xy 54.461324 -28.349921) (xy 54.434028 -28.301286)
			(xy 54.414105 -28.249195) (xy 54.401979 -28.194758) (xy 54.397908 -28.139136) (xy 53.118512 -28.139136)
			(xy 53.118512 -29.134308) (xy 53.118766 -29.139642) (xy 53.119833 -29.147394) (xy 53.126042 -29.161748)
			(xy 53.130958 -29.167836) (xy 53.135276 -29.172154) (xy 53.191664 -29.2227) (xy 53.195668 -29.226093)
			(xy 53.204758 -29.231338) (xy 53.209698 -29.233114) (xy 53.219858 -29.236416) (xy 53.230526 -29.2354)
			(xy 53.240467 -29.234432) (xy 53.260416 -29.233415) (xy 53.270404 -29.233368) (xy 53.298139 -29.233873)
			(xy 53.353021 -29.241918) (xy 53.406161 -29.257824) (xy 53.456439 -29.281256) (xy 53.502794 -29.311719)
			(xy 53.544251 -29.348572) (xy 53.579936 -29.391039) (xy 53.609097 -29.438225) (xy 53.63112 -29.489135)
			(xy 53.64554 -29.542697) (xy 53.649372 -29.570172) (xy 53.650896 -29.583888) (xy 53.652166 -29.614876)
			(xy 53.651664 -29.642707) (xy 53.643581 -29.69778) (xy 53.627585 -29.751095) (xy 53.604014 -29.801521)
			(xy 53.573368 -29.847988) (xy 53.536297 -29.88951) (xy 53.51526 -29.907738) (xy 53.513228 -29.909262)
			(xy 53.509164 -29.913326) (xy 53.506281 -29.916329) (xy 53.501431 -29.923094) (xy 53.499512 -29.926788)
			(xy 53.492908 -29.94025) (xy 53.492654 -29.941012) (xy 53.490114 -29.946092) (xy 53.486304 -29.957268)
			(xy 53.485288 -29.967174) (xy 53.485288 -30.02026) (xy 53.485542 -30.023562) (xy 53.48732 -30.040326)
			(xy 53.491384 -30.048708) (xy 53.496718 -30.059376) (xy 53.497226 -30.060392) (xy 53.498496 -30.063186)
			(xy 53.500451 -30.067241) (xy 53.505558 -30.074652) (xy 53.508656 -30.077918) (xy 53.513228 -30.08249)
			(xy 53.515006 -30.084014) (xy 53.536033 -30.102253) (xy 53.573096 -30.143779) (xy 53.603739 -30.190245)
			(xy 53.627313 -30.240667) (xy 53.643318 -30.293977) (xy 53.651416 -30.349046) (xy 53.651912 -30.376876)
			(xy 53.65145 -30.40413) (xy 53.643696 -30.458084) (xy 53.628342 -30.510385) (xy 53.605701 -30.559968)
			(xy 53.576234 -30.605825) (xy 53.54054 -30.64702) (xy 53.499347 -30.682717) (xy 53.453493 -30.712188)
			(xy 53.403911 -30.734832) (xy 53.351611 -30.75019) (xy 53.297658 -30.757948) (xy 53.270404 -30.758384)
			(xy 53.269642 -30.758384) (xy 53.259845 -30.758316) (xy 53.240277 -30.757301) (xy 53.230526 -30.756352)
			(xy 53.230272 -30.756352) (xy 53.220222 -30.755896) (xy 53.201004 -30.761775) (xy 53.192934 -30.767782)
			(xy 53.135276 -30.819598) (xy 53.131466 -30.823408) (xy 53.126453 -30.829405) (xy 53.11999 -30.843628)
			(xy 53.118766 -30.851348) (xy 53.118512 -30.857444) (xy 53.118512 -31.11246) (xy 53.118946 -31.122525)
			(xy 53.126677 -31.141113) (xy 53.133498 -31.148528) (xy 53.140102 -31.153862) (xy 53.207412 -31.201614)
			(xy 53.212514 -31.205042) (xy 53.223948 -31.20954) (xy 53.230018 -31.210504) (xy 53.24221 -31.212028)
			(xy 53.24602 -31.210758) (xy 53.278325 -31.199443) (xy 53.345658 -31.187176) (xy 53.379878 -31.186374)
			(xy 53.38064 -31.186374) (xy 53.407891 -31.186863) (xy 53.461837 -31.194624) (xy 53.514129 -31.209983)
			(xy 53.563704 -31.232628) (xy 53.609551 -31.262097) (xy 53.650738 -31.29779) (xy 53.686427 -31.338981)
			(xy 53.715891 -31.384832) (xy 53.738531 -31.434408) (xy 53.753884 -31.486703) (xy 53.76164 -31.540649)
			(xy 53.76164 -31.595151) (xy 53.753884 -31.649097) (xy 53.738531 -31.701392) (xy 53.730368 -31.719266)
			(xy 54.285386 -31.719266) (xy 54.289457 -31.663644) (xy 54.301583 -31.609207) (xy 54.321506 -31.557116)
			(xy 54.348802 -31.508481) (xy 54.382888 -31.464338) (xy 54.423037 -31.425629) (xy 54.468395 -31.393178)
			(xy 54.517995 -31.367677) (xy 54.570779 -31.34967) (xy 54.625622 -31.33954) (xy 54.681356 -31.337503)
			(xy 54.736793 -31.343603) (xy 54.79075 -31.357709) (xy 54.842079 -31.379521) (xy 54.889685 -31.408575)
			(xy 54.932553 -31.44425) (xy 54.96977 -31.485787) (xy 55.000543 -31.5323) (xy 55.024215 -31.582797)
			(xy 55.040283 -31.636204) (xy 55.044433 -31.664402) (xy 55.560974 -31.664402) (xy 55.565045 -31.60878)
			(xy 55.577171 -31.554343) (xy 55.597094 -31.502252) (xy 55.62439 -31.453617) (xy 55.658476 -31.409474)
			(xy 55.698625 -31.370765) (xy 55.743983 -31.338314) (xy 55.793583 -31.312813) (xy 55.846367 -31.294806)
			(xy 55.90121 -31.284676) (xy 55.956944 -31.282639) (xy 56.012381 -31.288739) (xy 56.066338 -31.302845)
			(xy 56.117667 -31.324657) (xy 56.165273 -31.353711) (xy 56.208141 -31.389386) (xy 56.245358 -31.430923)
			(xy 56.276131 -31.477436) (xy 56.299803 -31.527933) (xy 56.315871 -31.58134) (xy 56.323991 -31.636516)
			(xy 56.3245 -31.664402) (xy 56.323991 -31.692288) (xy 56.315871 -31.747464) (xy 56.299803 -31.800871)
			(xy 56.276131 -31.851368) (xy 56.245358 -31.897881) (xy 56.208141 -31.939418) (xy 56.165273 -31.975093)
			(xy 56.117667 -32.004147) (xy 56.066338 -32.025959) (xy 56.012381 -32.040065) (xy 55.956944 -32.046165)
			(xy 55.90121 -32.044128) (xy 55.846367 -32.033998) (xy 55.793583 -32.015991) (xy 55.743983 -31.99049)
			(xy 55.698625 -31.958039) (xy 55.658476 -31.91933) (xy 55.62439 -31.875187) (xy 55.597094 -31.826552)
			(xy 55.577171 -31.774461) (xy 55.565045 -31.720024) (xy 55.560974 -31.664402) (xy 55.044433 -31.664402)
			(xy 55.048403 -31.69138) (xy 55.048912 -31.719266) (xy 55.048403 -31.747152) (xy 55.040283 -31.802328)
			(xy 55.024215 -31.855735) (xy 55.000543 -31.906232) (xy 54.96977 -31.952745) (xy 54.932553 -31.994282)
			(xy 54.889685 -32.029957) (xy 54.842079 -32.059011) (xy 54.79075 -32.080823) (xy 54.736793 -32.094929)
			(xy 54.681356 -32.101029) (xy 54.625622 -32.098992) (xy 54.570779 -32.088862) (xy 54.517995 -32.070855)
			(xy 54.468395 -32.045354) (xy 54.423037 -32.012903) (xy 54.382888 -31.974194) (xy 54.348802 -31.930051)
			(xy 54.321506 -31.881416) (xy 54.301583 -31.829325) (xy 54.289457 -31.774888) (xy 54.285386 -31.719266)
			(xy 53.730368 -31.719266) (xy 53.715891 -31.750968) (xy 53.686427 -31.796819) (xy 53.650738 -31.83801)
			(xy 53.609551 -31.873703) (xy 53.563704 -31.903172) (xy 53.514129 -31.925817) (xy 53.461837 -31.941176)
			(xy 53.407891 -31.948937) (xy 53.38064 -31.94939) (xy 53.379878 -31.94939) (xy 53.345651 -31.948655)
			(xy 53.278305 -31.936394) (xy 53.24602 -31.925006) (xy 53.24221 -31.923736) (xy 53.230018 -31.92526)
			(xy 53.223961 -31.926273) (xy 53.212534 -31.930763) (xy 53.207412 -31.93415) (xy 53.140102 -31.981902)
			(xy 53.133498 -31.987236) (xy 53.126658 -31.994637) (xy 53.118937 -32.013235) (xy 53.118512 -32.023304)
			(xy 53.118512 -33.36798) (xy 53.119782 -33.378648) (xy 53.121485 -33.385598) (xy 53.128194 -33.398229)
			(xy 53.13299 -33.40354) (xy 54.994302 -35.264852) (xy 55.90235 -35.264852) (xy 55.906421 -35.20923)
			(xy 55.918547 -35.154793) (xy 55.93847 -35.102702) (xy 55.965766 -35.054067) (xy 55.999852 -35.009924)
			(xy 56.040001 -34.971215) (xy 56.085359 -34.938764) (xy 56.134959 -34.913263) (xy 56.187743 -34.895256)
			(xy 56.242586 -34.885126) (xy 56.29832 -34.883089) (xy 56.353757 -34.889189) (xy 56.407714 -34.903295)
			(xy 56.459043 -34.925107) (xy 56.506649 -34.954161) (xy 56.549517 -34.989836) (xy 56.586734 -35.031373)
			(xy 56.617507 -35.077886) (xy 56.641179 -35.128383) (xy 56.657247 -35.18179) (xy 56.665367 -35.236966)
			(xy 56.665876 -35.264852) (xy 56.665367 -35.292738) (xy 56.657247 -35.347914) (xy 56.641179 -35.401321)
			(xy 56.617507 -35.451818) (xy 56.586734 -35.498331) (xy 56.549517 -35.539868) (xy 56.506649 -35.575543)
			(xy 56.459043 -35.604597) (xy 56.407714 -35.626409) (xy 56.353757 -35.640515) (xy 56.29832 -35.646615)
			(xy 56.242586 -35.644578) (xy 56.187743 -35.634448) (xy 56.134959 -35.616441) (xy 56.085359 -35.59094)
			(xy 56.040001 -35.558489) (xy 55.999852 -35.51978) (xy 55.965766 -35.475637) (xy 55.93847 -35.427002)
			(xy 55.918547 -35.374911) (xy 55.906421 -35.320474) (xy 55.90235 -35.264852) (xy 54.994302 -35.264852)
			(xy 56.016398 -36.286948) (xy 57.20029 -36.286948) (xy 57.204361 -36.231326) (xy 57.216487 -36.176889)
			(xy 57.23641 -36.124798) (xy 57.263706 -36.076163) (xy 57.297792 -36.03202) (xy 57.337941 -35.993311)
			(xy 57.383299 -35.96086) (xy 57.432899 -35.935359) (xy 57.485683 -35.917352) (xy 57.540526 -35.907222)
			(xy 57.59626 -35.905185) (xy 57.651697 -35.911285) (xy 57.705654 -35.925391) (xy 57.756983 -35.947203)
			(xy 57.804589 -35.976257) (xy 57.847457 -36.011932) (xy 57.884674 -36.053469) (xy 57.915447 -36.099982)
			(xy 57.939119 -36.150479) (xy 57.955187 -36.203886) (xy 57.963307 -36.259062) (xy 57.963816 -36.286948)
			(xy 57.963307 -36.314834) (xy 57.955187 -36.37001) (xy 57.939119 -36.423417) (xy 57.915447 -36.473914)
			(xy 57.884674 -36.520427) (xy 57.847457 -36.561964) (xy 57.804589 -36.597639) (xy 57.756983 -36.626693)
			(xy 57.705654 -36.648505) (xy 57.651697 -36.662611) (xy 57.59626 -36.668711) (xy 57.540526 -36.666674)
			(xy 57.485683 -36.656544) (xy 57.432899 -36.638537) (xy 57.383299 -36.613036) (xy 57.337941 -36.580585)
			(xy 57.297792 -36.541876) (xy 57.263706 -36.497733) (xy 57.23641 -36.449098) (xy 57.216487 -36.397007)
			(xy 57.204361 -36.34257) (xy 57.20029 -36.286948) (xy 56.016398 -36.286948) (xy 57.351422 -37.621972)
			(xy 57.360062 -37.62859) (xy 57.380982 -37.634514) (xy 57.391808 -37.633402) (xy 57.401714 -37.631878)
			(xy 57.472834 -37.62121) (xy 57.478764 -37.620169) (xy 57.489931 -37.615674) (xy 57.494932 -37.61232)
			(xy 57.49925 -37.609018) (xy 57.50687 -37.600636) (xy 57.509918 -37.594794) (xy 57.524262 -37.569018)
			(xy 57.559663 -37.521836) (xy 57.601905 -37.480667) (xy 57.649982 -37.446493) (xy 57.702748 -37.420127)
			(xy 57.758943 -37.402199) (xy 57.817229 -37.393137) (xy 57.846722 -37.39261) (xy 57.873972 -37.393098)
			(xy 57.927916 -37.400857) (xy 57.980207 -37.416214) (xy 58.02978 -37.438857) (xy 58.075627 -37.468324)
			(xy 58.116813 -37.504016) (xy 58.1525 -37.545205) (xy 58.181962 -37.591055) (xy 58.2046 -37.64063)
			(xy 58.219952 -37.692923) (xy 58.227705 -37.746868) (xy 58.22823 -37.774118) (xy 58.227679 -37.803609)
			(xy 58.218604 -37.86189) (xy 58.200672 -37.918081) (xy 58.174311 -37.970845) (xy 58.140147 -38.018926)
			(xy 58.098995 -38.06118) (xy 58.051832 -38.096602) (xy 58.026046 -38.110922) (xy 58.025538 -38.111176)
			(xy 58.020495 -38.114078) (xy 58.011771 -38.121772) (xy 58.008266 -38.126416) (xy 58.004964 -38.130988)
			(xy 58.000392 -38.14191) (xy 57.988962 -38.219126) (xy 57.987438 -38.229032) (xy 57.986301 -38.239862)
			(xy 57.992216 -38.260798) (xy 57.998868 -38.269418) (xy 58.98769 -39.25824) (xy 58.994772 -39.264653)
			(xy 59.012324 -39.272166) (xy 59.031407 -39.272781) (xy 59.040522 -39.269924) (xy 59.042808 -39.268908)
			(xy 59.049796 -39.265751) (xy 59.061675 -39.256067) (xy 59.066176 -39.249858) (xy 59.069986 -39.244016)
			(xy 59.074304 -39.230046) (xy 59.074304 -36.720272) (xy 59.07278 -36.717986) (xy 59.069986 -36.713668)
			(xy 59.066684 -36.707826) (xy 59.056049 -36.689053) (xy 59.038605 -36.649589) (xy 59.031886 -36.629086)
			(xy 59.031886 -36.628578) (xy 59.029845 -36.622913) (xy 59.023566 -36.612642) (xy 59.01944 -36.608258)
			(xy 57.528714 -35.117532) (xy 57.510602 -35.098751) (xy 57.479919 -35.056554) (xy 57.456222 -35.010073)
			(xy 57.440095 -34.960454) (xy 57.431936 -34.908923) (xy 57.431432 -34.882836) (xy 57.431432 -32.410654)
			(xy 57.427114 -32.405574) (xy 57.374536 -32.362394) (xy 57.36336 -32.35325) (xy 57.360502 -32.350958)
			(xy 57.354255 -32.347133) (xy 57.350914 -32.34563) (xy 57.329832 -32.350202) (xy 57.299774 -32.356213)
			(xy 57.238816 -32.3627) (xy 57.208166 -32.363156) (xy 57.172755 -32.362619) (xy 57.10245 -32.354079)
			(xy 57.033687 -32.337126) (xy 56.967468 -32.312009) (xy 56.90476 -32.279093) (xy 56.846477 -32.238859)
			(xy 56.793468 -32.191892) (xy 56.746507 -32.138879) (xy 56.706278 -32.080592) (xy 56.673368 -32.017881)
			(xy 56.648257 -31.95166) (xy 56.631311 -31.882895) (xy 56.622777 -31.812589) (xy 56.622188 -31.777178)
			(xy 56.622188 -30.776164) (xy 56.619773 -30.773071) (xy 56.614162 -30.767583) (xy 56.611012 -30.765242)
			(xy 56.576214 -30.743906) (xy 56.538622 -30.720792) (xy 56.528208 -30.715966) (xy 56.525922 -30.715204)
			(xy 56.516672 -30.71296) (xy 56.497742 -30.714789) (xy 56.489092 -30.71876) (xy 56.488838 -30.71876)
			(xy 56.47817 -30.724094) (xy 56.451941 -30.736187) (xy 56.396766 -30.753261) (xy 56.339662 -30.761916)
			(xy 56.310784 -30.762448) (xy 56.31053 -30.762448) (xy 56.282986 -30.761982) (xy 56.228458 -30.754146)
			(xy 56.175601 -30.738628) (xy 56.125491 -30.715746) (xy 56.079147 -30.685965) (xy 56.037514 -30.64989)
			(xy 56.001439 -30.608258) (xy 55.971657 -30.561915) (xy 55.948774 -30.511804) (xy 55.933256 -30.458947)
			(xy 55.925419 -30.40442) (xy 55.924958 -30.376876) (xy 55.92548 -30.347938) (xy 55.934141 -30.290713)
			(xy 55.951265 -30.235428) (xy 55.976466 -30.183327) (xy 56.009178 -30.135582) (xy 56.048664 -30.093267)
			(xy 56.071008 -30.07487) (xy 56.075834 -30.07106) (xy 56.082692 -30.062678) (xy 56.087264 -30.053026)
			(xy 56.090312 -30.047184) (xy 56.092775 -30.041859) (xy 56.095473 -30.030443) (xy 56.095646 -30.024578)
			(xy 56.095646 -29.967682) (xy 56.095504 -29.962242) (xy 56.093197 -29.95161) (xy 56.091074 -29.9466)
			(xy 56.087772 -29.939742) (xy 56.087772 -29.939234) (xy 56.080914 -29.925518) (xy 56.072532 -29.914088)
			(xy 56.067706 -29.909262) (xy 56.065928 -29.907738) (xy 56.044902 -29.889499) (xy 56.007841 -29.847973)
			(xy 55.977201 -29.801506) (xy 55.953631 -29.751084) (xy 55.937631 -29.697774) (xy 55.92954 -29.642706)
			(xy 55.929022 -29.614876) (xy 55.929487 -29.587625) (xy 55.937247 -29.533678) (xy 55.952605 -29.481385)
			(xy 55.97525 -29.43181) (xy 56.004719 -29.385962) (xy 56.040413 -29.344775) (xy 56.081605 -29.309086)
			(xy 56.127457 -29.279624) (xy 56.177036 -29.256986) (xy 56.229331 -29.241635) (xy 56.283279 -29.233883)
			(xy 56.31053 -29.233368) (xy 56.335958 -29.23379) (xy 56.386362 -29.24055) (xy 56.435421 -29.253947)
			(xy 56.482266 -29.273741) (xy 56.526066 -29.299584) (xy 56.566044 -29.331016) (xy 56.584088 -29.348938)
			(xy 56.590946 -29.35605) (xy 56.626506 -29.371798) (xy 56.638952 -29.37129) (xy 56.665114 -29.37002)
			(xy 56.67502 -29.368496) (xy 56.684646 -29.365684) (xy 56.700752 -29.353762) (xy 56.706262 -29.345382)
			(xy 56.706262 -29.345128) (xy 56.708294 -29.34208) (xy 56.70931 -29.340302) (xy 56.727677 -29.311481)
			(xy 56.770073 -29.257876) (xy 56.793892 -29.233368) (xy 59.234832 -26.792428) (xy 59.238134 -26.788364)
			(xy 59.242275 -26.781855) (xy 59.246813 -26.767119) (xy 59.247024 -26.759408) (xy 59.247024 -24.158194)
			(xy 59.247519 -24.124108) (xy 59.255434 -24.056398) (xy 59.271155 -23.990064) (xy 59.294471 -23.926004)
			(xy 59.325066 -23.865084) (xy 59.362527 -23.808127) (xy 59.406347 -23.755905) (xy 59.455933 -23.709123)
			(xy 59.510615 -23.668414) (xy 59.569653 -23.634328) (xy 59.632249 -23.607327) (xy 59.697556 -23.587775)
			(xy 59.764692 -23.575937) (xy 59.832748 -23.571974) (xy 59.900804 -23.575937) (xy 59.96794 -23.587775)
			(xy 60.033247 -23.607327) (xy 60.095843 -23.634328) (xy 60.154881 -23.668414) (xy 60.209563 -23.709123)
			(xy 60.259149 -23.755905) (xy 60.302969 -23.808127) (xy 60.34043 -23.865084) (xy 60.371025 -23.926004)
			(xy 60.394341 -23.990064) (xy 60.410062 -24.056398) (xy 60.417977 -24.124108) (xy 60.418472 -24.158194)
			(xy 60.418472 -24.807418) (xy 60.620146 -24.807418) (xy 60.624217 -24.751796) (xy 60.636343 -24.697359)
			(xy 60.656266 -24.645268) (xy 60.683562 -24.596633) (xy 60.717648 -24.55249) (xy 60.757797 -24.513781)
			(xy 60.803155 -24.48133) (xy 60.852755 -24.455829) (xy 60.905539 -24.437822) (xy 60.960382 -24.427692)
			(xy 61.016116 -24.425655) (xy 61.071553 -24.431755) (xy 61.12551 -24.445861) (xy 61.176839 -24.467673)
			(xy 61.224445 -24.496727) (xy 61.267313 -24.532402) (xy 61.30453 -24.573939) (xy 61.335303 -24.620452)
			(xy 61.358975 -24.670949) (xy 61.375043 -24.724356) (xy 61.383163 -24.779532) (xy 61.383672 -24.807418)
			(xy 61.383163 -24.835304) (xy 61.375043 -24.89048) (xy 61.358975 -24.943887) (xy 61.335303 -24.994384)
			(xy 61.30453 -25.040897) (xy 61.267313 -25.082434) (xy 61.224445 -25.118109) (xy 61.176839 -25.147163)
			(xy 61.12551 -25.168975) (xy 61.071553 -25.183081) (xy 61.016116 -25.189181) (xy 60.960382 -25.187144)
			(xy 60.905539 -25.177014) (xy 60.852755 -25.159007) (xy 60.803155 -25.133506) (xy 60.757797 -25.101055)
			(xy 60.717648 -25.062346) (xy 60.683562 -25.018203) (xy 60.656266 -24.969568) (xy 60.636343 -24.917477)
			(xy 60.624217 -24.86304) (xy 60.620146 -24.807418) (xy 60.418472 -24.807418) (xy 60.418472 -26.724356)
			(xy 60.420685 -26.727203) (xy 60.425784 -26.732304) (xy 60.428632 -26.734516) (xy 60.741306 -26.734516)
			(xy 60.746326 -26.734428) (xy 60.756181 -26.732517) (xy 60.760864 -26.730706) (xy 60.76569 -26.728166)
			(xy 60.773056 -26.72461) (xy 60.776866 -26.722832) (xy 60.78093 -26.7208) (xy 60.792614 -26.709116)
			(xy 60.799081 -26.702033) (xy 60.806644 -26.684423) (xy 60.807195 -26.665266) (xy 60.800657 -26.647251)
			(xy 60.794646 -26.639774) (xy 60.784232 -26.62936) (xy 60.773564 -26.62555) (xy 60.746185 -26.615181)
			(xy 60.694728 -26.587258) (xy 60.64814 -26.551803) (xy 60.607514 -26.509648) (xy 60.573803 -26.461783)
			(xy 60.547798 -26.409331) (xy 60.53011 -26.353522) (xy 60.521154 -26.295666) (xy 60.52058 -26.266394)
			(xy 60.521066 -26.239143) (xy 60.528823 -26.185195) (xy 60.544179 -26.1329) (xy 60.56682 -26.083323)
			(xy 60.596286 -26.037473) (xy 60.631978 -25.996282) (xy 60.673168 -25.96059) (xy 60.719018 -25.931123)
			(xy 60.768595 -25.908481) (xy 60.820889 -25.893125) (xy 60.874837 -25.885367) (xy 60.902088 -25.884886)
			(xy 60.929825 -25.88539) (xy 60.984714 -25.893432) (xy 61.03786 -25.909336) (xy 61.088144 -25.932765)
			(xy 61.134507 -25.963226) (xy 61.175973 -26.000077) (xy 61.211667 -26.042543) (xy 61.240839 -26.089728)
			(xy 61.262873 -26.140639) (xy 61.277306 -26.194203) (xy 61.281056 -26.22169) (xy 61.28258 -26.235406)
			(xy 61.284308 -26.262498) (xy 61.281006 -26.316684) (xy 61.270061 -26.369855) (xy 61.251693 -26.42094)
			(xy 61.226274 -26.468907) (xy 61.194316 -26.51279) (xy 61.156464 -26.551702) (xy 61.13526 -26.568654)
			(xy 61.130688 -26.57221) (xy 61.122306 -26.58237) (xy 61.119345 -26.586087) (xy 61.114731 -26.594395)
			(xy 61.113162 -26.59888) (xy 61.110368 -26.607516) (xy 61.110876 -26.617168) (xy 61.1124 -26.648156)
			(xy 61.1124 -26.648664) (xy 61.11494 -26.688034) (xy 61.115194 -26.690828) (xy 61.11594 -26.695979)
			(xy 61.119269 -26.705837) (xy 61.121798 -26.710386) (xy 61.125862 -26.717244) (xy 61.130942 -26.725372)
			(xy 61.138308 -26.73477) (xy 61.149738 -26.7462) (xy 61.154056 -26.748994) (xy 61.176109 -26.764232)
			(xy 61.216118 -26.799904) (xy 61.250738 -26.840827) (xy 61.279287 -26.886194) (xy 61.301202 -26.935112)
			(xy 61.316052 -26.986616) (xy 61.323544 -27.039693) (xy 61.323982 -27.066494) (xy 61.323507 -27.093598)
			(xy 61.315837 -27.147259) (xy 61.300649 -27.199295) (xy 61.278251 -27.248658) (xy 61.249091 -27.294354)
			(xy 61.213759 -27.335464) (xy 61.172964 -27.371159) (xy 61.127528 -27.400723) (xy 61.078366 -27.423558)
			(xy 61.026466 -27.439206) (xy 60.972875 -27.447352) (xy 60.945776 -27.448002) (xy 60.936632 -27.448002)
			(xy 60.906525 -27.447135) (xy 60.847143 -27.437074) (xy 60.790082 -27.4178) (xy 60.76315 -27.404314)
			(xy 60.75762 -27.401614) (xy 60.745679 -27.398651) (xy 60.739528 -27.398472) (xy 60.578238 -27.398472)
			(xy 60.573412 -27.403552) (xy 60.571634 -27.405076) (xy 60.570364 -27.406092) (xy 58.854086 -29.12237)
			(xy 60.60694 -29.12237) (xy 60.60694 -28.25877) (xy 60.60743 -28.228802) (xy 60.615253 -28.16938)
			(xy 60.630766 -28.111487) (xy 60.653702 -28.056114) (xy 60.683669 -28.004208) (xy 60.720156 -27.956658)
			(xy 60.762536 -27.914278) (xy 60.810086 -27.877791) (xy 60.861992 -27.847824) (xy 60.917365 -27.824888)
			(xy 60.975258 -27.809375) (xy 61.03468 -27.801552) (xy 61.094616 -27.801552) (xy 61.154038 -27.809375)
			(xy 61.211931 -27.824888) (xy 61.267304 -27.847824) (xy 61.31921 -27.877791) (xy 61.36676 -27.914278)
			(xy 61.40914 -27.956658) (xy 61.445627 -28.004208) (xy 61.475594 -28.056114) (xy 61.49853 -28.111487)
			(xy 61.514043 -28.16938) (xy 61.521866 -28.228802) (xy 61.522356 -28.25877) (xy 61.522356 -29.12237)
			(xy 61.521866 -29.152338) (xy 61.514043 -29.21176) (xy 61.49853 -29.269653) (xy 61.475594 -29.325026)
			(xy 61.445627 -29.376932) (xy 61.40914 -29.424482) (xy 61.36676 -29.466862) (xy 61.31921 -29.503349)
			(xy 61.267304 -29.533316) (xy 61.211931 -29.556252) (xy 61.154038 -29.571765) (xy 61.094616 -29.579588)
			(xy 61.03468 -29.579588) (xy 60.975258 -29.571765) (xy 60.917365 -29.556252) (xy 60.861992 -29.533316)
			(xy 60.810086 -29.503349) (xy 60.762536 -29.466862) (xy 60.720156 -29.424482) (xy 60.683669 -29.376932)
			(xy 60.653702 -29.325026) (xy 60.630766 -29.269653) (xy 60.615253 -29.21176) (xy 60.60743 -29.152338)
			(xy 60.60694 -29.12237) (xy 58.854086 -29.12237) (xy 58.097166 -29.87929) (xy 58.095388 -29.881576)
			(xy 58.095388 -30.922468) (xy 58.75274 -30.922468) (xy 58.75274 -30.058868) (xy 58.75323 -30.0289)
			(xy 58.761053 -29.969478) (xy 58.776566 -29.911585) (xy 58.799502 -29.856212) (xy 58.829469 -29.804306)
			(xy 58.865956 -29.756756) (xy 58.908336 -29.714376) (xy 58.955886 -29.677889) (xy 59.007792 -29.647922)
			(xy 59.063165 -29.624986) (xy 59.121058 -29.609473) (xy 59.18048 -29.60165) (xy 59.240416 -29.60165)
			(xy 59.299838 -29.609473) (xy 59.357731 -29.624986) (xy 59.413104 -29.647922) (xy 59.46501 -29.677889)
			(xy 59.51256 -29.714376) (xy 59.55494 -29.756756) (xy 59.591427 -29.804306) (xy 59.621394 -29.856212)
			(xy 59.64433 -29.911585) (xy 59.659843 -29.969478) (xy 59.667666 -30.0289) (xy 59.668156 -30.058868)
			(xy 59.668156 -30.92069) (xy 73.489312 -30.92069) (xy 73.489312 -30.05709) (xy 73.489802 -30.027106)
			(xy 73.49763 -29.96765) (xy 73.513151 -29.909725) (xy 73.5361 -29.854321) (xy 73.566084 -29.802387)
			(xy 73.60259 -29.754811) (xy 73.644995 -29.712406) (xy 73.692571 -29.6759) (xy 73.744505 -29.645916)
			(xy 73.799909 -29.622967) (xy 73.857834 -29.607446) (xy 73.91729 -29.599618) (xy 73.977258 -29.599618)
			(xy 74.036714 -29.607446) (xy 74.094639 -29.622967) (xy 74.150043 -29.645916) (xy 74.201977 -29.6759)
			(xy 74.249553 -29.712406) (xy 74.291958 -29.754811) (xy 74.328464 -29.802387) (xy 74.358448 -29.854321)
			(xy 74.381397 -29.909725) (xy 74.396918 -29.96765) (xy 74.404746 -30.027106) (xy 74.405236 -30.05709)
			(xy 74.405236 -30.92069) (xy 74.404746 -30.950674) (xy 74.396918 -31.01013) (xy 74.381397 -31.068055)
			(xy 74.358448 -31.123459) (xy 74.328464 -31.175393) (xy 74.291958 -31.222969) (xy 74.249553 -31.265374)
			(xy 74.201977 -31.30188) (xy 74.150043 -31.331864) (xy 74.094639 -31.354813) (xy 74.036714 -31.370334)
			(xy 73.977258 -31.378162) (xy 73.91729 -31.378162) (xy 73.857834 -31.370334) (xy 73.799909 -31.354813)
			(xy 73.744505 -31.331864) (xy 73.692571 -31.30188) (xy 73.644995 -31.265374) (xy 73.60259 -31.222969)
			(xy 73.566084 -31.175393) (xy 73.5361 -31.123459) (xy 73.513151 -31.068055) (xy 73.49763 -31.01013)
			(xy 73.489802 -30.950674) (xy 73.489312 -30.92069) (xy 59.668156 -30.92069) (xy 59.668156 -30.922468)
			(xy 59.667666 -30.952436) (xy 59.659843 -31.011858) (xy 59.64433 -31.069751) (xy 59.621394 -31.125124)
			(xy 59.591427 -31.17703) (xy 59.55494 -31.22458) (xy 59.51256 -31.26696) (xy 59.46501 -31.303447)
			(xy 59.413104 -31.333414) (xy 59.357731 -31.35635) (xy 59.299838 -31.371863) (xy 59.240416 -31.379686)
			(xy 59.18048 -31.379686) (xy 59.121058 -31.371863) (xy 59.063165 -31.35635) (xy 59.007792 -31.333414)
			(xy 58.955886 -31.303447) (xy 58.908336 -31.26696) (xy 58.865956 -31.22458) (xy 58.829469 -31.17703)
			(xy 58.799502 -31.125124) (xy 58.776566 -31.069751) (xy 58.761053 -31.011858) (xy 58.75323 -30.952436)
			(xy 58.75274 -30.922468) (xy 58.095388 -30.922468) (xy 58.095388 -32.722312) (xy 60.60694 -32.722312)
			(xy 60.60694 -31.858712) (xy 60.60743 -31.828744) (xy 60.615253 -31.769322) (xy 60.630766 -31.711429)
			(xy 60.653702 -31.656056) (xy 60.683669 -31.60415) (xy 60.720156 -31.5566) (xy 60.762536 -31.51422)
			(xy 60.810086 -31.477733) (xy 60.861992 -31.447766) (xy 60.917365 -31.42483) (xy 60.975258 -31.409317)
			(xy 61.03468 -31.401494) (xy 61.094616 -31.401494) (xy 61.154038 -31.409317) (xy 61.211931 -31.42483)
			(xy 61.267304 -31.447766) (xy 61.31921 -31.477733) (xy 61.36676 -31.51422) (xy 61.40914 -31.5566)
			(xy 61.445627 -31.60415) (xy 61.475594 -31.656056) (xy 61.49853 -31.711429) (xy 61.514043 -31.769322)
			(xy 61.521866 -31.828744) (xy 61.522356 -31.858712) (xy 61.522356 -32.714184) (xy 70.847204 -32.714184)
			(xy 70.847204 -31.850584) (xy 70.847694 -31.8206) (xy 70.855522 -31.761144) (xy 70.871043 -31.703219)
			(xy 70.893992 -31.647815) (xy 70.923976 -31.595881) (xy 70.960482 -31.548305) (xy 71.002887 -31.5059)
			(xy 71.050463 -31.469394) (xy 71.102397 -31.43941) (xy 71.157801 -31.416461) (xy 71.215726 -31.40094)
			(xy 71.275182 -31.393112) (xy 71.33515 -31.393112) (xy 71.394606 -31.40094) (xy 71.452531 -31.416461)
			(xy 71.507935 -31.43941) (xy 71.559869 -31.469394) (xy 71.607445 -31.5059) (xy 71.64985 -31.548305)
			(xy 71.686356 -31.595881) (xy 71.71634 -31.647815) (xy 71.739289 -31.703219) (xy 71.75481 -31.761144)
			(xy 71.762638 -31.8206) (xy 71.763128 -31.850584) (xy 71.763128 -32.714184) (xy 71.762638 -32.744168)
			(xy 71.75481 -32.803624) (xy 71.739289 -32.861549) (xy 71.71634 -32.916953) (xy 71.686356 -32.968887)
			(xy 71.64985 -33.016463) (xy 71.607445 -33.058868) (xy 71.559869 -33.095374) (xy 71.507935 -33.125358)
			(xy 71.452531 -33.148307) (xy 71.394606 -33.163828) (xy 71.33515 -33.171656) (xy 71.275182 -33.171656)
			(xy 71.215726 -33.163828) (xy 71.157801 -33.148307) (xy 71.102397 -33.125358) (xy 71.050463 -33.095374)
			(xy 71.002887 -33.058868) (xy 70.960482 -33.016463) (xy 70.923976 -32.968887) (xy 70.893992 -32.916953)
			(xy 70.871043 -32.861549) (xy 70.855522 -32.803624) (xy 70.847694 -32.744168) (xy 70.847204 -32.714184)
			(xy 61.522356 -32.714184) (xy 61.522356 -32.722312) (xy 61.521866 -32.75228) (xy 61.514043 -32.811702)
			(xy 61.49853 -32.869595) (xy 61.475594 -32.924968) (xy 61.445627 -32.976874) (xy 61.40914 -33.024424)
			(xy 61.36676 -33.066804) (xy 61.31921 -33.103291) (xy 61.267304 -33.133258) (xy 61.211931 -33.156194)
			(xy 61.154038 -33.171707) (xy 61.094616 -33.17953) (xy 61.03468 -33.17953) (xy 60.975258 -33.171707)
			(xy 60.917365 -33.156194) (xy 60.861992 -33.133258) (xy 60.810086 -33.103291) (xy 60.762536 -33.066804)
			(xy 60.720156 -33.024424) (xy 60.683669 -32.976874) (xy 60.653702 -32.924968) (xy 60.630766 -32.869595)
			(xy 60.615253 -32.811702) (xy 60.60743 -32.75228) (xy 60.60694 -32.722312) (xy 58.095388 -32.722312)
			(xy 58.095388 -34.52241) (xy 58.75274 -34.52241) (xy 58.75274 -33.65881) (xy 58.75323 -33.628842)
			(xy 58.761053 -33.56942) (xy 58.776566 -33.511527) (xy 58.799502 -33.456154) (xy 58.829469 -33.404248)
			(xy 58.865956 -33.356698) (xy 58.908336 -33.314318) (xy 58.955886 -33.277831) (xy 59.007792 -33.247864)
			(xy 59.063165 -33.224928) (xy 59.121058 -33.209415) (xy 59.18048 -33.201592) (xy 59.240416 -33.201592)
			(xy 59.299838 -33.209415) (xy 59.357731 -33.224928) (xy 59.413104 -33.247864) (xy 59.46501 -33.277831)
			(xy 59.51256 -33.314318) (xy 59.55494 -33.356698) (xy 59.591427 -33.404248) (xy 59.621394 -33.456154)
			(xy 59.64433 -33.511527) (xy 59.659843 -33.56942) (xy 59.667666 -33.628842) (xy 59.668156 -33.65881)
			(xy 59.668156 -34.520886) (xy 73.489312 -34.520886) (xy 73.489312 -33.657286) (xy 73.489802 -33.627302)
			(xy 73.49763 -33.567846) (xy 73.513151 -33.509921) (xy 73.5361 -33.454517) (xy 73.566084 -33.402583)
			(xy 73.60259 -33.355007) (xy 73.644995 -33.312602) (xy 73.692571 -33.276096) (xy 73.744505 -33.246112)
			(xy 73.799909 -33.223163) (xy 73.857834 -33.207642) (xy 73.91729 -33.199814) (xy 73.977258 -33.199814)
			(xy 74.036714 -33.207642) (xy 74.094639 -33.223163) (xy 74.150043 -33.246112) (xy 74.201977 -33.276096)
			(xy 74.249553 -33.312602) (xy 74.291958 -33.355007) (xy 74.328464 -33.402583) (xy 74.358448 -33.454517)
			(xy 74.381397 -33.509921) (xy 74.396918 -33.567846) (xy 74.404746 -33.627302) (xy 74.405236 -33.657286)
			(xy 74.405236 -34.520886) (xy 74.404746 -34.55087) (xy 74.396918 -34.610326) (xy 74.381397 -34.668251)
			(xy 74.358448 -34.723655) (xy 74.328464 -34.775589) (xy 74.291958 -34.823165) (xy 74.249553 -34.86557)
			(xy 74.201977 -34.902076) (xy 74.150043 -34.93206) (xy 74.094639 -34.955009) (xy 74.036714 -34.97053)
			(xy 73.977258 -34.978358) (xy 73.91729 -34.978358) (xy 73.857834 -34.97053) (xy 73.799909 -34.955009)
			(xy 73.744505 -34.93206) (xy 73.692571 -34.902076) (xy 73.644995 -34.86557) (xy 73.60259 -34.823165)
			(xy 73.566084 -34.775589) (xy 73.5361 -34.723655) (xy 73.513151 -34.668251) (xy 73.49763 -34.610326)
			(xy 73.489802 -34.55087) (xy 73.489312 -34.520886) (xy 59.668156 -34.520886) (xy 59.668156 -34.52241)
			(xy 59.667666 -34.552378) (xy 59.659843 -34.6118) (xy 59.64433 -34.669693) (xy 59.621394 -34.725066)
			(xy 59.591427 -34.776972) (xy 59.55494 -34.824522) (xy 59.51256 -34.866902) (xy 59.46501 -34.903389)
			(xy 59.413104 -34.933356) (xy 59.357731 -34.956292) (xy 59.299838 -34.971805) (xy 59.240416 -34.979628)
			(xy 59.18048 -34.979628) (xy 59.121058 -34.971805) (xy 59.063165 -34.956292) (xy 59.007792 -34.933356)
			(xy 58.955886 -34.903389) (xy 58.908336 -34.866902) (xy 58.865956 -34.824522) (xy 58.829469 -34.776972)
			(xy 58.799502 -34.725066) (xy 58.776566 -34.669693) (xy 58.761053 -34.6118) (xy 58.75323 -34.552378)
			(xy 58.75274 -34.52241) (xy 58.095388 -34.52241) (xy 58.095388 -34.72434) (xy 58.096404 -34.733992)
			(xy 58.098036 -34.741234) (xy 58.104882 -34.754398) (xy 58.109866 -34.7599) (xy 59.497468 -36.147502)
			(xy 59.504072 -36.149534) (xy 59.529882 -36.157636) (xy 59.579087 -36.180111) (xy 59.624623 -36.209313)
			(xy 59.665576 -36.244656) (xy 59.701126 -36.28543) (xy 59.730558 -36.330817) (xy 59.753282 -36.379907)
			(xy 59.768843 -36.431716) (xy 59.776929 -36.485203) (xy 59.77763 -36.512246) (xy 59.77763 -36.519104)
			(xy 59.777052 -36.543004) (xy 59.770687 -36.590388) (xy 59.76827 -36.60013) (xy 63.998101 -36.60013)
			(xy 64.002106 -36.512222) (xy 64.014089 -36.425042) (xy 64.033949 -36.339313) (xy 64.061524 -36.255745)
			(xy 64.096583 -36.175031) (xy 64.138836 -36.097839) (xy 64.187934 -36.02481) (xy 64.24347 -35.956548)
			(xy 64.304982 -35.893618) (xy 64.371963 -35.836544) (xy 64.443856 -35.785796) (xy 64.520065 -35.741796)
			(xy 64.59996 -35.704909) (xy 64.682879 -35.67544) (xy 64.768134 -35.653633) (xy 64.855018 -35.639669)
			(xy 64.942812 -35.633663) (xy 65.030789 -35.635667) (xy 65.118219 -35.645662) (xy 65.204378 -35.663566)
			(xy 65.288552 -35.68923) (xy 65.370043 -35.722443) (xy 65.448177 -35.762929) (xy 65.522305 -35.810351)
			(xy 65.591813 -35.864318) (xy 65.605112 -35.876738) (xy 70.717154 -35.876738) (xy 70.721225 -35.821116)
			(xy 70.733351 -35.766679) (xy 70.753274 -35.714588) (xy 70.78057 -35.665953) (xy 70.814656 -35.62181)
			(xy 70.854805 -35.583101) (xy 70.900163 -35.55065) (xy 70.949763 -35.525149) (xy 71.002547 -35.507142)
			(xy 71.05739 -35.497012) (xy 71.113124 -35.494975) (xy 71.168561 -35.501075) (xy 71.222518 -35.515181)
			(xy 71.273847 -35.536993) (xy 71.321453 -35.566047) (xy 71.364321 -35.601722) (xy 71.401538 -35.643259)
			(xy 71.432311 -35.689772) (xy 71.455983 -35.740269) (xy 71.472051 -35.793676) (xy 71.480171 -35.848852)
			(xy 71.48068 -35.876738) (xy 71.480171 -35.904624) (xy 71.472051 -35.9598) (xy 71.455983 -36.013207)
			(xy 71.432311 -36.063704) (xy 71.401538 -36.110217) (xy 71.364321 -36.151754) (xy 71.321453 -36.187429)
			(xy 71.273847 -36.216483) (xy 71.222518 -36.238295) (xy 71.168561 -36.252401) (xy 71.113124 -36.258501)
			(xy 71.05739 -36.256464) (xy 71.002547 -36.246334) (xy 70.949763 -36.228327) (xy 70.900163 -36.202826)
			(xy 70.854805 -36.170375) (xy 70.814656 -36.131666) (xy 70.78057 -36.087523) (xy 70.753274 -36.038888)
			(xy 70.733351 -35.986797) (xy 70.721225 -35.93236) (xy 70.717154 -35.876738) (xy 65.605112 -35.876738)
			(xy 65.656127 -35.924383) (xy 65.714711 -35.990047) (xy 65.767082 -36.060766) (xy 65.812805 -36.135954)
			(xy 65.851502 -36.214989) (xy 65.882851 -36.297215) (xy 65.906593 -36.381951) (xy 65.922531 -36.468495)
			(xy 65.926317 -36.50996) (xy 72.613772 -36.50996) (xy 72.617843 -36.454338) (xy 72.629969 -36.399901)
			(xy 72.649892 -36.34781) (xy 72.677188 -36.299175) (xy 72.711274 -36.255032) (xy 72.751423 -36.216323)
			(xy 72.796781 -36.183872) (xy 72.846381 -36.158371) (xy 72.899165 -36.140364) (xy 72.954008 -36.130234)
			(xy 73.009742 -36.128197) (xy 73.065179 -36.134297) (xy 73.119136 -36.148403) (xy 73.170465 -36.170215)
			(xy 73.218071 -36.199269) (xy 73.260939 -36.234944) (xy 73.298156 -36.276481) (xy 73.328929 -36.322994)
			(xy 73.352601 -36.373491) (xy 73.368669 -36.426898) (xy 73.376789 -36.482074) (xy 73.377298 -36.50996)
			(xy 73.376789 -36.537846) (xy 73.368669 -36.593022) (xy 73.352601 -36.646429) (xy 73.328929 -36.696926)
			(xy 73.298156 -36.743439) (xy 73.260939 -36.784976) (xy 73.218071 -36.820651) (xy 73.170465 -36.849705)
			(xy 73.119136 -36.871517) (xy 73.065179 -36.885623) (xy 73.009742 -36.891723) (xy 72.954008 -36.889686)
			(xy 72.899165 -36.879556) (xy 72.846381 -36.861549) (xy 72.796781 -36.836048) (xy 72.751423 -36.803597)
			(xy 72.711274 -36.764888) (xy 72.677188 -36.720745) (xy 72.649892 -36.67211) (xy 72.629969 -36.620019)
			(xy 72.617843 -36.565582) (xy 72.613772 -36.50996) (xy 65.926317 -36.50996) (xy 65.930533 -36.55613)
			(xy 65.931034 -36.60013) (xy 65.930533 -36.64413) (xy 65.922531 -36.731765) (xy 65.906593 -36.818309)
			(xy 65.882851 -36.903045) (xy 65.851502 -36.985271) (xy 65.812805 -37.064306) (xy 65.767082 -37.139494)
			(xy 65.714711 -37.210213) (xy 65.656127 -37.275877) (xy 65.591813 -37.335942) (xy 65.522305 -37.389909)
			(xy 65.448177 -37.437331) (xy 65.375171 -37.47516) (xy 69.759066 -37.47516) (xy 69.763137 -37.419538)
			(xy 69.775263 -37.365101) (xy 69.795186 -37.31301) (xy 69.822482 -37.264375) (xy 69.856568 -37.220232)
			(xy 69.896717 -37.181523) (xy 69.942075 -37.149072) (xy 69.991675 -37.123571) (xy 70.044459 -37.105564)
			(xy 70.099302 -37.095434) (xy 70.155036 -37.093397) (xy 70.210473 -37.099497) (xy 70.26443 -37.113603)
			(xy 70.315759 -37.135415) (xy 70.363365 -37.164469) (xy 70.406233 -37.200144) (xy 70.44345 -37.241681)
			(xy 70.474223 -37.288194) (xy 70.497895 -37.338691) (xy 70.513963 -37.392098) (xy 70.522083 -37.447274)
			(xy 70.522592 -37.47516) (xy 70.522083 -37.503046) (xy 70.513963 -37.558222) (xy 70.497895 -37.611629)
			(xy 70.474223 -37.662126) (xy 70.47407 -37.662358) (xy 71.948292 -37.662358) (xy 71.952363 -37.606736)
			(xy 71.964489 -37.552299) (xy 71.984412 -37.500208) (xy 72.011708 -37.451573) (xy 72.045794 -37.40743)
			(xy 72.085943 -37.368721) (xy 72.131301 -37.33627) (xy 72.180901 -37.310769) (xy 72.233685 -37.292762)
			(xy 72.288528 -37.282632) (xy 72.344262 -37.280595) (xy 72.399699 -37.286695) (xy 72.453656 -37.300801)
			(xy 72.504985 -37.322613) (xy 72.552591 -37.351667) (xy 72.595459 -37.387342) (xy 72.632676 -37.428879)
			(xy 72.663449 -37.475392) (xy 72.687121 -37.525889) (xy 72.703189 -37.579296) (xy 72.711309 -37.634472)
			(xy 72.711818 -37.662358) (xy 72.711309 -37.690244) (xy 72.703189 -37.74542) (xy 72.687121 -37.798827)
			(xy 72.663449 -37.849324) (xy 72.632676 -37.895837) (xy 72.595459 -37.937374) (xy 72.552591 -37.973049)
			(xy 72.504985 -38.002103) (xy 72.453656 -38.023915) (xy 72.399699 -38.038021) (xy 72.344262 -38.044121)
			(xy 72.288528 -38.042084) (xy 72.233685 -38.031954) (xy 72.180901 -38.013947) (xy 72.131301 -37.988446)
			(xy 72.085943 -37.955995) (xy 72.045794 -37.917286) (xy 72.011708 -37.873143) (xy 71.984412 -37.824508)
			(xy 71.964489 -37.772417) (xy 71.952363 -37.71798) (xy 71.948292 -37.662358) (xy 70.47407 -37.662358)
			(xy 70.44345 -37.708639) (xy 70.406233 -37.750176) (xy 70.363365 -37.785851) (xy 70.315759 -37.814905)
			(xy 70.26443 -37.836717) (xy 70.210473 -37.850823) (xy 70.155036 -37.856923) (xy 70.099302 -37.854886)
			(xy 70.044459 -37.844756) (xy 69.991675 -37.826749) (xy 69.942075 -37.801248) (xy 69.896717 -37.768797)
			(xy 69.856568 -37.730088) (xy 69.822482 -37.685945) (xy 69.795186 -37.63731) (xy 69.775263 -37.585219)
			(xy 69.763137 -37.530782) (xy 69.759066 -37.47516) (xy 65.375171 -37.47516) (xy 65.370043 -37.477817)
			(xy 65.288552 -37.51103) (xy 65.204378 -37.536694) (xy 65.118219 -37.554598) (xy 65.030789 -37.564593)
			(xy 64.942812 -37.566597) (xy 64.855018 -37.560591) (xy 64.768134 -37.546627) (xy 64.682879 -37.52482)
			(xy 64.59996 -37.495351) (xy 64.520065 -37.458464) (xy 64.443856 -37.414464) (xy 64.371963 -37.363716)
			(xy 64.304982 -37.306642) (xy 64.24347 -37.243712) (xy 64.187934 -37.17545) (xy 64.138836 -37.102421)
			(xy 64.096583 -37.025229) (xy 64.061524 -36.944515) (xy 64.033949 -36.860947) (xy 64.014089 -36.775218)
			(xy 64.002106 -36.688038) (xy 63.998101 -36.60013) (xy 59.76827 -36.60013) (xy 59.76493 -36.613592)
			(xy 59.761547 -36.626148) (xy 59.753285 -36.650808) (xy 59.74842 -36.662868) (xy 59.748166 -36.663376)
			(xy 59.738006 -36.685474) (xy 59.737752 -36.685982) (xy 59.737752 -38.729948) (xy 75.70092 -38.729948)
			(xy 75.70092 -38.675452) (xy 75.708676 -38.621511) (xy 75.724028 -38.569223) (xy 75.746666 -38.519652)
			(xy 75.776128 -38.473807) (xy 75.811815 -38.432622) (xy 75.852999 -38.396934) (xy 75.898843 -38.367471)
			(xy 75.948414 -38.344832) (xy 76.000702 -38.329478) (xy 76.054642 -38.321721) (xy 76.08189 -38.321234)
			(xy 76.110195 -38.321716) (xy 76.166184 -38.330067) (xy 76.220324 -38.346603) (xy 76.271425 -38.370959)
			(xy 76.318365 -38.402601) (xy 76.360112 -38.440834) (xy 76.395749 -38.484818) (xy 76.410566 -38.50894)
			(xy 76.418111 -38.521011) (xy 76.438741 -38.540615) (xy 76.463984 -38.553756) (xy 76.491876 -38.559412)
			(xy 76.520244 -38.557141) (xy 76.54688 -38.54712) (xy 76.569711 -38.53013) (xy 76.578714 -38.5191)
			(xy 76.596897 -38.496221) (xy 76.639061 -38.455758) (xy 76.686897 -38.42219) (xy 76.73929 -38.396304)
			(xy 76.795015 -38.378702) (xy 76.852771 -38.369797) (xy 76.88199 -38.36924) (xy 76.909247 -38.369606)
			(xy 76.963206 -38.377363) (xy 77.015511 -38.39272) (xy 77.065099 -38.415365) (xy 77.110959 -38.444836)
			(xy 77.152158 -38.480535) (xy 77.187858 -38.521733) (xy 77.21733 -38.567592) (xy 77.239976 -38.617179)
			(xy 77.255335 -38.669485) (xy 77.263093 -38.723443) (xy 77.263093 -38.777957) (xy 77.255335 -38.831915)
			(xy 77.239976 -38.884221) (xy 77.21733 -38.933808) (xy 77.187858 -38.979667) (xy 77.152158 -39.020865)
			(xy 77.110959 -39.056564) (xy 77.065099 -39.086035) (xy 77.015511 -39.10868) (xy 76.963206 -39.124037)
			(xy 76.909247 -39.131794) (xy 76.88199 -39.132256) (xy 76.853685 -39.131795) (xy 76.797694 -39.12344)
			(xy 76.743553 -39.106902) (xy 76.692452 -39.082542) (xy 76.645512 -39.050896) (xy 76.603766 -39.01266)
			(xy 76.56813 -38.968674) (xy 76.553314 -38.94455) (xy 76.545665 -38.932552) (xy 76.525056 -38.912954)
			(xy 76.499835 -38.899812) (xy 76.471965 -38.894149) (xy 76.443615 -38.896405) (xy 76.416992 -38.906406)
			(xy 76.394168 -38.923372) (xy 76.385166 -38.93439) (xy 76.366991 -38.957276) (xy 76.324827 -38.99774)
			(xy 76.276988 -39.031306) (xy 76.224594 -39.057192) (xy 76.168868 -39.074792) (xy 76.11111 -39.083695)
			(xy 76.08189 -39.08425) (xy 76.054642 -39.083679) (xy 76.000702 -39.075922) (xy 75.948414 -39.060568)
			(xy 75.898843 -39.037929) (xy 75.852999 -39.008466) (xy 75.811815 -38.972778) (xy 75.776128 -38.931593)
			(xy 75.746666 -38.885748) (xy 75.724028 -38.836177) (xy 75.708676 -38.783889) (xy 75.70092 -38.729948)
			(xy 59.737752 -38.729948) (xy 59.737752 -38.940486) (xy 59.743086 -38.946836) (xy 62.065005 -41.268755)
			(xy 67.843827 -41.268755) (xy 67.843827 -41.214245) (xy 67.851585 -41.160289) (xy 67.866942 -41.107987)
			(xy 67.889587 -41.058402) (xy 67.919058 -41.012545) (xy 67.954755 -40.971349) (xy 67.995952 -40.935653)
			(xy 68.041809 -40.906183) (xy 68.091394 -40.883539) (xy 68.143697 -40.868183) (xy 68.197653 -40.860426)
			(xy 68.224908 -40.859964) (xy 68.253647 -40.860492) (xy 68.310473 -40.869115) (xy 68.365364 -40.886165)
			(xy 68.417075 -40.911255) (xy 68.464439 -40.943818) (xy 68.485766 -40.963088) (xy 68.492624 -40.969692)
			(xy 68.510658 -40.976804) (xy 68.599558 -40.976804) (xy 68.617592 -40.969692) (xy 68.62445 -40.963088)
			(xy 68.645781 -40.943822) (xy 68.693141 -40.911253) (xy 68.744852 -40.886159) (xy 68.799742 -40.869107)
			(xy 68.856569 -40.860484) (xy 68.885308 -40.859964) (xy 68.912557 -40.860507) (xy 68.9665 -40.868264)
			(xy 69.01879 -40.883618) (xy 69.068362 -40.906258) (xy 69.114208 -40.935722) (xy 69.155394 -40.971411)
			(xy 69.191082 -41.012598) (xy 69.220546 -41.058445) (xy 69.243185 -41.108018) (xy 69.258538 -41.160308)
			(xy 69.266294 -41.214251) (xy 69.266294 -41.268749) (xy 69.258538 -41.322692) (xy 69.243185 -41.374982)
			(xy 69.220546 -41.424555) (xy 69.191082 -41.470402) (xy 69.155394 -41.511589) (xy 69.114208 -41.547277)
			(xy 69.068362 -41.576742) (xy 69.01879 -41.599382) (xy 68.9665 -41.614736) (xy 68.912557 -41.622493)
			(xy 68.885308 -41.62298) (xy 68.85657 -41.62243) (xy 68.799745 -41.613811) (xy 68.744855 -41.596765)
			(xy 68.693143 -41.57168) (xy 68.645779 -41.539123) (xy 68.62445 -41.519856) (xy 68.617592 -41.513252)
			(xy 68.599558 -41.50614) (xy 68.510658 -41.50614) (xy 68.492624 -41.513252) (xy 68.485766 -41.519856)
			(xy 68.464435 -41.539122) (xy 68.417074 -41.571689) (xy 68.365363 -41.596783) (xy 68.310474 -41.613834)
			(xy 68.253647 -41.622458) (xy 68.224908 -41.62298) (xy 68.197653 -41.622574) (xy 68.143697 -41.614817)
			(xy 68.091394 -41.599461) (xy 68.041809 -41.576817) (xy 67.995952 -41.547347) (xy 67.954755 -41.511651)
			(xy 67.919058 -41.470455) (xy 67.889587 -41.424598) (xy 67.866942 -41.375013) (xy 67.851585 -41.322711)
			(xy 67.843827 -41.268755) (xy 62.065005 -41.268755) (xy 64.101472 -43.305222) (xy 70.3072 -43.305222)
			(xy 70.307679 -43.277852) (xy 70.315494 -43.223674) (xy 70.33098 -43.171171) (xy 70.353819 -43.121424)
			(xy 70.38354 -43.075456) (xy 70.40118 -43.054524) (xy 70.401434 -43.05427) (xy 70.407001 -43.04717)
			(xy 70.413258 -43.030263) (xy 70.413626 -43.02125) (xy 70.413626 -42.954194) (xy 70.413266 -42.945178)
			(xy 70.40702 -42.928261) (xy 70.401434 -42.921174) (xy 70.40118 -42.921174) (xy 70.40118 -42.92092)
			(xy 70.383534 -42.899994) (xy 70.353824 -42.854019) (xy 70.330989 -42.80427) (xy 70.3155 -42.751768)
			(xy 70.307673 -42.697592) (xy 70.3072 -42.670222) (xy 70.307737 -42.641484) (xy 70.316356 -42.584657)
			(xy 70.333403 -42.529766) (xy 70.358492 -42.478054) (xy 70.391054 -42.430691) (xy 70.410324 -42.409364)
			(xy 70.416928 -42.402506) (xy 70.42404 -42.384472) (xy 70.42404 -42.295572) (xy 70.416928 -42.277538)
			(xy 70.410324 -42.27068) (xy 70.391075 -42.249334) (xy 70.358509 -42.201975) (xy 70.333416 -42.150266)
			(xy 70.316365 -42.095379) (xy 70.30774 -42.038554) (xy 70.307738 -41.981078) (xy 70.316357 -41.924253)
			(xy 70.333404 -41.869364) (xy 70.358493 -41.817653) (xy 70.391055 -41.770291) (xy 70.410324 -41.748964)
			(xy 70.416928 -41.742106) (xy 70.42404 -41.724072) (xy 70.42404 -41.635172) (xy 70.416928 -41.617138)
			(xy 70.410324 -41.61028) (xy 70.391061 -41.588946) (xy 70.358494 -41.541586) (xy 70.333401 -41.489876)
			(xy 70.316348 -41.434987) (xy 70.307723 -41.37816) (xy 70.3072 -41.349422) (xy 70.307686 -41.322171)
			(xy 70.315442 -41.268223) (xy 70.330797 -41.215928) (xy 70.353439 -41.166351) (xy 70.382905 -41.120501)
			(xy 70.418596 -41.07931) (xy 70.459787 -41.043619) (xy 70.505637 -41.014153) (xy 70.555214 -40.991511)
			(xy 70.607509 -40.976156) (xy 70.661457 -40.9684) (xy 70.715959 -40.9684) (xy 70.73908 -40.971724)
			(xy 78.593948 -40.971724) (xy 78.598019 -40.916102) (xy 78.610145 -40.861665) (xy 78.630068 -40.809574)
			(xy 78.657364 -40.760939) (xy 78.69145 -40.716796) (xy 78.731599 -40.678087) (xy 78.776957 -40.645636)
			(xy 78.826557 -40.620135) (xy 78.879341 -40.602128) (xy 78.934184 -40.591998) (xy 78.989918 -40.589961)
			(xy 79.045355 -40.596061) (xy 79.099312 -40.610167) (xy 79.150641 -40.631979) (xy 79.198247 -40.661033)
			(xy 79.241115 -40.696708) (xy 79.278332 -40.738245) (xy 79.309105 -40.784758) (xy 79.332777 -40.835255)
			(xy 79.348845 -40.888662) (xy 79.356965 -40.943838) (xy 79.357474 -40.971724) (xy 79.356965 -40.99961)
			(xy 79.348845 -41.054786) (xy 79.332777 -41.108193) (xy 79.309105 -41.15869) (xy 79.278332 -41.205203)
			(xy 79.241115 -41.24674) (xy 79.198247 -41.282415) (xy 79.150641 -41.311469) (xy 79.099312 -41.333281)
			(xy 79.045355 -41.347387) (xy 78.989918 -41.353487) (xy 78.934184 -41.35145) (xy 78.879341 -41.34132)
			(xy 78.826557 -41.323313) (xy 78.776957 -41.297812) (xy 78.731599 -41.265361) (xy 78.69145 -41.226652)
			(xy 78.657364 -41.182509) (xy 78.630068 -41.133874) (xy 78.610145 -41.081783) (xy 78.598019 -41.027346)
			(xy 78.593948 -40.971724) (xy 70.73908 -40.971724) (xy 70.769907 -40.976156) (xy 70.822202 -40.991511)
			(xy 70.871779 -41.014153) (xy 70.917629 -41.043619) (xy 70.95882 -41.07931) (xy 70.994511 -41.120501)
			(xy 71.023977 -41.166351) (xy 71.046619 -41.215928) (xy 71.061974 -41.268223) (xy 71.06973 -41.322171)
			(xy 71.070216 -41.349422) (xy 71.069701 -41.378161) (xy 71.061076 -41.434989) (xy 71.044023 -41.489879)
			(xy 71.01893 -41.541591) (xy 70.986363 -41.588953) (xy 70.967092 -41.61028) (xy 70.960488 -41.617138)
			(xy 70.953376 -41.635172) (xy 70.953376 -41.724072) (xy 70.960488 -41.742106) (xy 70.967092 -41.748964)
			(xy 70.986384 -41.770272) (xy 71.018947 -41.817638) (xy 71.044036 -41.869353) (xy 71.061084 -41.924247)
			(xy 71.069704 -41.981076) (xy 71.069702 -42.038556) (xy 71.061077 -42.095385) (xy 71.044025 -42.150277)
			(xy 71.018931 -42.201989) (xy 70.986364 -42.249353) (xy 70.967092 -42.27068) (xy 70.960488 -42.277538)
			(xy 70.953376 -42.295572) (xy 70.953376 -42.384472) (xy 70.960488 -42.402506) (xy 70.967092 -42.409364)
			(xy 70.986378 -42.430678) (xy 71.018941 -42.478044) (xy 71.04403 -42.529759) (xy 71.061077 -42.584652)
			(xy 71.069697 -42.641482) (xy 71.070216 -42.670222) (xy 71.069783 -42.697594) (xy 71.061961 -42.751775)
			(xy 71.046465 -42.804279) (xy 71.025906 -42.849038) (xy 72.891902 -42.849038) (xy 72.895973 -42.793416)
			(xy 72.908099 -42.738979) (xy 72.928022 -42.686888) (xy 72.955318 -42.638253) (xy 72.989404 -42.59411)
			(xy 73.029553 -42.555401) (xy 73.074911 -42.52295) (xy 73.124511 -42.497449) (xy 73.177295 -42.479442)
			(xy 73.232138 -42.469312) (xy 73.287872 -42.467275) (xy 73.343309 -42.473375) (xy 73.397266 -42.487481)
			(xy 73.448595 -42.509293) (xy 73.496201 -42.538347) (xy 73.539069 -42.574022) (xy 73.576286 -42.615559)
			(xy 73.607059 -42.662072) (xy 73.630731 -42.712569) (xy 73.646799 -42.765976) (xy 73.654919 -42.821152)
			(xy 73.65528 -42.84091) (xy 78.933038 -42.84091) (xy 78.937109 -42.785288) (xy 78.949235 -42.730851)
			(xy 78.969158 -42.67876) (xy 78.996454 -42.630125) (xy 79.03054 -42.585982) (xy 79.070689 -42.547273)
			(xy 79.116047 -42.514822) (xy 79.165647 -42.489321) (xy 79.218431 -42.471314) (xy 79.273274 -42.461184)
			(xy 79.329008 -42.459147) (xy 79.384445 -42.465247) (xy 79.438402 -42.479353) (xy 79.489731 -42.501165)
			(xy 79.537337 -42.530219) (xy 79.580205 -42.565894) (xy 79.617422 -42.607431) (xy 79.648195 -42.653944)
			(xy 79.671867 -42.704441) (xy 79.687935 -42.757848) (xy 79.696055 -42.813024) (xy 79.696564 -42.84091)
			(xy 79.696055 -42.868796) (xy 79.687935 -42.923972) (xy 79.671867 -42.977379) (xy 79.648195 -43.027876)
			(xy 79.617422 -43.074389) (xy 79.580205 -43.115926) (xy 79.537337 -43.151601) (xy 79.489731 -43.180655)
			(xy 79.438402 -43.202467) (xy 79.384445 -43.216573) (xy 79.329008 -43.222673) (xy 79.273274 -43.220636)
			(xy 79.218431 -43.210506) (xy 79.165647 -43.192499) (xy 79.116047 -43.166998) (xy 79.070689 -43.134547)
			(xy 79.03054 -43.095838) (xy 78.996454 -43.051695) (xy 78.969158 -43.00306) (xy 78.949235 -42.950969)
			(xy 78.937109 -42.896532) (xy 78.933038 -42.84091) (xy 73.65528 -42.84091) (xy 73.655428 -42.849038)
			(xy 73.654919 -42.876924) (xy 73.646799 -42.9321) (xy 73.630731 -42.985507) (xy 73.607059 -43.036004)
			(xy 73.576286 -43.082517) (xy 73.539069 -43.124054) (xy 73.496201 -43.159729) (xy 73.448595 -43.188783)
			(xy 73.397266 -43.210595) (xy 73.343309 -43.224701) (xy 73.287872 -43.230801) (xy 73.232138 -43.228764)
			(xy 73.177295 -43.218634) (xy 73.124511 -43.200627) (xy 73.074911 -43.175126) (xy 73.029553 -43.142675)
			(xy 72.989404 -43.103966) (xy 72.955318 -43.059823) (xy 72.928022 -43.011188) (xy 72.908099 -42.959097)
			(xy 72.895973 -42.90466) (xy 72.891902 -42.849038) (xy 71.025906 -42.849038) (xy 71.023615 -42.854026)
			(xy 70.993882 -42.89999) (xy 70.976236 -42.92092) (xy 70.975982 -42.921174) (xy 70.970398 -42.928262)
			(xy 70.96415 -42.945178) (xy 70.96379 -42.954194) (xy 70.96379 -43.02125) (xy 70.964173 -43.030264)
			(xy 70.970403 -43.047181) (xy 70.975982 -43.05427) (xy 70.976236 -43.05427) (xy 70.976236 -43.054524)
			(xy 70.993859 -43.075469) (xy 71.023572 -43.121439) (xy 71.04641 -43.171183) (xy 71.061905 -43.223681)
			(xy 71.069739 -43.277854) (xy 71.070216 -43.305222) (xy 71.06973 -43.332473) (xy 71.061974 -43.386421)
			(xy 71.046619 -43.438716) (xy 71.023977 -43.488293) (xy 70.994511 -43.534143) (xy 70.95882 -43.575334)
			(xy 70.917629 -43.611025) (xy 70.871779 -43.640491) (xy 70.822202 -43.663133) (xy 70.769907 -43.678488)
			(xy 70.715959 -43.686244) (xy 70.661457 -43.686244) (xy 70.607509 -43.678488) (xy 70.555214 -43.663133)
			(xy 70.505637 -43.640491) (xy 70.459787 -43.611025) (xy 70.418596 -43.575334) (xy 70.382905 -43.534143)
			(xy 70.353439 -43.488293) (xy 70.330797 -43.438716) (xy 70.315442 -43.386421) (xy 70.307686 -43.332473)
			(xy 70.3072 -43.305222) (xy 64.101472 -43.305222) (xy 64.53251 -43.73626) (xy 72.21296 -43.73626)
			(xy 72.217031 -43.680638) (xy 72.229157 -43.626201) (xy 72.24908 -43.57411) (xy 72.276376 -43.525475)
			(xy 72.310462 -43.481332) (xy 72.350611 -43.442623) (xy 72.395969 -43.410172) (xy 72.445569 -43.384671)
			(xy 72.498353 -43.366664) (xy 72.553196 -43.356534) (xy 72.60893 -43.354497) (xy 72.664367 -43.360597)
			(xy 72.718324 -43.374703) (xy 72.769653 -43.396515) (xy 72.817259 -43.425569) (xy 72.860127 -43.461244)
			(xy 72.897344 -43.502781) (xy 72.928117 -43.549294) (xy 72.951789 -43.599791) (xy 72.967857 -43.653198)
			(xy 72.975977 -43.708374) (xy 72.976486 -43.73626) (xy 72.975977 -43.764146) (xy 72.967857 -43.819322)
			(xy 72.956548 -43.85691) (xy 76.719682 -43.85691) (xy 76.723753 -43.801288) (xy 76.735879 -43.746851)
			(xy 76.755802 -43.69476) (xy 76.783098 -43.646125) (xy 76.817184 -43.601982) (xy 76.857333 -43.563273)
			(xy 76.902691 -43.530822) (xy 76.952291 -43.505321) (xy 77.005075 -43.487314) (xy 77.059918 -43.477184)
			(xy 77.115652 -43.475147) (xy 77.171089 -43.481247) (xy 77.225046 -43.495353) (xy 77.276375 -43.517165)
			(xy 77.323981 -43.546219) (xy 77.366849 -43.581894) (xy 77.404066 -43.623431) (xy 77.434839 -43.669944)
			(xy 77.458511 -43.720441) (xy 77.474579 -43.773848) (xy 77.482699 -43.829024) (xy 77.483208 -43.85691)
			(xy 77.482699 -43.884796) (xy 77.474579 -43.939972) (xy 77.458511 -43.993379) (xy 77.434839 -44.043876)
			(xy 77.404066 -44.090389) (xy 77.366849 -44.131926) (xy 77.323981 -44.167601) (xy 77.276375 -44.196655)
			(xy 77.225046 -44.218467) (xy 77.171089 -44.232573) (xy 77.115652 -44.238673) (xy 77.059918 -44.236636)
			(xy 77.005075 -44.226506) (xy 76.952291 -44.208499) (xy 76.902691 -44.182998) (xy 76.857333 -44.150547)
			(xy 76.817184 -44.111838) (xy 76.783098 -44.067695) (xy 76.755802 -44.01906) (xy 76.735879 -43.966969)
			(xy 76.723753 -43.912532) (xy 76.719682 -43.85691) (xy 72.956548 -43.85691) (xy 72.951789 -43.872729)
			(xy 72.928117 -43.923226) (xy 72.897344 -43.969739) (xy 72.860127 -44.011276) (xy 72.817259 -44.046951)
			(xy 72.769653 -44.076005) (xy 72.718324 -44.097817) (xy 72.664367 -44.111923) (xy 72.60893 -44.118023)
			(xy 72.553196 -44.115986) (xy 72.498353 -44.105856) (xy 72.445569 -44.087849) (xy 72.395969 -44.062348)
			(xy 72.350611 -44.029897) (xy 72.310462 -43.991188) (xy 72.276376 -43.947045) (xy 72.24908 -43.89841)
			(xy 72.229157 -43.846319) (xy 72.217031 -43.791882) (xy 72.21296 -43.73626) (xy 64.53251 -43.73626)
			(xy 65.275714 -44.479464) (xy 65.27673 -44.480226) (xy 65.296901 -44.50039) (xy 65.330502 -44.54647)
			(xy 65.355465 -44.597745) (xy 65.363852 -44.625006) (xy 65.36436 -44.6278) (xy 65.365122 -44.630594)
			(xy 65.370133 -44.650672) (xy 65.375609 -44.691692) (xy 65.376044 -44.712382) (xy 65.376044 -45.114464)
			(xy 72.065386 -45.114464) (xy 72.069457 -45.058842) (xy 72.081583 -45.004405) (xy 72.101506 -44.952314)
			(xy 72.128802 -44.903679) (xy 72.162888 -44.859536) (xy 72.203037 -44.820827) (xy 72.248395 -44.788376)
			(xy 72.297995 -44.762875) (xy 72.350779 -44.744868) (xy 72.405622 -44.734738) (xy 72.461356 -44.732701)
			(xy 72.516793 -44.738801) (xy 72.57075 -44.752907) (xy 72.622079 -44.774719) (xy 72.669685 -44.803773)
			(xy 72.712553 -44.839448) (xy 72.742535 -44.87291) (xy 78.933038 -44.87291) (xy 78.937109 -44.817288)
			(xy 78.949235 -44.762851) (xy 78.969158 -44.71076) (xy 78.996454 -44.662125) (xy 79.03054 -44.617982)
			(xy 79.070689 -44.579273) (xy 79.116047 -44.546822) (xy 79.165647 -44.521321) (xy 79.218431 -44.503314)
			(xy 79.273274 -44.493184) (xy 79.329008 -44.491147) (xy 79.384445 -44.497247) (xy 79.438402 -44.511353)
			(xy 79.489731 -44.533165) (xy 79.537337 -44.562219) (xy 79.580205 -44.597894) (xy 79.617422 -44.639431)
			(xy 79.648195 -44.685944) (xy 79.671867 -44.736441) (xy 79.687935 -44.789848) (xy 79.696055 -44.845024)
			(xy 79.696564 -44.87291) (xy 79.696055 -44.900796) (xy 79.687935 -44.955972) (xy 79.671867 -45.009379)
			(xy 79.648195 -45.059876) (xy 79.617422 -45.106389) (xy 79.580205 -45.147926) (xy 79.537337 -45.183601)
			(xy 79.489731 -45.212655) (xy 79.438402 -45.234467) (xy 79.384445 -45.248573) (xy 79.329008 -45.254673)
			(xy 79.273274 -45.252636) (xy 79.218431 -45.242506) (xy 79.165647 -45.224499) (xy 79.116047 -45.198998)
			(xy 79.070689 -45.166547) (xy 79.03054 -45.127838) (xy 78.996454 -45.083695) (xy 78.969158 -45.03506)
			(xy 78.949235 -44.982969) (xy 78.937109 -44.928532) (xy 78.933038 -44.87291) (xy 72.742535 -44.87291)
			(xy 72.74977 -44.880985) (xy 72.780543 -44.927498) (xy 72.804215 -44.977995) (xy 72.820283 -45.031402)
			(xy 72.828403 -45.086578) (xy 72.828912 -45.114464) (xy 72.828403 -45.14235) (xy 72.820283 -45.197526)
			(xy 72.804215 -45.250933) (xy 72.780543 -45.30143) (xy 72.74977 -45.347943) (xy 72.744128 -45.35424)
			(xy 76.70368 -45.35424) (xy 76.707751 -45.298618) (xy 76.719877 -45.244181) (xy 76.7398 -45.19209)
			(xy 76.767096 -45.143455) (xy 76.801182 -45.099312) (xy 76.841331 -45.060603) (xy 76.886689 -45.028152)
			(xy 76.936289 -45.002651) (xy 76.989073 -44.984644) (xy 77.043916 -44.974514) (xy 77.09965 -44.972477)
			(xy 77.155087 -44.978577) (xy 77.209044 -44.992683) (xy 77.260373 -45.014495) (xy 77.307979 -45.043549)
			(xy 77.350847 -45.079224) (xy 77.388064 -45.120761) (xy 77.418837 -45.167274) (xy 77.442509 -45.217771)
			(xy 77.458577 -45.271178) (xy 77.466697 -45.326354) (xy 77.467206 -45.35424) (xy 77.466697 -45.382126)
			(xy 77.458577 -45.437302) (xy 77.442509 -45.490709) (xy 77.418837 -45.541206) (xy 77.388064 -45.587719)
			(xy 77.350847 -45.629256) (xy 77.307979 -45.664931) (xy 77.260373 -45.693985) (xy 77.209044 -45.715797)
			(xy 77.155087 -45.729903) (xy 77.09965 -45.736003) (xy 77.043916 -45.733966) (xy 76.989073 -45.723836)
			(xy 76.936289 -45.705829) (xy 76.886689 -45.680328) (xy 76.841331 -45.647877) (xy 76.801182 -45.609168)
			(xy 76.767096 -45.565025) (xy 76.7398 -45.51639) (xy 76.719877 -45.464299) (xy 76.707751 -45.409862)
			(xy 76.70368 -45.35424) (xy 72.744128 -45.35424) (xy 72.712553 -45.38948) (xy 72.669685 -45.425155)
			(xy 72.622079 -45.454209) (xy 72.57075 -45.476021) (xy 72.516793 -45.490127) (xy 72.461356 -45.496227)
			(xy 72.405622 -45.49419) (xy 72.350779 -45.48406) (xy 72.297995 -45.466053) (xy 72.248395 -45.440552)
			(xy 72.203037 -45.408101) (xy 72.162888 -45.369392) (xy 72.128802 -45.325249) (xy 72.101506 -45.276614)
			(xy 72.081583 -45.224523) (xy 72.069457 -45.170086) (xy 72.065386 -45.114464) (xy 65.376044 -45.114464)
			(xy 65.376044 -46.082204) (xy 70.052438 -46.082204) (xy 70.052859 -46.054949) (xy 70.060617 -46.000994)
			(xy 70.075975 -45.948693) (xy 70.09862 -45.89911) (xy 70.128092 -45.853254) (xy 70.16379 -45.81206)
			(xy 70.204988 -45.776367) (xy 70.250847 -45.7469) (xy 70.300432 -45.72426) (xy 70.352735 -45.708908)
			(xy 70.406691 -45.701156) (xy 70.433946 -45.700696) (xy 70.46085 -45.701123) (xy 70.514121 -45.708701)
			(xy 70.5658 -45.723687) (xy 70.614862 -45.745783) (xy 70.660334 -45.77455) (xy 70.701315 -45.80942)
			(xy 70.736991 -45.8497) (xy 70.752208 -45.871892) (xy 70.75932 -45.882814) (xy 70.78218 -45.894752)
			(xy 70.894448 -45.89272) (xy 70.9168 -45.879766) (xy 70.923658 -45.86859) (xy 70.938554 -45.844971)
			(xy 70.974237 -45.80202) (xy 71.0158 -45.764728) (xy 71.062354 -45.733892) (xy 71.112906 -45.710172)
			(xy 71.166375 -45.694073) (xy 71.22162 -45.68594) (xy 71.24954 -45.685456) (xy 71.276534 -45.685894)
			(xy 71.329983 -45.693506) (xy 71.381827 -45.708571) (xy 71.431031 -45.73079) (xy 71.476614 -45.75972)
			(xy 71.497444 -45.776896) (xy 71.505572 -45.784008) (xy 71.526146 -45.790104) (xy 71.61149 -45.779182)
			(xy 71.622036 -45.777413) (xy 71.640318 -45.766355) (xy 71.646796 -45.757846) (xy 71.662158 -45.736622)
			(xy 71.697744 -45.698169) (xy 71.738259 -45.66495) (xy 71.782941 -45.637591) (xy 71.830948 -45.616606)
			(xy 71.881375 -45.602391) (xy 71.933274 -45.595214) (xy 71.95947 -45.594778) (xy 71.986723 -45.595267)
			(xy 72.040675 -45.60302) (xy 72.092975 -45.618373) (xy 72.142557 -45.641013) (xy 72.188412 -45.670479)
			(xy 72.229607 -45.706172) (xy 72.265303 -45.747364) (xy 72.294772 -45.793217) (xy 72.317416 -45.842797)
			(xy 72.332773 -45.895095) (xy 72.340531 -45.949047) (xy 72.340531 -46.003553) (xy 72.332773 -46.057505)
			(xy 72.317416 -46.109803) (xy 72.294772 -46.159383) (xy 72.265303 -46.205236) (xy 72.229607 -46.246428)
			(xy 72.188412 -46.282121) (xy 72.142557 -46.311587) (xy 72.092975 -46.334227) (xy 72.040675 -46.34958)
			(xy 71.986723 -46.357333) (xy 71.95947 -46.357794) (xy 71.932477 -46.357338) (xy 71.879029 -46.349729)
			(xy 71.827186 -46.334667) (xy 71.777981 -46.312452) (xy 71.732397 -46.283528) (xy 71.711566 -46.266354)
			(xy 71.703438 -46.259242) (xy 71.682864 -46.253146) (xy 71.59752 -46.264068) (xy 71.58698 -46.26586)
			(xy 71.568696 -46.276903) (xy 71.562214 -46.285404) (xy 71.544596 -46.3097) (xy 71.503004 -46.352962)
			(xy 71.47941 -46.37151) (xy 71.471536 -46.377352) (xy 71.461122 -46.394878) (xy 71.447914 -46.485302)
			(xy 71.45274 -46.504606) (xy 71.458582 -46.51248) (xy 71.458582 -46.512734) (xy 71.476086 -46.537478)
			(xy 71.503888 -46.591331) (xy 71.522824 -46.648903) (xy 71.530027 -46.693836) (xy 76.67625 -46.693836)
			(xy 76.676736 -46.666585) (xy 76.684492 -46.612637) (xy 76.699847 -46.560342) (xy 76.722489 -46.510765)
			(xy 76.751955 -46.464915) (xy 76.787646 -46.423724) (xy 76.828837 -46.388033) (xy 76.874687 -46.358567)
			(xy 76.924264 -46.335925) (xy 76.976559 -46.32057) (xy 77.030507 -46.312814) (xy 77.085009 -46.312814)
			(xy 77.138957 -46.32057) (xy 77.191252 -46.335925) (xy 77.240829 -46.358567) (xy 77.286679 -46.388033)
			(xy 77.32787 -46.423724) (xy 77.363561 -46.464915) (xy 77.393027 -46.510765) (xy 77.415669 -46.560342)
			(xy 77.431024 -46.612637) (xy 77.43878 -46.666585) (xy 77.439266 -46.693836) (xy 77.438798 -46.720264)
			(xy 77.431488 -46.772611) (xy 77.417013 -46.823446) (xy 77.395652 -46.871793) (xy 77.382116 -46.894496)
			(xy 77.381862 -46.89475) (xy 77.376525 -46.904768) (xy 77.374267 -46.927318) (xy 77.377544 -46.938184)
			(xy 77.403706 -47.01286) (xy 77.408066 -47.023388) (xy 77.424171 -47.039472) (xy 77.434694 -47.043848)
			(xy 77.434948 -47.043848) (xy 77.459457 -47.052916) (xy 77.50591 -47.076859) (xy 77.548661 -47.106915)
			(xy 77.586913 -47.142523) (xy 77.61995 -47.183016) (xy 77.647153 -47.227637) (xy 77.668015 -47.275552)
			(xy 77.682145 -47.325866) (xy 77.689279 -47.377636) (xy 77.68971 -47.403766) (xy 77.689224 -47.431017)
			(xy 77.687701 -47.441612) (xy 78.96174 -47.441612) (xy 78.965811 -47.38599) (xy 78.977937 -47.331553)
			(xy 78.99786 -47.279462) (xy 79.025156 -47.230827) (xy 79.059242 -47.186684) (xy 79.099391 -47.147975)
			(xy 79.144749 -47.115524) (xy 79.194349 -47.090023) (xy 79.247133 -47.072016) (xy 79.301976 -47.061886)
			(xy 79.35771 -47.059849) (xy 79.413147 -47.065949) (xy 79.467104 -47.080055) (xy 79.518433 -47.101867)
			(xy 79.566039 -47.130921) (xy 79.608907 -47.166596) (xy 79.646124 -47.208133) (xy 79.676897 -47.254646)
			(xy 79.700569 -47.305143) (xy 79.716637 -47.35855) (xy 79.724757 -47.413726) (xy 79.725266 -47.441612)
			(xy 79.724757 -47.469498) (xy 79.716637 -47.524674) (xy 79.700569 -47.578081) (xy 79.676897 -47.628578)
			(xy 79.646124 -47.675091) (xy 79.608907 -47.716628) (xy 79.566039 -47.752303) (xy 79.518433 -47.781357)
			(xy 79.467104 -47.803169) (xy 79.413147 -47.817275) (xy 79.35771 -47.823375) (xy 79.301976 -47.821338)
			(xy 79.247133 -47.811208) (xy 79.194349 -47.793201) (xy 79.144749 -47.7677) (xy 79.099391 -47.735249)
			(xy 79.059242 -47.69654) (xy 79.025156 -47.652397) (xy 78.99786 -47.603762) (xy 78.977937 -47.551671)
			(xy 78.965811 -47.497234) (xy 78.96174 -47.441612) (xy 77.687701 -47.441612) (xy 77.681468 -47.484965)
			(xy 77.666113 -47.53726) (xy 77.643471 -47.586837) (xy 77.614005 -47.632687) (xy 77.578314 -47.673878)
			(xy 77.537123 -47.709569) (xy 77.491273 -47.739035) (xy 77.441696 -47.761677) (xy 77.389401 -47.777032)
			(xy 77.335453 -47.784788) (xy 77.280951 -47.784788) (xy 77.227003 -47.777032) (xy 77.174708 -47.761677)
			(xy 77.125131 -47.739035) (xy 77.079281 -47.709569) (xy 77.03809 -47.673878) (xy 77.002399 -47.632687)
			(xy 76.972933 -47.586837) (xy 76.950291 -47.53726) (xy 76.934936 -47.484965) (xy 76.92718 -47.431017)
			(xy 76.926694 -47.403766) (xy 76.927168 -47.377339) (xy 76.934477 -47.324991) (xy 76.94895 -47.274156)
			(xy 76.970309 -47.225809) (xy 76.983844 -47.203106) (xy 76.984098 -47.202852) (xy 76.989433 -47.192833)
			(xy 76.991694 -47.170283) (xy 76.988416 -47.159418) (xy 76.962254 -47.084742) (xy 76.957866 -47.074228)
			(xy 76.94178 -47.058139) (xy 76.931266 -47.053754) (xy 76.931012 -47.053754) (xy 76.906495 -47.044706)
			(xy 76.860044 -47.020759) (xy 76.817293 -46.990699) (xy 76.779042 -46.955089) (xy 76.746007 -46.914593)
			(xy 76.718805 -46.86997) (xy 76.697944 -46.822053) (xy 76.683815 -46.771738) (xy 76.676681 -46.719966)
			(xy 76.67625 -46.693836) (xy 71.530027 -46.693836) (xy 71.532417 -46.708745) (xy 71.533004 -46.739048)
			(xy 71.532567 -46.766301) (xy 71.524804 -46.82025) (xy 71.509442 -46.872546) (xy 71.486795 -46.922124)
			(xy 71.457324 -46.967974) (xy 71.421627 -47.009164) (xy 71.380433 -47.044855) (xy 71.334578 -47.07432)
			(xy 71.284997 -47.09696) (xy 71.232699 -47.112315) (xy 71.178749 -47.120071) (xy 71.151496 -47.120556)
			(xy 71.125463 -47.120104) (xy 71.07388 -47.113017) (xy 71.023739 -47.098988) (xy 70.975968 -47.078278)
			(xy 70.931453 -47.051271) (xy 70.910958 -47.035212) (xy 70.903191 -47.029486) (xy 70.884788 -47.023736)
			(xy 70.875144 -47.024036) (xy 70.795388 -47.030386) (xy 70.777608 -47.039022) (xy 70.771258 -47.046388)
			(xy 70.753071 -47.066028) (xy 70.712165 -47.10055) (xy 70.666837 -47.12902) (xy 70.617977 -47.150879)
			(xy 70.566542 -47.165698) (xy 70.513541 -47.173186) (xy 70.486778 -47.173642) (xy 70.459528 -47.173143)
			(xy 70.405582 -47.165384) (xy 70.35329 -47.150028) (xy 70.303715 -47.127387) (xy 70.257866 -47.097921)
			(xy 70.216677 -47.062231) (xy 70.180986 -47.021043) (xy 70.151519 -46.975196) (xy 70.128876 -46.925621)
			(xy 70.113518 -46.873329) (xy 70.105758 -46.819384) (xy 70.10527 -46.792134) (xy 70.105803 -46.76336)
			(xy 70.114453 -46.706467) (xy 70.131548 -46.651517) (xy 70.156699 -46.599757) (xy 70.189337 -46.55236)
			(xy 70.208648 -46.531022) (xy 70.216014 -46.523148) (xy 70.223126 -46.503336) (xy 70.21576 -46.40707)
			(xy 70.205854 -46.388274) (xy 70.197472 -46.38167) (xy 70.175277 -46.363457) (xy 70.13607 -46.321518)
			(xy 70.103587 -46.274179) (xy 70.078561 -46.222509) (xy 70.061556 -46.167674) (xy 70.052956 -46.11091)
			(xy 70.052438 -46.082204) (xy 65.376044 -46.082204) (xy 65.376044 -48.753014) (xy 73.168254 -48.753014)
			(xy 73.172325 -48.697392) (xy 73.184451 -48.642955) (xy 73.204374 -48.590864) (xy 73.23167 -48.542229)
			(xy 73.265756 -48.498086) (xy 73.305905 -48.459377) (xy 73.351263 -48.426926) (xy 73.400863 -48.401425)
			(xy 73.453647 -48.383418) (xy 73.50849 -48.373288) (xy 73.564224 -48.371251) (xy 73.619661 -48.377351)
			(xy 73.673618 -48.391457) (xy 73.724947 -48.413269) (xy 73.772553 -48.442323) (xy 73.815421 -48.477998)
			(xy 73.852638 -48.519535) (xy 73.883411 -48.566048) (xy 73.907083 -48.616545) (xy 73.923151 -48.669952)
			(xy 73.931271 -48.725128) (xy 73.93178 -48.753014) (xy 73.931271 -48.7809) (xy 73.923151 -48.836076)
			(xy 73.907083 -48.889483) (xy 73.892893 -48.919754) (xy 75.214938 -48.919754) (xy 75.214938 -48.865246)
			(xy 75.222695 -48.811294) (xy 75.238051 -48.758995) (xy 75.260694 -48.709413) (xy 75.290162 -48.663559)
			(xy 75.325856 -48.622364) (xy 75.367049 -48.586669) (xy 75.412903 -48.557199) (xy 75.462484 -48.534555)
			(xy 75.514782 -48.519197) (xy 75.568734 -48.511439) (xy 75.595988 -48.510952) (xy 75.622735 -48.511351)
			(xy 75.675703 -48.518842) (xy 75.727107 -48.533652) (xy 75.775942 -48.55549) (xy 75.821251 -48.58393)
			(xy 75.862148 -48.618414) (xy 75.897832 -48.658268) (xy 75.927606 -48.702711) (xy 75.93965 -48.726598)
			(xy 75.943618 -48.734179) (xy 75.955675 -48.746307) (xy 75.971069 -48.753753) (xy 75.979528 -48.755046)
			(xy 76.077826 -48.766222) (xy 76.101956 -48.75657) (xy 76.110084 -48.74641) (xy 76.128305 -48.724697)
			(xy 76.170056 -48.686361) (xy 76.21702 -48.654627) (xy 76.268163 -48.630191) (xy 76.32236 -48.613594)
			(xy 76.378416 -48.605199) (xy 76.406756 -48.604678) (xy 76.407518 -48.604678) (xy 76.425537 -48.604901)
			(xy 76.461412 -48.608334) (xy 76.479146 -48.611536) (xy 76.49337 -48.61433) (xy 76.519786 -48.604424)
			(xy 76.593192 -48.51019) (xy 76.596494 -48.481742) (xy 76.590398 -48.468788) (xy 76.579001 -48.443355)
			(xy 76.562925 -48.389993) (xy 76.554809 -48.334856) (xy 76.55433 -48.30699) (xy 76.554789 -48.27974)
			(xy 76.562546 -48.225796) (xy 76.577901 -48.173504) (xy 76.600542 -48.12393) (xy 76.630007 -48.078082)
			(xy 76.665697 -48.036894) (xy 76.706885 -48.001205) (xy 76.752733 -47.97174) (xy 76.802308 -47.9491)
			(xy 76.8546 -47.933745) (xy 76.908544 -47.925989) (xy 76.963044 -47.925988) (xy 77.016989 -47.933743)
			(xy 77.069281 -47.949096) (xy 77.118856 -47.971734) (xy 77.164705 -48.001198) (xy 77.205894 -48.036886)
			(xy 77.241585 -48.078073) (xy 77.271052 -48.123919) (xy 77.293694 -48.173493) (xy 77.309051 -48.225784)
			(xy 77.31681 -48.279728) (xy 77.316813 -48.334228) (xy 77.309061 -48.388173) (xy 77.29371 -48.440466)
			(xy 77.271073 -48.490042) (xy 77.241612 -48.535892) (xy 77.205925 -48.577083) (xy 77.16474 -48.612776)
			(xy 77.118895 -48.642244) (xy 77.069322 -48.664889) (xy 77.017032 -48.680248) (xy 76.963088 -48.688009)
			(xy 76.935838 -48.688498) (xy 76.935076 -48.688498) (xy 76.917057 -48.688277) (xy 76.881182 -48.684843)
			(xy 76.863448 -48.68164) (xy 76.849224 -48.678846) (xy 76.822808 -48.688752) (xy 76.749402 -48.782986)
			(xy 76.7461 -48.811434) (xy 76.752196 -48.824388) (xy 76.763585 -48.849824) (xy 76.779663 -48.903185)
			(xy 76.78463 -48.93691) (xy 78.933038 -48.93691) (xy 78.937109 -48.881288) (xy 78.949235 -48.826851)
			(xy 78.969158 -48.77476) (xy 78.996454 -48.726125) (xy 79.03054 -48.681982) (xy 79.070689 -48.643273)
			(xy 79.116047 -48.610822) (xy 79.165647 -48.585321) (xy 79.218431 -48.567314) (xy 79.273274 -48.557184)
			(xy 79.329008 -48.555147) (xy 79.384445 -48.561247) (xy 79.438402 -48.575353) (xy 79.489731 -48.597165)
			(xy 79.537337 -48.626219) (xy 79.580205 -48.661894) (xy 79.617422 -48.703431) (xy 79.648195 -48.749944)
			(xy 79.671867 -48.800441) (xy 79.687935 -48.853848) (xy 79.696055 -48.909024) (xy 79.696564 -48.93691)
			(xy 79.696055 -48.964796) (xy 79.687935 -49.019972) (xy 79.671867 -49.073379) (xy 79.648195 -49.123876)
			(xy 79.617422 -49.170389) (xy 79.580205 -49.211926) (xy 79.537337 -49.247601) (xy 79.489731 -49.276655)
			(xy 79.438402 -49.298467) (xy 79.384445 -49.312573) (xy 79.329008 -49.318673) (xy 79.273274 -49.316636)
			(xy 79.218431 -49.306506) (xy 79.165647 -49.288499) (xy 79.116047 -49.262998) (xy 79.070689 -49.230547)
			(xy 79.03054 -49.191838) (xy 78.996454 -49.147695) (xy 78.969158 -49.09906) (xy 78.949235 -49.046969)
			(xy 78.937109 -48.992532) (xy 78.933038 -48.93691) (xy 76.78463 -48.93691) (xy 76.787783 -48.958321)
			(xy 76.788264 -48.986186) (xy 76.787832 -49.013441) (xy 76.780075 -49.067395) (xy 76.764719 -49.119696)
			(xy 76.742075 -49.169279) (xy 76.712604 -49.215134) (xy 76.676907 -49.256328) (xy 76.63571 -49.292022)
			(xy 76.589853 -49.321489) (xy 76.540268 -49.344129) (xy 76.487965 -49.359482) (xy 76.434011 -49.367234)
			(xy 76.406756 -49.367694) (xy 76.380011 -49.367232) (xy 76.327047 -49.359748) (xy 76.275646 -49.344946)
			(xy 76.226813 -49.323116) (xy 76.181504 -49.294686) (xy 76.140606 -49.26021) (xy 76.104919 -49.220365)
			(xy 76.075141 -49.17593) (xy 76.063094 -49.152048) (xy 76.059082 -49.144493) (xy 76.047046 -49.132359)
			(xy 76.031668 -49.124901) (xy 76.023216 -49.1236) (xy 75.924918 -49.112424) (xy 75.900788 -49.122076)
			(xy 75.89266 -49.132236) (xy 75.874426 -49.153937) (xy 75.832677 -49.192272) (xy 75.785715 -49.224007)
			(xy 75.734574 -49.248443) (xy 75.680381 -49.265044) (xy 75.624327 -49.273444) (xy 75.595988 -49.273968)
			(xy 75.568734 -49.273561) (xy 75.514782 -49.265803) (xy 75.462484 -49.250445) (xy 75.412903 -49.227801)
			(xy 75.367049 -49.198331) (xy 75.325856 -49.162636) (xy 75.290162 -49.121441) (xy 75.260694 -49.075587)
			(xy 75.238051 -49.026005) (xy 75.222695 -48.973706) (xy 75.214938 -48.919754) (xy 73.892893 -48.919754)
			(xy 73.883411 -48.93998) (xy 73.852638 -48.986493) (xy 73.815421 -49.02803) (xy 73.772553 -49.063705)
			(xy 73.724947 -49.092759) (xy 73.673618 -49.114571) (xy 73.619661 -49.128677) (xy 73.564224 -49.134777)
			(xy 73.50849 -49.13274) (xy 73.453647 -49.12261) (xy 73.400863 -49.104603) (xy 73.351263 -49.079102)
			(xy 73.305905 -49.046651) (xy 73.265756 -49.007942) (xy 73.23167 -48.963799) (xy 73.204374 -48.915164)
			(xy 73.184451 -48.863073) (xy 73.172325 -48.808636) (xy 73.168254 -48.753014) (xy 65.376044 -48.753014)
			(xy 65.376044 -49.95291) (xy 78.933038 -49.95291) (xy 78.937109 -49.897288) (xy 78.949235 -49.842851)
			(xy 78.969158 -49.79076) (xy 78.996454 -49.742125) (xy 79.03054 -49.697982) (xy 79.070689 -49.659273)
			(xy 79.116047 -49.626822) (xy 79.165647 -49.601321) (xy 79.218431 -49.583314) (xy 79.273274 -49.573184)
			(xy 79.329008 -49.571147) (xy 79.384445 -49.577247) (xy 79.438402 -49.591353) (xy 79.463337 -49.601949)
			(xy 84.112882 -49.601949) (xy 84.112882 -49.547451) (xy 84.120637 -49.493507) (xy 84.13599 -49.441216)
			(xy 84.158628 -49.391642) (xy 84.188091 -49.345793) (xy 84.223778 -49.304605) (xy 84.264963 -49.268914)
			(xy 84.310808 -49.239447) (xy 84.36038 -49.216803) (xy 84.41267 -49.201445) (xy 84.466613 -49.193684)
			(xy 84.493862 -49.193196) (xy 84.521231 -49.193685) (xy 84.575409 -49.201498) (xy 84.627912 -49.216981)
			(xy 84.677659 -49.239818) (xy 84.723627 -49.269537) (xy 84.74456 -49.287176) (xy 84.744814 -49.28743)
			(xy 84.75189 -49.293032) (xy 84.768815 -49.299268) (xy 84.777834 -49.299622) (xy 84.84489 -49.299622)
			(xy 84.853906 -49.299255) (xy 84.870823 -49.293014) (xy 84.87791 -49.28743) (xy 84.87791 -49.287176)
			(xy 84.878164 -49.287176) (xy 84.899097 -49.269535) (xy 84.945065 -49.239811) (xy 84.994811 -49.216965)
			(xy 85.047313 -49.201469) (xy 85.101491 -49.19364) (xy 85.156233 -49.19364) (xy 85.210411 -49.201469)
			(xy 85.262913 -49.216965) (xy 85.312659 -49.239811) (xy 85.358627 -49.269535) (xy 85.37956 -49.287176)
			(xy 85.379814 -49.28743) (xy 85.38689 -49.293032) (xy 85.403815 -49.299268) (xy 85.412834 -49.299622)
			(xy 85.47989 -49.299622) (xy 85.488906 -49.299255) (xy 85.505823 -49.293014) (xy 85.51291 -49.28743)
			(xy 85.51291 -49.287176) (xy 85.513164 -49.287176) (xy 85.534097 -49.269535) (xy 85.580065 -49.239811)
			(xy 85.629811 -49.216965) (xy 85.682313 -49.201469) (xy 85.736491 -49.19364) (xy 85.791233 -49.19364)
			(xy 85.845411 -49.201469) (xy 85.897913 -49.216965) (xy 85.947659 -49.239811) (xy 85.993627 -49.269535)
			(xy 86.01456 -49.287176) (xy 86.014814 -49.28743) (xy 86.02189 -49.293032) (xy 86.038815 -49.299268)
			(xy 86.047834 -49.299622) (xy 86.11489 -49.299622) (xy 86.123906 -49.299255) (xy 86.140823 -49.293014)
			(xy 86.14791 -49.28743) (xy 86.14791 -49.287176) (xy 86.148164 -49.287176) (xy 86.169096 -49.269537)
			(xy 86.215069 -49.239826) (xy 86.264817 -49.21699) (xy 86.317317 -49.201499) (xy 86.371493 -49.19367)
			(xy 86.398862 -49.193196) (xy 86.426117 -49.193649) (xy 86.480073 -49.201401) (xy 86.532375 -49.216754)
			(xy 86.581961 -49.239395) (xy 86.627819 -49.268862) (xy 86.669017 -49.304556) (xy 86.704715 -49.34575)
			(xy 86.734187 -49.391606) (xy 86.756832 -49.441189) (xy 86.77219 -49.49349) (xy 86.779949 -49.547445)
			(xy 86.779949 -49.601955) (xy 86.77219 -49.65591) (xy 86.756832 -49.708211) (xy 86.734187 -49.757794)
			(xy 86.704715 -49.80365) (xy 86.669017 -49.844844) (xy 86.627819 -49.880538) (xy 86.581961 -49.910005)
			(xy 86.532375 -49.932646) (xy 86.480073 -49.947999) (xy 86.426117 -49.955751) (xy 86.398862 -49.956212)
			(xy 86.371493 -49.955707) (xy 86.317316 -49.947898) (xy 86.264813 -49.932418) (xy 86.215066 -49.909585)
			(xy 86.169097 -49.879869) (xy 86.148164 -49.862232) (xy 86.14791 -49.861978) (xy 86.140827 -49.856387)
			(xy 86.123907 -49.850144) (xy 86.11489 -49.849786) (xy 86.047834 -49.849786) (xy 86.038819 -49.850162)
			(xy 86.021902 -49.856397) (xy 86.014814 -49.861978) (xy 86.01456 -49.862232) (xy 85.993627 -49.879873)
			(xy 85.947659 -49.909597) (xy 85.897913 -49.932443) (xy 85.845411 -49.947939) (xy 85.791233 -49.955768)
			(xy 85.736491 -49.955768) (xy 85.682313 -49.947939) (xy 85.629811 -49.932443) (xy 85.580065 -49.909597)
			(xy 85.534097 -49.879873) (xy 85.513164 -49.862232) (xy 85.51291 -49.861978) (xy 85.505827 -49.856387)
			(xy 85.488907 -49.850144) (xy 85.47989 -49.849786) (xy 85.412834 -49.849786) (xy 85.403819 -49.850162)
			(xy 85.386902 -49.856397) (xy 85.379814 -49.861978) (xy 85.379814 -49.862232) (xy 85.37956 -49.862232)
			(xy 85.358627 -49.879873) (xy 85.312659 -49.909597) (xy 85.262913 -49.932443) (xy 85.210411 -49.947939)
			(xy 85.156233 -49.955768) (xy 85.101491 -49.955768) (xy 85.047313 -49.947939) (xy 84.994811 -49.932443)
			(xy 84.945065 -49.909597) (xy 84.899097 -49.879873) (xy 84.878164 -49.862232) (xy 84.87791 -49.861978)
			(xy 84.870827 -49.856387) (xy 84.853907 -49.850144) (xy 84.84489 -49.849786) (xy 84.777834 -49.849786)
			(xy 84.768819 -49.850162) (xy 84.751902 -49.856397) (xy 84.744814 -49.861978) (xy 84.744814 -49.862232)
			(xy 84.74456 -49.862232) (xy 84.72362 -49.879861) (xy 84.677649 -49.909574) (xy 84.627903 -49.932411)
			(xy 84.575405 -49.947904) (xy 84.521231 -49.955736) (xy 84.493862 -49.956212) (xy 84.466613 -49.955716)
			(xy 84.41267 -49.947955) (xy 84.36038 -49.932597) (xy 84.310808 -49.909953) (xy 84.264963 -49.880486)
			(xy 84.223778 -49.844795) (xy 84.188091 -49.803607) (xy 84.158628 -49.757758) (xy 84.13599 -49.708184)
			(xy 84.120637 -49.655893) (xy 84.112882 -49.601949) (xy 79.463337 -49.601949) (xy 79.489731 -49.613165)
			(xy 79.537337 -49.642219) (xy 79.580205 -49.677894) (xy 79.617422 -49.719431) (xy 79.648195 -49.765944)
			(xy 79.671867 -49.816441) (xy 79.687935 -49.869848) (xy 79.696055 -49.925024) (xy 79.696564 -49.95291)
			(xy 79.696055 -49.980796) (xy 79.687935 -50.035972) (xy 79.671867 -50.089379) (xy 79.648195 -50.139876)
			(xy 79.617422 -50.186389) (xy 79.580205 -50.227926) (xy 79.537337 -50.263601) (xy 79.489731 -50.292655)
			(xy 79.438402 -50.314467) (xy 79.384445 -50.328573) (xy 79.329008 -50.334673) (xy 79.273274 -50.332636)
			(xy 79.218431 -50.322506) (xy 79.165647 -50.304499) (xy 79.116047 -50.278998) (xy 79.070689 -50.246547)
			(xy 79.03054 -50.207838) (xy 78.996454 -50.163695) (xy 78.969158 -50.11506) (xy 78.949235 -50.062969)
			(xy 78.937109 -50.008532) (xy 78.933038 -49.95291) (xy 65.376044 -49.95291) (xy 65.376044 -51.019456)
			(xy 76.7494 -51.019456) (xy 76.753471 -50.963834) (xy 76.765597 -50.909397) (xy 76.78552 -50.857306)
			(xy 76.812816 -50.808671) (xy 76.846902 -50.764528) (xy 76.887051 -50.725819) (xy 76.932409 -50.693368)
			(xy 76.982009 -50.667867) (xy 77.034793 -50.64986) (xy 77.089636 -50.63973) (xy 77.14537 -50.637693)
			(xy 77.200807 -50.643793) (xy 77.254764 -50.657899) (xy 77.306093 -50.679711) (xy 77.353699 -50.708765)
			(xy 77.396567 -50.74444) (xy 77.433784 -50.785977) (xy 77.464557 -50.83249) (xy 77.488229 -50.882987)
			(xy 77.504297 -50.936394) (xy 77.512417 -50.99157) (xy 77.512926 -51.019456) (xy 77.512417 -51.047342)
			(xy 77.504297 -51.102518) (xy 77.488229 -51.155925) (xy 77.464557 -51.206422) (xy 77.439701 -51.243992)
			(xy 85.132926 -51.243992) (xy 85.133381 -51.216621) (xy 85.141201 -51.162441) (xy 85.156692 -51.109938)
			(xy 85.179536 -51.060191) (xy 85.209263 -51.014225) (xy 85.226906 -50.993294) (xy 85.22716 -50.99304)
			(xy 85.232743 -50.985951) (xy 85.23899 -50.969036) (xy 85.239352 -50.96002) (xy 85.239352 -50.892964)
			(xy 85.239023 -50.883944) (xy 85.232757 -50.867027) (xy 85.22716 -50.859944) (xy 85.226906 -50.859944)
			(xy 85.226906 -50.85969) (xy 85.20925 -50.838772) (xy 85.17954 -50.792795) (xy 85.156708 -50.743044)
			(xy 85.141221 -50.69054) (xy 85.133397 -50.636362) (xy 85.132926 -50.608992) (xy 85.133348 -50.581737)
			(xy 85.141107 -50.527783) (xy 85.156466 -50.475483) (xy 85.179112 -50.4259) (xy 85.208584 -50.380045)
			(xy 85.244282 -50.338852) (xy 85.285479 -50.303158) (xy 85.331337 -50.273691) (xy 85.380922 -50.251051)
			(xy 85.433224 -50.235698) (xy 85.487179 -50.227945) (xy 85.514434 -50.227484) (xy 85.543351 -50.228018)
			(xy 85.600523 -50.236739) (xy 85.655722 -50.253992) (xy 85.707685 -50.279381) (xy 85.755219 -50.312323)
			(xy 85.797235 -50.352064) (xy 85.815424 -50.37455) (xy 85.823022 -50.383367) (xy 85.84393 -50.393543)
			(xy 85.855556 -50.394108) (xy 85.935312 -50.394108) (xy 85.946942 -50.393559) (xy 85.967852 -50.383377)
			(xy 85.975444 -50.37455) (xy 85.993598 -50.352035) (xy 86.035627 -50.312304) (xy 86.08317 -50.27937)
			(xy 86.135138 -50.253988) (xy 86.190342 -50.236738) (xy 86.247516 -50.228016) (xy 86.276434 -50.227484)
			(xy 86.303686 -50.227946) (xy 86.357634 -50.235707) (xy 86.409929 -50.251066) (xy 86.459505 -50.273711)
			(xy 86.505355 -50.30318) (xy 86.546545 -50.338874) (xy 86.582236 -50.380066) (xy 86.611702 -50.425917)
			(xy 86.634343 -50.475496) (xy 86.649698 -50.527792) (xy 86.657456 -50.58174) (xy 86.657942 -50.608992)
			(xy 86.657488 -50.635307) (xy 86.650253 -50.687436) (xy 86.635932 -50.73808) (xy 86.614798 -50.78628)
			(xy 86.587248 -50.831123) (xy 86.553806 -50.871761) (xy 86.534752 -50.889916) (xy 86.527349 -50.897437)
			(xy 86.518824 -50.916717) (xy 86.518242 -50.927254) (xy 86.518242 -51.00193) (xy 86.518783 -51.012479)
			(xy 86.527308 -51.031775) (xy 86.534752 -51.039268) (xy 86.553843 -51.057387) (xy 86.587295 -51.098026)
			(xy 86.614848 -51.142874) (xy 86.63598 -51.191082) (xy 86.65029 -51.241735) (xy 86.657507 -51.293874)
			(xy 86.657942 -51.320192) (xy 86.657415 -51.347442) (xy 86.64966 -51.401386) (xy 86.634308 -51.453678)
			(xy 86.61167 -51.503253) (xy 86.582208 -51.549102) (xy 86.546521 -51.590291) (xy 86.505335 -51.625983)
			(xy 86.45949 -51.65545) (xy 86.409917 -51.678093) (xy 86.357627 -51.693451) (xy 86.303683 -51.701212)
			(xy 86.276434 -51.7017) (xy 86.24877 -51.701161) (xy 86.194022 -51.693167) (xy 86.141001 -51.677355)
			(xy 86.090817 -51.654056) (xy 86.044521 -51.623759) (xy 86.003082 -51.587097) (xy 85.967368 -51.544839)
			(xy 85.95233 -51.521614) (xy 85.945689 -51.511941) (xy 85.925831 -51.499496) (xy 85.91423 -51.497738)
			(xy 85.83422 -51.489864) (xy 85.822582 -51.489248) (xy 85.800745 -51.497317) (xy 85.79231 -51.505358)
			(xy 85.792056 -51.505612) (xy 85.773981 -51.524199) (xy 85.733647 -51.556776) (xy 85.689272 -51.583588)
			(xy 85.641672 -51.60414) (xy 85.591727 -51.618052) (xy 85.540357 -51.625069) (xy 85.514434 -51.6255)
			(xy 85.487182 -51.625013) (xy 85.433231 -51.61726) (xy 85.380933 -51.601908) (xy 85.331353 -51.579269)
			(xy 85.285499 -51.549804) (xy 85.244306 -51.514113) (xy 85.208612 -51.472922) (xy 85.179143 -51.42707)
			(xy 85.156501 -51.377491) (xy 85.141145 -51.325194) (xy 85.133389 -51.271244) (xy 85.132926 -51.243992)
			(xy 77.439701 -51.243992) (xy 77.433784 -51.252935) (xy 77.396567 -51.294472) (xy 77.353699 -51.330147)
			(xy 77.306093 -51.359201) (xy 77.254764 -51.381013) (xy 77.200807 -51.395119) (xy 77.14537 -51.401219)
			(xy 77.089636 -51.399182) (xy 77.034793 -51.389052) (xy 76.982009 -51.371045) (xy 76.932409 -51.345544)
			(xy 76.887051 -51.313093) (xy 76.846902 -51.274384) (xy 76.812816 -51.230241) (xy 76.78552 -51.181606)
			(xy 76.765597 -51.129515) (xy 76.753471 -51.075078) (xy 76.7494 -51.019456) (xy 65.376044 -51.019456)
			(xy 65.376044 -52.035456) (xy 78.941166 -52.035456) (xy 78.945237 -51.979834) (xy 78.957363 -51.925397)
			(xy 78.977286 -51.873306) (xy 79.004582 -51.824671) (xy 79.038668 -51.780528) (xy 79.078817 -51.741819)
			(xy 79.124175 -51.709368) (xy 79.173775 -51.683867) (xy 79.226559 -51.66586) (xy 79.281402 -51.65573)
			(xy 79.337136 -51.653693) (xy 79.392573 -51.659793) (xy 79.44653 -51.673899) (xy 79.497859 -51.695711)
			(xy 79.545465 -51.724765) (xy 79.588333 -51.76044) (xy 79.62555 -51.801977) (xy 79.656323 -51.84849)
			(xy 79.679995 -51.898987) (xy 79.696063 -51.952394) (xy 79.704183 -52.00757) (xy 79.704692 -52.035456)
			(xy 79.704183 -52.063342) (xy 79.696063 -52.118518) (xy 79.679995 -52.171925) (xy 79.656323 -52.222422)
			(xy 79.62555 -52.268935) (xy 79.588333 -52.310472) (xy 79.545465 -52.346147) (xy 79.497859 -52.375201)
			(xy 79.44653 -52.397013) (xy 79.392573 -52.411119) (xy 79.337136 -52.417219) (xy 79.281402 -52.415182)
			(xy 79.226559 -52.405052) (xy 79.173775 -52.387045) (xy 79.124175 -52.361544) (xy 79.078817 -52.329093)
			(xy 79.038668 -52.290384) (xy 79.004582 -52.246241) (xy 78.977286 -52.197606) (xy 78.957363 -52.145515)
			(xy 78.945237 -52.091078) (xy 78.941166 -52.035456) (xy 65.376044 -52.035456) (xy 65.376044 -54.731412)
			(xy 65.52057 -54.731412) (xy 65.521026 -54.704041) (xy 65.528844 -54.649861) (xy 65.544334 -54.597357)
			(xy 65.567179 -54.54761) (xy 65.596907 -54.501645) (xy 65.61455 -54.480714) (xy 65.614804 -54.48046)
			(xy 65.620372 -54.473361) (xy 65.62663 -54.456454) (xy 65.626996 -54.44744) (xy 65.626996 -54.380384)
			(xy 65.626647 -54.371366) (xy 65.620394 -54.354449) (xy 65.614804 -54.347364) (xy 65.61455 -54.347364)
			(xy 65.61455 -54.34711) (xy 65.59692 -54.326168) (xy 65.567193 -54.280203) (xy 65.544346 -54.230458)
			(xy 65.528847 -54.177957) (xy 65.521017 -54.123779) (xy 65.521016 -54.069039) (xy 65.528844 -54.014861)
			(xy 65.544339 -53.962359) (xy 65.567184 -53.912613) (xy 65.596909 -53.866646) (xy 65.61455 -53.845714)
			(xy 65.614804 -53.84546) (xy 65.620372 -53.838361) (xy 65.62663 -53.821454) (xy 65.626996 -53.81244)
			(xy 65.626996 -53.745384) (xy 65.626647 -53.736366) (xy 65.620394 -53.719449) (xy 65.614804 -53.712364)
			(xy 65.61455 -53.712364) (xy 65.61455 -53.71211) (xy 65.59692 -53.691168) (xy 65.567193 -53.645203)
			(xy 65.544346 -53.595458) (xy 65.528847 -53.542957) (xy 65.521017 -53.488779) (xy 65.521016 -53.434039)
			(xy 65.528844 -53.379861) (xy 65.544339 -53.327359) (xy 65.567184 -53.277613) (xy 65.596909 -53.231646)
			(xy 65.61455 -53.210714) (xy 65.614804 -53.21046) (xy 65.620372 -53.203361) (xy 65.62663 -53.186454)
			(xy 65.626996 -53.17744) (xy 65.626996 -53.110384) (xy 65.626647 -53.101366) (xy 65.620394 -53.084449)
			(xy 65.614804 -53.077364) (xy 65.61455 -53.077364) (xy 65.61455 -53.07711) (xy 65.59691 -53.056179)
			(xy 65.567197 -53.010206) (xy 65.54436 -52.960459) (xy 65.528869 -52.907958) (xy 65.521043 -52.853781)
			(xy 65.52057 -52.826412) (xy 65.521056 -52.799161) (xy 65.528812 -52.745213) (xy 65.544167 -52.692918)
			(xy 65.566809 -52.643341) (xy 65.596275 -52.597491) (xy 65.631966 -52.5563) (xy 65.673157 -52.520609)
			(xy 65.719007 -52.491143) (xy 65.768584 -52.468501) (xy 65.820879 -52.453146) (xy 65.874827 -52.44539)
			(xy 65.929329 -52.44539) (xy 65.983277 -52.453146) (xy 66.035572 -52.468501) (xy 66.085149 -52.491143)
			(xy 66.130999 -52.520609) (xy 66.17219 -52.5563) (xy 66.207881 -52.597491) (xy 66.237347 -52.643341)
			(xy 66.259989 -52.692918) (xy 66.275344 -52.745213) (xy 66.2831 -52.799161) (xy 66.283586 -52.826412)
			(xy 66.28313 -52.853783) (xy 66.275311 -52.907962) (xy 66.259819 -52.960466) (xy 66.236975 -53.010212)
			(xy 66.207248 -53.056179) (xy 66.189606 -53.07711) (xy 66.189352 -53.077364) (xy 66.183769 -53.084453)
			(xy 66.177521 -53.101368) (xy 66.17716 -53.110384) (xy 66.17716 -53.17744) (xy 66.177485 -53.18646)
			(xy 66.183753 -53.203378) (xy 66.189352 -53.21046) (xy 66.189606 -53.21046) (xy 66.189606 -53.210714)
			(xy 66.207257 -53.231638) (xy 66.236979 -53.277608) (xy 66.259822 -53.327356) (xy 66.275315 -53.379859)
			(xy 66.283142 -53.434038) (xy 66.283141 -53.48878) (xy 66.275312 -53.542959) (xy 66.259815 -53.595461)
			(xy 66.23697 -53.645208) (xy 66.207246 -53.691177) (xy 66.189606 -53.71211) (xy 66.189352 -53.712364)
			(xy 66.183769 -53.719453) (xy 66.177521 -53.736368) (xy 66.17716 -53.745384) (xy 66.17716 -53.81244)
			(xy 66.177485 -53.82146) (xy 66.183753 -53.838378) (xy 66.189352 -53.84546) (xy 66.189606 -53.84546)
			(xy 66.189606 -53.845714) (xy 66.207257 -53.866638) (xy 66.236979 -53.912608) (xy 66.259822 -53.962356)
			(xy 66.275315 -54.014859) (xy 66.283142 -54.069038) (xy 66.283141 -54.12378) (xy 66.275312 -54.177959)
			(xy 66.259815 -54.230461) (xy 66.23697 -54.280208) (xy 66.207246 -54.326177) (xy 66.189606 -54.34711)
			(xy 66.189352 -54.347364) (xy 66.183769 -54.354453) (xy 66.177521 -54.371368) (xy 66.17716 -54.380384)
			(xy 66.17716 -54.44744) (xy 66.177485 -54.45646) (xy 66.183753 -54.473378) (xy 66.189352 -54.48046)
			(xy 66.189606 -54.48046) (xy 66.189606 -54.480714) (xy 66.207219 -54.501667) (xy 66.236935 -54.547634)
			(xy 66.259776 -54.597376) (xy 66.275273 -54.649872) (xy 66.283108 -54.704044) (xy 66.283586 -54.731412)
			(xy 66.2831 -54.758663) (xy 66.278436 -54.791102) (xy 68.176394 -54.791102) (xy 68.176863 -54.763732)
			(xy 68.18468 -54.709553) (xy 68.200169 -54.65705) (xy 68.22301 -54.607303) (xy 68.252733 -54.561336)
			(xy 68.270374 -54.540404) (xy 68.270628 -54.54015) (xy 68.276203 -54.533056) (xy 68.282456 -54.516145)
			(xy 68.28282 -54.50713) (xy 68.28282 -54.440074) (xy 68.282471 -54.431056) (xy 68.276218 -54.41414)
			(xy 68.270628 -54.407054) (xy 68.270374 -54.407054) (xy 68.270374 -54.4068) (xy 68.252733 -54.385867)
			(xy 68.223005 -54.3399) (xy 68.200157 -54.290154) (xy 68.184658 -54.237652) (xy 68.176828 -54.183473)
			(xy 68.176828 -54.12873) (xy 68.184657 -54.074551) (xy 68.200155 -54.022049) (xy 68.223003 -53.972303)
			(xy 68.252731 -53.926336) (xy 68.270374 -53.905404) (xy 68.270628 -53.90515) (xy 68.276203 -53.898056)
			(xy 68.282456 -53.881145) (xy 68.28282 -53.87213) (xy 68.28282 -53.805074) (xy 68.282471 -53.796056)
			(xy 68.276218 -53.77914) (xy 68.270628 -53.772054) (xy 68.270374 -53.772054) (xy 68.270374 -53.7718)
			(xy 68.252733 -53.750867) (xy 68.223005 -53.7049) (xy 68.200157 -53.655154) (xy 68.184658 -53.602652)
			(xy 68.176828 -53.548473) (xy 68.176828 -53.49373) (xy 68.184657 -53.439551) (xy 68.200155 -53.387049)
			(xy 68.223003 -53.337303) (xy 68.252731 -53.291336) (xy 68.270374 -53.270404) (xy 68.270628 -53.27015)
			(xy 68.276203 -53.263056) (xy 68.282456 -53.246145) (xy 68.28282 -53.23713) (xy 68.28282 -53.170074)
			(xy 68.282471 -53.161056) (xy 68.276218 -53.14414) (xy 68.270628 -53.137054) (xy 68.270374 -53.137054)
			(xy 68.270374 -53.1368) (xy 68.252717 -53.115882) (xy 68.223009 -53.069905) (xy 68.200177 -53.020154)
			(xy 68.18469 -52.96765) (xy 68.176866 -52.913472) (xy 68.176394 -52.886102) (xy 68.17688 -52.858851)
			(xy 68.184636 -52.804903) (xy 68.199991 -52.752608) (xy 68.222633 -52.703031) (xy 68.252099 -52.657181)
			(xy 68.28779 -52.61599) (xy 68.328981 -52.580299) (xy 68.374831 -52.550833) (xy 68.424408 -52.528191)
			(xy 68.476703 -52.512836) (xy 68.530651 -52.50508) (xy 68.585153 -52.50508) (xy 68.639101 -52.512836)
			(xy 68.691396 -52.528191) (xy 68.730496 -52.546048) (xy 73.679596 -52.546048) (xy 73.679596 -52.491552)
			(xy 73.687351 -52.437611) (xy 73.702703 -52.385322) (xy 73.72534 -52.33575) (xy 73.754801 -52.289903)
			(xy 73.790487 -52.248716) (xy 73.83167 -52.213027) (xy 73.877513 -52.183561) (xy 73.927082 -52.160918)
			(xy 73.979369 -52.14556) (xy 74.03331 -52.137799) (xy 74.060558 -52.13731) (xy 74.087927 -52.137798)
			(xy 74.142106 -52.14561) (xy 74.194609 -52.161094) (xy 74.244356 -52.183931) (xy 74.290324 -52.213651)
			(xy 74.311256 -52.23129) (xy 74.31151 -52.231544) (xy 74.318586 -52.237146) (xy 74.335511 -52.243382)
			(xy 74.34453 -52.243736) (xy 74.411586 -52.243736) (xy 74.420601 -52.243364) (xy 74.437518 -52.237126)
			(xy 74.444606 -52.231544) (xy 74.444606 -52.23129) (xy 74.44486 -52.23129) (xy 74.465793 -52.213649)
			(xy 74.511761 -52.183925) (xy 74.561507 -52.161079) (xy 74.614009 -52.145583) (xy 74.668187 -52.137754)
			(xy 74.722929 -52.137754) (xy 74.777107 -52.145583) (xy 74.829609 -52.161079) (xy 74.879355 -52.183925)
			(xy 74.925323 -52.213649) (xy 74.946256 -52.23129) (xy 74.94651 -52.231544) (xy 74.953586 -52.237146)
			(xy 74.970511 -52.243382) (xy 74.97953 -52.243736) (xy 75.046586 -52.243736) (xy 75.055601 -52.243364)
			(xy 75.072518 -52.237126) (xy 75.079606 -52.231544) (xy 75.079606 -52.23129) (xy 75.07986 -52.23129)
			(xy 75.100795 -52.213655) (xy 75.146767 -52.183943) (xy 75.196514 -52.161106) (xy 75.249014 -52.145614)
			(xy 75.303189 -52.137785) (xy 75.330558 -52.13731) (xy 75.357814 -52.137734) (xy 75.411772 -52.145487)
			(xy 75.464078 -52.16084) (xy 75.513665 -52.183481) (xy 75.559526 -52.212949) (xy 75.600726 -52.248645)
			(xy 75.636426 -52.28984) (xy 75.665899 -52.335698) (xy 75.688546 -52.385283) (xy 75.703905 -52.437587)
			(xy 75.711663 -52.491544) (xy 75.711663 -52.546056) (xy 75.705719 -52.587398) (xy 76.755242 -52.587398)
			(xy 76.759313 -52.531776) (xy 76.771439 -52.477339) (xy 76.791362 -52.425248) (xy 76.818658 -52.376613)
			(xy 76.852744 -52.33247) (xy 76.892893 -52.293761) (xy 76.938251 -52.26131) (xy 76.987851 -52.235809)
			(xy 77.040635 -52.217802) (xy 77.095478 -52.207672) (xy 77.151212 -52.205635) (xy 77.206649 -52.211735)
			(xy 77.260606 -52.225841) (xy 77.311935 -52.247653) (xy 77.359541 -52.276707) (xy 77.402409 -52.312382)
			(xy 77.439626 -52.353919) (xy 77.470399 -52.400432) (xy 77.494071 -52.450929) (xy 77.510139 -52.504336)
			(xy 77.517735 -52.555949) (xy 84.583802 -52.555949) (xy 84.583802 -52.501452) (xy 84.591558 -52.447509)
			(xy 84.606911 -52.39522) (xy 84.629549 -52.345647) (xy 84.659011 -52.299801) (xy 84.694698 -52.258614)
			(xy 84.735883 -52.222924) (xy 84.781728 -52.193459) (xy 84.831299 -52.170818) (xy 84.883588 -52.155462)
			(xy 84.93753 -52.147704) (xy 84.964778 -52.147216) (xy 84.992148 -52.147691) (xy 85.046327 -52.155506)
			(xy 85.09883 -52.170993) (xy 85.148577 -52.193833) (xy 85.194544 -52.223556) (xy 85.215476 -52.241196)
			(xy 85.21573 -52.24145) (xy 85.222828 -52.247019) (xy 85.239736 -52.253275) (xy 85.24875 -52.253642)
			(xy 85.315806 -52.253642) (xy 85.324825 -52.2533) (xy 85.341742 -52.247043) (xy 85.348826 -52.24145)
			(xy 85.348826 -52.241196) (xy 85.34908 -52.241196) (xy 85.370008 -52.223552) (xy 85.415982 -52.193841)
			(xy 85.465731 -52.171006) (xy 85.518232 -52.155516) (xy 85.572409 -52.147689) (xy 85.599778 -52.147216)
			(xy 85.627034 -52.147629) (xy 85.68099 -52.155384) (xy 85.733294 -52.170739) (xy 85.78288 -52.193382)
			(xy 85.828739 -52.222851) (xy 85.869937 -52.258547) (xy 85.905635 -52.299743) (xy 85.935107 -52.3456)
			(xy 85.957753 -52.395185) (xy 85.973111 -52.447488) (xy 85.980869 -52.501444) (xy 85.980869 -52.555956)
			(xy 85.973111 -52.609912) (xy 85.957753 -52.662215) (xy 85.935107 -52.7118) (xy 85.905635 -52.757657)
			(xy 85.869937 -52.798853) (xy 85.828739 -52.834549) (xy 85.78288 -52.864018) (xy 85.733294 -52.886661)
			(xy 85.68099 -52.902016) (xy 85.627034 -52.909771) (xy 85.599778 -52.910232) (xy 85.572407 -52.909795)
			(xy 85.518225 -52.901973) (xy 85.465721 -52.886478) (xy 85.415975 -52.863629) (xy 85.37001 -52.833897)
			(xy 85.34908 -52.816252) (xy 85.348826 -52.815998) (xy 85.341736 -52.810416) (xy 85.324822 -52.804167)
			(xy 85.315806 -52.803806) (xy 85.24875 -52.803806) (xy 85.239735 -52.804186) (xy 85.222818 -52.810418)
			(xy 85.21573 -52.815998) (xy 85.21573 -52.816252) (xy 85.215476 -52.816252) (xy 85.19452 -52.833861)
			(xy 85.148554 -52.863579) (xy 85.098813 -52.886422) (xy 85.046318 -52.90192) (xy 84.992146 -52.909755)
			(xy 84.964778 -52.910232) (xy 84.93753 -52.909696) (xy 84.883588 -52.901938) (xy 84.831299 -52.886582)
			(xy 84.781728 -52.863941) (xy 84.735883 -52.834476) (xy 84.694698 -52.798786) (xy 84.659011 -52.757599)
			(xy 84.629549 -52.711753) (xy 84.606911 -52.66218) (xy 84.591558 -52.609891) (xy 84.583802 -52.555949)
			(xy 77.517735 -52.555949) (xy 77.518259 -52.559512) (xy 77.518768 -52.587398) (xy 77.518259 -52.615284)
			(xy 77.510139 -52.67046) (xy 77.494071 -52.723867) (xy 77.470399 -52.774364) (xy 77.439626 -52.820877)
			(xy 77.402409 -52.862414) (xy 77.359541 -52.898089) (xy 77.311935 -52.927143) (xy 77.260606 -52.948955)
			(xy 77.206649 -52.963061) (xy 77.151212 -52.969161) (xy 77.095478 -52.967124) (xy 77.040635 -52.956994)
			(xy 76.987851 -52.938987) (xy 76.938251 -52.913486) (xy 76.892893 -52.881035) (xy 76.852744 -52.842326)
			(xy 76.818658 -52.798183) (xy 76.791362 -52.749548) (xy 76.771439 -52.697457) (xy 76.759313 -52.64302)
			(xy 76.755242 -52.587398) (xy 75.705719 -52.587398) (xy 75.703905 -52.600013) (xy 75.688546 -52.652317)
			(xy 75.665899 -52.701902) (xy 75.636426 -52.74776) (xy 75.600726 -52.788955) (xy 75.559526 -52.824651)
			(xy 75.513665 -52.854119) (xy 75.464078 -52.87676) (xy 75.411772 -52.892113) (xy 75.357814 -52.899866)
			(xy 75.330558 -52.900326) (xy 75.303188 -52.899844) (xy 75.249009 -52.892033) (xy 75.196505 -52.876548)
			(xy 75.146758 -52.85371) (xy 75.100791 -52.823987) (xy 75.07986 -52.806346) (xy 75.079606 -52.806092)
			(xy 75.072523 -52.800501) (xy 75.055603 -52.794257) (xy 75.046586 -52.7939) (xy 74.97953 -52.7939)
			(xy 74.970515 -52.794271) (xy 74.953597 -52.800509) (xy 74.94651 -52.806092) (xy 74.946256 -52.806346)
			(xy 74.925323 -52.823987) (xy 74.879355 -52.853711) (xy 74.829609 -52.876557) (xy 74.777107 -52.892053)
			(xy 74.722929 -52.899882) (xy 74.668187 -52.899882) (xy 74.614009 -52.892053) (xy 74.561507 -52.876557)
			(xy 74.511761 -52.853711) (xy 74.465793 -52.823987) (xy 74.44486 -52.806346) (xy 74.444606 -52.806092)
			(xy 74.437523 -52.800501) (xy 74.420603 -52.794257) (xy 74.411586 -52.7939) (xy 74.34453 -52.7939)
			(xy 74.335515 -52.794271) (xy 74.318597 -52.800509) (xy 74.31151 -52.806092) (xy 74.31151 -52.806346)
			(xy 74.311256 -52.806346) (xy 74.290307 -52.823964) (xy 74.244339 -52.853681) (xy 74.194596 -52.876522)
			(xy 74.142099 -52.892018) (xy 74.087926 -52.89985) (xy 74.060558 -52.900326) (xy 74.03331 -52.899801)
			(xy 73.979369 -52.89204) (xy 73.927082 -52.876682) (xy 73.877513 -52.854039) (xy 73.83167 -52.824573)
			(xy 73.790487 -52.788884) (xy 73.754801 -52.747697) (xy 73.72534 -52.70185) (xy 73.702703 -52.652278)
			(xy 73.687351 -52.599989) (xy 73.679596 -52.546048) (xy 68.730496 -52.546048) (xy 68.740973 -52.550833)
			(xy 68.786823 -52.580299) (xy 68.828014 -52.61599) (xy 68.863705 -52.657181) (xy 68.893171 -52.703031)
			(xy 68.915813 -52.752608) (xy 68.931168 -52.804903) (xy 68.938924 -52.858851) (xy 68.93941 -52.886102)
			(xy 68.938943 -52.913472) (xy 68.931125 -52.967651) (xy 68.915636 -53.020154) (xy 68.892794 -53.069901)
			(xy 68.863071 -53.115868) (xy 68.84543 -53.1368) (xy 68.845176 -53.137054) (xy 68.8396 -53.144148)
			(xy 68.833348 -53.161059) (xy 68.832984 -53.170074) (xy 68.832984 -53.23713) (xy 68.83333 -53.246148)
			(xy 68.839585 -53.263065) (xy 68.845176 -53.27015) (xy 68.84543 -53.27015) (xy 68.84543 -53.270404)
			(xy 68.863074 -53.291334) (xy 68.892802 -53.337301) (xy 68.91565 -53.387048) (xy 68.931148 -53.439551)
			(xy 68.938978 -53.49373) (xy 68.938977 -53.548473) (xy 68.931148 -53.602652) (xy 68.915649 -53.655155)
			(xy 68.892801 -53.704901) (xy 68.863073 -53.750868) (xy 68.8465 -53.77053) (xy 69.210682 -53.77053)
			(xy 69.211191 -53.741612) (xy 69.219917 -53.684439) (xy 69.237175 -53.629239) (xy 69.262568 -53.577276)
			(xy 69.295515 -53.529743) (xy 69.33526 -53.487728) (xy 69.357748 -53.46954) (xy 69.366535 -53.461914)
			(xy 69.376728 -53.441027) (xy 69.377306 -53.429408) (xy 69.377306 -53.349652) (xy 69.376778 -53.338019)
			(xy 69.366581 -53.31711) (xy 69.357748 -53.30952) (xy 69.335263 -53.291331) (xy 69.295531 -53.249309)
			(xy 69.262593 -53.201773) (xy 69.237206 -53.149812) (xy 69.219949 -53.094615) (xy 69.211218 -53.037446)
			(xy 69.210682 -53.00853) (xy 69.211183 -52.981278) (xy 69.218936 -52.927329) (xy 69.234288 -52.875033)
			(xy 69.256926 -52.825453) (xy 69.28639 -52.779601) (xy 69.32208 -52.738408) (xy 69.363269 -52.702714)
			(xy 69.409118 -52.673245) (xy 69.458695 -52.650602) (xy 69.51099 -52.635244) (xy 69.564938 -52.627486)
			(xy 69.59219 -52.627022) (xy 69.618504 -52.627489) (xy 69.670633 -52.634723) (xy 69.721276 -52.649042)
			(xy 69.769475 -52.670174) (xy 69.814318 -52.697721) (xy 69.854958 -52.73116) (xy 69.873114 -52.750212)
			(xy 69.880627 -52.757624) (xy 69.899914 -52.766142) (xy 69.910452 -52.766722) (xy 69.985128 -52.766722)
			(xy 69.995674 -52.766161) (xy 70.014969 -52.757648) (xy 70.022466 -52.750212) (xy 70.040599 -52.731134)
			(xy 70.081233 -52.697678) (xy 70.126078 -52.670122) (xy 70.174283 -52.648987) (xy 70.224935 -52.634675)
			(xy 70.277072 -52.627457) (xy 70.30339 -52.627022) (xy 70.330644 -52.627465) (xy 70.384597 -52.635221)
			(xy 70.436897 -52.650577) (xy 70.486479 -52.673221) (xy 70.532334 -52.702691) (xy 70.573528 -52.738387)
			(xy 70.609221 -52.779582) (xy 70.638689 -52.825438) (xy 70.66133 -52.875022) (xy 70.676683 -52.927322)
			(xy 70.684437 -52.981276) (xy 70.684898 -53.00853) (xy 70.68441 -53.036196) (xy 70.676407 -53.090946)
			(xy 70.660586 -53.143969) (xy 70.637279 -53.194153) (xy 70.606974 -53.240448) (xy 70.570305 -53.281885)
			(xy 70.52804 -53.317598) (xy 70.504812 -53.332634) (xy 70.495114 -53.339245) (xy 70.482682 -53.359125)
			(xy 70.480936 -53.370734) (xy 70.473062 -53.450744) (xy 70.472407 -53.462383) (xy 70.480503 -53.484222)
			(xy 70.488556 -53.492654) (xy 70.48881 -53.492908) (xy 70.507379 -53.511001) (xy 70.539958 -53.55133)
			(xy 70.566773 -53.595702) (xy 70.587328 -53.643298) (xy 70.601244 -53.69324) (xy 70.608264 -53.744608)
			(xy 70.608698 -53.77053) (xy 70.60825 -53.797782) (xy 70.600489 -53.851732) (xy 70.58513 -53.904028)
			(xy 70.562484 -53.953606) (xy 70.533014 -53.999457) (xy 70.497319 -54.040647) (xy 70.456125 -54.076338)
			(xy 70.410271 -54.105804) (xy 70.360691 -54.128444) (xy 70.308393 -54.143798) (xy 70.254442 -54.151553)
			(xy 70.22719 -54.152038) (xy 70.199819 -54.151593) (xy 70.145638 -54.143772) (xy 70.093134 -54.128279)
			(xy 70.043388 -54.105432) (xy 69.997422 -54.075702) (xy 69.976492 -54.058058) (xy 69.976238 -54.057804)
			(xy 69.969144 -54.052228) (xy 69.952233 -54.045975) (xy 69.943218 -54.045612) (xy 69.876162 -54.045612)
			(xy 69.867143 -54.045948) (xy 69.850226 -54.05221) (xy 69.843142 -54.057804) (xy 69.843142 -54.058058)
			(xy 69.842888 -54.058058) (xy 69.821928 -54.075663) (xy 69.775964 -54.105381) (xy 69.726223 -54.128224)
			(xy 69.673728 -54.143723) (xy 69.619557 -54.15156) (xy 69.59219 -54.152038) (xy 69.56494 -54.151532)
			(xy 69.510994 -54.143775) (xy 69.458702 -54.12842) (xy 69.409127 -54.10578) (xy 69.363278 -54.076315)
			(xy 69.322088 -54.040626) (xy 69.286397 -53.999438) (xy 69.25693 -53.953591) (xy 69.234287 -53.904017)
			(xy 69.21893 -53.851725) (xy 69.21117 -53.79778) (xy 69.210682 -53.77053) (xy 68.8465 -53.77053)
			(xy 68.84543 -53.7718) (xy 68.845176 -53.772054) (xy 68.8396 -53.779148) (xy 68.833348 -53.796059)
			(xy 68.832984 -53.805074) (xy 68.832984 -53.87213) (xy 68.83333 -53.881148) (xy 68.839585 -53.898065)
			(xy 68.845176 -53.90515) (xy 68.84543 -53.90515) (xy 68.84543 -53.905404) (xy 68.863074 -53.926334)
			(xy 68.892802 -53.972301) (xy 68.91565 -54.022048) (xy 68.931148 -54.074551) (xy 68.938978 -54.12873)
			(xy 68.938977 -54.183473) (xy 68.931148 -54.237652) (xy 68.915649 -54.290155) (xy 68.901856 -54.320186)
			(xy 71.130414 -54.320186) (xy 71.130868 -54.292815) (xy 71.138689 -54.238636) (xy 71.15418 -54.186132)
			(xy 71.177025 -54.136386) (xy 71.206752 -54.090419) (xy 71.224394 -54.069488) (xy 71.224648 -54.069234)
			(xy 71.230232 -54.062146) (xy 71.236479 -54.04523) (xy 71.23684 -54.036214) (xy 71.23684 -53.969158)
			(xy 71.236468 -53.960142) (xy 71.230232 -53.943225) (xy 71.224648 -53.936138) (xy 71.224394 -53.936138)
			(xy 71.224394 -53.935884) (xy 71.20678 -53.914932) (xy 71.177065 -53.868964) (xy 71.154224 -53.819222)
			(xy 71.138727 -53.766726) (xy 71.130892 -53.712554) (xy 71.130414 -53.685186) (xy 71.1309 -53.657935)
			(xy 71.138656 -53.603987) (xy 71.154011 -53.551692) (xy 71.176653 -53.502115) (xy 71.206119 -53.456265)
			(xy 71.24181 -53.415074) (xy 71.283001 -53.379383) (xy 71.328851 -53.349917) (xy 71.378428 -53.327275)
			(xy 71.430723 -53.31192) (xy 71.484671 -53.304164) (xy 71.539173 -53.304164) (xy 71.593121 -53.31192)
			(xy 71.645416 -53.327275) (xy 71.694993 -53.349917) (xy 71.740843 -53.379383) (xy 71.782034 -53.415074)
			(xy 71.817725 -53.456265) (xy 71.847191 -53.502115) (xy 71.869833 -53.551692) (xy 71.885188 -53.603987)
			(xy 71.892944 -53.657935) (xy 71.89343 -53.685186) (xy 71.892973 -53.712557) (xy 71.885155 -53.766737)
			(xy 71.869665 -53.819241) (xy 71.846821 -53.868988) (xy 71.817093 -53.914953) (xy 71.79945 -53.935884)
			(xy 71.799196 -53.936138) (xy 71.793629 -53.943238) (xy 71.787371 -53.960144) (xy 71.787004 -53.969158)
			(xy 71.787004 -54.036214) (xy 71.787354 -54.045232) (xy 71.793606 -54.062149) (xy 71.799196 -54.069234)
			(xy 71.79945 -54.069234) (xy 71.79945 -54.069488) (xy 71.817089 -54.09042) (xy 71.846803 -54.136392)
			(xy 71.869639 -54.18614) (xy 71.88513 -54.238641) (xy 71.892957 -54.292817) (xy 71.89343 -54.320186)
			(xy 71.892944 -54.347437) (xy 71.885188 -54.401385) (xy 71.869833 -54.45368) (xy 71.847191 -54.503257)
			(xy 71.817725 -54.549107) (xy 71.782034 -54.590298) (xy 71.740843 -54.625989) (xy 71.694993 -54.655455)
			(xy 71.645416 -54.678097) (xy 71.593121 -54.693452) (xy 71.539173 -54.701208) (xy 71.484671 -54.701208)
			(xy 71.430723 -54.693452) (xy 71.378428 -54.678097) (xy 71.328851 -54.655455) (xy 71.283001 -54.625989)
			(xy 71.24181 -54.590298) (xy 71.206119 -54.549107) (xy 71.176653 -54.503257) (xy 71.154011 -54.45368)
			(xy 71.138656 -54.401385) (xy 71.1309 -54.347437) (xy 71.130414 -54.320186) (xy 68.901856 -54.320186)
			(xy 68.892801 -54.339901) (xy 68.863073 -54.385868) (xy 68.84543 -54.4068) (xy 68.845176 -54.407054)
			(xy 68.8396 -54.414148) (xy 68.833348 -54.431059) (xy 68.832984 -54.440074) (xy 68.832984 -54.50713)
			(xy 68.83333 -54.516148) (xy 68.839585 -54.533065) (xy 68.845176 -54.54015) (xy 68.84543 -54.54015)
			(xy 68.84543 -54.540404) (xy 68.863089 -54.56132) (xy 68.892797 -54.607298) (xy 68.915629 -54.657049)
			(xy 68.931115 -54.709553) (xy 68.938938 -54.763732) (xy 68.939055 -54.770528) (xy 72.070976 -54.770528)
			(xy 72.07144 -54.743157) (xy 72.079255 -54.688978) (xy 72.094744 -54.636474) (xy 72.117587 -54.586727)
			(xy 72.147313 -54.540761) (xy 72.164956 -54.51983) (xy 72.16521 -54.519576) (xy 72.170814 -54.512501)
			(xy 72.17705 -54.495575) (xy 72.177402 -54.486556) (xy 72.177402 -54.4195) (xy 72.177045 -54.410483)
			(xy 72.170797 -54.393566) (xy 72.16521 -54.38648) (xy 72.164956 -54.38648) (xy 72.164956 -54.386226)
			(xy 72.147308 -54.365301) (xy 72.117599 -54.319326) (xy 72.094766 -54.269576) (xy 72.079276 -54.217074)
			(xy 72.071449 -54.162898) (xy 72.070976 -54.135528) (xy 72.071462 -54.108277) (xy 72.079218 -54.054329)
			(xy 72.094573 -54.002034) (xy 72.117215 -53.952457) (xy 72.146681 -53.906607) (xy 72.182372 -53.865416)
			(xy 72.223563 -53.829725) (xy 72.269413 -53.800259) (xy 72.31899 -53.777617) (xy 72.371285 -53.762262)
			(xy 72.425233 -53.754506) (xy 72.479735 -53.754506) (xy 72.533683 -53.762262) (xy 72.585978 -53.777617)
			(xy 72.635555 -53.800259) (xy 72.681405 -53.829725) (xy 72.722596 -53.865416) (xy 72.758287 -53.906607)
			(xy 72.787753 -53.952457) (xy 72.792828 -53.96357) (xy 76.772006 -53.96357) (xy 76.776077 -53.907948)
			(xy 76.788203 -53.853511) (xy 76.808126 -53.80142) (xy 76.835422 -53.752785) (xy 76.869508 -53.708642)
			(xy 76.909657 -53.669933) (xy 76.955015 -53.637482) (xy 77.004615 -53.611981) (xy 77.057399 -53.593974)
			(xy 77.112242 -53.583844) (xy 77.167976 -53.581807) (xy 77.223413 -53.587907) (xy 77.27737 -53.602013)
			(xy 77.328699 -53.623825) (xy 77.376305 -53.652879) (xy 77.419173 -53.688554) (xy 77.45639 -53.730091)
			(xy 77.487163 -53.776604) (xy 77.510835 -53.827101) (xy 77.526903 -53.880508) (xy 77.535023 -53.935684)
			(xy 77.535532 -53.96357) (xy 77.535023 -53.991456) (xy 77.526903 -54.046632) (xy 77.510835 -54.100039)
			(xy 77.487163 -54.150536) (xy 77.45639 -54.197049) (xy 77.419173 -54.238586) (xy 77.376305 -54.274261)
			(xy 77.328699 -54.303315) (xy 77.27737 -54.325127) (xy 77.223413 -54.339233) (xy 77.167976 -54.345333)
			(xy 77.112242 -54.343296) (xy 77.057399 -54.333166) (xy 77.004615 -54.315159) (xy 76.955015 -54.289658)
			(xy 76.909657 -54.257207) (xy 76.869508 -54.218498) (xy 76.835422 -54.174355) (xy 76.808126 -54.12572)
			(xy 76.788203 -54.073629) (xy 76.776077 -54.019192) (xy 76.772006 -53.96357) (xy 72.792828 -53.96357)
			(xy 72.810395 -54.002034) (xy 72.82575 -54.054329) (xy 72.833506 -54.108277) (xy 72.833992 -54.135528)
			(xy 72.833544 -54.162899) (xy 72.825722 -54.217079) (xy 72.810229 -54.269582) (xy 72.787383 -54.319329)
			(xy 72.757655 -54.365295) (xy 72.740012 -54.386226) (xy 72.739758 -54.38648) (xy 72.734169 -54.393564)
			(xy 72.727925 -54.410483) (xy 72.727566 -54.4195) (xy 72.727566 -54.486556) (xy 72.727951 -54.49557)
			(xy 72.73418 -54.512487) (xy 72.739758 -54.519576) (xy 72.740012 -54.519576) (xy 72.740012 -54.51983)
			(xy 72.757634 -54.540776) (xy 72.787348 -54.586745) (xy 72.810187 -54.636489) (xy 72.825682 -54.688987)
			(xy 72.833515 -54.74316) (xy 72.833992 -54.770528) (xy 72.833506 -54.797779) (xy 72.82575 -54.851727)
			(xy 72.810395 -54.904022) (xy 72.787753 -54.953599) (xy 72.758287 -54.999449) (xy 72.722596 -55.04064)
			(xy 72.681405 -55.076331) (xy 72.635555 -55.105797) (xy 72.585978 -55.128439) (xy 72.533683 -55.143794)
			(xy 72.479735 -55.15155) (xy 72.425233 -55.15155) (xy 72.371285 -55.143794) (xy 72.31899 -55.128439)
			(xy 72.269413 -55.105797) (xy 72.223563 -55.076331) (xy 72.182372 -55.04064) (xy 72.146681 -54.999449)
			(xy 72.117215 -54.953599) (xy 72.094573 -54.904022) (xy 72.079218 -54.851727) (xy 72.071462 -54.797779)
			(xy 72.070976 -54.770528) (xy 68.939055 -54.770528) (xy 68.93941 -54.791102) (xy 68.938924 -54.818353)
			(xy 68.931168 -54.872301) (xy 68.915813 -54.924596) (xy 68.893171 -54.974173) (xy 68.863705 -55.020023)
			(xy 68.828014 -55.061214) (xy 68.786823 -55.096905) (xy 68.740973 -55.126371) (xy 68.691396 -55.149013)
			(xy 68.639101 -55.164368) (xy 68.585153 -55.172124) (xy 68.530651 -55.172124) (xy 68.476703 -55.164368)
			(xy 68.424408 -55.149013) (xy 68.374831 -55.126371) (xy 68.328981 -55.096905) (xy 68.28779 -55.061214)
			(xy 68.252099 -55.020023) (xy 68.222633 -54.974173) (xy 68.199991 -54.924596) (xy 68.184636 -54.872301)
			(xy 68.17688 -54.818353) (xy 68.176394 -54.791102) (xy 66.278436 -54.791102) (xy 66.275344 -54.812611)
			(xy 66.259989 -54.864906) (xy 66.237347 -54.914483) (xy 66.207881 -54.960333) (xy 66.17219 -55.001524)
			(xy 66.130999 -55.037215) (xy 66.085149 -55.066681) (xy 66.035572 -55.089323) (xy 65.983277 -55.104678)
			(xy 65.929329 -55.112434) (xy 65.874827 -55.112434) (xy 65.820879 -55.104678) (xy 65.768584 -55.089323)
			(xy 65.719007 -55.066681) (xy 65.673157 -55.037215) (xy 65.631966 -55.001524) (xy 65.596275 -54.960333)
			(xy 65.566809 -54.914483) (xy 65.544167 -54.864906) (xy 65.528812 -54.812611) (xy 65.521056 -54.758663)
			(xy 65.52057 -54.731412) (xy 65.376044 -54.731412) (xy 65.376044 -57.002934) (xy 73.56348 -57.002934)
			(xy 73.564003 -56.974843) (xy 73.572225 -56.919268) (xy 73.588511 -56.865499) (xy 73.612509 -56.814702)
			(xy 73.6437 -56.767975) (xy 73.681408 -56.726329) (xy 73.724817 -56.690665) (xy 73.748646 -56.675782)
			(xy 73.757536 -56.670448) (xy 73.769728 -56.65343) (xy 73.790048 -56.560212) (xy 73.78573 -56.539638)
			(xy 73.779888 -56.531002) (xy 73.763885 -56.50694) (xy 73.738544 -56.455008) (xy 73.721319 -56.399849)
			(xy 73.712604 -56.342725) (xy 73.71207 -56.313832) (xy 73.712585 -56.286581) (xy 73.720337 -56.232633)
			(xy 73.735688 -56.180337) (xy 73.758325 -56.130759) (xy 73.787788 -56.084907) (xy 73.823476 -56.043714)
			(xy 73.864663 -56.00802) (xy 73.910511 -55.978551) (xy 73.960087 -55.955907) (xy 74.01238 -55.940549)
			(xy 74.066327 -55.932789) (xy 74.093578 -55.932324) (xy 74.120948 -55.932797) (xy 74.175127 -55.940612)
			(xy 74.22763 -55.956099) (xy 74.277377 -55.97894) (xy 74.323344 -56.008663) (xy 74.344276 -56.026304)
			(xy 74.34453 -56.026558) (xy 74.351627 -56.032128) (xy 74.368536 -56.038383) (xy 74.37755 -56.03875)
			(xy 74.444606 -56.03875) (xy 74.453624 -56.038406) (xy 74.470542 -56.032151) (xy 74.477626 -56.026558)
			(xy 74.477626 -56.026304) (xy 74.47788 -56.026304) (xy 74.498813 -56.008663) (xy 74.544781 -55.978939)
			(xy 74.594527 -55.956093) (xy 74.647029 -55.940597) (xy 74.701207 -55.932768) (xy 74.755949 -55.932768)
			(xy 74.810127 -55.940597) (xy 74.862629 -55.956093) (xy 74.912375 -55.978939) (xy 74.958343 -56.008663)
			(xy 74.979276 -56.026304) (xy 74.97953 -56.026558) (xy 74.986627 -56.032128) (xy 75.003536 -56.038383)
			(xy 75.01255 -56.03875) (xy 75.079606 -56.03875) (xy 75.088624 -56.038406) (xy 75.105542 -56.032151)
			(xy 75.112626 -56.026558) (xy 75.112626 -56.026304) (xy 75.11288 -56.026304) (xy 75.133809 -56.008661)
			(xy 75.179783 -55.97895) (xy 75.229531 -55.956115) (xy 75.282032 -55.940624) (xy 75.336209 -55.932797)
			(xy 75.363578 -55.932324) (xy 75.390834 -55.932721) (xy 75.444792 -55.940477) (xy 75.497097 -55.955832)
			(xy 75.546684 -55.978475) (xy 75.592544 -56.007945) (xy 75.633743 -56.043642) (xy 75.669442 -56.084838)
			(xy 75.698914 -56.130697) (xy 75.72156 -56.180282) (xy 75.736919 -56.232586) (xy 75.744677 -56.286544)
			(xy 75.744677 -56.341056) (xy 75.736919 -56.395014) (xy 75.72156 -56.447318) (xy 75.698914 -56.496903)
			(xy 75.669442 -56.542762) (xy 75.633743 -56.583958) (xy 75.592544 -56.619655) (xy 75.546684 -56.649125)
			(xy 75.497097 -56.671768) (xy 75.444792 -56.687123) (xy 75.390834 -56.694879) (xy 75.363578 -56.69534)
			(xy 75.336207 -56.694901) (xy 75.282026 -56.687079) (xy 75.229522 -56.671585) (xy 75.179775 -56.648736)
			(xy 75.13381 -56.619005) (xy 75.11288 -56.60136) (xy 75.112626 -56.601106) (xy 75.105536 -56.595525)
			(xy 75.088622 -56.589275) (xy 75.079606 -56.588914) (xy 75.01255 -56.588914) (xy 75.003535 -56.589292)
			(xy 74.986618 -56.595525) (xy 74.97953 -56.601106) (xy 74.97953 -56.60136) (xy 74.979276 -56.60136)
			(xy 74.958343 -56.619001) (xy 74.912375 -56.648725) (xy 74.862629 -56.671571) (xy 74.810127 -56.687067)
			(xy 74.755949 -56.694896) (xy 74.701207 -56.694896) (xy 74.647029 -56.687067) (xy 74.594527 -56.671571)
			(xy 74.544781 -56.648725) (xy 74.498813 -56.619001) (xy 74.47788 -56.60136) (xy 74.477626 -56.601106)
			(xy 74.470536 -56.595525) (xy 74.453622 -56.589275) (xy 74.444606 -56.588914) (xy 74.37755 -56.588914)
			(xy 74.368535 -56.589292) (xy 74.351618 -56.595525) (xy 74.34453 -56.601106) (xy 74.344022 -56.60136)
			(xy 74.33129 -56.612307) (xy 74.304197 -56.632146) (xy 74.28992 -56.640984) (xy 74.28103 -56.646318)
			(xy 74.268838 -56.663336) (xy 74.248518 -56.756554) (xy 74.252836 -56.777128) (xy 74.258678 -56.785764)
			(xy 74.274662 -56.809838) (xy 74.300009 -56.861765) (xy 74.317239 -56.91692) (xy 74.325959 -56.974042)
			(xy 74.326496 -57.002934) (xy 74.32601 -57.030185) (xy 74.318254 -57.084133) (xy 74.302899 -57.136428)
			(xy 74.280257 -57.186005) (xy 74.250791 -57.231855) (xy 74.2151 -57.273046) (xy 74.173909 -57.308737)
			(xy 74.128059 -57.338203) (xy 74.078482 -57.360845) (xy 74.026187 -57.3762) (xy 73.972239 -57.383956)
			(xy 73.917737 -57.383956) (xy 73.863789 -57.3762) (xy 73.811494 -57.360845) (xy 73.761917 -57.338203)
			(xy 73.716067 -57.308737) (xy 73.674876 -57.273046) (xy 73.639185 -57.231855) (xy 73.609719 -57.186005)
			(xy 73.587077 -57.136428) (xy 73.571722 -57.084133) (xy 73.563966 -57.030185) (xy 73.56348 -57.002934)
			(xy 65.376044 -57.002934) (xy 65.376044 -58.679334) (xy 73.99528 -58.679334) (xy 73.99571 -58.653019)
			(xy 74.002953 -58.600889) (xy 74.01728 -58.550246) (xy 74.03842 -58.502047) (xy 74.065972 -58.457204)
			(xy 74.099416 -58.416566) (xy 74.11847 -58.39841) (xy 74.125865 -58.390883) (xy 74.134394 -58.371607)
			(xy 74.13498 -58.361072) (xy 74.13498 -58.286396) (xy 74.134472 -58.275844) (xy 74.125923 -58.256548)
			(xy 74.11847 -58.249058) (xy 74.099395 -58.230922) (xy 74.065941 -58.190287) (xy 74.038385 -58.145443)
			(xy 74.01725 -58.097238) (xy 74.002937 -58.046588) (xy 73.995716 -57.994451) (xy 73.99528 -57.968134)
			(xy 73.995766 -57.940883) (xy 74.003522 -57.886935) (xy 74.018877 -57.83464) (xy 74.041519 -57.785063)
			(xy 74.070985 -57.739213) (xy 74.106676 -57.698022) (xy 74.147867 -57.662331) (xy 74.193717 -57.632865)
			(xy 74.243294 -57.610223) (xy 74.295589 -57.594868) (xy 74.349537 -57.587112) (xy 74.404039 -57.587112)
			(xy 74.457987 -57.594868) (xy 74.510282 -57.610223) (xy 74.559859 -57.632865) (xy 74.605709 -57.662331)
			(xy 74.6469 -57.698022) (xy 74.682591 -57.739213) (xy 74.712057 -57.785063) (xy 74.734699 -57.83464)
			(xy 74.750054 -57.886935) (xy 74.75781 -57.940883) (xy 74.758296 -57.968134) (xy 74.757853 -57.994449)
			(xy 74.750613 -58.046578) (xy 74.736289 -58.097222) (xy 74.715152 -58.145421) (xy 74.687602 -58.190263)
			(xy 74.654159 -58.230902) (xy 74.635106 -58.249058) (xy 74.627722 -58.256594) (xy 74.619187 -58.275863)
			(xy 74.618596 -58.286396) (xy 74.618596 -58.361072) (xy 74.619128 -58.371621) (xy 74.627661 -58.390917)
			(xy 74.635106 -58.39841) (xy 74.654161 -58.416567) (xy 74.687618 -58.457196) (xy 74.715177 -58.502036)
			(xy 74.736315 -58.550237) (xy 74.750633 -58.600884) (xy 74.757857 -58.653018) (xy 74.758296 -58.679334)
			(xy 74.75781 -58.706585) (xy 74.750054 -58.760533) (xy 74.734699 -58.812828) (xy 74.712057 -58.862405)
			(xy 74.682591 -58.908255) (xy 74.6469 -58.949446) (xy 74.605709 -58.985137) (xy 74.559859 -59.014603)
			(xy 74.510282 -59.037245) (xy 74.457987 -59.0526) (xy 74.404039 -59.060356) (xy 74.349537 -59.060356)
			(xy 74.295589 -59.0526) (xy 74.243294 -59.037245) (xy 74.193717 -59.014603) (xy 74.147867 -58.985137)
			(xy 74.106676 -58.949446) (xy 74.070985 -58.908255) (xy 74.041519 -58.862405) (xy 74.018877 -58.812828)
			(xy 74.003522 -58.760533) (xy 73.995766 -58.706585) (xy 73.99528 -58.679334) (xy 65.376044 -58.679334)
			(xy 65.376044 -60.019254) (xy 74.135661 -60.019254) (xy 74.135661 -59.964746) (xy 74.143419 -59.910792)
			(xy 74.158777 -59.858492) (xy 74.181423 -59.808909) (xy 74.210894 -59.763055) (xy 74.246592 -59.721862)
			(xy 74.287789 -59.686169) (xy 74.333646 -59.656702) (xy 74.383231 -59.634063) (xy 74.435533 -59.61871)
			(xy 74.489488 -59.610958) (xy 74.516742 -59.610498) (xy 74.544111 -59.610999) (xy 74.598289 -59.618808)
			(xy 74.650791 -59.634289) (xy 74.700539 -59.657123) (xy 74.746507 -59.68684) (xy 74.76744 -59.704478)
			(xy 74.767694 -59.704732) (xy 74.774775 -59.710326) (xy 74.791696 -59.716567) (xy 74.800714 -59.716924)
			(xy 74.86777 -59.716924) (xy 74.876785 -59.716547) (xy 74.893702 -59.710313) (xy 74.90079 -59.704732)
			(xy 74.90079 -59.704478) (xy 74.901044 -59.704478) (xy 74.921977 -59.686837) (xy 74.967945 -59.657113)
			(xy 75.017691 -59.634267) (xy 75.070193 -59.618771) (xy 75.124371 -59.610942) (xy 75.179113 -59.610942)
			(xy 75.233291 -59.618771) (xy 75.285793 -59.634267) (xy 75.335539 -59.657113) (xy 75.381507 -59.686837)
			(xy 75.40244 -59.704478) (xy 75.402694 -59.704732) (xy 75.409775 -59.710326) (xy 75.426696 -59.716567)
			(xy 75.435714 -59.716924) (xy 75.50277 -59.716924) (xy 75.511785 -59.716547) (xy 75.528702 -59.710313)
			(xy 75.53579 -59.704732) (xy 75.53579 -59.704478) (xy 75.536044 -59.704478) (xy 75.556984 -59.686848)
			(xy 75.602955 -59.657136) (xy 75.6527 -59.634298) (xy 75.705199 -59.618805) (xy 75.759373 -59.610974)
			(xy 75.786742 -59.610498) (xy 75.813992 -59.610975) (xy 75.867936 -59.618736) (xy 75.920226 -59.634095)
			(xy 75.969799 -59.656739) (xy 76.015645 -59.686207) (xy 76.056831 -59.721899) (xy 76.092518 -59.763089)
			(xy 76.121981 -59.808938) (xy 76.14462 -59.858513) (xy 76.159973 -59.910805) (xy 76.167728 -59.96475)
			(xy 76.167728 -60.01925) (xy 76.159973 -60.073195) (xy 76.14462 -60.125487) (xy 76.121981 -60.175062)
			(xy 76.092518 -60.220911) (xy 76.056831 -60.262101) (xy 76.015645 -60.297793) (xy 75.969799 -60.327261)
			(xy 75.920226 -60.349905) (xy 75.867936 -60.365264) (xy 75.813992 -60.373025) (xy 75.786742 -60.373514)
			(xy 75.759373 -60.37302) (xy 75.705195 -60.365208) (xy 75.652692 -60.349726) (xy 75.602945 -60.32689)
			(xy 75.556977 -60.297172) (xy 75.536044 -60.279534) (xy 75.53579 -60.27928) (xy 75.528712 -60.273681)
			(xy 75.511789 -60.267442) (xy 75.50277 -60.267088) (xy 75.435714 -60.267088) (xy 75.426698 -60.267454)
			(xy 75.409781 -60.273696) (xy 75.402694 -60.27928) (xy 75.40244 -60.279534) (xy 75.381507 -60.297175)
			(xy 75.335539 -60.326899) (xy 75.285793 -60.349745) (xy 75.233291 -60.365241) (xy 75.179113 -60.37307)
			(xy 75.124371 -60.37307) (xy 75.070193 -60.365241) (xy 75.017691 -60.349745) (xy 74.967945 -60.326899)
			(xy 74.921977 -60.297175) (xy 74.901044 -60.279534) (xy 74.90079 -60.27928) (xy 74.893712 -60.273681)
			(xy 74.876789 -60.267442) (xy 74.86777 -60.267088) (xy 74.800714 -60.267088) (xy 74.791698 -60.267454)
			(xy 74.774781 -60.273696) (xy 74.767694 -60.27928) (xy 74.767694 -60.279534) (xy 74.76744 -60.279534)
			(xy 74.746508 -60.297173) (xy 74.700535 -60.326884) (xy 74.650787 -60.349719) (xy 74.598287 -60.36521)
			(xy 74.544111 -60.373039) (xy 74.516742 -60.373514) (xy 74.489488 -60.373042) (xy 74.435533 -60.36529)
			(xy 74.383231 -60.349937) (xy 74.333646 -60.327298) (xy 74.287789 -60.297831) (xy 74.246592 -60.262138)
			(xy 74.210894 -60.220945) (xy 74.181423 -60.175091) (xy 74.158777 -60.125508) (xy 74.143419 -60.073208)
			(xy 74.135661 -60.019254) (xy 65.376044 -60.019254) (xy 65.376044 -63.213549) (xy 74.120788 -63.213549)
			(xy 74.120788 -63.159052) (xy 74.128543 -63.105109) (xy 74.143896 -63.052819) (xy 74.166533 -63.003246)
			(xy 74.195994 -62.957399) (xy 74.23168 -62.916211) (xy 74.272864 -62.880521) (xy 74.318708 -62.851054)
			(xy 74.368278 -62.828411) (xy 74.420566 -62.813053) (xy 74.474508 -62.805291) (xy 74.501756 -62.804802)
			(xy 74.529125 -62.805293) (xy 74.583303 -62.813105) (xy 74.635806 -62.828588) (xy 74.685553 -62.851424)
			(xy 74.731521 -62.881143) (xy 74.752454 -62.898782) (xy 74.752708 -62.899036) (xy 74.759785 -62.904636)
			(xy 74.776709 -62.910874) (xy 74.785728 -62.911228) (xy 74.852784 -62.911228) (xy 74.861799 -62.910857)
			(xy 74.878716 -62.904618) (xy 74.885804 -62.899036) (xy 74.885804 -62.898782) (xy 74.886058 -62.898782)
			(xy 74.906991 -62.881141) (xy 74.952959 -62.851417) (xy 75.002705 -62.828571) (xy 75.055207 -62.813075)
			(xy 75.109385 -62.805246) (xy 75.164127 -62.805246) (xy 75.218305 -62.813075) (xy 75.270807 -62.828571)
			(xy 75.320553 -62.851417) (xy 75.366521 -62.881141) (xy 75.387454 -62.898782) (xy 75.387708 -62.899036)
			(xy 75.394785 -62.904636) (xy 75.411709 -62.910874) (xy 75.420728 -62.911228) (xy 75.487784 -62.911228)
			(xy 75.496799 -62.910857) (xy 75.513716 -62.904618) (xy 75.520804 -62.899036) (xy 75.520804 -62.898782)
			(xy 75.521058 -62.898782) (xy 75.541993 -62.881146) (xy 75.587965 -62.851435) (xy 75.637712 -62.828598)
			(xy 75.690212 -62.813106) (xy 75.744387 -62.805277) (xy 75.771756 -62.804802) (xy 75.799012 -62.805242)
			(xy 75.852969 -62.812994) (xy 75.905273 -62.828347) (xy 75.95486 -62.850987) (xy 76.00072 -62.880455)
			(xy 76.041919 -62.916149) (xy 76.077619 -62.957344) (xy 76.107092 -63.003201) (xy 76.129738 -63.052785)
			(xy 76.145097 -63.105088) (xy 76.152855 -63.159044) (xy 76.152855 -63.213556) (xy 76.145097 -63.267512)
			(xy 76.129738 -63.319815) (xy 76.107092 -63.369399) (xy 76.077619 -63.415256) (xy 76.041919 -63.456451)
			(xy 76.00072 -63.492145) (xy 75.95486 -63.521613) (xy 75.905273 -63.544253) (xy 75.852969 -63.559606)
			(xy 75.799012 -63.567358) (xy 75.771756 -63.567818) (xy 75.744386 -63.567339) (xy 75.690207 -63.559527)
			(xy 75.637703 -63.544042) (xy 75.587956 -63.521203) (xy 75.541989 -63.491479) (xy 75.521058 -63.473838)
			(xy 75.520804 -63.473584) (xy 75.513722 -63.467991) (xy 75.496802 -63.461749) (xy 75.487784 -63.461392)
			(xy 75.420728 -63.461392) (xy 75.411713 -63.461764) (xy 75.394796 -63.468001) (xy 75.387708 -63.473584)
			(xy 75.387454 -63.473838) (xy 75.366521 -63.491479) (xy 75.320553 -63.521203) (xy 75.270807 -63.544049)
			(xy 75.218305 -63.559545) (xy 75.164127 -63.567374) (xy 75.109385 -63.567374) (xy 75.055207 -63.559545)
			(xy 75.002705 -63.544049) (xy 74.952959 -63.521203) (xy 74.906991 -63.491479) (xy 74.886058 -63.473838)
			(xy 74.885804 -63.473584) (xy 74.878722 -63.467991) (xy 74.861802 -63.461749) (xy 74.852784 -63.461392)
			(xy 74.785728 -63.461392) (xy 74.776713 -63.461764) (xy 74.759796 -63.468001) (xy 74.752708 -63.473584)
			(xy 74.752708 -63.473838) (xy 74.752454 -63.473838) (xy 74.731518 -63.491472) (xy 74.685545 -63.521183)
			(xy 74.635799 -63.54402) (xy 74.583299 -63.559512) (xy 74.529125 -63.567343) (xy 74.501756 -63.567818)
			(xy 74.474508 -63.567309) (xy 74.420566 -63.559547) (xy 74.368278 -63.544189) (xy 74.318708 -63.521546)
			(xy 74.272864 -63.492079) (xy 74.23168 -63.456389) (xy 74.195994 -63.415201) (xy 74.166533 -63.369354)
			(xy 74.143896 -63.319781) (xy 74.128543 -63.267491) (xy 74.120788 -63.213549) (xy 65.376044 -63.213549)
			(xy 65.376044 -67.128953) (xy 66.366575 -67.128953) (xy 66.366575 -67.074447) (xy 66.374333 -67.020495)
			(xy 66.389691 -66.968196) (xy 66.412335 -66.918616) (xy 66.441806 -66.872763) (xy 66.477502 -66.831571)
			(xy 66.518698 -66.795879) (xy 66.564554 -66.766414) (xy 66.614137 -66.743775) (xy 66.666438 -66.728424)
			(xy 66.720391 -66.720672) (xy 66.747644 -66.720212) (xy 66.775013 -66.720708) (xy 66.829191 -66.728518)
			(xy 66.881694 -66.744) (xy 66.931441 -66.766835) (xy 66.977409 -66.796554) (xy 66.998342 -66.814192)
			(xy 66.998596 -66.814446) (xy 67.005676 -66.820043) (xy 67.022598 -66.826282) (xy 67.031616 -66.826638)
			(xy 67.098672 -66.826638) (xy 67.107686 -66.826259) (xy 67.124603 -66.820026) (xy 67.131692 -66.814446)
			(xy 67.131692 -66.814192) (xy 67.131946 -66.814192) (xy 67.152887 -66.796564) (xy 67.198857 -66.76685)
			(xy 67.248603 -66.744013) (xy 67.301101 -66.728519) (xy 67.355275 -66.720688) (xy 67.382644 -66.720212)
			(xy 67.409895 -66.720661) (xy 67.46384 -66.728423) (xy 67.516133 -66.743783) (xy 67.565707 -66.766427)
			(xy 67.611554 -66.795896) (xy 67.652741 -66.83159) (xy 67.68843 -66.872781) (xy 67.717894 -66.918632)
			(xy 67.740533 -66.968209) (xy 67.755887 -67.020503) (xy 67.763642 -67.074449) (xy 67.763642 -67.128951)
			(xy 67.755887 -67.182897) (xy 67.740533 -67.235191) (xy 67.717894 -67.284768) (xy 67.68843 -67.330619)
			(xy 67.652741 -67.37181) (xy 67.611554 -67.407504) (xy 67.565707 -67.436973) (xy 67.516133 -67.459617)
			(xy 67.46384 -67.474977) (xy 67.409895 -67.482739) (xy 67.382644 -67.483228) (xy 67.355274 -67.482754)
			(xy 67.301094 -67.474941) (xy 67.248591 -67.459454) (xy 67.198844 -67.436614) (xy 67.152877 -67.40689)
			(xy 67.131946 -67.389248) (xy 67.131692 -67.388994) (xy 67.124612 -67.383397) (xy 67.10769 -67.377157)
			(xy 67.098672 -67.376802) (xy 67.031616 -67.376802) (xy 67.0226 -67.377166) (xy 67.005683 -67.383409)
			(xy 66.998596 -67.388994) (xy 66.998596 -67.389248) (xy 66.998342 -67.389248) (xy 66.977398 -67.406873)
			(xy 66.931429 -67.436589) (xy 66.881685 -67.459428) (xy 66.829187 -67.474922) (xy 66.775013 -67.482753)
			(xy 66.747644 -67.483228) (xy 66.720391 -67.482728) (xy 66.666438 -67.474976) (xy 66.614137 -67.459625)
			(xy 66.564554 -67.436986) (xy 66.518698 -67.407521) (xy 66.477502 -67.371829) (xy 66.441806 -67.330637)
			(xy 66.412335 -67.284784) (xy 66.389691 -67.235204) (xy 66.374333 -67.182905) (xy 66.366575 -67.128953)
			(xy 65.376044 -67.128953) (xy 65.376044 -67.488054) (xy 70.77913 -67.488054) (xy 70.783201 -67.432432)
			(xy 70.795327 -67.377995) (xy 70.81525 -67.325904) (xy 70.842546 -67.277269) (xy 70.876632 -67.233126)
			(xy 70.916781 -67.194417) (xy 70.962139 -67.161966) (xy 71.011739 -67.136465) (xy 71.064523 -67.118458)
			(xy 71.119366 -67.108328) (xy 71.1751 -67.106291) (xy 71.230537 -67.112391) (xy 71.284494 -67.126497)
			(xy 71.335823 -67.148309) (xy 71.383429 -67.177363) (xy 71.426297 -67.213038) (xy 71.463514 -67.254575)
			(xy 71.494287 -67.301088) (xy 71.517959 -67.351585) (xy 71.534027 -67.404992) (xy 71.542147 -67.460168)
			(xy 71.542656 -67.488054) (xy 71.542147 -67.51594) (xy 71.538962 -67.537584) (xy 72.071228 -67.537584)
			(xy 72.075299 -67.481962) (xy 72.087425 -67.427525) (xy 72.107348 -67.375434) (xy 72.134644 -67.326799)
			(xy 72.16873 -67.282656) (xy 72.208879 -67.243947) (xy 72.254237 -67.211496) (xy 72.303837 -67.185995)
			(xy 72.356621 -67.167988) (xy 72.411464 -67.157858) (xy 72.467198 -67.155821) (xy 72.522635 -67.161921)
			(xy 72.576592 -67.176027) (xy 72.627921 -67.197839) (xy 72.675527 -67.226893) (xy 72.718395 -67.262568)
			(xy 72.755612 -67.304105) (xy 72.786385 -67.350618) (xy 72.810057 -67.401115) (xy 72.826125 -67.454522)
			(xy 72.834245 -67.509698) (xy 72.834754 -67.537584) (xy 72.834245 -67.56547) (xy 72.8302 -67.592956)
			(xy 73.345292 -67.592956) (xy 73.349363 -67.537334) (xy 73.361489 -67.482897) (xy 73.381412 -67.430806)
			(xy 73.408708 -67.382171) (xy 73.442794 -67.338028) (xy 73.482943 -67.299319) (xy 73.528301 -67.266868)
			(xy 73.577901 -67.241367) (xy 73.630685 -67.22336) (xy 73.685528 -67.21323) (xy 73.741262 -67.211193)
			(xy 73.796699 -67.217293) (xy 73.850656 -67.231399) (xy 73.901985 -67.253211) (xy 73.949591 -67.282265)
			(xy 73.992459 -67.31794) (xy 74.029676 -67.359477) (xy 74.060449 -67.40599) (xy 74.084121 -67.456487)
			(xy 74.100189 -67.509894) (xy 74.108306 -67.565052) (xy 76.446593 -67.565052) (xy 76.446593 -67.510548)
			(xy 76.45435 -67.4566) (xy 76.469707 -67.404304) (xy 76.492349 -67.354727) (xy 76.521818 -67.308877)
			(xy 76.557511 -67.267687) (xy 76.598704 -67.231997) (xy 76.644557 -67.202533) (xy 76.694136 -67.179895)
			(xy 76.746433 -67.164543) (xy 76.800382 -67.156791) (xy 76.827634 -67.15633) (xy 76.855005 -67.156769)
			(xy 76.909186 -67.164592) (xy 76.96169 -67.180087) (xy 77.011436 -67.202935) (xy 77.057401 -67.232666)
			(xy 77.078332 -67.25031) (xy 77.078586 -67.250564) (xy 77.085667 -67.256158) (xy 77.102588 -67.262399)
			(xy 77.111606 -67.262756) (xy 77.178662 -67.262756) (xy 77.187678 -67.26239) (xy 77.204596 -67.25615)
			(xy 77.211682 -67.250564) (xy 77.211682 -67.25031) (xy 77.211936 -67.25031) (xy 77.232883 -67.232689)
			(xy 77.278851 -67.202974) (xy 77.328595 -67.180135) (xy 77.381093 -67.164639) (xy 77.435266 -67.156806)
			(xy 77.462634 -67.15633) (xy 77.489886 -67.156742) (xy 77.543836 -67.164503) (xy 77.596132 -67.179863)
			(xy 77.64571 -67.202508) (xy 77.69156 -67.231978) (xy 77.732751 -67.267674) (xy 77.768442 -67.308867)
			(xy 77.797908 -67.35472) (xy 77.820549 -67.4043) (xy 77.835904 -67.456597) (xy 77.84366 -67.510548)
			(xy 77.84366 -67.565052) (xy 77.835904 -67.619003) (xy 77.820549 -67.6713) (xy 77.797908 -67.72088)
			(xy 77.768442 -67.766733) (xy 77.732751 -67.807926) (xy 77.69156 -67.843622) (xy 77.64571 -67.873092)
			(xy 77.596132 -67.895737) (xy 77.543836 -67.911097) (xy 77.489886 -67.918858) (xy 77.462634 -67.919346)
			(xy 77.435264 -67.918873) (xy 77.381085 -67.911059) (xy 77.328581 -67.895572) (xy 77.278834 -67.872732)
			(xy 77.232867 -67.843007) (xy 77.211936 -67.825366) (xy 77.211682 -67.825112) (xy 77.204604 -67.819513)
			(xy 77.187681 -67.813273) (xy 77.178662 -67.81292) (xy 77.111606 -67.81292) (xy 77.102589 -67.813275)
			(xy 77.085672 -67.819524) (xy 77.078586 -67.825112) (xy 77.078586 -67.825366) (xy 77.078332 -67.825366)
			(xy 77.057394 -67.842998) (xy 77.011424 -67.872712) (xy 76.961678 -67.89555) (xy 76.909178 -67.911043)
			(xy 76.855003 -67.918872) (xy 76.827634 -67.919346) (xy 76.800382 -67.918809) (xy 76.746433 -67.911057)
			(xy 76.694136 -67.895705) (xy 76.644557 -67.873067) (xy 76.598704 -67.843603) (xy 76.557511 -67.807913)
			(xy 76.521818 -67.766723) (xy 76.492349 -67.720873) (xy 76.469707 -67.671296) (xy 76.45435 -67.619)
			(xy 76.446593 -67.565052) (xy 74.108306 -67.565052) (xy 74.108309 -67.56507) (xy 74.108818 -67.592956)
			(xy 74.108309 -67.620842) (xy 74.100189 -67.676018) (xy 74.084121 -67.729425) (xy 74.060449 -67.779922)
			(xy 74.029676 -67.826435) (xy 73.992459 -67.867972) (xy 73.949591 -67.903647) (xy 73.901985 -67.932701)
			(xy 73.850656 -67.954513) (xy 73.796699 -67.968619) (xy 73.741262 -67.974719) (xy 73.685528 -67.972682)
			(xy 73.630685 -67.962552) (xy 73.577901 -67.944545) (xy 73.528301 -67.919044) (xy 73.482943 -67.886593)
			(xy 73.442794 -67.847884) (xy 73.408708 -67.803741) (xy 73.381412 -67.755106) (xy 73.361489 -67.703015)
			(xy 73.349363 -67.648578) (xy 73.345292 -67.592956) (xy 72.8302 -67.592956) (xy 72.826125 -67.620646)
			(xy 72.810057 -67.674053) (xy 72.786385 -67.72455) (xy 72.755612 -67.771063) (xy 72.718395 -67.8126)
			(xy 72.675527 -67.848275) (xy 72.627921 -67.877329) (xy 72.576592 -67.899141) (xy 72.522635 -67.913247)
			(xy 72.467198 -67.919347) (xy 72.411464 -67.91731) (xy 72.356621 -67.90718) (xy 72.303837 -67.889173)
			(xy 72.254237 -67.863672) (xy 72.208879 -67.831221) (xy 72.16873 -67.792512) (xy 72.134644 -67.748369)
			(xy 72.107348 -67.699734) (xy 72.087425 -67.647643) (xy 72.075299 -67.593206) (xy 72.071228 -67.537584)
			(xy 71.538962 -67.537584) (xy 71.534027 -67.571116) (xy 71.517959 -67.624523) (xy 71.494287 -67.67502)
			(xy 71.463514 -67.721533) (xy 71.426297 -67.76307) (xy 71.383429 -67.798745) (xy 71.335823 -67.827799)
			(xy 71.284494 -67.849611) (xy 71.230537 -67.863717) (xy 71.1751 -67.869817) (xy 71.119366 -67.86778)
			(xy 71.064523 -67.85765) (xy 71.011739 -67.839643) (xy 70.962139 -67.814142) (xy 70.916781 -67.781691)
			(xy 70.876632 -67.742982) (xy 70.842546 -67.698839) (xy 70.81525 -67.650204) (xy 70.795327 -67.598113)
			(xy 70.783201 -67.543676) (xy 70.77913 -67.488054) (xy 65.376044 -67.488054) (xy 65.376044 -68.586604)
			(xy 68.625212 -68.586604) (xy 68.625677 -68.559234) (xy 68.633495 -68.505054) (xy 68.648984 -68.452551)
			(xy 68.671826 -68.402804) (xy 68.701551 -68.356838) (xy 68.719192 -68.335906) (xy 68.719446 -68.335652)
			(xy 68.725023 -68.328559) (xy 68.731274 -68.311647) (xy 68.731638 -68.302632) (xy 68.731638 -68.235576)
			(xy 68.731284 -68.226559) (xy 68.725034 -68.209642) (xy 68.719446 -68.202556) (xy 68.719192 -68.202556)
			(xy 68.719192 -68.202302) (xy 68.701539 -68.181381) (xy 68.67183 -68.135405) (xy 68.648996 -68.085655)
			(xy 68.633509 -68.033152) (xy 68.625684 -67.978974) (xy 68.625212 -67.951604) (xy 68.625659 -67.92435)
			(xy 68.633416 -67.870398) (xy 68.648773 -67.818098) (xy 68.671416 -67.768517) (xy 68.700886 -67.722663)
			(xy 68.736581 -67.68147) (xy 68.777776 -67.645776) (xy 68.823631 -67.616308) (xy 68.873213 -67.593667)
			(xy 68.925513 -67.578313) (xy 68.979466 -67.570558) (xy 69.00672 -67.570096) (xy 69.033034 -67.570551)
			(xy 69.085163 -67.577789) (xy 69.135806 -67.59211) (xy 69.184005 -67.613245) (xy 69.228848 -67.640793)
			(xy 69.269488 -67.674234) (xy 69.287644 -67.693286) (xy 69.295149 -67.700707) (xy 69.314442 -67.709221)
			(xy 69.324982 -67.709796) (xy 69.399658 -67.709796) (xy 69.410207 -67.709259) (xy 69.429502 -67.70073)
			(xy 69.436996 -67.693286) (xy 69.455158 -67.674237) (xy 69.495786 -67.64078) (xy 69.540626 -67.61322)
			(xy 69.588825 -67.592081) (xy 69.639471 -67.577762) (xy 69.691604 -67.570535) (xy 69.71792 -67.570096)
			(xy 69.745291 -67.570551) (xy 69.79947 -67.578372) (xy 69.851973 -67.593864) (xy 69.90172 -67.616708)
			(xy 69.947686 -67.646434) (xy 69.968618 -67.664076) (xy 69.968872 -67.66433) (xy 69.97596 -67.669914)
			(xy 69.992876 -67.676161) (xy 70.001892 -67.676522) (xy 70.068948 -67.676522) (xy 70.077962 -67.676135)
			(xy 70.094879 -67.669908) (xy 70.101968 -67.66433) (xy 70.101968 -67.664076) (xy 70.102222 -67.664076)
			(xy 70.12317 -67.646456) (xy 70.169139 -67.616742) (xy 70.218882 -67.593903) (xy 70.271379 -67.578407)
			(xy 70.325552 -67.570573) (xy 70.35292 -67.570096) (xy 70.380172 -67.570559) (xy 70.434121 -67.578319)
			(xy 70.486416 -67.593676) (xy 70.535994 -67.61632) (xy 70.581844 -67.645789) (xy 70.623034 -67.681483)
			(xy 70.658725 -67.722675) (xy 70.688191 -67.768527) (xy 70.710832 -67.818106) (xy 70.726187 -67.870403)
			(xy 70.733943 -67.924352) (xy 70.734428 -67.951604) (xy 70.733982 -67.978975) (xy 70.726162 -68.033156)
			(xy 70.710669 -68.08566) (xy 70.687823 -68.135406) (xy 70.658092 -68.181372) (xy 70.640448 -68.202302)
			(xy 70.640194 -68.202556) (xy 70.634619 -68.209651) (xy 70.628366 -68.226561) (xy 70.628002 -68.235576)
			(xy 70.628002 -68.302632) (xy 70.628343 -68.31165) (xy 70.634602 -68.328567) (xy 70.640194 -68.335652)
			(xy 70.640448 -68.335652) (xy 70.640448 -68.335906) (xy 70.658095 -68.356832) (xy 70.687808 -68.402805)
			(xy 70.710643 -68.452554) (xy 70.726132 -68.505057) (xy 70.733956 -68.559234) (xy 70.734428 -68.586604)
			(xy 70.733926 -68.613854) (xy 70.726169 -68.667801) (xy 70.710815 -68.720094) (xy 70.694176 -68.75653)
			(xy 74.170286 -68.75653) (xy 74.170773 -68.729161) (xy 74.178586 -68.674983) (xy 74.194071 -68.62248)
			(xy 74.216908 -68.572733) (xy 74.246627 -68.526765) (xy 74.264266 -68.505832) (xy 74.26452 -68.505578)
			(xy 74.270124 -68.498504) (xy 74.27636 -68.481577) (xy 74.276712 -68.472558) (xy 74.276712 -68.405502)
			(xy 74.276351 -68.396486) (xy 74.270106 -68.379569) (xy 74.26452 -68.372482) (xy 74.264266 -68.372482)
			(xy 74.264266 -68.372228) (xy 74.246621 -68.351301) (xy 74.216911 -68.305326) (xy 74.194077 -68.255577)
			(xy 74.178587 -68.203076) (xy 74.17076 -68.148899) (xy 74.170286 -68.12153) (xy 74.170783 -68.094278)
			(xy 74.178536 -68.040329) (xy 74.193888 -67.988032) (xy 74.216526 -67.938452) (xy 74.245991 -67.892599)
			(xy 74.281681 -67.851406) (xy 74.32287 -67.815712) (xy 74.368721 -67.786244) (xy 74.418298 -67.7636)
			(xy 74.470594 -67.748244) (xy 74.524542 -67.740486) (xy 74.551794 -67.740022) (xy 74.579164 -67.740486)
			(xy 74.633344 -67.748304) (xy 74.685847 -67.763793) (xy 74.735594 -67.786635) (xy 74.781561 -67.81636)
			(xy 74.802492 -67.834002) (xy 74.802746 -67.834256) (xy 74.809839 -67.839833) (xy 74.826751 -67.846084)
			(xy 74.835766 -67.846448) (xy 74.902822 -67.846448) (xy 74.911841 -67.846113) (xy 74.928759 -67.839852)
			(xy 74.935842 -67.834256) (xy 74.935842 -67.834002) (xy 74.936096 -67.834002) (xy 74.957019 -67.816352)
			(xy 75.002994 -67.786641) (xy 75.052744 -67.763808) (xy 75.105247 -67.748319) (xy 75.159424 -67.740494)
			(xy 75.186794 -67.740022) (xy 75.213108 -67.740486) (xy 75.265237 -67.747721) (xy 75.31588 -67.76204)
			(xy 75.364079 -67.783173) (xy 75.408923 -67.81072) (xy 75.449562 -67.84416) (xy 75.467718 -67.863212)
			(xy 75.475229 -67.870625) (xy 75.494517 -67.879143) (xy 75.505056 -67.879722) (xy 75.579732 -67.879722)
			(xy 75.590278 -67.879163) (xy 75.609573 -67.870648) (xy 75.61707 -67.863212) (xy 75.63525 -67.84418)
			(xy 75.675874 -67.810721) (xy 75.720709 -67.783158) (xy 75.768905 -67.762015) (xy 75.819549 -67.747693)
			(xy 75.871679 -67.740463) (xy 75.897994 -67.740022) (xy 75.925248 -67.740461) (xy 75.979201 -67.748218)
			(xy 76.031502 -67.763575) (xy 76.081084 -67.786219) (xy 76.126938 -67.815689) (xy 76.168132 -67.851385)
			(xy 76.203826 -67.892581) (xy 76.233293 -67.938437) (xy 76.255934 -67.988021) (xy 76.271287 -68.040322)
			(xy 76.279041 -68.094276) (xy 76.279502 -68.12153) (xy 76.279053 -68.148901) (xy 76.271231 -68.203081)
			(xy 76.255738 -68.255584) (xy 76.232892 -68.30533) (xy 76.203165 -68.351297) (xy 76.185522 -68.372228)
			(xy 76.185268 -68.372482) (xy 76.179679 -68.379567) (xy 76.173435 -68.396485) (xy 76.173076 -68.405502)
			(xy 76.173076 -68.472558) (xy 76.173458 -68.481572) (xy 76.179689 -68.498489) (xy 76.185268 -68.505578)
			(xy 76.185522 -68.505578) (xy 76.185522 -68.505832) (xy 76.203146 -68.526776) (xy 76.232859 -68.572746)
			(xy 76.255698 -68.62249) (xy 76.271193 -68.674988) (xy 76.279025 -68.729162) (xy 76.279502 -68.75653)
			(xy 76.27905 -68.783782) (xy 76.271289 -68.837732) (xy 76.25593 -68.890027) (xy 76.233285 -68.939605)
			(xy 76.203815 -68.985456) (xy 76.16812 -69.026646) (xy 76.126927 -69.062337) (xy 76.081073 -69.091802)
			(xy 76.031493 -69.114443) (xy 75.979196 -69.129797) (xy 75.925246 -69.137553) (xy 75.897994 -69.138038)
			(xy 75.871679 -69.137594) (xy 75.819549 -69.130357) (xy 75.768905 -69.116035) (xy 75.720705 -69.094898)
			(xy 75.675863 -69.067347) (xy 75.635225 -69.033903) (xy 75.61707 -69.014848) (xy 75.609555 -69.007438)
			(xy 75.59027 -68.998917) (xy 75.579732 -68.998338) (xy 75.505056 -68.998338) (xy 75.494507 -68.998873)
			(xy 75.475211 -69.007403) (xy 75.467718 -69.014848) (xy 75.449556 -69.033897) (xy 75.408927 -69.067353)
			(xy 75.364087 -69.094912) (xy 75.315888 -69.116051) (xy 75.265242 -69.13037) (xy 75.21311 -69.137598)
			(xy 75.186794 -69.138038) (xy 75.159423 -69.137591) (xy 75.105242 -69.129771) (xy 75.052739 -69.114278)
			(xy 75.002992 -69.091432) (xy 74.957026 -69.061702) (xy 74.936096 -69.044058) (xy 74.935842 -69.043804)
			(xy 74.928747 -69.038229) (xy 74.911837 -69.031975) (xy 74.902822 -69.031612) (xy 74.835766 -69.031612)
			(xy 74.826747 -69.03195) (xy 74.80983 -69.038211) (xy 74.802746 -69.043804) (xy 74.802746 -69.044058)
			(xy 74.802492 -69.044058) (xy 74.781568 -69.061708) (xy 74.735594 -69.091419) (xy 74.685844 -69.114254)
			(xy 74.633342 -69.129742) (xy 74.579164 -69.137567) (xy 74.551794 -69.138038) (xy 74.524544 -69.137528)
			(xy 74.470599 -69.129771) (xy 74.418306 -69.114417) (xy 74.368731 -69.091777) (xy 74.322882 -69.062313)
			(xy 74.281693 -69.026624) (xy 74.246001 -68.985437) (xy 74.216534 -68.93959) (xy 74.193891 -68.890016)
			(xy 74.178534 -68.837725) (xy 74.170774 -68.78378) (xy 74.170286 -68.75653) (xy 70.694176 -68.75653)
			(xy 70.688175 -68.76967) (xy 70.65871 -68.815519) (xy 70.62302 -68.856709) (xy 70.581832 -68.8924)
			(xy 70.535984 -68.921867) (xy 70.486409 -68.944509) (xy 70.434116 -68.959866) (xy 70.38017 -68.967625)
			(xy 70.35292 -68.968112) (xy 70.32555 -68.967631) (xy 70.271372 -68.959817) (xy 70.218869 -68.944331)
			(xy 70.169122 -68.921492) (xy 70.123154 -68.891771) (xy 70.102222 -68.874132) (xy 70.101968 -68.873878)
			(xy 70.094868 -68.868311) (xy 70.077961 -68.862053) (xy 70.068948 -68.861686) (xy 70.001892 -68.861686)
			(xy 69.992875 -68.862042) (xy 69.975958 -68.868291) (xy 69.968872 -68.873878) (xy 69.968872 -68.874132)
			(xy 69.968618 -68.874132) (xy 69.947694 -68.891781) (xy 69.901719 -68.92149) (xy 69.851969 -68.944324)
			(xy 69.799467 -68.959813) (xy 69.74529 -68.967639) (xy 69.71792 -68.968112) (xy 69.691607 -68.967627)
			(xy 69.639479 -68.960396) (xy 69.588837 -68.94608) (xy 69.540638 -68.92495) (xy 69.495794 -68.897407)
			(xy 69.455153 -68.863972) (xy 69.436996 -68.844922) (xy 69.429475 -68.83752) (xy 69.410195 -68.828995)
			(xy 69.399658 -68.828412) (xy 69.324982 -68.828412) (xy 69.314435 -68.828968) (xy 69.295139 -68.837484)
			(xy 69.287644 -68.844922) (xy 69.269513 -68.864002) (xy 69.228878 -68.897456) (xy 69.184032 -68.925011)
			(xy 69.135826 -68.946145) (xy 69.085175 -68.960458) (xy 69.033037 -68.967677) (xy 69.00672 -68.968112)
			(xy 68.979468 -68.967626) (xy 68.925518 -68.959872) (xy 68.873221 -68.944519) (xy 68.823641 -68.921879)
			(xy 68.777788 -68.892413) (xy 68.736595 -68.856722) (xy 68.700901 -68.815531) (xy 68.671433 -68.76968)
			(xy 68.64879 -68.720102) (xy 68.633433 -68.667806) (xy 68.625676 -68.613856) (xy 68.625212 -68.586604)
			(xy 65.376044 -68.586604) (xy 65.376044 -71.555864) (xy 71.19442 -71.555864) (xy 71.198491 -71.500242)
			(xy 71.210617 -71.445805) (xy 71.23054 -71.393714) (xy 71.257836 -71.345079) (xy 71.291922 -71.300936)
			(xy 71.332071 -71.262227) (xy 71.377429 -71.229776) (xy 71.427029 -71.204275) (xy 71.479813 -71.186268)
			(xy 71.534656 -71.176138) (xy 71.59039 -71.174101) (xy 71.645827 -71.180201) (xy 71.699784 -71.194307)
			(xy 71.751113 -71.216119) (xy 71.798719 -71.245173) (xy 71.841587 -71.280848) (xy 71.878804 -71.322385)
			(xy 71.909577 -71.368898) (xy 71.933249 -71.419395) (xy 71.949317 -71.472802) (xy 71.957437 -71.527978)
			(xy 71.957946 -71.555864) (xy 71.957437 -71.58375) (xy 71.951598 -71.623428) (xy 72.703434 -71.623428)
			(xy 72.707505 -71.567806) (xy 72.719631 -71.513369) (xy 72.739554 -71.461278) (xy 72.76685 -71.412643)
			(xy 72.800936 -71.3685) (xy 72.841085 -71.329791) (xy 72.886443 -71.29734) (xy 72.936043 -71.271839)
			(xy 72.988827 -71.253832) (xy 73.04367 -71.243702) (xy 73.099404 -71.241665) (xy 73.154841 -71.247765)
			(xy 73.208798 -71.261871) (xy 73.260127 -71.283683) (xy 73.307733 -71.312737) (xy 73.350601 -71.348412)
			(xy 73.387818 -71.389949) (xy 73.418591 -71.436462) (xy 73.442263 -71.486959) (xy 73.458331 -71.540366)
			(xy 73.466451 -71.595542) (xy 73.46696 -71.623428) (xy 73.466451 -71.651314) (xy 73.458331 -71.70649)
			(xy 73.442263 -71.759897) (xy 73.418591 -71.810394) (xy 73.387818 -71.856907) (xy 73.350601 -71.898444)
			(xy 73.307733 -71.934119) (xy 73.260127 -71.963173) (xy 73.208798 -71.984985) (xy 73.154841 -71.999091)
			(xy 73.099404 -72.005191) (xy 73.04367 -72.003154) (xy 72.988827 -71.993024) (xy 72.936043 -71.975017)
			(xy 72.886443 -71.949516) (xy 72.841085 -71.917065) (xy 72.800936 -71.878356) (xy 72.76685 -71.834213)
			(xy 72.739554 -71.785578) (xy 72.719631 -71.733487) (xy 72.707505 -71.67905) (xy 72.703434 -71.623428)
			(xy 71.951598 -71.623428) (xy 71.949317 -71.638926) (xy 71.933249 -71.692333) (xy 71.909577 -71.74283)
			(xy 71.878804 -71.789343) (xy 71.841587 -71.83088) (xy 71.798719 -71.866555) (xy 71.751113 -71.895609)
			(xy 71.699784 -71.917421) (xy 71.645827 -71.931527) (xy 71.59039 -71.937627) (xy 71.534656 -71.93559)
			(xy 71.479813 -71.92546) (xy 71.427029 -71.907453) (xy 71.377429 -71.881952) (xy 71.332071 -71.849501)
			(xy 71.291922 -71.810792) (xy 71.257836 -71.766649) (xy 71.23054 -71.718014) (xy 71.210617 -71.665923)
			(xy 71.198491 -71.611486) (xy 71.19442 -71.555864) (xy 65.376044 -71.555864) (xy 65.376044 -75.155806)
			(xy 65.376552 -75.162918) (xy 66.274696 -76.061062) (xy 66.292728 -76.079833) (xy 66.323309 -76.12195)
			(xy 66.346938 -76.168326) (xy 66.363033 -76.217823) (xy 66.3712 -76.269226) (xy 66.371724 -76.29525)
			(xy 66.371724 -77.031088) (xy 66.371978 -79.871062) (xy 66.371393 -79.89858) (xy 66.362236 -79.95285)
			(xy 66.344264 -80.00487) (xy 66.336466 -80.019906) (xy 72.500742 -80.019906) (xy 72.504813 -79.964284)
			(xy 72.516939 -79.909847) (xy 72.536862 -79.857756) (xy 72.564158 -79.809121) (xy 72.598244 -79.764978)
			(xy 72.638393 -79.726269) (xy 72.683751 -79.693818) (xy 72.733351 -79.668317) (xy 72.786135 -79.65031)
			(xy 72.840978 -79.64018) (xy 72.896712 -79.638143) (xy 72.952149 -79.644243) (xy 73.006106 -79.658349)
			(xy 73.057435 -79.680161) (xy 73.105041 -79.709215) (xy 73.147909 -79.74489) (xy 73.185126 -79.786427)
			(xy 73.215899 -79.83294) (xy 73.239571 -79.883437) (xy 73.255639 -79.936844) (xy 73.263759 -79.99202)
			(xy 73.264268 -80.019906) (xy 73.263759 -80.047792) (xy 73.255639 -80.102968) (xy 73.239571 -80.156375)
			(xy 73.215899 -80.206872) (xy 73.185126 -80.253385) (xy 73.147909 -80.294922) (xy 73.105041 -80.330597)
			(xy 73.057435 -80.359651) (xy 73.006106 -80.381463) (xy 72.952149 -80.395569) (xy 72.896712 -80.401669)
			(xy 72.840978 -80.399632) (xy 72.786135 -80.389502) (xy 72.733351 -80.371495) (xy 72.683751 -80.345994)
			(xy 72.638393 -80.313543) (xy 72.598244 -80.274834) (xy 72.564158 -80.230691) (xy 72.536862 -80.182056)
			(xy 72.516939 -80.129965) (xy 72.504813 -80.075528) (xy 72.500742 -80.019906) (xy 66.336466 -80.019906)
			(xy 66.331592 -80.029304) (xy 66.331338 -80.029812) (xy 66.328666 -80.035284) (xy 66.325718 -80.047095)
			(xy 66.325496 -80.05318) (xy 66.325496 -80.557624) (xy 66.325068 -80.567692) (xy 66.317347 -80.58629)
			(xy 66.31051 -80.593692) (xy 62.309248 -84.594954) (xy 62.306539 -84.597803) (xy 62.30194 -84.604178)
			(xy 62.300104 -84.607654) (xy 62.297522 -84.613081) (xy 62.2947 -84.624761) (xy 62.294516 -84.630768)
			(xy 62.294516 -86.453726) (xy 62.294089 -86.463794) (xy 62.286369 -86.482394) (xy 62.27953 -86.489794)
			(xy 59.923934 -88.84539) (xy 59.921228 -88.848241) (xy 59.916634 -88.854619) (xy 59.91479 -88.85809)
			(xy 59.912212 -88.863518) (xy 59.9094 -88.875198) (xy 59.909202 -88.881204) (xy 59.909202 -91.854274)
			(xy 59.910218 -91.863672) (xy 59.910218 -91.86418) (xy 59.911923 -91.871339) (xy 59.918757 -91.884364)
			(xy 59.92368 -91.889834) (xy 60.821316 -92.78747) (xy 60.828728 -92.794154) (xy 60.847161 -92.801751)
			(xy 60.867099 -92.801751) (xy 60.885532 -92.794154) (xy 60.892944 -92.78747) (xy 78.607666 -75.072494)
			(xy 78.612646 -75.067063) (xy 78.619493 -75.054024) (xy 78.621128 -75.04684) (xy 78.622144 -75.036934)
			(xy 78.622144 -66.631058) (xy 78.621978 -66.625048) (xy 78.619158 -66.613364) (xy 78.616556 -66.607944)
			(xy 78.614713 -66.604472) (xy 78.610113 -66.5981) (xy 78.607412 -66.595244) (xy 77.432408 -65.42024)
			(xy 77.429525 -65.417435) (xy 77.423015 -65.412713) (xy 77.419454 -65.410842) (xy 77.411072 -65.40754)
			(xy 77.407593 -65.406589) (xy 77.400454 -65.405564) (xy 77.396848 -65.405508) (xy 74.4601 -65.405508)
			(xy 74.454092 -65.405681) (xy 74.442415 -65.408516) (xy 74.436986 -65.411096) (xy 74.433512 -65.412935)
			(xy 74.427132 -65.417528) (xy 74.424286 -65.42024) (xy 73.96607 -65.878456) (xy 73.947299 -65.896486)
			(xy 73.905181 -65.927062) (xy 73.858804 -65.950684) (xy 73.809307 -65.966771) (xy 73.757905 -65.974929)
			(xy 73.731882 -65.975484) (xy 73.05675 -65.975484) (xy 73.030726 -65.974957) (xy 72.979322 -65.966791)
			(xy 72.929824 -65.950698) (xy 72.883446 -65.927073) (xy 72.841325 -65.896496) (xy 72.822562 -65.878456)
			(xy 72.417686 -65.47358) (xy 72.407018 -65.46723) (xy 72.401176 -65.465452) (xy 72.375581 -65.456998)
			(xy 72.326883 -65.433894) (xy 72.28192 -65.404167) (xy 72.241588 -65.368409) (xy 72.206689 -65.327331)
			(xy 72.177918 -65.28175) (xy 72.155847 -65.232575) (xy 72.140915 -65.180783) (xy 72.133421 -65.127405)
			(xy 72.132952 -65.100454) (xy 72.132952 -65.092834) (xy 72.13473 -65.063116) (xy 72.134984 -65.060576)
			(xy 72.134476 -65.050924) (xy 72.133427 -65.042774) (xy 72.126819 -65.027741) (xy 72.121522 -65.02146)
			(xy 72.078596 -64.9732) (xy 72.070468 -64.964056) (xy 72.065772 -64.959715) (xy 72.054719 -64.953293)
			(xy 72.048624 -64.951356) (xy 72.048116 -64.951102) (xy 72.040242 -64.948816) (xy 71.515224 -64.948816)
			(xy 71.510334 -64.948955) (xy 71.500743 -64.950878) (xy 71.496174 -64.952626) (xy 71.486522 -64.956436)
			(xy 71.47941 -64.963802) (xy 70.460362 -65.983104) (xy 70.447916 -65.995042) (xy 70.4469 -65.995804)
			(xy 70.446138 -65.996566) (xy 70.427532 -66.013501) (xy 70.386166 -66.042135) (xy 70.340955 -66.064206)
			(xy 70.292935 -66.079208) (xy 70.243201 -66.0868) (xy 70.218046 -66.087244) (xy 66.917316 -66.087244)
			(xy 66.913506 -66.089276) (xy 66.885016 -66.104275) (xy 66.824253 -66.125558) (xy 66.760785 -66.13636)
			(xy 66.728594 -66.137028) (xy 66.701342 -66.136542) (xy 66.647392 -66.128784) (xy 66.595095 -66.113428)
			(xy 66.545516 -66.090785) (xy 66.499664 -66.061317) (xy 66.458472 -66.025624) (xy 66.422779 -65.984431)
			(xy 66.393312 -65.938579) (xy 66.37067 -65.888999) (xy 66.355315 -65.836702) (xy 66.347558 -65.782752)
			(xy 66.347558 -65.728248) (xy 66.355315 -65.674298) (xy 66.37067 -65.622001) (xy 66.393312 -65.572421)
			(xy 66.422779 -65.526569) (xy 66.458472 -65.485376) (xy 66.499664 -65.449683) (xy 66.545516 -65.420215)
			(xy 66.595095 -65.397572) (xy 66.647392 -65.382216) (xy 66.701342 -65.374458) (xy 66.728594 -65.374012)
			(xy 66.760785 -65.374679) (xy 66.824255 -65.385476) (xy 66.885014 -65.406767) (xy 66.913506 -65.421764)
			(xy 66.917316 -65.423796) (xy 70.05955 -65.423796) (xy 70.068694 -65.423034) (xy 70.076186 -65.421405)
			(xy 70.089761 -65.414297) (xy 70.095364 -65.409064) (xy 71.121778 -64.382396) (xy 71.140549 -64.364365)
			(xy 71.182667 -64.333787) (xy 71.229043 -64.310161) (xy 71.27854 -64.294069) (xy 71.329943 -64.285904)
			(xy 71.355966 -64.285368) (xy 77.208888 -64.285368) (xy 77.214896 -64.285196) (xy 77.226574 -64.282363)
			(xy 77.232002 -64.27978) (xy 77.235476 -64.277941) (xy 77.241855 -64.273347) (xy 77.244702 -64.270636)
			(xy 77.397356 -64.117982) (xy 77.400061 -64.115131) (xy 77.404653 -64.108752) (xy 77.4065 -64.105282)
			(xy 77.409086 -64.099856) (xy 77.411915 -64.088176) (xy 77.412088 -64.082168) (xy 77.412088 -58.106564)
			(xy 77.407262 -58.101992) (xy 77.033628 -57.728612) (xy 77.017296 -57.711692) (xy 76.989261 -57.673935)
			(xy 76.967042 -57.632489) (xy 76.958698 -57.610502) (xy 76.949794 -57.584014) (xy 76.94021 -57.528966)
			(xy 76.939648 -57.501028) (xy 76.939648 -56.96966) (xy 76.936854 -56.961532) (xy 76.928679 -56.935688)
			(xy 76.919878 -56.882207) (xy 76.919328 -56.855106) (xy 76.919328 -56.567832) (xy 76.909168 -56.561736)
			(xy 76.81341 -56.526938) (xy 76.806622 -56.525117) (xy 76.792576 -56.524867) (xy 76.785724 -56.52643)
			(xy 76.778612 -56.528462) (xy 76.765658 -56.53659) (xy 76.760324 -56.54294) (xy 76.742092 -56.563797)
			(xy 76.700638 -56.600543) (xy 76.654307 -56.63091) (xy 76.604073 -56.654261) (xy 76.550991 -56.670105)
			(xy 76.496176 -56.67811) (xy 76.468478 -56.678576) (xy 76.441227 -56.678111) (xy 76.38728 -56.670351)
			(xy 76.334987 -56.654993) (xy 76.285411 -56.632349) (xy 76.239563 -56.60288) (xy 76.198376 -56.567186)
			(xy 76.162688 -56.525993) (xy 76.133225 -56.480141) (xy 76.110588 -56.430563) (xy 76.095237 -56.378267)
			(xy 76.087485 -56.324319) (xy 76.08697 -56.297068) (xy 76.08747 -56.269328) (xy 76.095506 -56.214433)
			(xy 76.111404 -56.161279) (xy 76.134829 -56.110987) (xy 76.165288 -56.064616) (xy 76.202139 -56.023142)
			(xy 76.244606 -55.98744) (xy 76.291793 -55.958261) (xy 76.342708 -55.936221) (xy 76.396276 -55.921783)
			(xy 76.423774 -55.9181) (xy 76.438506 -55.916576) (xy 76.468478 -55.915306) (xy 76.488798 -55.915306)
			(xy 76.500736 -55.916576) (xy 76.501244 -55.916576) (xy 76.530709 -55.919673) (xy 76.588238 -55.933819)
			(xy 76.642885 -55.956697) (xy 76.693335 -55.987755) (xy 76.738371 -56.026246) (xy 76.758038 -56.048402)
			(xy 76.759308 -56.049926) (xy 76.763626 -56.054244) (xy 76.770192 -56.060363) (xy 76.786464 -56.067905)
			(xy 76.795376 -56.068976) (xy 76.800871 -56.069243) (xy 76.811763 -56.067713) (xy 76.816966 -56.065928)
			(xy 76.827634 -56.062118) (xy 76.908914 -56.0324) (xy 76.919328 -56.026304) (xy 76.919328 -55.10911)
			(xy 76.919813 -55.083022) (xy 76.927978 -55.03149) (xy 76.944109 -54.98187) (xy 76.967807 -54.935387)
			(xy 76.998489 -54.893187) (xy 77.01661 -54.874414) (xy 78.961488 -52.92979) (xy 78.965298 -52.919122)
			(xy 78.975212 -52.893659) (xy 79.001279 -52.845637) (xy 79.033929 -52.801824) (xy 79.072496 -52.763116)
			(xy 79.116189 -52.730305) (xy 79.164116 -52.704063) (xy 79.215296 -52.684925) (xy 79.268683 -52.673284)
			(xy 79.323184 -52.669377) (xy 79.377685 -52.673284) (xy 79.431072 -52.684925) (xy 79.482252 -52.704063)
			(xy 79.530179 -52.730305) (xy 79.573872 -52.763116) (xy 79.612439 -52.801824) (xy 79.645089 -52.845637)
			(xy 79.671156 -52.893659) (xy 79.68107 -52.919122) (xy 79.68488 -52.92979) (xy 80.151986 -53.396642)
			(xy 80.1701 -53.415422) (xy 80.200786 -53.457619) (xy 80.22064 -53.496556) (xy 84.133341 -53.496556)
			(xy 84.133341 -53.442044) (xy 84.141099 -53.388088) (xy 84.156458 -53.335786) (xy 84.179104 -53.286201)
			(xy 84.208576 -53.240345) (xy 84.244275 -53.199149) (xy 84.285474 -53.163454) (xy 84.331333 -53.133986)
			(xy 84.380919 -53.111345) (xy 84.433224 -53.095992) (xy 84.48718 -53.088238) (xy 84.514436 -53.087778)
			(xy 84.541808 -53.088204) (xy 84.595989 -53.096029) (xy 84.648494 -53.111526) (xy 84.69824 -53.134377)
			(xy 84.744204 -53.164112) (xy 84.765134 -53.181758) (xy 84.765388 -53.182012) (xy 84.772473 -53.187601)
			(xy 84.789391 -53.193846) (xy 84.798408 -53.194204) (xy 84.865464 -53.194204) (xy 84.874479 -53.193829)
			(xy 84.891396 -53.187594) (xy 84.898484 -53.182012) (xy 84.898484 -53.181758) (xy 84.898738 -53.181758)
			(xy 84.919677 -53.164128) (xy 84.965648 -53.134416) (xy 85.015394 -53.111579) (xy 85.067893 -53.096085)
			(xy 85.122067 -53.088254) (xy 85.149436 -53.087778) (xy 85.176685 -53.088295) (xy 85.230626 -53.096055)
			(xy 85.282915 -53.111413) (xy 85.332486 -53.134055) (xy 85.37833 -53.163521) (xy 85.419514 -53.199211)
			(xy 85.4552 -53.240399) (xy 85.484662 -53.286246) (xy 85.5073 -53.335819) (xy 85.522653 -53.388109)
			(xy 85.530408 -53.442051) (xy 85.530408 -53.496549) (xy 85.522653 -53.550491) (xy 85.5073 -53.602781)
			(xy 85.484662 -53.652354) (xy 85.4552 -53.698201) (xy 85.419514 -53.739389) (xy 85.37833 -53.775079)
			(xy 85.332486 -53.804545) (xy 85.282915 -53.827187) (xy 85.230626 -53.842545) (xy 85.176685 -53.850305)
			(xy 85.149436 -53.850794) (xy 85.122066 -53.850308) (xy 85.067888 -53.842495) (xy 85.015385 -53.827011)
			(xy 84.965638 -53.804174) (xy 84.91967 -53.774453) (xy 84.898738 -53.756814) (xy 84.898484 -53.75656)
			(xy 84.89141 -53.750956) (xy 84.874483 -53.744721) (xy 84.865464 -53.744368) (xy 84.798408 -53.744368)
			(xy 84.789392 -53.744736) (xy 84.772476 -53.750977) (xy 84.765388 -53.75656) (xy 84.765388 -53.756814)
			(xy 84.765134 -53.756814) (xy 84.744202 -53.774453) (xy 84.698229 -53.804164) (xy 84.648481 -53.827)
			(xy 84.595981 -53.842491) (xy 84.541805 -53.85032) (xy 84.514436 -53.850794) (xy 84.48718 -53.850362)
			(xy 84.433224 -53.842608) (xy 84.380919 -53.827255) (xy 84.331333 -53.804614) (xy 84.285474 -53.775146)
			(xy 84.244275 -53.739451) (xy 84.208576 -53.698255) (xy 84.179104 -53.652399) (xy 84.156458 -53.602814)
			(xy 84.141099 -53.550512) (xy 84.133341 -53.496556) (xy 80.22064 -53.496556) (xy 80.224487 -53.5041)
			(xy 80.240618 -53.553718) (xy 80.248781 -53.605251) (xy 80.249268 -53.631338) (xy 80.249268 -54.989055)
			(xy 81.900945 -54.989055) (xy 81.900945 -54.934545) (xy 81.908703 -54.88059) (xy 81.924061 -54.828288)
			(xy 81.946706 -54.778705) (xy 81.976178 -54.732849) (xy 82.011876 -54.691654) (xy 82.053073 -54.65596)
			(xy 82.098931 -54.626492) (xy 82.148516 -54.60385) (xy 82.200819 -54.588497) (xy 82.254775 -54.580743)
			(xy 82.28203 -54.580282) (xy 82.310122 -54.580753) (xy 82.365701 -54.588985) (xy 82.41947 -54.60528)
			(xy 82.470268 -54.629286) (xy 82.516994 -54.660485) (xy 82.558639 -54.6982) (xy 82.5943 -54.741616)
			(xy 82.609182 -54.765448) (xy 82.614516 -54.774338) (xy 82.631534 -54.78653) (xy 82.724752 -54.80685)
			(xy 82.745326 -54.802532) (xy 82.753962 -54.79669) (xy 82.778034 -54.780703) (xy 82.829963 -54.755357)
			(xy 82.885118 -54.738128) (xy 82.94224 -54.729409) (xy 82.971132 -54.728872) (xy 82.998383 -54.729348)
			(xy 83.05233 -54.737108) (xy 83.104624 -54.752467) (xy 83.1542 -54.77511) (xy 83.200049 -54.804578)
			(xy 83.241238 -54.84027) (xy 83.27693 -54.88146) (xy 83.306396 -54.927311) (xy 83.329038 -54.976887)
			(xy 83.344394 -55.029182) (xy 83.352153 -55.083129) (xy 83.35264 -55.11038) (xy 83.352177 -55.137751)
			(xy 83.344361 -55.19193) (xy 83.328872 -55.244434) (xy 83.306029 -55.294181) (xy 83.276302 -55.340147)
			(xy 83.25866 -55.361078) (xy 83.258406 -55.361332) (xy 83.252842 -55.368434) (xy 83.246582 -55.385339)
			(xy 83.246214 -55.394352) (xy 83.246214 -55.461408) (xy 83.246564 -55.470426) (xy 83.252816 -55.487343)
			(xy 83.258406 -55.494428) (xy 83.25866 -55.494428) (xy 83.25866 -55.494682) (xy 83.276282 -55.51563)
			(xy 83.306008 -55.561595) (xy 83.328856 -55.611339) (xy 83.344354 -55.663839) (xy 83.352185 -55.718015)
			(xy 83.352187 -55.772755) (xy 83.34436 -55.826932) (xy 83.328866 -55.879433) (xy 83.306023 -55.929178)
			(xy 83.2763 -55.975146) (xy 83.25866 -55.996078) (xy 83.258406 -55.996332) (xy 83.252842 -56.003434)
			(xy 83.246582 -56.020339) (xy 83.246214 -56.029352) (xy 83.246214 -56.096408) (xy 83.246564 -56.105426)
			(xy 83.252816 -56.122343) (xy 83.258406 -56.129428) (xy 83.25866 -56.129428) (xy 83.25866 -56.129682)
			(xy 83.276298 -56.150615) (xy 83.306011 -56.196587) (xy 83.328848 -56.246334) (xy 83.344339 -56.298835)
			(xy 83.352167 -56.353011) (xy 83.35264 -56.38038) (xy 83.352154 -56.407631) (xy 83.344398 -56.461579)
			(xy 83.329043 -56.513874) (xy 83.306401 -56.563451) (xy 83.276935 -56.609301) (xy 83.241244 -56.650492)
			(xy 83.200053 -56.686183) (xy 83.154203 -56.715649) (xy 83.104626 -56.738291) (xy 83.052331 -56.753646)
			(xy 82.998383 -56.761402) (xy 82.943881 -56.761402) (xy 82.889933 -56.753646) (xy 82.837638 -56.738291)
			(xy 82.788061 -56.715649) (xy 82.742211 -56.686183) (xy 82.70102 -56.650492) (xy 82.665329 -56.609301)
			(xy 82.635863 -56.563451) (xy 82.613221 -56.513874) (xy 82.597866 -56.461579) (xy 82.59011 -56.407631)
			(xy 82.589624 -56.38038) (xy 82.590072 -56.353009) (xy 82.597894 -56.298829) (xy 82.613387 -56.246325)
			(xy 82.636232 -56.196579) (xy 82.665961 -56.150613) (xy 82.683604 -56.129682) (xy 82.683858 -56.129428)
			(xy 82.689446 -56.122343) (xy 82.69569 -56.105425) (xy 82.69605 -56.096408) (xy 82.69605 -56.029352)
			(xy 82.695679 -56.020336) (xy 82.689442 -56.003419) (xy 82.683858 -55.996332) (xy 82.683604 -55.996332)
			(xy 82.683604 -55.996078) (xy 82.665945 -55.975161) (xy 82.636222 -55.92919) (xy 82.61338 -55.879441)
			(xy 82.597886 -55.826936) (xy 82.59006 -55.772756) (xy 82.590062 -55.718014) (xy 82.597892 -55.663834)
			(xy 82.61339 -55.611331) (xy 82.636237 -55.561584) (xy 82.665963 -55.515615) (xy 82.683604 -55.494682)
			(xy 82.683858 -55.494428) (xy 82.689446 -55.487343) (xy 82.69569 -55.470425) (xy 82.69605 -55.461408)
			(xy 82.69605 -55.394352) (xy 82.695679 -55.385336) (xy 82.689442 -55.368419) (xy 82.683858 -55.361332)
			(xy 82.683604 -55.360824) (xy 82.672661 -55.348089) (xy 82.652819 -55.320998) (xy 82.64398 -55.306722)
			(xy 82.638646 -55.297832) (xy 82.621628 -55.28564) (xy 82.52841 -55.26532) (xy 82.507836 -55.269638)
			(xy 82.4992 -55.27548) (xy 82.475136 -55.29148) (xy 82.423205 -55.316823) (xy 82.368047 -55.334049)
			(xy 82.310923 -55.342764) (xy 82.28203 -55.343298) (xy 82.254775 -55.342857) (xy 82.200819 -55.335103)
			(xy 82.148516 -55.31975) (xy 82.098931 -55.297108) (xy 82.053073 -55.26764) (xy 82.011876 -55.231946)
			(xy 81.976178 -55.190751) (xy 81.946706 -55.144895) (xy 81.924061 -55.095312) (xy 81.908703 -55.04301)
			(xy 81.900945 -54.989055) (xy 80.249268 -54.989055) (xy 80.249268 -55.03672) (xy 80.253586 -55.039768)
			(xy 80.293464 -55.061104) (xy 80.293972 -55.061104) (xy 80.333596 -55.081932) (xy 80.342571 -55.086206)
			(xy 80.362348 -55.088056) (xy 80.37195 -55.085488) (xy 80.387698 -55.080154) (xy 80.393286 -55.076344)
			(xy 80.416886 -55.061145) (xy 80.467602 -55.037087) (xy 80.521293 -55.020713) (xy 80.576803 -55.012375)
			(xy 80.604868 -55.011828) (xy 80.616552 -55.012082) (xy 80.646088 -55.01349) (xy 80.704222 -55.024285)
			(xy 80.759999 -55.043907) (xy 80.812087 -55.071887) (xy 80.859243 -55.107557) (xy 80.880204 -55.128414)
			(xy 80.887062 -55.135526) (xy 80.913986 -55.147464) (xy 80.918767 -55.149441) (xy 80.928881 -55.151607)
			(xy 80.934052 -55.151782) (xy 80.983582 -55.151782) (xy 80.994504 -55.150512) (xy 81.00314 -55.148734)
			(xy 81.012792 -55.145686) (xy 81.035652 -55.135526) (xy 81.04251 -55.128414) (xy 81.060539 -55.110347)
			(xy 81.100589 -55.078704) (xy 81.144501 -55.052687) (xy 81.191492 -55.032761) (xy 81.240722 -55.019281)
			(xy 81.291309 -55.012489) (xy 81.31683 -55.012082) (xy 81.344081 -55.01257) (xy 81.398026 -55.02033)
			(xy 81.450319 -55.035688) (xy 81.499894 -55.058332) (xy 81.545742 -55.087799) (xy 81.586929 -55.123492)
			(xy 81.622619 -55.164682) (xy 81.652083 -55.210533) (xy 81.674722 -55.260109) (xy 81.690076 -55.312403)
			(xy 81.697832 -55.366349) (xy 81.697832 -55.420851) (xy 81.690076 -55.474797) (xy 81.674722 -55.527091)
			(xy 81.652083 -55.576667) (xy 81.622619 -55.622518) (xy 81.586929 -55.663708) (xy 81.545742 -55.699401)
			(xy 81.499894 -55.728868) (xy 81.450319 -55.751512) (xy 81.398026 -55.76687) (xy 81.344081 -55.77463)
			(xy 81.31683 -55.775098) (xy 81.291343 -55.774669) (xy 81.240824 -55.767874) (xy 81.19166 -55.754413)
			(xy 81.144725 -55.734526) (xy 81.100856 -55.708568) (xy 81.060833 -55.677001) (xy 81.042764 -55.65902)
			(xy 81.042002 -55.658258) (xy 81.038699 -55.655067) (xy 81.03116 -55.649823) (xy 81.027016 -55.647844)
			(xy 81.008474 -55.639716) (xy 80.998568 -55.635398) (xy 80.939386 -55.635398) (xy 80.92948 -55.636414)
			(xy 80.91932 -55.6387) (xy 80.909414 -55.641748) (xy 80.886808 -55.651654) (xy 80.879696 -55.65902)
			(xy 80.861659 -55.677036) (xy 80.821634 -55.708608) (xy 80.777759 -55.734567) (xy 80.730817 -55.754449)
			(xy 80.681645 -55.767901) (xy 80.63112 -55.774683) (xy 80.60563 -55.775098) (xy 80.569562 -55.773574)
			(xy 80.560926 -55.772558) (xy 80.530156 -55.768288) (xy 80.47047 -55.751078) (xy 80.41435 -55.724448)
			(xy 80.38846 -55.70728) (xy 80.38211 -55.702962) (xy 80.370172 -55.698644) (xy 80.36306 -55.69839)
			(xy 80.357145 -55.698134) (xy 80.345466 -55.700059) (xy 80.339946 -55.7022) (xy 80.268826 -55.739284)
			(xy 80.256126 -55.745888) (xy 80.249268 -55.750206) (xy 80.249268 -57.48528) (xy 82.605878 -57.48528)
			(xy 82.609949 -57.429658) (xy 82.622075 -57.375221) (xy 82.641998 -57.32313) (xy 82.669294 -57.274495)
			(xy 82.70338 -57.230352) (xy 82.743529 -57.191643) (xy 82.788887 -57.159192) (xy 82.838487 -57.133691)
			(xy 82.891271 -57.115684) (xy 82.946114 -57.105554) (xy 83.001848 -57.103517) (xy 83.057285 -57.109617)
			(xy 83.111242 -57.123723) (xy 83.162571 -57.145535) (xy 83.210177 -57.174589) (xy 83.253045 -57.210264)
			(xy 83.290262 -57.251801) (xy 83.321035 -57.298314) (xy 83.344707 -57.348811) (xy 83.360775 -57.402218)
			(xy 83.368895 -57.457394) (xy 83.369404 -57.48528) (xy 83.368895 -57.513166) (xy 83.360775 -57.568342)
			(xy 83.344707 -57.621749) (xy 83.321035 -57.672246) (xy 83.290262 -57.718759) (xy 83.253045 -57.760296)
			(xy 83.210177 -57.795971) (xy 83.162571 -57.825025) (xy 83.111242 -57.846837) (xy 83.057285 -57.860943)
			(xy 83.001848 -57.867043) (xy 82.946114 -57.865006) (xy 82.891271 -57.854876) (xy 82.838487 -57.836869)
			(xy 82.788887 -57.811368) (xy 82.743529 -57.778917) (xy 82.70338 -57.740208) (xy 82.669294 -57.696065)
			(xy 82.641998 -57.64743) (xy 82.622075 -57.595339) (xy 82.609949 -57.540902) (xy 82.605878 -57.48528)
			(xy 80.249268 -57.48528) (xy 80.249268 -58.561224) (xy 84.562186 -58.561224) (xy 84.566257 -58.505602)
			(xy 84.578383 -58.451165) (xy 84.598306 -58.399074) (xy 84.625602 -58.350439) (xy 84.659688 -58.306296)
			(xy 84.699837 -58.267587) (xy 84.745195 -58.235136) (xy 84.794795 -58.209635) (xy 84.847579 -58.191628)
			(xy 84.902422 -58.181498) (xy 84.958156 -58.179461) (xy 85.013593 -58.185561) (xy 85.06755 -58.199667)
			(xy 85.118879 -58.221479) (xy 85.166485 -58.250533) (xy 85.209353 -58.286208) (xy 85.24657 -58.327745)
			(xy 85.277343 -58.374258) (xy 85.301015 -58.424755) (xy 85.308525 -58.449718) (xy 86.808816 -58.449718)
			(xy 86.812887 -58.394096) (xy 86.825013 -58.339659) (xy 86.844936 -58.287568) (xy 86.872232 -58.238933)
			(xy 86.906318 -58.19479) (xy 86.946467 -58.156081) (xy 86.991825 -58.12363) (xy 87.041425 -58.098129)
			(xy 87.094209 -58.080122) (xy 87.149052 -58.069992) (xy 87.204786 -58.067955) (xy 87.260223 -58.074055)
			(xy 87.31418 -58.088161) (xy 87.365509 -58.109973) (xy 87.413115 -58.139027) (xy 87.455983 -58.174702)
			(xy 87.4932 -58.216239) (xy 87.523973 -58.262752) (xy 87.547645 -58.313249) (xy 87.563713 -58.366656)
			(xy 87.571833 -58.421832) (xy 87.572342 -58.449718) (xy 87.571833 -58.477604) (xy 87.563713 -58.53278)
			(xy 87.547645 -58.586187) (xy 87.523973 -58.636684) (xy 87.4932 -58.683197) (xy 87.455983 -58.724734)
			(xy 87.413115 -58.760409) (xy 87.365509 -58.789463) (xy 87.31418 -58.811275) (xy 87.260223 -58.825381)
			(xy 87.204786 -58.831481) (xy 87.149052 -58.829444) (xy 87.094209 -58.819314) (xy 87.041425 -58.801307)
			(xy 86.991825 -58.775806) (xy 86.946467 -58.743355) (xy 86.906318 -58.704646) (xy 86.872232 -58.660503)
			(xy 86.844936 -58.611868) (xy 86.825013 -58.559777) (xy 86.812887 -58.50534) (xy 86.808816 -58.449718)
			(xy 85.308525 -58.449718) (xy 85.317083 -58.478162) (xy 85.325203 -58.533338) (xy 85.325712 -58.561224)
			(xy 85.325203 -58.58911) (xy 85.317083 -58.644286) (xy 85.301015 -58.697693) (xy 85.277343 -58.74819)
			(xy 85.24657 -58.794703) (xy 85.209353 -58.83624) (xy 85.166485 -58.871915) (xy 85.118879 -58.900969)
			(xy 85.06755 -58.922781) (xy 85.013593 -58.936887) (xy 84.958156 -58.942987) (xy 84.902422 -58.94095)
			(xy 84.847579 -58.93082) (xy 84.794795 -58.912813) (xy 84.745195 -58.887312) (xy 84.699837 -58.854861)
			(xy 84.659688 -58.816152) (xy 84.625602 -58.772009) (xy 84.598306 -58.723374) (xy 84.578383 -58.671283)
			(xy 84.566257 -58.616846) (xy 84.562186 -58.561224) (xy 80.249268 -58.561224) (xy 80.249268 -59.174634)
			(xy 83.09305 -59.174634) (xy 83.097121 -59.119012) (xy 83.109247 -59.064575) (xy 83.12917 -59.012484)
			(xy 83.156466 -58.963849) (xy 83.190552 -58.919706) (xy 83.230701 -58.880997) (xy 83.276059 -58.848546)
			(xy 83.325659 -58.823045) (xy 83.378443 -58.805038) (xy 83.433286 -58.794908) (xy 83.48902 -58.792871)
			(xy 83.544457 -58.798971) (xy 83.598414 -58.813077) (xy 83.649743 -58.834889) (xy 83.697349 -58.863943)
			(xy 83.740217 -58.899618) (xy 83.777434 -58.941155) (xy 83.808207 -58.987668) (xy 83.831879 -59.038165)
			(xy 83.847947 -59.091572) (xy 83.856067 -59.146748) (xy 83.856576 -59.174634) (xy 83.856067 -59.20252)
			(xy 83.847947 -59.257696) (xy 83.831879 -59.311103) (xy 83.808207 -59.3616) (xy 83.777434 -59.408113)
			(xy 83.740217 -59.44965) (xy 83.697349 -59.485325) (xy 83.649743 -59.514379) (xy 83.598414 -59.536191)
			(xy 83.544457 -59.550297) (xy 83.48902 -59.556397) (xy 83.433286 -59.55436) (xy 83.378443 -59.54423)
			(xy 83.325659 -59.526223) (xy 83.276059 -59.500722) (xy 83.230701 -59.468271) (xy 83.190552 -59.429562)
			(xy 83.156466 -59.385419) (xy 83.12917 -59.336784) (xy 83.109247 -59.284693) (xy 83.097121 -59.230256)
			(xy 83.09305 -59.174634) (xy 80.249268 -59.174634) (xy 80.249268 -60.633356) (xy 85.79688 -60.633356)
			(xy 85.800951 -60.577734) (xy 85.813077 -60.523297) (xy 85.833 -60.471206) (xy 85.860296 -60.422571)
			(xy 85.894382 -60.378428) (xy 85.934531 -60.339719) (xy 85.979889 -60.307268) (xy 86.029489 -60.281767)
			(xy 86.082273 -60.26376) (xy 86.137116 -60.25363) (xy 86.19285 -60.251593) (xy 86.248287 -60.257693)
			(xy 86.302244 -60.271799) (xy 86.353573 -60.293611) (xy 86.401179 -60.322665) (xy 86.444047 -60.35834)
			(xy 86.481264 -60.399877) (xy 86.512037 -60.44639) (xy 86.535709 -60.496887) (xy 86.551777 -60.550294)
			(xy 86.559897 -60.60547) (xy 86.560406 -60.633356) (xy 86.559897 -60.661242) (xy 86.551777 -60.716418)
			(xy 86.535709 -60.769825) (xy 86.512037 -60.820322) (xy 86.481264 -60.866835) (xy 86.444047 -60.908372)
			(xy 86.401179 -60.944047) (xy 86.353573 -60.973101) (xy 86.302244 -60.994913) (xy 86.248287 -61.009019)
			(xy 86.19285 -61.015119) (xy 86.137116 -61.013082) (xy 86.082273 -61.002952) (xy 86.029489 -60.984945)
			(xy 85.979889 -60.959444) (xy 85.934531 -60.926993) (xy 85.894382 -60.888284) (xy 85.860296 -60.844141)
			(xy 85.833 -60.795506) (xy 85.813077 -60.743415) (xy 85.800951 -60.688978) (xy 85.79688 -60.633356)
			(xy 80.249268 -60.633356) (xy 80.249268 -61.487812) (xy 84.304376 -61.487812) (xy 84.308447 -61.43219)
			(xy 84.320573 -61.377753) (xy 84.340496 -61.325662) (xy 84.367792 -61.277027) (xy 84.401878 -61.232884)
			(xy 84.442027 -61.194175) (xy 84.487385 -61.161724) (xy 84.536985 -61.136223) (xy 84.589769 -61.118216)
			(xy 84.644612 -61.108086) (xy 84.700346 -61.106049) (xy 84.755783 -61.112149) (xy 84.80974 -61.126255)
			(xy 84.861069 -61.148067) (xy 84.908675 -61.177121) (xy 84.951543 -61.212796) (xy 84.98876 -61.254333)
			(xy 85.019533 -61.300846) (xy 85.043205 -61.351343) (xy 85.059273 -61.40475) (xy 85.067393 -61.459926)
			(xy 85.067902 -61.487812) (xy 85.067393 -61.515698) (xy 85.059273 -61.570874) (xy 85.043205 -61.624281)
			(xy 85.019533 -61.674778) (xy 84.98876 -61.721291) (xy 84.951543 -61.762828) (xy 84.908675 -61.798503)
			(xy 84.861069 -61.827557) (xy 84.80974 -61.849369) (xy 84.755783 -61.863475) (xy 84.700346 -61.869575)
			(xy 84.644612 -61.867538) (xy 84.589769 -61.857408) (xy 84.536985 -61.839401) (xy 84.487385 -61.8139)
			(xy 84.442027 -61.781449) (xy 84.401878 -61.74274) (xy 84.367792 -61.698597) (xy 84.340496 -61.649962)
			(xy 84.320573 -61.597871) (xy 84.308447 -61.543434) (xy 84.304376 -61.487812) (xy 80.249268 -61.487812)
			(xy 80.249268 -61.935614) (xy 80.250284 -61.945266) (xy 80.251912 -61.95251) (xy 80.258751 -61.965681)
			(xy 80.263746 -61.971174) (xy 80.413606 -62.121034) (xy 82.24215 -62.121034) (xy 82.246221 -62.065412)
			(xy 82.258347 -62.010975) (xy 82.27827 -61.958884) (xy 82.305566 -61.910249) (xy 82.339652 -61.866106)
			(xy 82.379801 -61.827397) (xy 82.425159 -61.794946) (xy 82.474759 -61.769445) (xy 82.527543 -61.751438)
			(xy 82.582386 -61.741308) (xy 82.63812 -61.739271) (xy 82.693557 -61.745371) (xy 82.747514 -61.759477)
			(xy 82.798843 -61.781289) (xy 82.846449 -61.810343) (xy 82.889317 -61.846018) (xy 82.926534 -61.887555)
			(xy 82.957307 -61.934068) (xy 82.980979 -61.984565) (xy 82.997047 -62.037972) (xy 83.005167 -62.093148)
			(xy 83.005676 -62.121034) (xy 83.005167 -62.14892) (xy 82.997047 -62.204096) (xy 82.980979 -62.257503)
			(xy 82.957307 -62.308) (xy 82.926534 -62.354513) (xy 82.889317 -62.39605) (xy 82.846449 -62.431725)
			(xy 82.798843 -62.460779) (xy 82.747514 -62.482591) (xy 82.693557 -62.496697) (xy 82.63812 -62.502797)
			(xy 82.582386 -62.50076) (xy 82.527543 -62.49063) (xy 82.474759 -62.472623) (xy 82.425159 -62.447122)
			(xy 82.379801 -62.414671) (xy 82.339652 -62.375962) (xy 82.305566 -62.331819) (xy 82.27827 -62.283184)
			(xy 82.258347 -62.231093) (xy 82.246221 -62.176656) (xy 82.24215 -62.121034) (xy 80.413606 -62.121034)
			(xy 80.574896 -62.282324) (xy 80.592925 -62.301096) (xy 80.623498 -62.343215) (xy 80.647117 -62.389591)
			(xy 80.663204 -62.439088) (xy 80.671361 -62.49049) (xy 80.671924 -62.516512) (xy 80.671924 -63.273432)
			(xy 81.57667 -63.273432) (xy 81.580741 -63.21781) (xy 81.592867 -63.163373) (xy 81.61279 -63.111282)
			(xy 81.640086 -63.062647) (xy 81.674172 -63.018504) (xy 81.714321 -62.979795) (xy 81.759679 -62.947344)
			(xy 81.809279 -62.921843) (xy 81.862063 -62.903836) (xy 81.916906 -62.893706) (xy 81.97264 -62.891669)
			(xy 82.028077 -62.897769) (xy 82.082034 -62.911875) (xy 82.133363 -62.933687) (xy 82.180969 -62.962741)
			(xy 82.223837 -62.998416) (xy 82.261054 -63.039953) (xy 82.291827 -63.086466) (xy 82.315499 -63.136963)
			(xy 82.331567 -63.19037) (xy 82.339687 -63.245546) (xy 82.340196 -63.273432) (xy 82.339687 -63.301318)
			(xy 82.331567 -63.356494) (xy 82.315499 -63.409901) (xy 82.291827 -63.460398) (xy 82.261054 -63.506911)
			(xy 82.223837 -63.548448) (xy 82.180969 -63.584123) (xy 82.133363 -63.613177) (xy 82.082034 -63.634989)
			(xy 82.028077 -63.649095) (xy 81.97264 -63.655195) (xy 81.916906 -63.653158) (xy 81.862063 -63.643028)
			(xy 81.809279 -63.625021) (xy 81.759679 -63.59952) (xy 81.714321 -63.567069) (xy 81.674172 -63.52836)
			(xy 81.640086 -63.484217) (xy 81.61279 -63.435582) (xy 81.592867 -63.383491) (xy 81.580741 -63.329054)
			(xy 81.57667 -63.273432) (xy 80.671924 -63.273432) (xy 80.671924 -74.431652) (xy 80.671396 -74.457675)
			(xy 80.663229 -74.509078) (xy 80.647133 -74.558574) (xy 80.623505 -74.60495) (xy 80.592925 -74.647066)
			(xy 80.574896 -74.66584) (xy 78.034388 -77.206348) (xy 82.68411 -77.206348) (xy 82.688181 -77.150726)
			(xy 82.700307 -77.096289) (xy 82.72023 -77.044198) (xy 82.747526 -76.995563) (xy 82.781612 -76.95142)
			(xy 82.821761 -76.912711) (xy 82.867119 -76.88026) (xy 82.916719 -76.854759) (xy 82.969503 -76.836752)
			(xy 83.024346 -76.826622) (xy 83.08008 -76.824585) (xy 83.135517 -76.830685) (xy 83.189474 -76.844791)
			(xy 83.240803 -76.866603) (xy 83.288409 -76.895657) (xy 83.331277 -76.931332) (xy 83.368494 -76.972869)
			(xy 83.399267 -77.019382) (xy 83.422939 -77.069879) (xy 83.439007 -77.123286) (xy 83.447127 -77.178462)
			(xy 83.447636 -77.206348) (xy 83.447127 -77.234234) (xy 83.439007 -77.28941) (xy 83.422939 -77.342817)
			(xy 83.399267 -77.393314) (xy 83.368494 -77.439827) (xy 83.331277 -77.481364) (xy 83.288409 -77.517039)
			(xy 83.240803 -77.546093) (xy 83.189474 -77.567905) (xy 83.135517 -77.582011) (xy 83.08008 -77.588111)
			(xy 83.024346 -77.586074) (xy 82.969503 -77.575944) (xy 82.916719 -77.557937) (xy 82.867119 -77.532436)
			(xy 82.821761 -77.499985) (xy 82.781612 -77.461276) (xy 82.747526 -77.417133) (xy 82.72023 -77.368498)
			(xy 82.700307 -77.316407) (xy 82.688181 -77.26197) (xy 82.68411 -77.206348) (xy 78.034388 -77.206348)
			(xy 76.058776 -79.18196) (xy 79.591662 -79.18196) (xy 79.592148 -79.154709) (xy 79.599904 -79.100761)
			(xy 79.615259 -79.048466) (xy 79.637901 -78.998889) (xy 79.667367 -78.953039) (xy 79.703058 -78.911848)
			(xy 79.744249 -78.876157) (xy 79.790099 -78.846691) (xy 79.839676 -78.824049) (xy 79.891971 -78.808694)
			(xy 79.945919 -78.800938) (xy 80.000421 -78.800938) (xy 80.054369 -78.808694) (xy 80.106664 -78.824049)
			(xy 80.156241 -78.846691) (xy 80.202091 -78.876157) (xy 80.243282 -78.911848) (xy 80.278973 -78.953039)
			(xy 80.308439 -78.998889) (xy 80.331081 -79.048466) (xy 80.346436 -79.100761) (xy 80.354192 -79.154709)
			(xy 80.354678 -79.18196) (xy 80.354093 -79.210842) (xy 80.345378 -79.267945) (xy 80.328157 -79.323083)
			(xy 80.302823 -79.374995) (xy 80.269955 -79.422497) (xy 80.230304 -79.464502) (xy 80.207866 -79.482696)
			(xy 80.19695 -79.491864) (xy 80.180205 -79.514917) (xy 80.17047 -79.541695) (xy 80.168502 -79.570119)
			(xy 80.174454 -79.597983) (xy 80.187863 -79.623123) (xy 80.207689 -79.643587) (xy 80.219804 -79.651098)
			(xy 80.244418 -79.665742) (xy 80.289288 -79.701335) (xy 80.328334 -79.743237) (xy 80.360676 -79.790504)
			(xy 80.385589 -79.842076) (xy 80.402512 -79.896792) (xy 80.411065 -79.953423) (xy 80.411574 -79.98206)
			(xy 80.411088 -80.009311) (xy 80.403332 -80.063259) (xy 80.387977 -80.115554) (xy 80.365335 -80.165131)
			(xy 80.335869 -80.210981) (xy 80.300178 -80.252172) (xy 80.258987 -80.287863) (xy 80.213137 -80.317329)
			(xy 80.16356 -80.339971) (xy 80.111265 -80.355326) (xy 80.057317 -80.363082) (xy 80.002815 -80.363082)
			(xy 79.948867 -80.355326) (xy 79.896572 -80.339971) (xy 79.846995 -80.317329) (xy 79.801145 -80.287863)
			(xy 79.759954 -80.252172) (xy 79.724263 -80.210981) (xy 79.694797 -80.165131) (xy 79.672155 -80.115554)
			(xy 79.6568 -80.063259) (xy 79.649044 -80.009311) (xy 79.648558 -79.98206) (xy 79.649073 -79.953175)
			(xy 79.6578 -79.896068) (xy 79.675034 -79.840929) (xy 79.700381 -79.789016) (xy 79.733262 -79.741517)
			(xy 79.772926 -79.699515) (xy 79.79537 -79.681324) (xy 79.806276 -79.672141) (xy 79.823033 -79.649095)
			(xy 79.832777 -79.622319) (xy 79.834749 -79.593893) (xy 79.828797 -79.566027) (xy 79.815384 -79.540887)
			(xy 79.795551 -79.520428) (xy 79.783432 -79.512922) (xy 79.758835 -79.49825) (xy 79.713963 -79.462663)
			(xy 79.674916 -79.420767) (xy 79.64257 -79.373504) (xy 79.617655 -79.321937) (xy 79.600729 -79.267224)
			(xy 79.592172 -79.210596) (xy 79.591662 -79.18196) (xy 76.058776 -79.18196) (xy 72.813164 -82.427572)
			(xy 78.932784 -82.427572) (xy 78.936855 -82.37195) (xy 78.948981 -82.317513) (xy 78.968904 -82.265422)
			(xy 78.9962 -82.216787) (xy 79.030286 -82.172644) (xy 79.070435 -82.133935) (xy 79.115793 -82.101484)
			(xy 79.165393 -82.075983) (xy 79.218177 -82.057976) (xy 79.27302 -82.047846) (xy 79.328754 -82.045809)
			(xy 79.384191 -82.051909) (xy 79.438148 -82.066015) (xy 79.489477 -82.087827) (xy 79.537083 -82.116881)
			(xy 79.579951 -82.152556) (xy 79.617168 -82.194093) (xy 79.647941 -82.240606) (xy 79.671613 -82.291103)
			(xy 79.687681 -82.34451) (xy 79.695801 -82.399686) (xy 79.69631 -82.427572) (xy 79.695801 -82.455458)
			(xy 79.687681 -82.510634) (xy 79.671613 -82.564041) (xy 79.647941 -82.614538) (xy 79.617168 -82.661051)
			(xy 79.579951 -82.702588) (xy 79.537083 -82.738263) (xy 79.489477 -82.767317) (xy 79.438148 -82.789129)
			(xy 79.384191 -82.803235) (xy 79.328754 -82.809335) (xy 79.27302 -82.807298) (xy 79.218177 -82.797168)
			(xy 79.165393 -82.779161) (xy 79.115793 -82.75366) (xy 79.070435 -82.721209) (xy 79.030286 -82.6825)
			(xy 78.9962 -82.638357) (xy 78.968904 -82.589722) (xy 78.948981 -82.537631) (xy 78.936855 -82.483194)
			(xy 78.932784 -82.427572) (xy 72.813164 -82.427572) (xy 71.708518 -83.532218) (xy 76.311504 -83.532218)
			(xy 76.315575 -83.476596) (xy 76.327701 -83.422159) (xy 76.347624 -83.370068) (xy 76.37492 -83.321433)
			(xy 76.409006 -83.27729) (xy 76.449155 -83.238581) (xy 76.494513 -83.20613) (xy 76.544113 -83.180629)
			(xy 76.596897 -83.162622) (xy 76.65174 -83.152492) (xy 76.707474 -83.150455) (xy 76.762911 -83.156555)
			(xy 76.816868 -83.170661) (xy 76.868197 -83.192473) (xy 76.915803 -83.221527) (xy 76.958671 -83.257202)
			(xy 76.995888 -83.298739) (xy 77.026661 -83.345252) (xy 77.050333 -83.395749) (xy 77.066401 -83.449156)
			(xy 77.074521 -83.504332) (xy 77.07503 -83.532218) (xy 77.074521 -83.560104) (xy 77.066401 -83.61528)
			(xy 77.050333 -83.668687) (xy 77.026661 -83.719184) (xy 76.995888 -83.765697) (xy 76.958671 -83.807234)
			(xy 76.915803 -83.842909) (xy 76.868197 -83.871963) (xy 76.816868 -83.893775) (xy 76.762911 -83.907881)
			(xy 76.707474 -83.913981) (xy 76.65174 -83.911944) (xy 76.596897 -83.901814) (xy 76.544113 -83.883807)
			(xy 76.494513 -83.858306) (xy 76.449155 -83.825855) (xy 76.409006 -83.787146) (xy 76.37492 -83.743003)
			(xy 76.347624 -83.694368) (xy 76.327701 -83.642277) (xy 76.315575 -83.58784) (xy 76.311504 -83.532218)
			(xy 71.708518 -83.532218) (xy 68.99275 -86.247986) (xy 75.238608 -86.247986) (xy 75.242679 -86.192364)
			(xy 75.254805 -86.137927) (xy 75.274728 -86.085836) (xy 75.302024 -86.037201) (xy 75.33611 -85.993058)
			(xy 75.376259 -85.954349) (xy 75.421617 -85.921898) (xy 75.471217 -85.896397) (xy 75.524001 -85.87839)
			(xy 75.578844 -85.86826) (xy 75.634578 -85.866223) (xy 75.690015 -85.872323) (xy 75.743972 -85.886429)
			(xy 75.795301 -85.908241) (xy 75.842907 -85.937295) (xy 75.885775 -85.97297) (xy 75.922992 -86.014507)
			(xy 75.953765 -86.06102) (xy 75.977437 -86.111517) (xy 75.993505 -86.164924) (xy 76.001625 -86.2201)
			(xy 76.002134 -86.247986) (xy 76.001625 -86.275872) (xy 75.993505 -86.331048) (xy 75.977437 -86.384455)
			(xy 75.953765 -86.434952) (xy 75.922992 -86.481465) (xy 75.885775 -86.523002) (xy 75.842907 -86.558677)
			(xy 75.795301 -86.587731) (xy 75.743972 -86.609543) (xy 75.690015 -86.623649) (xy 75.634578 -86.629749)
			(xy 75.578844 -86.627712) (xy 75.524001 -86.617582) (xy 75.471217 -86.599575) (xy 75.421617 -86.574074)
			(xy 75.376259 -86.541623) (xy 75.33611 -86.502914) (xy 75.302024 -86.458771) (xy 75.274728 -86.410136)
			(xy 75.254805 -86.358045) (xy 75.242679 -86.303608) (xy 75.238608 -86.247986) (xy 68.99275 -86.247986)
			(xy 66.284094 -88.956642) (xy 73.632566 -88.956642) (xy 73.636637 -88.90102) (xy 73.648763 -88.846583)
			(xy 73.668686 -88.794492) (xy 73.695982 -88.745857) (xy 73.730068 -88.701714) (xy 73.770217 -88.663005)
			(xy 73.815575 -88.630554) (xy 73.865175 -88.605053) (xy 73.917959 -88.587046) (xy 73.972802 -88.576916)
			(xy 74.028536 -88.574879) (xy 74.083973 -88.580979) (xy 74.13793 -88.595085) (xy 74.189259 -88.616897)
			(xy 74.236865 -88.645951) (xy 74.279733 -88.681626) (xy 74.31695 -88.723163) (xy 74.347723 -88.769676)
			(xy 74.371395 -88.820173) (xy 74.387463 -88.87358) (xy 74.395583 -88.928756) (xy 74.396092 -88.956642)
			(xy 74.395583 -88.984528) (xy 74.387463 -89.039704) (xy 74.371395 -89.093111) (xy 74.347723 -89.143608)
			(xy 74.31695 -89.190121) (xy 74.279733 -89.231658) (xy 74.236865 -89.267333) (xy 74.189259 -89.296387)
			(xy 74.13793 -89.318199) (xy 74.083973 -89.332305) (xy 74.028536 -89.338405) (xy 73.972802 -89.336368)
			(xy 73.917959 -89.326238) (xy 73.865175 -89.308231) (xy 73.815575 -89.28273) (xy 73.770217 -89.250279)
			(xy 73.730068 -89.21157) (xy 73.695982 -89.167427) (xy 73.668686 -89.118792) (xy 73.648763 -89.066701)
			(xy 73.636637 -89.012264) (xy 73.632566 -88.956642) (xy 66.284094 -88.956642) (xy 62.192154 -93.048582)
			(xy 62.193585 -93.056686) (xy 62.200844 -93.071446) (xy 62.206378 -93.077538) (xy 62.581028 -93.452188)
			(xy 62.587884 -93.459582) (xy 62.595635 -93.478181) (xy 62.596014 -93.488256) (xy 62.596014 -95.214948)
			(xy 71.639189 -95.214948) (xy 71.643144 -95.123111) (xy 71.654979 -95.031954) (xy 71.674606 -94.942151)
			(xy 71.70188 -94.854369) (xy 71.7366 -94.769255) (xy 71.778508 -94.687442) (xy 71.827294 -94.609534)
			(xy 71.882597 -94.536109) (xy 71.944007 -94.467709) (xy 72.011069 -94.404842) (xy 72.083288 -94.347972)
			(xy 72.160128 -94.297521) (xy 72.241021 -94.253862) (xy 72.325367 -94.217319) (xy 72.412543 -94.188162)
			(xy 72.501902 -94.166608) (xy 72.592783 -94.152814) (xy 72.684514 -94.146884) (xy 72.776415 -94.148862)
			(xy 72.867806 -94.158733) (xy 72.95801 -94.176423) (xy 73.046359 -94.201803) (xy 73.132199 -94.234683)
			(xy 73.214895 -94.274821) (xy 73.293835 -94.32192) (xy 73.368433 -94.37563) (xy 73.438139 -94.435554)
			(xy 73.502434 -94.501248) (xy 73.560845 -94.572226) (xy 73.612937 -94.647963) (xy 73.658326 -94.727898)
			(xy 73.696676 -94.811438) (xy 73.727701 -94.897966) (xy 73.751174 -94.986841) (xy 73.76692 -95.077405)
			(xy 73.774822 -95.168987) (xy 73.775316 -95.214948) (xy 73.774822 -95.260909) (xy 73.76692 -95.352491)
			(xy 73.751174 -95.443055) (xy 73.727701 -95.53193) (xy 73.696676 -95.618458) (xy 73.658326 -95.701998)
			(xy 73.612937 -95.781933) (xy 73.560845 -95.85767) (xy 73.502434 -95.928648) (xy 73.442733 -95.989648)
			(xy 75.563982 -95.989648) (xy 75.568053 -95.934026) (xy 75.580179 -95.879589) (xy 75.600102 -95.827498)
			(xy 75.627398 -95.778863) (xy 75.661484 -95.73472) (xy 75.701633 -95.696011) (xy 75.746991 -95.66356)
			(xy 75.796591 -95.638059) (xy 75.849375 -95.620052) (xy 75.904218 -95.609922) (xy 75.959952 -95.607885)
			(xy 76.015389 -95.613985) (xy 76.069346 -95.628091) (xy 76.120675 -95.649903) (xy 76.168281 -95.678957)
			(xy 76.211149 -95.714632) (xy 76.248366 -95.756169) (xy 76.279139 -95.802682) (xy 76.302811 -95.853179)
			(xy 76.318879 -95.906586) (xy 76.326999 -95.961762) (xy 76.327508 -95.989648) (xy 76.326999 -96.017534)
			(xy 76.318879 -96.07271) (xy 76.302811 -96.126117) (xy 76.279139 -96.176614) (xy 76.248366 -96.223127)
			(xy 76.211149 -96.264664) (xy 76.168281 -96.300339) (xy 76.120675 -96.329393) (xy 76.069346 -96.351205)
			(xy 76.015389 -96.365311) (xy 75.959952 -96.371411) (xy 75.904218 -96.369374) (xy 75.849375 -96.359244)
			(xy 75.796591 -96.341237) (xy 75.746991 -96.315736) (xy 75.701633 -96.283285) (xy 75.661484 -96.244576)
			(xy 75.627398 -96.200433) (xy 75.600102 -96.151798) (xy 75.580179 -96.099707) (xy 75.568053 -96.04527)
			(xy 75.563982 -95.989648) (xy 73.442733 -95.989648) (xy 73.438139 -95.994342) (xy 73.368433 -96.054266)
			(xy 73.293835 -96.107976) (xy 73.214895 -96.155075) (xy 73.132199 -96.195213) (xy 73.046359 -96.228093)
			(xy 72.95801 -96.253473) (xy 72.867806 -96.271163) (xy 72.776415 -96.281034) (xy 72.684514 -96.283012)
			(xy 72.592783 -96.277082) (xy 72.501902 -96.263288) (xy 72.412543 -96.241734) (xy 72.325367 -96.212577)
			(xy 72.241021 -96.176034) (xy 72.160128 -96.132375) (xy 72.083288 -96.081924) (xy 72.011069 -96.025054)
			(xy 71.944007 -95.962187) (xy 71.882597 -95.893787) (xy 71.827294 -95.820362) (xy 71.778508 -95.742454)
			(xy 71.7366 -95.660641) (xy 71.70188 -95.575527) (xy 71.674606 -95.487745) (xy 71.654979 -95.397942)
			(xy 71.643144 -95.306785) (xy 71.639189 -95.214948) (xy 62.596014 -95.214948) (xy 62.596014 -95.670878)
			(xy 62.59703 -95.680276) (xy 62.59703 -95.680784) (xy 62.598736 -95.687942) (xy 62.605572 -95.700966)
			(xy 62.610492 -95.706438) (xy 62.626494 -95.72244) (xy 62.627256 -95.72244) (xy 64.238886 -97.33407)
			(xy 64.244321 -97.339041) (xy 64.257364 -97.345868) (xy 64.26454 -97.347532) (xy 64.265048 -97.347532)
			(xy 64.274446 -97.348548) (xy 66.298826 -97.348548) (xy 66.308224 -97.347532) (xy 66.308732 -97.347532)
			(xy 66.315889 -97.345823) (xy 66.328909 -97.338984) (xy 66.334386 -97.33407) (xy 66.341498 -97.326958)
			(xy 66.34891 -97.320274) (xy 66.367343 -97.312677) (xy 66.387281 -97.312677) (xy 66.405714 -97.320274)
			(xy 66.413126 -97.326958) (xy 66.641726 -97.555558) (xy 66.647408 -97.560746) (xy 66.661115 -97.567714)
			(xy 66.66865 -97.569274) (xy 66.669158 -97.569274) (xy 66.677286 -97.570036) (xy 69.331332 -97.570036)
			(xy 69.343176 -97.569411) (xy 69.364361 -97.558813) (xy 69.371972 -97.549716) (xy 69.371972 -97.089976)
			(xy 69.368924 -97.084134) (xy 69.36613 -97.078546) (xy 69.352415 -97.051068) (xy 69.332966 -96.99282)
			(xy 69.323081 -96.932212) (xy 69.322442 -96.901508) (xy 69.322442 -96.901) (xy 69.322928 -96.873749)
			(xy 69.330684 -96.819801) (xy 69.346039 -96.767506) (xy 69.368681 -96.717929) (xy 69.398147 -96.672079)
			(xy 69.433838 -96.630888) (xy 69.475029 -96.595197) (xy 69.520879 -96.565731) (xy 69.570456 -96.543089)
			(xy 69.622751 -96.527734) (xy 69.676699 -96.519978) (xy 69.731201 -96.519978) (xy 69.785149 -96.527734)
			(xy 69.837444 -96.543089) (xy 69.887021 -96.565731) (xy 69.932871 -96.595197) (xy 69.974062 -96.630888)
			(xy 70.009753 -96.672079) (xy 70.039219 -96.717929) (xy 70.061861 -96.767506) (xy 70.077216 -96.819801)
			(xy 70.084972 -96.873749) (xy 70.085458 -96.901) (xy 70.085458 -96.901508) (xy 70.084826 -96.932213)
			(xy 70.074952 -96.992825) (xy 70.059211 -97.039938) (xy 74.725528 -97.039938) (xy 74.729599 -96.984316)
			(xy 74.741725 -96.929879) (xy 74.761648 -96.877788) (xy 74.788944 -96.829153) (xy 74.82303 -96.78501)
			(xy 74.863179 -96.746301) (xy 74.908537 -96.71385) (xy 74.958137 -96.688349) (xy 75.010921 -96.670342)
			(xy 75.065764 -96.660212) (xy 75.121498 -96.658175) (xy 75.176935 -96.664275) (xy 75.230892 -96.678381)
			(xy 75.282221 -96.700193) (xy 75.329827 -96.729247) (xy 75.372695 -96.764922) (xy 75.409912 -96.806459)
			(xy 75.440685 -96.852972) (xy 75.464357 -96.903469) (xy 75.480425 -96.956876) (xy 75.488545 -97.012052)
			(xy 75.489054 -97.039938) (xy 75.488545 -97.067824) (xy 75.480425 -97.123) (xy 75.464357 -97.176407)
			(xy 75.440685 -97.226904) (xy 75.409912 -97.273417) (xy 75.372695 -97.314954) (xy 75.329827 -97.350629)
			(xy 75.282221 -97.379683) (xy 75.230892 -97.401495) (xy 75.176935 -97.415601) (xy 75.121498 -97.421701)
			(xy 75.065764 -97.419664) (xy 75.010921 -97.409534) (xy 74.958137 -97.391527) (xy 74.908537 -97.366026)
			(xy 74.863179 -97.333575) (xy 74.82303 -97.294866) (xy 74.788944 -97.250723) (xy 74.761648 -97.202088)
			(xy 74.741725 -97.149997) (xy 74.729599 -97.09556) (xy 74.725528 -97.039938) (xy 70.059211 -97.039938)
			(xy 70.055492 -97.05107) (xy 70.04177 -97.078546) (xy 70.038976 -97.084134) (xy 70.035928 -97.089976)
			(xy 70.035928 -97.549462) (xy 70.04349 -97.558649) (xy 70.064687 -97.569391) (xy 70.076568 -97.570036)
			(xy 70.412102 -97.570036) (xy 70.42212 -97.570457) (xy 70.44063 -97.578128) (xy 70.454793 -97.592302)
			(xy 70.462451 -97.610817) (xy 70.462902 -97.620836) (xy 70.462902 -97.64014) (xy 73.918062 -97.64014)
			(xy 73.922133 -97.584518) (xy 73.934259 -97.530081) (xy 73.954182 -97.47799) (xy 73.981478 -97.429355)
			(xy 74.015564 -97.385212) (xy 74.055713 -97.346503) (xy 74.101071 -97.314052) (xy 74.150671 -97.288551)
			(xy 74.203455 -97.270544) (xy 74.258298 -97.260414) (xy 74.314032 -97.258377) (xy 74.369469 -97.264477)
			(xy 74.423426 -97.278583) (xy 74.474755 -97.300395) (xy 74.522361 -97.329449) (xy 74.565229 -97.365124)
			(xy 74.602446 -97.406661) (xy 74.633219 -97.453174) (xy 74.656891 -97.503671) (xy 74.672959 -97.557078)
			(xy 74.681079 -97.612254) (xy 74.681588 -97.64014) (xy 74.681079 -97.668026) (xy 74.672959 -97.723202)
			(xy 74.656891 -97.776609) (xy 74.633219 -97.827106) (xy 74.602446 -97.873619) (xy 74.565229 -97.915156)
			(xy 74.522361 -97.950831) (xy 74.474755 -97.979885) (xy 74.423426 -98.001697) (xy 74.369469 -98.015803)
			(xy 74.314032 -98.021903) (xy 74.258298 -98.019866) (xy 74.203455 -98.009736) (xy 74.150671 -97.991729)
			(xy 74.101071 -97.966228) (xy 74.055713 -97.933777) (xy 74.015564 -97.895068) (xy 73.981478 -97.850925)
			(xy 73.954182 -97.80229) (xy 73.934259 -97.750199) (xy 73.922133 -97.695762) (xy 73.918062 -97.64014)
			(xy 70.462902 -97.64014) (xy 70.462902 -98.171) (xy 75.563982 -98.171) (xy 75.568053 -98.115378)
			(xy 75.580179 -98.060941) (xy 75.600102 -98.00885) (xy 75.627398 -97.960215) (xy 75.661484 -97.916072)
			(xy 75.701633 -97.877363) (xy 75.746991 -97.844912) (xy 75.796591 -97.819411) (xy 75.849375 -97.801404)
			(xy 75.904218 -97.791274) (xy 75.959952 -97.789237) (xy 76.015389 -97.795337) (xy 76.069346 -97.809443)
			(xy 76.120675 -97.831255) (xy 76.168281 -97.860309) (xy 76.211149 -97.895984) (xy 76.248366 -97.937521)
			(xy 76.279139 -97.984034) (xy 76.302811 -98.034531) (xy 76.318879 -98.087938) (xy 76.326999 -98.143114)
			(xy 76.327508 -98.171) (xy 76.326999 -98.198886) (xy 76.318879 -98.254062) (xy 76.302811 -98.307469)
			(xy 76.279139 -98.357966) (xy 76.248366 -98.404479) (xy 76.211149 -98.446016) (xy 76.168281 -98.481691)
			(xy 76.120675 -98.510745) (xy 76.069346 -98.532557) (xy 76.015389 -98.546663) (xy 75.959952 -98.552763)
			(xy 75.904218 -98.550726) (xy 75.849375 -98.540596) (xy 75.796591 -98.522589) (xy 75.746991 -98.497088)
			(xy 75.701633 -98.464637) (xy 75.661484 -98.425928) (xy 75.627398 -98.381785) (xy 75.600102 -98.33315)
			(xy 75.580179 -98.281059) (xy 75.568053 -98.226622) (xy 75.563982 -98.171) (xy 70.462902 -98.171)
			(xy 70.462902 -99.439984) (xy 75.309982 -99.439984) (xy 75.314053 -99.384362) (xy 75.326179 -99.329925)
			(xy 75.346102 -99.277834) (xy 75.373398 -99.229199) (xy 75.407484 -99.185056) (xy 75.447633 -99.146347)
			(xy 75.492991 -99.113896) (xy 75.542591 -99.088395) (xy 75.595375 -99.070388) (xy 75.650218 -99.060258)
			(xy 75.705952 -99.058221) (xy 75.761389 -99.064321) (xy 75.815346 -99.078427) (xy 75.866675 -99.100239)
			(xy 75.914281 -99.129293) (xy 75.957149 -99.164968) (xy 75.994366 -99.206505) (xy 76.025139 -99.253018)
			(xy 76.048811 -99.303515) (xy 76.064879 -99.356922) (xy 76.072999 -99.412098) (xy 76.073508 -99.439984)
			(xy 76.072999 -99.46787) (xy 76.064879 -99.523046) (xy 76.048811 -99.576453) (xy 76.025139 -99.62695)
			(xy 75.994366 -99.673463) (xy 75.957149 -99.715) (xy 75.914281 -99.750675) (xy 75.866675 -99.779729)
			(xy 75.815346 -99.801541) (xy 75.761389 -99.815647) (xy 75.705952 -99.821747) (xy 75.650218 -99.81971)
			(xy 75.595375 -99.80958) (xy 75.542591 -99.791573) (xy 75.492991 -99.766072) (xy 75.447633 -99.733621)
			(xy 75.407484 -99.694912) (xy 75.373398 -99.650769) (xy 75.346102 -99.602134) (xy 75.326179 -99.550043)
			(xy 75.314053 -99.495606) (xy 75.309982 -99.439984) (xy 70.462902 -99.439984) (xy 70.462902 -99.63785)
			(xy 70.46247 -99.647916) (xy 70.454743 -99.666508) (xy 70.447916 -99.673918) (xy 70.178676 -99.943158)
			(xy 70.174876 -99.947179) (xy 70.16898 -99.956537) (xy 70.166992 -99.9617) (xy 70.177914 -99.988116)
			(xy 70.182125 -99.997245) (xy 70.196306 -100.011475) (xy 70.214859 -100.019178) (xy 70.224904 -100.019612)
			(xy 70.315074 -100.019612) (xy 70.317614 -100.018342) (xy 70.339028 -100.006806) (xy 70.384157 -99.988655)
			(xy 70.431227 -99.976388) (xy 70.479475 -99.970204) (xy 70.503796 -99.969828) (xy 70.50405 -99.969828)
			(xy 70.531304 -99.970288) (xy 70.585259 -99.978039) (xy 70.63756 -99.993391) (xy 70.687145 -100.016032)
			(xy 70.724338 -100.039932) (xy 73.876914 -100.039932) (xy 73.880985 -99.98431) (xy 73.893111 -99.929873)
			(xy 73.913034 -99.877782) (xy 73.94033 -99.829147) (xy 73.974416 -99.785004) (xy 74.014565 -99.746295)
			(xy 74.059923 -99.713844) (xy 74.109523 -99.688343) (xy 74.162307 -99.670336) (xy 74.21715 -99.660206)
			(xy 74.272884 -99.658169) (xy 74.328321 -99.664269) (xy 74.382278 -99.678375) (xy 74.433607 -99.700187)
			(xy 74.481213 -99.729241) (xy 74.524081 -99.764916) (xy 74.561298 -99.806453) (xy 74.592071 -99.852966)
			(xy 74.615743 -99.903463) (xy 74.631811 -99.95687) (xy 74.639931 -100.012046) (xy 74.64044 -100.039932)
			(xy 74.639931 -100.067818) (xy 74.631811 -100.122994) (xy 74.615743 -100.176401) (xy 74.592071 -100.226898)
			(xy 74.561298 -100.273411) (xy 74.524081 -100.314948) (xy 74.481213 -100.350623) (xy 74.433607 -100.379677)
			(xy 74.382278 -100.401489) (xy 74.328321 -100.415595) (xy 74.272884 -100.421695) (xy 74.21715 -100.419658)
			(xy 74.162307 -100.409528) (xy 74.109523 -100.391521) (xy 74.059923 -100.36602) (xy 74.014565 -100.333569)
			(xy 73.974416 -100.29486) (xy 73.94033 -100.250717) (xy 73.913034 -100.202082) (xy 73.893111 -100.149991)
			(xy 73.880985 -100.095554) (xy 73.876914 -100.039932) (xy 70.724338 -100.039932) (xy 70.733001 -100.045499)
			(xy 70.774197 -100.081193) (xy 70.809893 -100.122387) (xy 70.839362 -100.168243) (xy 70.862004 -100.217826)
			(xy 70.877358 -100.270128) (xy 70.885111 -100.324082) (xy 70.885558 -100.351336) (xy 70.885076 -100.378495)
			(xy 70.877368 -100.432262) (xy 70.862113 -100.484393) (xy 70.839619 -100.533834) (xy 70.810341 -100.579585)
			(xy 70.77487 -100.620722) (xy 70.733925 -100.656412) (xy 70.688331 -100.685935) (xy 70.639012 -100.708694)
			(xy 70.586963 -100.724229) (xy 70.533238 -100.732225) (xy 70.506082 -100.732844) (xy 70.503288 -100.732844)
			(xy 70.471227 -100.732114) (xy 70.408027 -100.721263) (xy 70.347523 -100.700017) (xy 70.319138 -100.685092)
			(xy 70.315328 -100.68306) (xy 69.43852 -100.68306) (xy 69.433948 -100.687886) (xy 68.881752 -101.240082)
			(xy 74.293982 -101.240082) (xy 74.298053 -101.18446) (xy 74.310179 -101.130023) (xy 74.330102 -101.077932)
			(xy 74.357398 -101.029297) (xy 74.391484 -100.985154) (xy 74.431633 -100.946445) (xy 74.476991 -100.913994)
			(xy 74.526591 -100.888493) (xy 74.579375 -100.870486) (xy 74.634218 -100.860356) (xy 74.689952 -100.858319)
			(xy 74.745389 -100.864419) (xy 74.799346 -100.878525) (xy 74.850675 -100.900337) (xy 74.898281 -100.929391)
			(xy 74.941149 -100.965066) (xy 74.978366 -101.006603) (xy 75.009139 -101.053116) (xy 75.016889 -101.069648)
			(xy 75.586334 -101.069648) (xy 75.590405 -101.014026) (xy 75.602531 -100.959589) (xy 75.622454 -100.907498)
			(xy 75.64975 -100.858863) (xy 75.683836 -100.81472) (xy 75.723985 -100.776011) (xy 75.769343 -100.74356)
			(xy 75.818943 -100.718059) (xy 75.871727 -100.700052) (xy 75.92657 -100.689922) (xy 75.982304 -100.687885)
			(xy 76.037741 -100.693985) (xy 76.091698 -100.708091) (xy 76.143027 -100.729903) (xy 76.190633 -100.758957)
			(xy 76.233501 -100.794632) (xy 76.270718 -100.836169) (xy 76.301491 -100.882682) (xy 76.325163 -100.933179)
			(xy 76.341231 -100.986586) (xy 76.349351 -101.041762) (xy 76.34986 -101.069648) (xy 76.349351 -101.097534)
			(xy 76.341231 -101.15271) (xy 76.325163 -101.206117) (xy 76.301491 -101.256614) (xy 76.270718 -101.303127)
			(xy 76.233501 -101.344664) (xy 76.190633 -101.380339) (xy 76.143027 -101.409393) (xy 76.091698 -101.431205)
			(xy 76.037741 -101.445311) (xy 75.982304 -101.451411) (xy 75.92657 -101.449374) (xy 75.871727 -101.439244)
			(xy 75.818943 -101.421237) (xy 75.769343 -101.395736) (xy 75.723985 -101.363285) (xy 75.683836 -101.324576)
			(xy 75.64975 -101.280433) (xy 75.622454 -101.231798) (xy 75.602531 -101.179707) (xy 75.590405 -101.12527)
			(xy 75.586334 -101.069648) (xy 75.016889 -101.069648) (xy 75.032811 -101.103613) (xy 75.048879 -101.15702)
			(xy 75.056999 -101.212196) (xy 75.057508 -101.240082) (xy 75.056999 -101.267968) (xy 75.048879 -101.323144)
			(xy 75.032811 -101.376551) (xy 75.009139 -101.427048) (xy 74.978366 -101.473561) (xy 74.941149 -101.515098)
			(xy 74.898281 -101.550773) (xy 74.850675 -101.579827) (xy 74.799346 -101.601639) (xy 74.745389 -101.615745)
			(xy 74.689952 -101.621845) (xy 74.634218 -101.619808) (xy 74.579375 -101.609678) (xy 74.526591 -101.591671)
			(xy 74.476991 -101.56617) (xy 74.431633 -101.533719) (xy 74.391484 -101.49501) (xy 74.357398 -101.450867)
			(xy 74.330102 -101.402232) (xy 74.310179 -101.350141) (xy 74.298053 -101.295704) (xy 74.293982 -101.240082)
			(xy 68.881752 -101.240082) (xy 67.709034 -102.4128) (xy 67.70243 -102.420928) (xy 67.70243 -102.421436)
			(xy 67.699074 -102.426939) (xy 67.69497 -102.439154) (xy 67.694302 -102.445566) (xy 67.694302 -102.447598)
			(xy 67.693315 -102.474148) (xy 67.690932 -102.489) (xy 74.801982 -102.489) (xy 74.806053 -102.433378)
			(xy 74.818179 -102.378941) (xy 74.838102 -102.32685) (xy 74.865398 -102.278215) (xy 74.899484 -102.234072)
			(xy 74.939633 -102.195363) (xy 74.984991 -102.162912) (xy 75.034591 -102.137411) (xy 75.087375 -102.119404)
			(xy 75.142218 -102.109274) (xy 75.197952 -102.107237) (xy 75.253389 -102.113337) (xy 75.307346 -102.127443)
			(xy 75.358675 -102.149255) (xy 75.406281 -102.178309) (xy 75.449149 -102.213984) (xy 75.486366 -102.255521)
			(xy 75.517139 -102.302034) (xy 75.540811 -102.352531) (xy 75.556879 -102.405938) (xy 75.564999 -102.461114)
			(xy 75.565508 -102.489) (xy 75.564999 -102.516886) (xy 75.556879 -102.572062) (xy 75.540811 -102.625469)
			(xy 75.517139 -102.675966) (xy 75.486366 -102.722479) (xy 75.449149 -102.764016) (xy 75.406281 -102.799691)
			(xy 75.358675 -102.828745) (xy 75.307346 -102.850557) (xy 75.253389 -102.864663) (xy 75.197952 -102.870763)
			(xy 75.142218 -102.868726) (xy 75.087375 -102.858596) (xy 75.034591 -102.840589) (xy 74.984991 -102.815088)
			(xy 74.939633 -102.782637) (xy 74.899484 -102.743928) (xy 74.865398 -102.699785) (xy 74.838102 -102.65115)
			(xy 74.818179 -102.599059) (xy 74.806053 -102.544622) (xy 74.801982 -102.489) (xy 67.690932 -102.489)
			(xy 67.684898 -102.526605) (xy 67.669286 -102.577387) (xy 67.64678 -102.625513) (xy 67.617815 -102.670051)
			(xy 67.582951 -102.71014) (xy 67.542864 -102.745005) (xy 67.498327 -102.773972) (xy 67.450202 -102.79648)
			(xy 67.399421 -102.812094) (xy 67.346964 -102.820513) (xy 67.320414 -102.821486) (xy 67.319906 -102.821486)
			(xy 67.3152 -102.821762) (xy 67.305998 -102.823806) (xy 67.301618 -102.82555) (xy 67.297192 -102.827517)
			(xy 67.289131 -102.832886) (xy 67.285616 -102.836218) (xy 66.235834 -103.886) (xy 75.309982 -103.886)
			(xy 75.314053 -103.830378) (xy 75.326179 -103.775941) (xy 75.346102 -103.72385) (xy 75.373398 -103.675215)
			(xy 75.407484 -103.631072) (xy 75.447633 -103.592363) (xy 75.492991 -103.559912) (xy 75.542591 -103.534411)
			(xy 75.595375 -103.516404) (xy 75.650218 -103.506274) (xy 75.705952 -103.504237) (xy 75.761389 -103.510337)
			(xy 75.815346 -103.524443) (xy 75.866675 -103.546255) (xy 75.914281 -103.575309) (xy 75.957149 -103.610984)
			(xy 75.994366 -103.652521) (xy 76.025139 -103.699034) (xy 76.048811 -103.749531) (xy 76.064879 -103.802938)
			(xy 76.072999 -103.858114) (xy 76.073508 -103.886) (xy 76.072999 -103.913886) (xy 76.064879 -103.969062)
			(xy 76.048811 -104.022469) (xy 76.025139 -104.072966) (xy 75.994366 -104.119479) (xy 75.957149 -104.161016)
			(xy 75.914281 -104.196691) (xy 75.866675 -104.225745) (xy 75.815346 -104.247557) (xy 75.761389 -104.261663)
			(xy 75.705952 -104.267763) (xy 75.650218 -104.265726) (xy 75.595375 -104.255596) (xy 75.542591 -104.237589)
			(xy 75.492991 -104.212088) (xy 75.447633 -104.179637) (xy 75.407484 -104.140928) (xy 75.373398 -104.096785)
			(xy 75.346102 -104.04815) (xy 75.326179 -103.996059) (xy 75.314053 -103.941622) (xy 75.309982 -103.886)
			(xy 66.235834 -103.886) (xy 63.70066 -106.421174) (xy 63.697952 -106.424023) (xy 63.693354 -106.430399)
			(xy 63.691516 -106.433874) (xy 63.688935 -106.439301) (xy 63.686118 -106.450981) (xy 63.685928 -106.456988)
			(xy 63.685928 -107.210352) (xy 64.762632 -107.210352) (xy 64.766703 -107.15473) (xy 64.778829 -107.100293)
			(xy 64.798752 -107.048202) (xy 64.826048 -106.999567) (xy 64.860134 -106.955424) (xy 64.900283 -106.916715)
			(xy 64.945641 -106.884264) (xy 64.995241 -106.858763) (xy 65.048025 -106.840756) (xy 65.102868 -106.830626)
			(xy 65.158602 -106.828589) (xy 65.214039 -106.834689) (xy 65.267996 -106.848795) (xy 65.319325 -106.870607)
			(xy 65.366931 -106.899661) (xy 65.409799 -106.935336) (xy 65.447016 -106.976873) (xy 65.477789 -107.023386)
			(xy 65.501461 -107.073883) (xy 65.517529 -107.12729) (xy 65.525649 -107.182466) (xy 65.526158 -107.210352)
			(xy 65.525649 -107.238238) (xy 65.517529 -107.293414) (xy 65.501461 -107.346821) (xy 65.477789 -107.397318)
			(xy 65.447016 -107.443831) (xy 65.409799 -107.485368) (xy 65.366931 -107.521043) (xy 65.319325 -107.550097)
			(xy 65.267996 -107.571909) (xy 65.214039 -107.586015) (xy 65.158602 -107.592115) (xy 65.102868 -107.590078)
			(xy 65.048025 -107.579948) (xy 64.995241 -107.561941) (xy 64.945641 -107.53644) (xy 64.900283 -107.503989)
			(xy 64.860134 -107.46528) (xy 64.826048 -107.421137) (xy 64.798752 -107.372502) (xy 64.778829 -107.320411)
			(xy 64.766703 -107.265974) (xy 64.762632 -107.210352) (xy 63.685928 -107.210352) (xy 63.685928 -110.530132)
			(xy 70.429118 -110.530132) (xy 70.433189 -110.47451) (xy 70.445315 -110.420073) (xy 70.465238 -110.367982)
			(xy 70.492534 -110.319347) (xy 70.52662 -110.275204) (xy 70.566769 -110.236495) (xy 70.612127 -110.204044)
			(xy 70.661727 -110.178543) (xy 70.714511 -110.160536) (xy 70.769354 -110.150406) (xy 70.825088 -110.148369)
			(xy 70.880525 -110.154469) (xy 70.934482 -110.168575) (xy 70.985811 -110.190387) (xy 71.033417 -110.219441)
			(xy 71.076285 -110.255116) (xy 71.113502 -110.296653) (xy 71.144275 -110.343166) (xy 71.167947 -110.393663)
			(xy 71.184015 -110.44707) (xy 71.192135 -110.502246) (xy 71.192644 -110.530132) (xy 71.192135 -110.558018)
			(xy 71.184015 -110.613194) (xy 71.167947 -110.666601) (xy 71.144275 -110.717098) (xy 71.113502 -110.763611)
			(xy 71.076285 -110.805148) (xy 71.033417 -110.840823) (xy 70.985811 -110.869877) (xy 70.934482 -110.891689)
			(xy 70.880525 -110.905795) (xy 70.825088 -110.911895) (xy 70.769354 -110.909858) (xy 70.714511 -110.899728)
			(xy 70.661727 -110.881721) (xy 70.612127 -110.85622) (xy 70.566769 -110.823769) (xy 70.52662 -110.78506)
			(xy 70.492534 -110.740917) (xy 70.465238 -110.692282) (xy 70.445315 -110.640191) (xy 70.433189 -110.585754)
			(xy 70.429118 -110.530132) (xy 63.685928 -110.530132) (xy 63.685928 -111.009938) (xy 63.686944 -111.019336)
			(xy 63.686944 -111.019844) (xy 63.688654 -111.027) (xy 63.695492 -111.040021) (xy 63.700406 -111.045498)
			(xy 64.091566 -111.436658) (xy 64.098948 -111.443238) (xy 64.117247 -111.450683) (xy 64.127126 -111.451136)
			(xy 64.141096 -111.451136) (xy 64.222122 -111.414306) (xy 64.22263 -111.414306) (xy 64.242188 -111.405924)
			(xy 64.248792 -111.399828) (xy 64.25624 -111.392336) (xy 64.26478 -111.373041) (xy 64.265302 -111.36249)
			(xy 64.265302 -111.356648) (xy 64.26454 -111.334042) (xy 64.26454 -111.333788) (xy 64.265041 -111.306548)
			(xy 64.272822 -111.252626) (xy 64.288196 -111.200359) (xy 64.31085 -111.150812) (xy 64.340323 -111.104992)
			(xy 64.376015 -111.063831) (xy 64.4172 -111.028167) (xy 64.46304 -110.998725) (xy 64.512603 -110.976105)
			(xy 64.56488 -110.960767) (xy 64.618808 -110.953022) (xy 64.646048 -110.952534) (xy 64.673296 -110.953024)
			(xy 64.727236 -110.960786) (xy 64.779523 -110.976146) (xy 64.829091 -110.99879) (xy 64.874932 -111.028258)
			(xy 64.916113 -111.06395) (xy 64.951796 -111.10514) (xy 64.981253 -111.150988) (xy 65.003886 -111.200562)
			(xy 65.019233 -111.252852) (xy 65.026983 -111.306794) (xy 65.027556 -111.334042) (xy 65.027068 -111.361281)
			(xy 65.019314 -111.415204) (xy 65.003968 -111.467477) (xy 64.981344 -111.517035) (xy 64.951901 -111.562871)
			(xy 64.916238 -111.604053) (xy 64.875079 -111.639745) (xy 64.829263 -111.669219) (xy 64.77972 -111.691877)
			(xy 64.727459 -111.707258) (xy 64.673541 -111.71505) (xy 64.646302 -111.71555) (xy 64.642746 -111.71555)
			(xy 64.630808 -111.715296) (xy 64.6303 -111.715296) (xy 64.597277 -111.713185) (xy 64.532648 -111.699011)
			(xy 64.501776 -111.687102) (xy 64.494156 -111.684054) (xy 64.478154 -111.683038) (xy 64.468756 -111.685324)
			(xy 64.464943 -111.686342) (xy 64.45767 -111.689403) (xy 64.454278 -111.69142) (xy 64.450105 -111.694138)
			(xy 64.442811 -111.700916) (xy 64.4398 -111.704882) (xy 64.431926 -111.71555) (xy 64.427106 -111.722708)
			(xy 64.422124 -111.739218) (xy 64.422924 -111.756446) (xy 64.42583 -111.764572) (xy 64.426592 -111.76635)
			(xy 64.428601 -111.770856) (xy 64.434098 -111.779047) (xy 64.437514 -111.782606) (xy 64.460628 -111.80572)
			(xy 64.466308 -111.810911) (xy 64.480015 -111.817884) (xy 64.487552 -111.819436) (xy 64.48806 -111.819436)
			(xy 64.496188 -111.820198) (xy 68.756022 -111.820198) (xy 68.769992 -111.818166) (xy 68.782184 -111.814102)
			(xy 68.783454 -111.81334) (xy 68.797424 -111.808514) (xy 68.803774 -111.803688) (xy 68.823743 -111.789294)
			(xy 68.867312 -111.766392) (xy 68.913982 -111.750748) (xy 68.962552 -111.742764) (xy 68.987162 -111.74222)
			(xy 70.345554 -111.74222) (xy 70.35927 -111.740188) (xy 70.359778 -111.740188) (xy 70.370192 -111.73587)
			(xy 70.391528 -111.722916) (xy 70.400926 -111.71555) (xy 70.406514 -111.709962) (xy 70.41007 -111.703358)
			(xy 70.423561 -111.679288) (xy 70.456412 -111.634955) (xy 70.495303 -111.595814) (xy 70.539425 -111.56268)
			(xy 70.587857 -111.536244) (xy 70.639591 -111.517056) (xy 70.693548 -111.505516) (xy 70.748605 -111.501866)
			(xy 70.803614 -111.50618) (xy 70.857428 -111.518369) (xy 70.908927 -111.53818) (xy 70.957037 -111.565198)
			(xy 71.000756 -111.598862) (xy 71.039172 -111.63847) (xy 71.071486 -111.683195) (xy 71.084694 -111.707422)
			(xy 71.08825 -111.71428) (xy 71.101712 -111.727742) (xy 71.107142 -111.732723) (xy 71.120181 -111.739573)
			(xy 71.127366 -111.741204) (xy 71.127874 -111.741204) (xy 71.137272 -111.74222) (xy 71.86676 -111.74222)
			(xy 71.891372 -111.742751) (xy 71.939948 -111.750715) (xy 71.98662 -111.766363) (xy 72.030179 -111.789291)
			(xy 72.050148 -111.803688) (xy 72.056498 -111.808514) (xy 72.070468 -111.81334) (xy 72.071738 -111.814102)
			(xy 72.08393 -111.818166) (xy 72.0979 -111.820198) (xy 72.261984 -111.820198) (xy 72.275954 -111.818166)
			(xy 72.288146 -111.814102) (xy 72.289416 -111.81334) (xy 72.303386 -111.808514) (xy 72.309736 -111.803688)
			(xy 72.329704 -111.789291) (xy 72.373273 -111.766384) (xy 72.419942 -111.750735) (xy 72.468513 -111.742745)
			(xy 72.493124 -111.74222) (xy 73.857612 -111.74222) (xy 73.858628 -111.74222) (xy 73.886314 -111.742982)
			(xy 73.888346 -111.743236) (xy 73.958958 -111.743236) (xy 73.968102 -111.73968) (xy 73.973944 -111.737648)
			(xy 73.984612 -111.730282) (xy 73.990454 -111.723678) (xy 73.99274 -111.721392) (xy 73.993756 -111.720122)
			(xy 74.0029 -111.710216) (xy 74.003408 -111.709708) (xy 74.007726 -111.704882) (xy 74.011134 -111.700336)
			(xy 74.016008 -111.690076) (xy 74.017378 -111.684562) (xy 74.018394 -111.67364) (xy 74.018394 -111.616236)
			(xy 74.018059 -111.607632) (xy 74.012347 -111.591402) (xy 74.007218 -111.584486) (xy 74.00671 -111.583978)
			(xy 74.003662 -111.580422) (xy 74.000868 -111.577628) (xy 73.992486 -111.567722) (xy 73.975065 -111.546532)
			(xy 73.945848 -111.500104) (xy 73.923582 -111.44997) (xy 73.908727 -111.397164) (xy 73.90159 -111.342774)
			(xy 73.902318 -111.287923) (xy 73.910895 -111.233741) (xy 73.927144 -111.181347) (xy 73.950731 -111.131821)
			(xy 73.965562 -111.108744) (xy 73.974324 -111.095872) (xy 73.993652 -111.071457) (xy 74.00417 -111.059976)
			(xy 74.004932 -111.059214) (xy 74.008388 -111.055291) (xy 74.013766 -111.046329) (xy 74.0156 -111.041434)
			(xy 74.017378 -111.03483) (xy 74.018394 -111.024924) (xy 74.018394 -110.955836) (xy 74.018059 -110.947232)
			(xy 74.012347 -110.931002) (xy 74.007218 -110.924086) (xy 74.00671 -110.923578) (xy 74.003662 -110.920022)
			(xy 74.000868 -110.917228) (xy 73.992486 -110.907322) (xy 73.975065 -110.886132) (xy 73.945848 -110.839704)
			(xy 73.923582 -110.78957) (xy 73.908727 -110.736764) (xy 73.90159 -110.682374) (xy 73.902318 -110.627523)
			(xy 73.910895 -110.573341) (xy 73.927144 -110.520947) (xy 73.950731 -110.471421) (xy 73.965562 -110.448344)
			(xy 73.974324 -110.435472) (xy 73.993652 -110.411057) (xy 74.00417 -110.399576) (xy 74.004932 -110.398814)
			(xy 74.008388 -110.394891) (xy 74.013766 -110.385929) (xy 74.0156 -110.381034) (xy 74.017378 -110.37443)
			(xy 74.018394 -110.364524) (xy 74.018394 -110.295436) (xy 74.018059 -110.286832) (xy 74.012347 -110.270602)
			(xy 74.007218 -110.263686) (xy 74.00671 -110.263178) (xy 74.003662 -110.259622) (xy 74.000868 -110.256828)
			(xy 73.992486 -110.246922) (xy 73.975065 -110.225732) (xy 73.945848 -110.179304) (xy 73.923582 -110.12917)
			(xy 73.908727 -110.076364) (xy 73.90159 -110.021974) (xy 73.902318 -109.967123) (xy 73.910895 -109.912941)
			(xy 73.927144 -109.860547) (xy 73.950731 -109.811021) (xy 73.965562 -109.787944) (xy 73.974324 -109.775072)
			(xy 73.993652 -109.750657) (xy 74.00417 -109.739176) (xy 74.004932 -109.738414) (xy 74.008388 -109.734491)
			(xy 74.013766 -109.725529) (xy 74.0156 -109.720634) (xy 74.017378 -109.71403) (xy 74.018394 -109.704124)
			(xy 74.018394 -109.635036) (xy 74.018059 -109.626432) (xy 74.012347 -109.610202) (xy 74.007218 -109.603286)
			(xy 74.00671 -109.602778) (xy 74.003662 -109.599222) (xy 74.000868 -109.596428) (xy 73.992486 -109.586522)
			(xy 73.992232 -109.586268) (xy 73.98893 -109.582204) (xy 73.893934 -109.47019) (xy 73.888103 -109.462675)
			(xy 73.881971 -109.444682) (xy 73.882804 -109.425692) (xy 73.890489 -109.408306) (xy 73.896982 -109.401356)
			(xy 73.904602 -109.393736) (xy 73.903078 -109.373416) (xy 73.903078 -109.372654) (xy 73.901554 -109.339126)
			(xy 73.901554 -109.332776) (xy 73.902467 -109.305821) (xy 73.910947 -109.25256) (xy 73.926843 -109.201023)
			(xy 73.94984 -109.152239) (xy 73.979477 -109.10718) (xy 74.015166 -109.066744) (xy 74.056193 -109.031738)
			(xy 74.101742 -109.002858) (xy 74.150904 -108.980682) (xy 74.2027 -108.96565) (xy 74.256096 -108.958063)
			(xy 74.283062 -108.957618) (xy 74.308401 -108.95803) (xy 74.358635 -108.964735) (xy 74.407538 -108.978032)
			(xy 74.45425 -108.997688) (xy 74.497948 -109.023355) (xy 74.537863 -109.054582) (xy 74.555858 -109.072426)
			(xy 74.55789 -109.074458) (xy 74.560875 -109.077363) (xy 74.567644 -109.082214) (xy 74.571352 -109.08411)
			(xy 74.591926 -109.093254) (xy 74.596607 -109.095096) (xy 74.606456 -109.097137) (xy 74.611484 -109.097318)
			(xy 74.666094 -109.097318) (xy 74.67854 -109.094778) (xy 74.684382 -109.093762) (xy 74.713084 -109.081062)
			(xy 74.719942 -109.07395) (xy 74.737971 -109.055882) (xy 74.778021 -109.024237) (xy 74.821933 -108.998217)
			(xy 74.868924 -108.978286) (xy 74.918153 -108.9648) (xy 74.968741 -108.958) (xy 74.994262 -108.957618)
			(xy 75.021516 -108.958079) (xy 75.07547 -108.965831) (xy 75.127771 -108.981184) (xy 75.177354 -109.003825)
			(xy 75.22321 -109.033293) (xy 75.264405 -109.068987) (xy 75.3001 -109.110181) (xy 75.329569 -109.156036)
			(xy 75.352211 -109.205618) (xy 75.367566 -109.257919) (xy 75.37532 -109.311872) (xy 75.37577 -109.339126)
			(xy 75.375247 -109.367864) (xy 75.36662 -109.424689) (xy 75.349566 -109.479577) (xy 75.324471 -109.531286)
			(xy 75.291902 -109.578644) (xy 75.272646 -109.599984) (xy 75.265534 -109.607604) (xy 75.262232 -109.61624)
			(xy 75.26147 -109.618018) (xy 75.260242 -109.621967) (xy 75.258973 -109.630138) (xy 75.25893 -109.634274)
			(xy 75.25893 -109.70387) (xy 75.259692 -109.708188) (xy 75.261724 -109.72038) (xy 75.268328 -109.733842)
			(xy 75.273408 -109.73943) (xy 75.273662 -109.739684) (xy 75.277218 -109.743494) (xy 75.27798 -109.74451)
			(xy 75.28814 -109.756194) (xy 75.292458 -109.761528) (xy 75.30973 -109.784896) (xy 75.324716 -109.808772)
			(xy 75.32497 -109.80928) (xy 75.327256 -109.81309) (xy 75.338768 -109.834423) (xy 75.356907 -109.879377)
			(xy 75.369218 -109.926264) (xy 75.372722 -109.95025) (xy 75.372976 -109.953806) (xy 75.375805 -109.981432)
			(xy 75.374393 -110.036946) (xy 75.36495 -110.091668) (xy 75.347676 -110.144445) (xy 75.322935 -110.19416)
			(xy 75.291249 -110.239765) (xy 75.272646 -110.260384) (xy 75.265534 -110.268004) (xy 75.262232 -110.27664)
			(xy 75.26147 -110.278418) (xy 75.260242 -110.282367) (xy 75.258973 -110.290538) (xy 75.25893 -110.294674)
			(xy 75.25893 -110.36427) (xy 75.259692 -110.368588) (xy 75.261724 -110.38078) (xy 75.268328 -110.394242)
			(xy 75.273408 -110.39983) (xy 75.273662 -110.400084) (xy 75.277218 -110.403894) (xy 75.27798 -110.40491)
			(xy 75.28814 -110.416594) (xy 75.292458 -110.421928) (xy 75.30973 -110.445296) (xy 75.324716 -110.469172)
			(xy 75.32497 -110.46968) (xy 75.327256 -110.47349) (xy 75.338768 -110.494823) (xy 75.356907 -110.539777)
			(xy 75.369218 -110.586664) (xy 75.372722 -110.61065) (xy 75.372976 -110.614206) (xy 75.375805 -110.641832)
			(xy 75.374393 -110.697346) (xy 75.36495 -110.752068) (xy 75.347676 -110.804845) (xy 75.322935 -110.85456)
			(xy 75.291249 -110.900165) (xy 75.272646 -110.920784) (xy 75.265534 -110.928404) (xy 75.262232 -110.93704)
			(xy 75.26147 -110.938818) (xy 75.260242 -110.942767) (xy 75.258973 -110.950938) (xy 75.25893 -110.955074)
			(xy 75.25893 -111.02467) (xy 75.259692 -111.028988) (xy 75.261724 -111.04118) (xy 75.268328 -111.054642)
			(xy 75.273408 -111.06023) (xy 75.273662 -111.060484) (xy 75.277218 -111.064294) (xy 75.27798 -111.06531)
			(xy 75.28814 -111.076994) (xy 75.292458 -111.082328) (xy 75.30973 -111.105696) (xy 75.324716 -111.129572)
			(xy 75.32497 -111.13008) (xy 75.327256 -111.13389) (xy 75.338768 -111.155223) (xy 75.356907 -111.200177)
			(xy 75.369218 -111.247064) (xy 75.372722 -111.27105) (xy 75.372976 -111.274606) (xy 75.375805 -111.302232)
			(xy 75.374393 -111.357746) (xy 75.36495 -111.412468) (xy 75.347676 -111.465245) (xy 75.322935 -111.51496)
			(xy 75.291249 -111.560565) (xy 75.272646 -111.581184) (xy 75.265534 -111.588804) (xy 75.262232 -111.59744)
			(xy 75.26147 -111.599218) (xy 75.260242 -111.603167) (xy 75.258973 -111.611338) (xy 75.25893 -111.615474)
			(xy 75.25893 -111.674148) (xy 75.259024 -111.678902) (xy 75.26081 -111.68824) (xy 75.262486 -111.69269)
			(xy 75.265788 -111.701326) (xy 75.273154 -111.708946) (xy 75.287124 -111.724186) (xy 75.292412 -111.729854)
			(xy 75.305598 -111.73799) (xy 75.313032 -111.740188) (xy 75.319382 -111.741712) (xy 75.331574 -111.743236)
			(xy 75.388978 -111.743236) (xy 75.39101 -111.742982) (xy 75.418696 -111.74222) (xy 75.486514 -111.74222)
			(xy 75.491405 -111.742353) (xy 75.501 -111.744265) (xy 75.505564 -111.74603) (xy 75.597004 -111.783368)
			(xy 75.598528 -111.783876) (xy 75.60431 -111.78597) (xy 75.614715 -111.79252) (xy 75.619102 -111.79683)
			(xy 75.625452 -111.803434) (xy 75.627738 -111.80572) (xy 75.630786 -111.808514) (xy 75.636716 -111.813109)
			(xy 75.650532 -111.818931) (xy 75.657964 -111.819944) (xy 75.66279 -111.820198) (xy 76.56322 -111.820198)
			(xy 76.568801 -111.820048) (xy 76.579692 -111.817604) (xy 76.58481 -111.815372) (xy 76.589128 -111.81334)
			(xy 76.602844 -111.80699) (xy 76.609448 -111.800386) (xy 76.730606 -111.678974) (xy 77.011022 -111.398558)
			(xy 77.016002 -111.393128) (xy 77.022846 -111.380088) (xy 77.024484 -111.372904) (xy 77.024484 -111.372396)
			(xy 77.0255 -111.362998) (xy 77.0255 -108.559092) (xy 77.025764 -108.540765) (xy 77.029968 -108.504354)
			(xy 77.033882 -108.486448) (xy 77.035152 -108.48086) (xy 77.038454 -108.467144) (xy 77.039978 -108.462572)
			(xy 77.04074 -108.46054) (xy 77.042264 -108.455968) (xy 77.042264 -108.455714) (xy 77.043026 -108.453682)
			(xy 77.043534 -108.452412) (xy 77.043788 -108.451396) (xy 77.048843 -108.437793) (xy 77.06105 -108.411462)
			(xy 77.068172 -108.398818) (xy 77.074915 -108.387294) (xy 77.090046 -108.365293) (xy 77.098398 -108.354876)
			(xy 77.09916 -108.35386) (xy 77.136244 -108.303822) (xy 77.14107 -108.298234) (xy 77.50683 -107.932474)
			(xy 77.508354 -107.930696) (xy 77.52842 -107.908598) (xy 78.688946 -106.748072) (xy 78.69393 -106.742571)
			(xy 78.700767 -106.729404) (xy 78.702408 -106.722164) (xy 78.703424 -106.712512) (xy 78.703424 -93.624146)
			(xy 78.703256 -93.618136) (xy 78.700433 -93.606454) (xy 78.697836 -93.601032) (xy 78.696 -93.597555)
			(xy 78.691414 -93.591169) (xy 78.688692 -93.588332) (xy 77.672438 -92.572078) (xy 77.665591 -92.56468)
			(xy 77.657858 -92.546082) (xy 77.657452 -92.53601) (xy 77.657452 -91.970098) (xy 77.65288 -91.959938)
			(xy 77.643287 -91.938133) (xy 77.629744 -91.892463) (xy 77.622865 -91.845325) (xy 77.6224 -91.821508)
			(xy 77.6224 -87.941912) (xy 77.622846 -87.918093) (xy 77.629728 -87.870955) (xy 77.643281 -87.825285)
			(xy 77.65288 -87.803482) (xy 77.657452 -87.793322) (xy 77.657452 -87.750904) (xy 77.657876 -87.740835)
			(xy 77.665595 -87.722234) (xy 77.672438 -87.714836) (xy 79.21117 -86.176104) (xy 79.215996 -86.170516)
			(xy 79.215996 -83.730592) (xy 79.216528 -83.70457) (xy 79.224701 -83.65317) (xy 79.2408 -83.603677)
			(xy 79.264429 -83.557304) (xy 79.295008 -83.51519) (xy 79.313024 -83.496404) (xy 80.528414 -82.281014)
			(xy 80.534764 -82.270346) (xy 80.536542 -82.264504) (xy 80.544988 -82.238936) (xy 80.568064 -82.190285)
			(xy 80.597748 -82.145359) (xy 80.633451 -82.105052) (xy 80.674464 -82.070161) (xy 80.719973 -82.04138)
			(xy 80.769076 -82.019281) (xy 80.820796 -82.004301) (xy 80.874109 -81.996739) (xy 80.901032 -81.99628)
			(xy 80.928532 -81.996761) (xy 80.982963 -82.004648) (xy 81.035702 -82.020256) (xy 81.085658 -82.043262)
			(xy 81.131802 -82.073191) (xy 81.173179 -82.109425) (xy 81.208936 -82.151215) (xy 81.238334 -82.197699)
			(xy 81.250028 -82.222594) (xy 81.253076 -82.229198) (xy 81.257902 -82.234786) (xy 81.267808 -82.243676)
			(xy 81.275682 -82.24901) (xy 81.28254 -82.251296) (xy 81.288128 -82.253074) (xy 81.355692 -82.265774)
			(xy 81.365852 -82.266536) (xy 81.384648 -82.266282) (xy 81.389263 -82.265818) (xy 81.398213 -82.26339)
			(xy 81.402428 -82.261456) (xy 81.409032 -82.2579) (xy 81.416906 -82.25155) (xy 82.780886 -80.88757)
			(xy 82.788286 -80.88073) (xy 82.806885 -80.873015) (xy 82.816954 -80.872584) (xy 87.366602 -80.872584)
			(xy 87.373714 -80.872076) (xy 88.224106 -80.021684) (xy 88.230456 -80.011016) (xy 88.232234 -80.005174)
			(xy 88.240345 -79.980651) (xy 88.262268 -79.933882) (xy 88.275922 -79.911956) (xy 88.29279 -79.886771)
			(xy 88.333202 -79.841596) (xy 88.380258 -79.80339) (xy 88.406224 -79.78775) (xy 88.411558 -79.784702)
			(xy 88.419178 -79.77759) (xy 88.428068 -79.76489) (xy 88.442038 -79.745078) (xy 88.443816 -79.732886)
			(xy 88.451436 -79.681578) (xy 88.451436 -79.68107) (xy 88.453976 -79.666084) (xy 88.455271 -79.655913)
			(xy 88.450564 -79.635976) (xy 88.444832 -79.627476) (xy 88.441276 -79.622904) (xy 85.045804 -76.227686)
			(xy 85.026495 -76.207509) (xy 84.994439 -76.161784) (xy 84.98205 -76.136754) (xy 84.970112 -76.107798)
			(xy 84.96681 -76.097892) (xy 84.964524 -76.091796) (xy 84.963 -76.086208) (xy 84.962746 -76.08443)
			(xy 84.961984 -76.081636) (xy 84.957666 -76.062078) (xy 84.957666 -76.060808) (xy 84.95665 -76.055982)
			(xy 84.952586 -76.028296) (xy 84.952586 -76.026772) (xy 84.951824 -76.002896) (xy 84.951824 -65.444878)
			(xy 84.951393 -65.436025) (xy 84.945278 -65.419402) (xy 84.939886 -65.412366) (xy 84.935306 -65.407206)
			(xy 84.923975 -65.399345) (xy 84.917534 -65.396872) (xy 84.906358 -65.393062) (xy 84.906104 -65.393062)
			(xy 84.904834 -65.392554) (xy 84.874862 -65.381124) (xy 84.82838 -65.363344) (xy 84.823046 -65.36182)
			(xy 84.817299 -65.360786) (xy 84.805628 -65.361045) (xy 84.799932 -65.362328) (xy 84.794598 -65.364106)
			(xy 84.789069 -65.366348) (xy 84.77918 -65.373018) (xy 84.77504 -65.377314) (xy 84.774532 -65.377822)
			(xy 84.756323 -65.397553) (xy 84.715328 -65.432224) (xy 84.669884 -65.460817) (xy 84.620886 -65.482769)
			(xy 84.569298 -65.497648) (xy 84.516135 -65.50516) (xy 84.48929 -65.505584) (xy 84.462038 -65.50512)
			(xy 84.40809 -65.497362) (xy 84.355794 -65.482005) (xy 84.306217 -65.459361) (xy 84.260367 -65.429893)
			(xy 84.219177 -65.394199) (xy 84.183487 -65.353006) (xy 84.154023 -65.307153) (xy 84.131384 -65.257574)
			(xy 84.116031 -65.205277) (xy 84.108278 -65.151328) (xy 84.107782 -65.124076) (xy 84.108281 -65.096336)
			(xy 84.116316 -65.04144) (xy 84.132214 -64.988287) (xy 84.155639 -64.937994) (xy 84.186098 -64.891622)
			(xy 84.222949 -64.850149) (xy 84.265416 -64.814447) (xy 84.312604 -64.785269) (xy 84.363519 -64.76323)
			(xy 84.417088 -64.748793) (xy 84.444586 -64.745108) (xy 84.459318 -64.74333) (xy 84.48929 -64.742314)
			(xy 84.515783 -64.742771) (xy 84.56826 -64.750097) (xy 84.619223 -64.764596) (xy 84.667698 -64.785991)
			(xy 84.712755 -64.813872) (xy 84.753533 -64.847706) (xy 84.78925 -64.886844) (xy 84.819223 -64.930537)
			(xy 84.842878 -64.97795) (xy 84.851748 -65.002918) (xy 84.852764 -65.00622) (xy 84.859876 -65.020444)
			(xy 84.862337 -65.023847) (xy 84.868209 -65.02985) (xy 84.87156 -65.032382) (xy 84.877656 -65.0367)
			(xy 84.892388 -65.041526) (xy 84.901532 -65.041526) (xy 84.924392 -65.036192) (xy 84.932439 -65.031529)
			(xy 84.944782 -65.017637) (xy 84.951398 -65.000271) (xy 84.951824 -64.99098) (xy 84.951824 -64.89827)
			(xy 84.951751 -64.894263) (xy 84.950467 -64.886352) (xy 84.949284 -64.882522) (xy 84.948268 -64.879474)
			(xy 84.944712 -64.870838) (xy 84.9376 -64.863472) (xy 84.936584 -64.862202) (xy 84.93506 -64.860424)
			(xy 84.59851 -64.524128) (xy 84.580958 -64.505912) (xy 84.551226 -64.464987) (xy 84.528268 -64.419913)
			(xy 84.512649 -64.371801) (xy 84.504754 -64.321836) (xy 84.504276 -64.296544) (xy 84.504276 -63.721488)
			(xy 84.501482 -63.713614) (xy 84.493315 -63.687833) (xy 84.4845 -63.63448) (xy 84.483956 -63.607442)
			(xy 84.483956 -62.580266) (xy 84.484445 -62.55418) (xy 84.492616 -62.502651) (xy 84.508753 -62.453037)
			(xy 84.532457 -62.40656) (xy 84.563143 -62.364367) (xy 84.581238 -62.34557) (xy 85.083904 -61.842904)
			(xy 85.103893 -61.823712) (xy 85.149036 -61.791582) (xy 85.198878 -61.767373) (xy 85.252042 -61.751754)
			(xy 85.279484 -61.747908) (xy 85.279992 -61.747908) (xy 85.289644 -61.745876) (xy 85.314099 -61.738306)
			(xy 85.364634 -61.730144) (xy 85.390228 -61.72962) (xy 86.38413 -61.72962) (xy 86.394036 -61.728604)
			(xy 86.416642 -61.722762) (xy 86.422738 -61.71946) (xy 86.444813 -61.707399) (xy 86.491449 -61.688544)
			(xy 86.515702 -61.681868) (xy 86.539608 -61.676137) (xy 86.588402 -61.670147) (xy 86.612984 -61.66993)
			(xy 86.617556 -61.66993) (xy 86.62864 -61.670195) (xy 86.650752 -61.671846) (xy 86.661752 -61.673232)
			(xy 86.680317 -61.675965) (xy 86.716832 -61.684619) (xy 86.73465 -61.690504) (xy 86.749432 -61.695757)
			(xy 86.778171 -61.708344) (xy 86.792054 -61.71565) (xy 86.793578 -61.716412) (xy 86.799928 -61.71946)
			(xy 86.961472 -61.71946) (xy 86.971124 -61.718444) (xy 86.978369 -61.716819) (xy 86.991541 -61.70998)
			(xy 86.997032 -61.704982) (xy 87.81288 -60.889134) (xy 87.813134 -60.887102) (xy 87.813388 -60.884054)
			(xy 87.813388 -54.579012) (xy 87.813135 -54.573751) (xy 87.810702 -54.563505) (xy 87.808562 -54.558692)
			(xy 87.802974 -54.556406) (xy 87.782146 -54.54777) (xy 87.772761 -54.544245) (xy 87.75273 -54.544107)
			(xy 87.73419 -54.551691) (xy 87.726774 -54.558438) (xy 84.418149 -57.867296) (xy 85.642956 -57.867296)
			(xy 85.647027 -57.811674) (xy 85.659153 -57.757237) (xy 85.679076 -57.705146) (xy 85.706372 -57.656511)
			(xy 85.740458 -57.612368) (xy 85.780607 -57.573659) (xy 85.825965 -57.541208) (xy 85.875565 -57.515707)
			(xy 85.928349 -57.4977) (xy 85.983192 -57.48757) (xy 86.038926 -57.485533) (xy 86.094363 -57.491633)
			(xy 86.14832 -57.505739) (xy 86.199649 -57.527551) (xy 86.247255 -57.556605) (xy 86.290123 -57.59228)
			(xy 86.32734 -57.633817) (xy 86.358113 -57.68033) (xy 86.381785 -57.730827) (xy 86.397853 -57.784234)
			(xy 86.405973 -57.83941) (xy 86.406482 -57.867296) (xy 86.405973 -57.895182) (xy 86.397853 -57.950358)
			(xy 86.381785 -58.003765) (xy 86.358113 -58.054262) (xy 86.32734 -58.100775) (xy 86.290123 -58.142312)
			(xy 86.247255 -58.177987) (xy 86.199649 -58.207041) (xy 86.14832 -58.228853) (xy 86.094363 -58.242959)
			(xy 86.038926 -58.249059) (xy 85.983192 -58.247022) (xy 85.928349 -58.236892) (xy 85.875565 -58.218885)
			(xy 85.825965 -58.193384) (xy 85.780607 -58.160933) (xy 85.740458 -58.122224) (xy 85.706372 -58.078081)
			(xy 85.679076 -58.029446) (xy 85.659153 -57.977355) (xy 85.647027 -57.922918) (xy 85.642956 -57.867296)
			(xy 84.418149 -57.867296) (xy 84.112608 -58.172858) (xy 84.106258 -58.183526) (xy 84.10448 -58.189368)
			(xy 84.096031 -58.214933) (xy 84.072949 -58.263578) (xy 84.043262 -58.308497) (xy 84.007558 -58.348799)
			(xy 83.966545 -58.383685) (xy 83.921037 -58.412462) (xy 83.871938 -58.434559) (xy 83.82022 -58.449539)
			(xy 83.766911 -58.457102) (xy 83.73999 -58.457592) (xy 83.712738 -58.457128) (xy 83.658789 -58.44937)
			(xy 83.606493 -58.434013) (xy 83.556915 -58.411369) (xy 83.511065 -58.381901) (xy 83.469875 -58.346207)
			(xy 83.434184 -58.305014) (xy 83.404718 -58.259162) (xy 83.382078 -58.209582) (xy 83.366725 -58.157286)
			(xy 83.35897 -58.103336) (xy 83.358482 -58.076084) (xy 83.358945 -58.049163) (xy 83.366513 -57.995855)
			(xy 83.381497 -57.94414) (xy 83.4036 -57.895043) (xy 83.432383 -57.84954) (xy 83.467274 -57.808533)
			(xy 83.507581 -57.772835) (xy 83.552505 -57.743156) (xy 83.601154 -57.720084) (xy 83.626706 -57.711594)
			(xy 83.632548 -57.709816) (xy 83.643216 -57.703466) (xy 87.450676 -53.89626) (xy 87.454976 -53.891752)
			(xy 87.461414 -53.88109) (xy 87.463376 -53.875178) (xy 87.46436 -53.871576) (xy 87.465385 -53.86418)
			(xy 87.465408 -53.860446) (xy 87.465408 -47.035974) (xy 87.465244 -47.029964) (xy 87.462425 -47.018279)
			(xy 87.45982 -47.01286) (xy 87.45798 -47.009386) (xy 87.453386 -47.003008) (xy 87.450676 -47.00016)
			(xy 80.768952 -40.318436) (xy 80.7661 -40.315732) (xy 80.759718 -40.311145) (xy 80.756252 -40.309292)
			(xy 80.750825 -40.30671) (xy 80.739145 -40.303888) (xy 80.733138 -40.303704) (xy 78.466442 -40.303704)
			(xy 78.462632 -40.305736) (xy 78.434141 -40.320735) (xy 78.373379 -40.342018) (xy 78.309911 -40.352823)
			(xy 78.27772 -40.353488) (xy 78.250467 -40.353026) (xy 78.196515 -40.345271) (xy 78.144216 -40.329917)
			(xy 78.094634 -40.307275) (xy 78.04878 -40.277807) (xy 78.007587 -40.242113) (xy 77.971893 -40.20092)
			(xy 77.942425 -40.155066) (xy 77.919783 -40.105484) (xy 77.904429 -40.053185) (xy 77.896674 -39.999233)
			(xy 77.896212 -39.97198) (xy 77.896693 -39.944822) (xy 77.9044 -39.891057) (xy 77.919654 -39.838928)
			(xy 77.942148 -39.78949) (xy 77.971427 -39.743742) (xy 78.006899 -39.702609) (xy 78.047846 -39.666923)
			(xy 78.09344 -39.637406) (xy 78.14276 -39.614654) (xy 78.194809 -39.599127) (xy 78.248534 -39.59114)
			(xy 78.275688 -39.590472) (xy 78.278482 -39.590472) (xy 78.310544 -39.591199) (xy 78.373747 -39.602044)
			(xy 78.434256 -39.623281) (xy 78.462632 -39.638224) (xy 78.466442 -39.640256) (xy 80.627982 -39.640256)
			(xy 80.637507 -39.639864) (xy 80.655243 -39.632913) (xy 80.669216 -39.619965) (xy 80.673702 -39.611554)
			(xy 80.674972 -39.608506) (xy 80.677686 -39.601336) (xy 80.679122 -39.586079) (xy 80.677766 -39.578534)
			(xy 80.676496 -39.57193) (xy 80.669638 -39.55923) (xy 77.333856 -36.223448) (xy 77.331004 -36.220744)
			(xy 77.324624 -36.216154) (xy 77.321156 -36.214304) (xy 77.315729 -36.211721) (xy 77.30405 -36.208897)
			(xy 77.298042 -36.208716) (xy 76.73848 -36.208716) (xy 76.72959 -36.216844) (xy 76.697078 -36.261802)
			(xy 76.680568 -36.284916) (xy 76.67683 -36.291025) (xy 76.672564 -36.304689) (xy 76.672186 -36.31184)
			(xy 76.672186 -36.331906) (xy 76.674472 -36.339526) (xy 76.682635 -36.367329) (xy 76.691429 -36.424601)
			(xy 76.691998 -36.453572) (xy 76.691537 -36.480826) (xy 76.683783 -36.534779) (xy 76.668429 -36.58708)
			(xy 76.645788 -36.636663) (xy 76.616321 -36.682519) (xy 76.580627 -36.723714) (xy 76.539433 -36.75941)
			(xy 76.493579 -36.788879) (xy 76.443997 -36.811523) (xy 76.391697 -36.826879) (xy 76.337744 -36.834635)
			(xy 76.31049 -36.83508) (xy 76.283367 -36.834602) (xy 76.229668 -36.826916) (xy 76.177599 -36.811701)
			(xy 76.128211 -36.789263) (xy 76.082499 -36.760054) (xy 76.041386 -36.724665) (xy 76.005701 -36.683809)
			(xy 75.976163 -36.638309) (xy 75.953369 -36.589084) (xy 75.937778 -36.537127) (xy 75.929704 -36.483485)
			(xy 75.928982 -36.456366) (xy 75.928982 -36.45281) (xy 75.929543 -36.423839) (xy 75.938351 -36.366569)
			(xy 75.946508 -36.338764) (xy 75.94727 -36.336224) (xy 75.948794 -36.331398) (xy 75.950064 -36.320984)
			(xy 75.950318 -36.31057) (xy 75.949302 -36.2966) (xy 75.893676 -36.219638) (xy 75.89137 -36.216576)
			(xy 75.886018 -36.211089) (xy 75.883008 -36.208716) (xy 75.360276 -36.208716) (xy 75.354434 -36.211764)
			(xy 75.351132 -36.213288) (xy 75.32333 -36.227423) (xy 75.264268 -36.247451) (xy 75.202736 -36.257614)
			(xy 75.171554 -36.258246) (xy 75.170792 -36.258246) (xy 75.143538 -36.25776) (xy 75.089586 -36.250001)
			(xy 75.037287 -36.234644) (xy 74.987706 -36.212) (xy 74.941852 -36.182531) (xy 74.900659 -36.146836)
			(xy 74.864964 -36.105642) (xy 74.835496 -36.059787) (xy 74.812853 -36.010205) (xy 74.797497 -35.957906)
			(xy 74.78974 -35.903954) (xy 74.78974 -35.849446) (xy 74.797497 -35.795494) (xy 74.812853 -35.743195)
			(xy 74.835496 -35.693613) (xy 74.864964 -35.647758) (xy 74.900659 -35.606564) (xy 74.941852 -35.570869)
			(xy 74.987706 -35.5414) (xy 75.037287 -35.518756) (xy 75.089586 -35.503399) (xy 75.143538 -35.49564)
			(xy 75.170792 -35.49523) (xy 75.171554 -35.49523) (xy 75.202736 -35.495867) (xy 75.264267 -35.506032)
			(xy 75.323333 -35.526049) (xy 75.351132 -35.540188) (xy 75.354434 -35.541712) (xy 75.360276 -35.54476)
			(xy 77.142848 -35.54476) (xy 77.151942 -35.544341) (xy 77.168954 -35.537897) (xy 77.182639 -35.525912)
			(xy 77.187298 -35.51809) (xy 77.18933 -35.51301) (xy 77.192059 -35.505979) (xy 77.193624 -35.490984)
			(xy 77.192378 -35.483546) (xy 77.191108 -35.476942) (xy 77.183996 -35.463734) (xy 75.899772 -34.17951)
			(xy 75.881738 -34.16074) (xy 75.851154 -34.118625) (xy 75.827525 -34.072248) (xy 75.811431 -34.022751)
			(xy 75.803266 -33.971346) (xy 75.802744 -33.945322) (xy 75.802744 -28.657804) (xy 75.800712 -28.653994)
			(xy 75.794059 -28.641682) (xy 75.782363 -28.616257) (xy 75.777344 -28.603194) (xy 75.770232 -28.58262)
			(xy 75.770232 -28.582112) (xy 75.7682 -28.57627) (xy 75.762104 -28.56611) (xy 75.59929 -28.403296)
			(xy 75.592178 -28.402788) (xy 72.685148 -28.402788) (xy 72.659859 -28.402289) (xy 72.609903 -28.394375)
			(xy 72.561799 -28.37875) (xy 72.516728 -28.355798) (xy 72.475799 -28.326083) (xy 72.457564 -28.308554)
			(xy 71.927974 -27.77871) (xy 71.921903 -27.773004) (xy 71.906981 -27.765611) (xy 71.898764 -27.764232)
			(xy 71.891906 -27.763724) (xy 71.71055 -27.763724) (xy 71.700882 -27.764194) (xy 71.682953 -27.771447)
			(xy 71.668986 -27.784825) (xy 71.664576 -27.793442) (xy 71.652638 -27.821128) (xy 71.627238 -27.88031)
			(xy 71.62533 -27.885171) (xy 71.623284 -27.895409) (xy 71.623174 -27.90063) (xy 71.63689 -27.93492)
			(xy 71.64324 -27.941778) (xy 71.661976 -27.96291) (xy 71.694649 -28.008975) (xy 71.721414 -28.058706)
			(xy 71.741864 -28.11135) (xy 71.75569 -28.166108) (xy 71.762681 -28.22215) (xy 71.763128 -28.250388)
			(xy 71.763128 -29.114242) (xy 71.762638 -29.144226) (xy 71.75481 -29.203682) (xy 71.739289 -29.261607)
			(xy 71.71634 -29.317011) (xy 71.686356 -29.368945) (xy 71.64985 -29.416521) (xy 71.607445 -29.458926)
			(xy 71.559869 -29.495432) (xy 71.507935 -29.525416) (xy 71.452531 -29.548365) (xy 71.394606 -29.563886)
			(xy 71.33515 -29.571714) (xy 71.275182 -29.571714) (xy 71.215726 -29.563886) (xy 71.157801 -29.548365)
			(xy 71.102397 -29.525416) (xy 71.050463 -29.495432) (xy 71.002887 -29.458926) (xy 70.960482 -29.416521)
			(xy 70.923976 -29.368945) (xy 70.893992 -29.317011) (xy 70.871043 -29.261607) (xy 70.855522 -29.203682)
			(xy 70.847694 -29.144226) (xy 70.847204 -29.114242) (xy 70.847204 -28.250388) (xy 70.847636 -28.222148)
			(xy 70.854611 -28.166101) (xy 70.86843 -28.111338) (xy 70.888882 -28.058691) (xy 70.915656 -28.008961)
			(xy 70.948346 -27.962903) (xy 70.967092 -27.941778) (xy 70.973442 -27.93492) (xy 70.987158 -27.90063)
			(xy 70.987088 -27.895404) (xy 70.985046 -27.885158) (xy 70.983094 -27.88031) (xy 70.957694 -27.821128)
			(xy 70.945756 -27.793442) (xy 70.941362 -27.784811) (xy 70.927392 -27.771419) (xy 70.909456 -27.764153)
			(xy 70.899782 -27.763724) (xy 70.833996 -27.763724) (xy 70.807974 -27.763192) (xy 70.756576 -27.755018)
			(xy 70.707084 -27.738916) (xy 70.660715 -27.715284) (xy 70.618605 -27.6847) (xy 70.599808 -27.666696)
			(xy 69.525896 -26.592784) (xy 69.516752 -26.594562) (xy 69.50314 -26.59829) (xy 69.478526 -26.612079)
			(xy 69.468238 -26.62174) (xy 69.46773 -26.622248) (xy 69.458911 -26.631873) (xy 69.446053 -26.65458)
			(xy 69.439399 -26.679813) (xy 69.439028 -26.69286) (xy 69.439028 -27.342846) (xy 69.438538 -27.372814)
			(xy 69.430715 -27.432236) (xy 69.415202 -27.490129) (xy 69.392266 -27.545502) (xy 69.362299 -27.597408)
			(xy 69.325812 -27.644958) (xy 69.283432 -27.687338) (xy 69.235882 -27.723825) (xy 69.183976 -27.753792)
			(xy 69.128603 -27.776728) (xy 69.07071 -27.792241) (xy 69.011288 -27.800064) (xy 68.951352 -27.800064)
			(xy 68.89193 -27.792241) (xy 68.834037 -27.776728) (xy 68.778664 -27.753792) (xy 68.726758 -27.723825)
			(xy 68.679208 -27.687338) (xy 68.636828 -27.644958) (xy 68.600341 -27.597408) (xy 68.570374 -27.545502)
			(xy 68.547438 -27.490129) (xy 68.531925 -27.432236) (xy 68.524102 -27.372814) (xy 68.523612 -27.342846)
			(xy 68.523612 -26.734008) (xy 68.523358 -26.479246) (xy 68.523885 -26.447747) (xy 68.532524 -26.385345)
			(xy 68.549631 -26.324715) (xy 68.574885 -26.267001) (xy 68.607807 -26.213291) (xy 68.647779 -26.164598)
			(xy 68.694045 -26.121841) (xy 68.745733 -26.085827) (xy 68.801868 -26.057234) (xy 68.83146 -26.04643)
			(xy 68.831714 -26.04643) (xy 68.832222 -26.046176) (xy 68.838128 -26.043857) (xy 68.848657 -26.036785)
			(xy 68.85305 -26.032206) (xy 68.857368 -26.02738) (xy 68.860162 -26.022046) (xy 68.864734 -26.0096)
			(xy 68.870068 -25.98547) (xy 68.870068 -25.984962) (xy 68.873116 -25.972262) (xy 68.874789 -25.961359)
			(xy 68.869785 -25.9399) (xy 68.863464 -25.93086) (xy 68.862448 -25.92959) (xy 68.8594 -25.926288)
			(xy 68.669916 -25.736804) (xy 68.667065 -25.734099) (xy 68.660686 -25.729506) (xy 68.657216 -25.72766)
			(xy 68.651789 -25.725079) (xy 68.640109 -25.722261) (xy 68.634102 -25.722072) (xy 66.379852 -25.722072)
			(xy 66.37401 -25.72512) (xy 66.368422 -25.727914) (xy 66.340921 -25.741684) (xy 66.282585 -25.761153)
			(xy 66.22188 -25.77101) (xy 66.19113 -25.771602) (xy 66.163876 -25.771141) (xy 66.109922 -25.763387)
			(xy 66.057621 -25.748034) (xy 66.008037 -25.725393) (xy 65.962181 -25.695926) (xy 65.920985 -25.660232)
			(xy 65.885289 -25.619038) (xy 65.855819 -25.573184) (xy 65.833175 -25.523602) (xy 65.817818 -25.471301)
			(xy 65.810061 -25.417348) (xy 65.809622 -25.390094) (xy 65.81011 -25.362163) (xy 65.818255 -25.306898)
			(xy 65.834372 -25.253411) (xy 65.858114 -25.202846) (xy 65.888976 -25.156282) (xy 65.926296 -25.114716)
			(xy 65.969279 -25.079035) (xy 66.017004 -25.050003) (xy 66.068452 -25.028239) (xy 66.095372 -25.020778)
			(xy 66.10223 -25.019) (xy 66.108834 -25.01519) (xy 66.118994 -25.007316) (xy 66.127122 -24.999188)
			(xy 66.135035 -24.990342) (xy 66.142447 -24.967826) (xy 66.141346 -24.956008) (xy 65.789556 -24.604218)
			(xy 65.764376 -24.578273) (xy 65.719936 -24.521242) (xy 65.682848 -24.459179) (xy 65.653674 -24.393025)
			(xy 65.632859 -24.323785) (xy 65.626234 -24.288242) (xy 65.621916 -24.263604) (xy 65.617834 -24.259836)
			(xy 65.608345 -24.254062) (xy 65.60312 -24.252174) (xy 65.593976 -24.249126) (xy 65.525396 -24.22779)
			(xy 65.515744 -24.224742) (xy 65.510408 -24.223297) (xy 65.499384 -24.222521) (xy 65.4939 -24.223218)
			(xy 65.292478 -24.42464) (xy 65.273707 -24.442672) (xy 65.23159 -24.47325) (xy 65.185214 -24.496874)
			(xy 65.135716 -24.512963) (xy 65.084313 -24.521123) (xy 65.05829 -24.521668) (xy 63.86957 -24.521668)
			(xy 63.86576 -24.5237) (xy 63.837269 -24.538695) (xy 63.776506 -24.559969) (xy 63.713038 -24.570762)
			(xy 63.680848 -24.571452) (xy 63.653592 -24.570992) (xy 63.599633 -24.563241) (xy 63.547327 -24.54789)
			(xy 63.497738 -24.525251) (xy 63.451876 -24.495785) (xy 63.410674 -24.460092) (xy 63.374971 -24.418898)
			(xy 63.345494 -24.373043) (xy 63.322842 -24.323459) (xy 63.307478 -24.271157) (xy 63.299714 -24.2172)
			(xy 63.29934 -24.189944) (xy 63.299816 -24.162782) (xy 63.307515 -24.109005) (xy 63.322763 -24.056865)
			(xy 63.345253 -24.007414) (xy 63.374529 -23.961652) (xy 63.409999 -23.920506) (xy 63.450947 -23.884807)
			(xy 63.496544 -23.855276) (xy 63.545869 -23.832511) (xy 63.597924 -23.816972) (xy 63.651656 -23.808973)
			(xy 63.678816 -23.808436) (xy 63.68161 -23.808436) (xy 63.713671 -23.809166) (xy 63.776872 -23.820016)
			(xy 63.837376 -23.84126) (xy 63.86576 -23.856188) (xy 63.86957 -23.85822) (xy 64.899286 -23.85822)
			(xy 64.902588 -23.85822) (xy 64.911606 -23.857268) (xy 64.928134 -23.849841) (xy 64.934846 -23.843742)
			(xy 65.014602 -23.763732) (xy 65.053718 -23.724616) (xy 65.05427 -23.720241) (xy 65.054012 -23.711427)
			(xy 65.05321 -23.70709) (xy 65.04813 -23.69058) (xy 65.04813 -23.690072) (xy 65.025016 -23.616412)
			(xy 65.023145 -23.611066) (xy 65.017367 -23.601327) (xy 65.013586 -23.597108) (xy 65.010538 -23.5966)
			(xy 64.988948 -23.59279) (xy 64.956131 -23.58636) (xy 64.892114 -23.567016) (xy 64.830719 -23.540503)
			(xy 64.772745 -23.507166) (xy 64.718949 -23.467438) (xy 64.67003 -23.421839) (xy 64.626627 -23.370961)
			(xy 64.589305 -23.315469) (xy 64.558551 -23.256085) (xy 64.546226 -23.224998) (xy 64.537336 -23.201884)
			(xy 64.533526 -23.198582) (xy 64.438276 -23.178516) (xy 64.433196 -23.1775) (xy 64.425322 -23.175722)
			(xy 64.421004 -23.176992) (xy 64.158622 -23.439374) (xy 64.135057 -23.462269) (xy 64.083672 -23.503219)
			(xy 64.028029 -23.538162) (xy 63.968825 -23.566661) (xy 63.906805 -23.588357) (xy 63.842747 -23.602978)
			(xy 63.777455 -23.610341) (xy 63.744602 -23.610824) (xy 63.744348 -23.610824) (xy 63.708947 -23.610314)
			(xy 63.638662 -23.601785) (xy 63.569917 -23.584846) (xy 63.503715 -23.559744) (xy 63.441022 -23.526844)
			(xy 63.382752 -23.486627) (xy 63.329754 -23.43968) (xy 63.282802 -23.386686) (xy 63.242581 -23.328419)
			(xy 63.209676 -23.265729) (xy 63.184569 -23.199529) (xy 63.167624 -23.130785) (xy 63.159089 -23.060501)
			(xy 63.158624 -23.0251) (xy 63.158624 -23.024846) (xy 63.159065 -22.991991) (xy 63.166418 -22.926692)
			(xy 63.181035 -22.862628) (xy 63.202733 -22.800603) (xy 63.23124 -22.741398) (xy 63.266196 -22.685757)
			(xy 63.307163 -22.634379) (xy 63.330074 -22.610826) (xy 63.822834 -22.118066) (xy 63.846398 -22.095167)
			(xy 63.89778 -22.054211) (xy 63.953423 -22.019261) (xy 64.012626 -21.990756) (xy 64.074647 -21.969054)
			(xy 64.138706 -21.954427) (xy 64.204 -21.947059) (xy 64.236854 -21.946616) (xy 68.068952 -21.946616)
			(xy 68.070476 -21.94433) (xy 68.071492 -21.942806) (xy 68.101972 -21.892514) (xy 68.101972 -21.892006)
			(xy 68.117466 -21.866098) (xy 68.122292 -21.85416) (xy 68.123816 -21.842476) (xy 68.12407 -21.830792)
			(xy 68.118482 -21.818854) (xy 68.117974 -21.817838) (xy 68.104075 -21.790282) (xy 68.084392 -21.731792)
			(xy 68.074392 -21.670894) (xy 68.073778 -21.640038) (xy 68.073778 -21.63572) (xy 68.074546 -21.607318)
			(xy 68.083459 -21.551206) (xy 68.100598 -21.497037) (xy 68.125585 -21.446011) (xy 68.157866 -21.399257)
			(xy 68.176902 -21.378164) (xy 68.18376 -21.371052) (xy 68.187316 -21.362162) (xy 68.189856 -21.353018)
			(xy 68.190618 -21.344128) (xy 68.190618 -21.27377) (xy 68.190554 -21.269636) (xy 68.189286 -21.261468)
			(xy 68.188078 -21.257514) (xy 68.187316 -21.255736) (xy 68.184014 -21.2471) (xy 68.176902 -21.23948)
			(xy 68.157631 -21.218153) (xy 68.125064 -21.170789) (xy 68.099971 -21.119076) (xy 68.082919 -21.064184)
			(xy 68.074294 -21.007356) (xy 68.074291 -20.949876) (xy 68.082911 -20.893047) (xy 68.099959 -20.838154)
			(xy 68.125048 -20.786439) (xy 68.15761 -20.739072) (xy 68.176902 -20.717764) (xy 68.184014 -20.710144)
			(xy 68.187316 -20.701508) (xy 68.188078 -20.69973) (xy 68.189311 -20.695782) (xy 68.190589 -20.68761)
			(xy 68.190618 -20.683474) (xy 68.190618 -20.61337) (xy 68.190554 -20.609236) (xy 68.189286 -20.601068)
			(xy 68.188078 -20.597114) (xy 68.187316 -20.595336) (xy 68.184014 -20.5867) (xy 68.176902 -20.57908)
			(xy 68.157631 -20.557753) (xy 68.125064 -20.510389) (xy 68.099971 -20.458676) (xy 68.082919 -20.403784)
			(xy 68.074294 -20.346956) (xy 68.074291 -20.289476) (xy 68.082911 -20.232647) (xy 68.099959 -20.177754)
			(xy 68.125048 -20.126039) (xy 68.15761 -20.078672) (xy 68.176902 -20.057364) (xy 68.184014 -20.049744)
			(xy 68.187316 -20.041108) (xy 68.188078 -20.03933) (xy 68.189311 -20.035382) (xy 68.190589 -20.02721)
			(xy 68.190618 -20.023074) (xy 68.190618 -19.95297) (xy 68.190554 -19.948836) (xy 68.189286 -19.940668)
			(xy 68.188078 -19.936714) (xy 68.187316 -19.934936) (xy 68.184014 -19.9263) (xy 68.176902 -19.91868)
			(xy 68.157631 -19.897353) (xy 68.125064 -19.849989) (xy 68.099971 -19.798276) (xy 68.082919 -19.743384)
			(xy 68.074294 -19.686556) (xy 68.074291 -19.629076) (xy 68.082911 -19.572247) (xy 68.099959 -19.517354)
			(xy 68.125048 -19.465639) (xy 68.15761 -19.418272) (xy 68.176902 -19.396964) (xy 68.184014 -19.389344)
			(xy 68.187316 -19.380708) (xy 68.188078 -19.37893) (xy 68.189311 -19.374982) (xy 68.190589 -19.36681)
			(xy 68.190618 -19.362674) (xy 68.190618 -19.29257) (xy 68.190554 -19.288436) (xy 68.189286 -19.280268)
			(xy 68.188078 -19.276314) (xy 68.187316 -19.274536) (xy 68.184014 -19.2659) (xy 68.176902 -19.25828)
			(xy 68.157631 -19.236953) (xy 68.125065 -19.189591) (xy 68.099972 -19.137879) (xy 68.08292 -19.082989)
			(xy 68.074294 -19.026161) (xy 68.073778 -18.997422) (xy 68.074264 -18.970171) (xy 68.08202 -18.916223)
			(xy 68.097375 -18.863928) (xy 68.120017 -18.814351) (xy 68.149483 -18.768501) (xy 68.185174 -18.72731)
			(xy 68.226365 -18.691619) (xy 68.272215 -18.662153) (xy 68.321792 -18.639511) (xy 68.374087 -18.624156)
			(xy 68.428035 -18.6164) (xy 68.482537 -18.6164) (xy 68.536485 -18.624156) (xy 68.58878 -18.639511)
			(xy 68.638357 -18.662153) (xy 68.684207 -18.691619) (xy 68.725398 -18.72731) (xy 68.761089 -18.768501)
			(xy 68.790555 -18.814351) (xy 68.813197 -18.863928) (xy 68.828552 -18.916223) (xy 68.836308 -18.970171)
			(xy 68.836794 -18.997422) (xy 68.836271 -19.02616) (xy 68.827646 -19.082986) (xy 68.810593 -19.137875)
			(xy 68.785499 -19.189585) (xy 68.752932 -19.236945) (xy 68.73367 -19.25828) (xy 68.726558 -19.2659)
			(xy 68.723256 -19.274536) (xy 68.722494 -19.276314) (xy 68.721265 -19.280263) (xy 68.719995 -19.288434)
			(xy 68.719954 -19.29257) (xy 68.719954 -19.362674) (xy 68.720021 -19.366807) (xy 68.721296 -19.374974)
			(xy 68.722494 -19.37893) (xy 68.723256 -19.380708) (xy 68.726558 -19.389344) (xy 68.73367 -19.396964)
			(xy 68.752939 -19.418291) (xy 68.785502 -19.465652) (xy 68.810591 -19.517363) (xy 68.827638 -19.572253)
			(xy 68.836258 -19.629078) (xy 68.836256 -19.686554) (xy 68.827631 -19.743379) (xy 68.810579 -19.798267)
			(xy 68.785486 -19.849975) (xy 68.752919 -19.897334) (xy 68.73367 -19.91868) (xy 68.726558 -19.9263)
			(xy 68.723256 -19.934936) (xy 68.722494 -19.936714) (xy 68.721265 -19.940663) (xy 68.719995 -19.948834)
			(xy 68.719954 -19.95297) (xy 68.719954 -20.023074) (xy 68.720021 -20.027207) (xy 68.721296 -20.035374)
			(xy 68.722494 -20.03933) (xy 68.723256 -20.041108) (xy 68.726558 -20.049744) (xy 68.73367 -20.057364)
			(xy 68.752939 -20.078691) (xy 68.785502 -20.126052) (xy 68.810591 -20.177763) (xy 68.827638 -20.232653)
			(xy 68.836258 -20.289478) (xy 68.836256 -20.346954) (xy 68.827631 -20.403779) (xy 68.810579 -20.458667)
			(xy 68.785486 -20.510375) (xy 68.752919 -20.557734) (xy 68.73367 -20.57908) (xy 68.726558 -20.5867)
			(xy 68.723256 -20.595336) (xy 68.722494 -20.597114) (xy 68.721265 -20.601063) (xy 68.719995 -20.609234)
			(xy 68.719954 -20.61337) (xy 68.719954 -20.683474) (xy 68.720021 -20.687607) (xy 68.721296 -20.695774)
			(xy 68.722494 -20.69973) (xy 68.723256 -20.701508) (xy 68.726558 -20.710144) (xy 68.73367 -20.717764)
			(xy 68.752939 -20.739091) (xy 68.785502 -20.786452) (xy 68.810591 -20.838163) (xy 68.827638 -20.893053)
			(xy 68.836258 -20.949878) (xy 68.836256 -21.007354) (xy 68.827631 -21.064179) (xy 68.810579 -21.119067)
			(xy 68.785486 -21.170775) (xy 68.752919 -21.218134) (xy 68.73367 -21.23948) (xy 68.726558 -21.2471)
			(xy 68.723256 -21.255736) (xy 68.722494 -21.257514) (xy 68.721265 -21.261463) (xy 68.719995 -21.269634)
			(xy 68.719954 -21.27377) (xy 68.719954 -21.343874) (xy 68.720021 -21.348007) (xy 68.721296 -21.356174)
			(xy 68.722494 -21.36013) (xy 68.723256 -21.361908) (xy 68.726558 -21.370544) (xy 68.73367 -21.378164)
			(xy 68.752999 -21.399573) (xy 68.785643 -21.447123) (xy 68.810759 -21.499044) (xy 68.827773 -21.554155)
			(xy 68.836299 -21.611198) (xy 68.836794 -21.640038) (xy 68.836794 -21.641308) (xy 68.836042 -21.671946)
			(xy 68.825971 -21.732397) (xy 68.806379 -21.790464) (xy 68.792598 -21.817838) (xy 68.791074 -21.820632)
			(xy 68.78895 -21.825769) (xy 68.786764 -21.836664) (xy 68.786756 -21.842222) (xy 68.78701 -21.855684)
			(xy 68.8086 -21.892006) (xy 68.8086 -21.892514) (xy 68.83908 -21.942552) (xy 68.841874 -21.946616)
			(xy 73.252584 -21.946616) (xy 73.260291 -21.94638) (xy 73.275019 -21.941842) (xy 73.28154 -21.937726)
			(xy 73.285604 -21.934424) (xy 73.628758 -21.59127) (xy 73.629266 -21.583904) (xy 73.629266 -21.567902)
			(xy 73.626218 -21.556218) (xy 73.6219 -21.547836) (xy 73.608366 -21.520574) (xy 73.58917 -21.46282)
			(xy 73.579382 -21.402751) (xy 73.57872 -21.372322) (xy 73.57872 -21.36394) (xy 73.579715 -21.337044)
			(xy 73.588335 -21.283919) (xy 73.604336 -21.232533) (xy 73.627402 -21.183906) (xy 73.657073 -21.139004)
			(xy 73.692762 -21.098718) (xy 73.733758 -21.063849) (xy 73.779249 -21.035089) (xy 73.828331 -21.013008)
			(xy 73.88003 -20.998045) (xy 73.933318 -20.990498) (xy 73.960228 -20.990052) (xy 73.963784 -20.990052)
			(xy 73.972674 -20.990306) (xy 73.978008 -20.99056) (xy 73.989438 -20.988274) (xy 73.996147 -20.986854)
			(xy 74.008508 -20.980925) (xy 74.013822 -20.97659) (xy 74.066908 -20.925536) (xy 74.072496 -20.919186)
			(xy 74.072496 -20.003008) (xy 74.072242 -19.453098) (xy 74.072775 -19.417376) (xy 74.081463 -19.346463)
			(xy 74.09871 -19.277133) (xy 74.124259 -19.210415) (xy 74.157733 -19.147298) (xy 74.198633 -19.088721)
			(xy 74.246353 -19.035552) (xy 74.272902 -19.011646) (xy 74.289666 -18.997168) (xy 74.290174 -18.991326)
			(xy 74.290682 -18.971514) (xy 74.291952 -18.922238) (xy 74.291952 -18.92046) (xy 74.29246 -18.906744)
			(xy 74.243946 -18.858484) (xy 74.221035 -18.834907) (xy 74.180059 -18.783493) (xy 74.145097 -18.727816)
			(xy 74.116586 -18.668575) (xy 74.094886 -18.606514) (xy 74.080269 -18.542415) (xy 74.07292 -18.477082)
			(xy 74.072496 -18.44421) (xy 74.072242 -18.432018) (xy 74.073497 -18.397095) (xy 74.083291 -18.327902)
			(xy 74.101242 -18.260364) (xy 74.127093 -18.195439) (xy 74.160479 -18.134047) (xy 74.200927 -18.077059)
			(xy 74.247861 -18.025283) (xy 74.300618 -17.979454) (xy 74.358449 -17.940221) (xy 74.420534 -17.908141)
			(xy 74.485991 -17.883669) (xy 74.553894 -17.867151) (xy 74.623279 -17.858823) (xy 74.65822 -17.858232)
			(xy 74.667364 -17.858232) (xy 74.704661 -17.859414) (xy 74.778517 -17.870075) (xy 74.85042 -17.890032)
			(xy 74.885042 -17.903952) (xy 74.919787 -17.919175) (xy 74.985372 -17.957294) (xy 75.045496 -18.003549)
			(xy 75.072748 -18.029936) (xy 75.6412 -18.598388) (xy 75.664144 -18.621943) (xy 75.70516 -18.673344)
			(xy 75.74016 -18.729016) (xy 75.768702 -18.788258) (xy 75.790427 -18.850325) (xy 75.805062 -18.914436)
			(xy 75.812423 -18.979782) (xy 75.812904 -19.012662) (xy 75.812904 -21.475192) (xy 75.816587 -21.479835)
			(xy 75.825703 -21.487401) (xy 75.830938 -21.490178) (xy 75.902566 -21.520404) (xy 75.903074 -21.520404)
			(xy 75.920346 -21.527516) (xy 75.927712 -21.530056) (xy 75.936058 -21.531703) (xy 75.952972 -21.529977)
			(xy 75.968385 -21.522799) (xy 75.974702 -21.517102) (xy 75.975464 -21.516594) (xy 76.282042 -21.21027)
			(xy 76.52258 -20.969732) (xy 76.53071 -20.960704) (xy 76.538137 -20.937612) (xy 76.536804 -20.925536)
			(xy 76.535026 -20.914868) (xy 76.523342 -20.842478) (xy 76.522094 -20.837234) (xy 76.51774 -20.827375)
			(xy 76.514706 -20.82292) (xy 76.509626 -20.816062) (xy 76.504038 -20.813268) (xy 76.479911 -20.801241)
			(xy 76.434999 -20.771424) (xy 76.394714 -20.735602) (xy 76.35985 -20.694484) (xy 76.331099 -20.648883)
			(xy 76.309027 -20.599699) (xy 76.294072 -20.547907) (xy 76.286528 -20.494528) (xy 76.286106 -20.467574)
			(xy 76.286594 -20.440196) (xy 76.294387 -20.385997) (xy 76.309814 -20.333458) (xy 76.33256 -20.28365)
			(xy 76.362164 -20.237586) (xy 76.398022 -20.196204) (xy 76.439404 -20.160346) (xy 76.485468 -20.130742)
			(xy 76.535276 -20.107996) (xy 76.587815 -20.092569) (xy 76.642014 -20.084776) (xy 76.69677 -20.084776)
			(xy 76.750969 -20.092569) (xy 76.803508 -20.107996) (xy 76.853316 -20.130742) (xy 76.89938 -20.160346)
			(xy 76.940762 -20.196204) (xy 76.97662 -20.237586) (xy 77.006224 -20.28365) (xy 77.02897 -20.333458)
			(xy 77.044397 -20.385997) (xy 77.05219 -20.440196) (xy 77.052678 -20.467574) (xy 77.052678 -20.468336)
			(xy 77.052002 -20.500184) (xy 77.041402 -20.562995) (xy 77.031596 -20.593304) (xy 77.028294 -20.602956)
			(xy 77.02804 -20.604734) (xy 77.027699 -20.613016) (xy 77.03171 -20.629087) (xy 77.035914 -20.63623)
			(xy 77.051662 -20.658328) (xy 77.051662 -20.658836) (xy 77.084936 -20.705064) (xy 77.085952 -20.706588)
			(xy 77.090144 -20.711635) (xy 77.100561 -20.719603) (xy 77.106526 -20.722336) (xy 77.116178 -20.7264)
			(xy 77.166724 -20.7264) (xy 77.173836 -20.724368) (xy 77.201284 -20.716457) (xy 77.257327 -20.705383)
			(xy 77.314183 -20.699822) (xy 77.342746 -20.699476) (xy 78.650338 -20.699476) (xy 78.683193 -20.699933)
			(xy 78.748491 -20.707283) (xy 78.804458 -20.72005) (xy 83.18552 -20.72005) (xy 83.18949 -20.589916)
			(xy 83.201386 -20.460266) (xy 83.221165 -20.331583) (xy 83.248751 -20.204344) (xy 83.284044 -20.079025)
			(xy 83.32691 -19.956089) (xy 83.377192 -19.835996) (xy 83.434701 -19.719192) (xy 83.499225 -19.60611)
			(xy 83.570522 -19.497173) (xy 83.648327 -19.392785) (xy 83.732352 -19.293334) (xy 83.822284 -19.199191)
			(xy 83.917788 -19.110706) (xy 84.018508 -19.028207) (xy 84.12407 -18.952002) (xy 84.234082 -18.882375)
			(xy 84.348134 -18.819584) (xy 84.465802 -18.763862) (xy 84.586648 -18.715418) (xy 84.710223 -18.674431)
			(xy 84.836066 -18.641054) (xy 84.963711 -18.615411) (xy 85.092681 -18.597597) (xy 85.222497 -18.587679)
			(xy 85.352676 -18.585694) (xy 85.482735 -18.591648) (xy 85.612188 -18.605521) (xy 85.740555 -18.627259)
			(xy 85.867358 -18.656783) (xy 85.992125 -18.693982) (xy 86.114392 -18.738718) (xy 86.233705 -18.790826)
			(xy 86.349618 -18.850109) (xy 86.461703 -18.91635) (xy 86.56954 -18.9893) (xy 86.672729 -19.068688)
			(xy 86.770887 -19.15422) (xy 86.863648 -19.245577) (xy 86.950667 -19.342419) (xy 87.03162 -19.444386)
			(xy 87.106206 -19.551098) (xy 87.174147 -19.662159) (xy 87.235192 -19.777155) (xy 87.289113 -19.895659)
			(xy 87.335708 -20.01723) (xy 87.374806 -20.141415) (xy 87.40626 -20.267753) (xy 87.429954 -20.395774)
			(xy 87.445798 -20.525) (xy 87.453736 -20.654953) (xy 87.454232 -20.72005) (xy 87.453736 -20.785147)
			(xy 87.445798 -20.9151) (xy 87.429954 -21.044326) (xy 87.40626 -21.172347) (xy 87.374806 -21.298685)
			(xy 87.335708 -21.42287) (xy 87.289113 -21.544441) (xy 87.235192 -21.662945) (xy 87.174147 -21.777941)
			(xy 87.106206 -21.889002) (xy 87.03162 -21.995714) (xy 86.950667 -22.097681) (xy 86.863648 -22.194523)
			(xy 86.770887 -22.28588) (xy 86.672729 -22.371412) (xy 86.56954 -22.4508) (xy 86.461703 -22.52375)
			(xy 86.349618 -22.589991) (xy 86.233705 -22.649274) (xy 86.114392 -22.701382) (xy 85.992125 -22.746118)
			(xy 85.867358 -22.783317) (xy 85.740555 -22.812841) (xy 85.612188 -22.834579) (xy 85.482735 -22.848452)
			(xy 85.352676 -22.854406) (xy 85.222497 -22.852421) (xy 85.092681 -22.842503) (xy 84.963711 -22.824689)
			(xy 84.836066 -22.799046) (xy 84.710223 -22.765669) (xy 84.586648 -22.724682) (xy 84.465802 -22.676238)
			(xy 84.348134 -22.620516) (xy 84.234082 -22.557725) (xy 84.12407 -22.488098) (xy 84.018508 -22.411893)
			(xy 83.917788 -22.329394) (xy 83.822284 -22.240909) (xy 83.732352 -22.146766) (xy 83.648327 -22.047315)
			(xy 83.570522 -21.942927) (xy 83.499225 -21.83399) (xy 83.434701 -21.720908) (xy 83.377192 -21.604104)
			(xy 83.32691 -21.484011) (xy 83.284044 -21.361075) (xy 83.248751 -21.235756) (xy 83.221165 -21.108517)
			(xy 83.201386 -20.979834) (xy 83.18949 -20.850184) (xy 83.18552 -20.72005) (xy 78.804458 -20.72005)
			(xy 78.812555 -20.721897) (xy 78.87458 -20.743592) (xy 78.933787 -20.772096) (xy 78.98943 -20.807048)
			(xy 79.040809 -20.848011) (xy 79.064358 -20.870926) (xy 79.634842 -21.44141) (xy 79.657737 -21.464975)
			(xy 79.698686 -21.51636) (xy 79.733628 -21.572003) (xy 79.762125 -21.631207) (xy 79.783819 -21.693227)
			(xy 79.798438 -21.757286) (xy 79.805797 -21.822577) (xy 79.806166 -21.847048) (xy 80.072736 -21.847048)
			(xy 80.076807 -21.791426) (xy 80.088933 -21.736989) (xy 80.108856 -21.684898) (xy 80.136152 -21.636263)
			(xy 80.170238 -21.59212) (xy 80.210387 -21.553411) (xy 80.255745 -21.52096) (xy 80.305345 -21.495459)
			(xy 80.358129 -21.477452) (xy 80.412972 -21.467322) (xy 80.468706 -21.465285) (xy 80.524143 -21.471385)
			(xy 80.5781 -21.485491) (xy 80.629429 -21.507303) (xy 80.677035 -21.536357) (xy 80.719903 -21.572032)
			(xy 80.75712 -21.613569) (xy 80.787893 -21.660082) (xy 80.811565 -21.710579) (xy 80.827633 -21.763986)
			(xy 80.835753 -21.819162) (xy 80.836262 -21.847048) (xy 80.835753 -21.874934) (xy 80.827633 -21.93011)
			(xy 80.811565 -21.983517) (xy 80.787893 -22.034014) (xy 80.75712 -22.080527) (xy 80.719903 -22.122064)
			(xy 80.677035 -22.157739) (xy 80.629429 -22.186793) (xy 80.5781 -22.208605) (xy 80.524143 -22.222711)
			(xy 80.468706 -22.228811) (xy 80.412972 -22.226774) (xy 80.358129 -22.216644) (xy 80.305345 -22.198637)
			(xy 80.255745 -22.173136) (xy 80.210387 -22.140685) (xy 80.170238 -22.101976) (xy 80.136152 -22.057833)
			(xy 80.108856 -22.009198) (xy 80.088933 -21.957107) (xy 80.076807 -21.90267) (xy 80.072736 -21.847048)
			(xy 79.806166 -21.847048) (xy 79.806292 -21.85543) (xy 79.806292 -21.855684) (xy 79.80578 -21.891083)
			(xy 79.797248 -21.961364) (xy 79.780306 -22.030104) (xy 79.755201 -22.096301) (xy 79.7223 -22.158989)
			(xy 79.682082 -22.217254) (xy 79.635135 -22.270246) (xy 79.582141 -22.317192) (xy 79.523875 -22.357408)
			(xy 79.461186 -22.390308) (xy 79.394989 -22.41541) (xy 79.326248 -22.43235) (xy 79.255967 -22.440881)
			(xy 79.220568 -22.441408) (xy 79.220314 -22.441408) (xy 79.18746 -22.440949) (xy 79.122165 -22.433594)
			(xy 79.058104 -22.418974) (xy 78.996083 -22.397275) (xy 78.936881 -22.368768) (xy 78.881242 -22.333812)
			(xy 78.829867 -22.292847) (xy 78.806294 -22.269958) (xy 78.74762 -22.211284) (xy 78.741778 -22.210776)
			(xy 78.729332 -22.210776) (xy 78.72375 -22.21092) (xy 78.712853 -22.213353) (xy 78.707742 -22.215602)
			(xy 78.696566 -22.222714) (xy 78.696312 -22.222968) (xy 78.694788 -22.224238) (xy 78.668353 -22.24584)
			(xy 78.611346 -22.283405) (xy 78.550359 -22.314089) (xy 78.486219 -22.337475) (xy 78.419795 -22.353246)
			(xy 78.351987 -22.361188) (xy 78.317852 -22.361652) (xy 78.16088 -22.361652) (xy 78.152244 -22.369272)
			(xy 78.132432 -22.393656) (xy 78.099412 -22.43455) (xy 78.096872 -22.438614) (xy 78.0923 -22.450552)
			(xy 78.088998 -22.463252) (xy 78.089506 -22.46503) (xy 78.091538 -22.47519) (xy 78.095373 -22.494395)
			(xy 78.099568 -22.533333) (xy 78.09992 -22.552914) (xy 78.09992 -22.553422) (xy 78.09992 -22.559264)
			(xy 78.099179 -22.58634) (xy 78.090991 -22.639881) (xy 78.075312 -22.691727) (xy 78.052459 -22.740833)
			(xy 78.022891 -22.786215) (xy 77.987202 -22.826958) (xy 77.946109 -22.862245) (xy 77.900439 -22.891365)
			(xy 77.85111 -22.913734) (xy 77.799113 -22.928902) (xy 77.745494 -22.936564) (xy 77.718412 -22.936962)
			(xy 77.718158 -22.936962) (xy 77.689997 -22.936461) (xy 77.634286 -22.928186) (xy 77.580398 -22.911807)
			(xy 77.529505 -22.88768) (xy 77.505814 -22.872446) (xy 77.496377 -22.866725) (xy 77.47462 -22.863169)
			(xy 77.453375 -22.869054) (xy 77.4446 -22.875748) (xy 77.33792 -22.982428) (xy 77.334618 -22.986492)
			(xy 77.330488 -22.993004) (xy 77.325971 -23.00774) (xy 77.325728 -23.015448) (xy 77.325728 -23.965154)
			(xy 78.077312 -23.965154) (xy 78.081383 -23.909532) (xy 78.093509 -23.855095) (xy 78.113432 -23.803004)
			(xy 78.140728 -23.754369) (xy 78.174814 -23.710226) (xy 78.214963 -23.671517) (xy 78.260321 -23.639066)
			(xy 78.309921 -23.613565) (xy 78.362705 -23.595558) (xy 78.417548 -23.585428) (xy 78.473282 -23.583391)
			(xy 78.528719 -23.589491) (xy 78.582676 -23.603597) (xy 78.634005 -23.625409) (xy 78.681611 -23.654463)
			(xy 78.724479 -23.690138) (xy 78.761696 -23.731675) (xy 78.792469 -23.778188) (xy 78.816141 -23.828685)
			(xy 78.832209 -23.882092) (xy 78.840329 -23.937268) (xy 78.840504 -23.946866) (xy 79.080358 -23.946866)
			(xy 79.084429 -23.891244) (xy 79.096555 -23.836807) (xy 79.116478 -23.784716) (xy 79.143774 -23.736081)
			(xy 79.17786 -23.691938) (xy 79.218009 -23.653229) (xy 79.263367 -23.620778) (xy 79.312967 -23.595277)
			(xy 79.365751 -23.57727) (xy 79.420594 -23.56714) (xy 79.476328 -23.565103) (xy 79.531765 -23.571203)
			(xy 79.585722 -23.585309) (xy 79.637051 -23.607121) (xy 79.684657 -23.636175) (xy 79.727525 -23.67185)
			(xy 79.764742 -23.713387) (xy 79.795515 -23.7599) (xy 79.819187 -23.810397) (xy 79.835255 -23.863804)
			(xy 79.843375 -23.91898) (xy 79.843884 -23.946866) (xy 79.843444 -23.970996) (xy 80.072736 -23.970996)
			(xy 80.076807 -23.915374) (xy 80.088933 -23.860937) (xy 80.108856 -23.808846) (xy 80.136152 -23.760211)
			(xy 80.170238 -23.716068) (xy 80.210387 -23.677359) (xy 80.255745 -23.644908) (xy 80.305345 -23.619407)
			(xy 80.358129 -23.6014) (xy 80.412972 -23.59127) (xy 80.468706 -23.589233) (xy 80.524143 -23.595333)
			(xy 80.5781 -23.609439) (xy 80.629429 -23.631251) (xy 80.677035 -23.660305) (xy 80.719903 -23.69598)
			(xy 80.75712 -23.737517) (xy 80.787893 -23.78403) (xy 80.811565 -23.834527) (xy 80.827633 -23.887934)
			(xy 80.835753 -23.94311) (xy 80.836262 -23.970996) (xy 80.835753 -23.998882) (xy 80.827633 -24.054058)
			(xy 80.811565 -24.107465) (xy 80.787893 -24.157962) (xy 80.75712 -24.204475) (xy 80.719903 -24.246012)
			(xy 80.677035 -24.281687) (xy 80.629429 -24.310741) (xy 80.5781 -24.332553) (xy 80.524143 -24.346659)
			(xy 80.468706 -24.352759) (xy 80.412972 -24.350722) (xy 80.358129 -24.340592) (xy 80.305345 -24.322585)
			(xy 80.255745 -24.297084) (xy 80.210387 -24.264633) (xy 80.170238 -24.225924) (xy 80.136152 -24.181781)
			(xy 80.108856 -24.133146) (xy 80.088933 -24.081055) (xy 80.076807 -24.026618) (xy 80.072736 -23.970996)
			(xy 79.843444 -23.970996) (xy 79.843375 -23.974752) (xy 79.835255 -24.029928) (xy 79.819187 -24.083335)
			(xy 79.795515 -24.133832) (xy 79.764742 -24.180345) (xy 79.727525 -24.221882) (xy 79.684657 -24.257557)
			(xy 79.637051 -24.286611) (xy 79.585722 -24.308423) (xy 79.531765 -24.322529) (xy 79.476328 -24.328629)
			(xy 79.420594 -24.326592) (xy 79.365751 -24.316462) (xy 79.312967 -24.298455) (xy 79.263367 -24.272954)
			(xy 79.218009 -24.240503) (xy 79.17786 -24.201794) (xy 79.143774 -24.157651) (xy 79.116478 -24.109016)
			(xy 79.096555 -24.056925) (xy 79.084429 -24.002488) (xy 79.080358 -23.946866) (xy 78.840504 -23.946866)
			(xy 78.840838 -23.965154) (xy 78.840329 -23.99304) (xy 78.832209 -24.048216) (xy 78.816141 -24.101623)
			(xy 78.792469 -24.15212) (xy 78.761696 -24.198633) (xy 78.724479 -24.24017) (xy 78.681611 -24.275845)
			(xy 78.634005 -24.304899) (xy 78.582676 -24.326711) (xy 78.528719 -24.340817) (xy 78.473282 -24.346917)
			(xy 78.417548 -24.34488) (xy 78.362705 -24.33475) (xy 78.309921 -24.316743) (xy 78.260321 -24.291242)
			(xy 78.214963 -24.258791) (xy 78.174814 -24.220082) (xy 78.140728 -24.175939) (xy 78.113432 -24.127304)
			(xy 78.093509 -24.075213) (xy 78.081383 -24.020776) (xy 78.077312 -23.965154) (xy 77.325728 -23.965154)
			(xy 77.325728 -24.807418) (xy 84.371178 -24.807418) (xy 84.375249 -24.751796) (xy 84.387375 -24.697359)
			(xy 84.407298 -24.645268) (xy 84.434594 -24.596633) (xy 84.46868 -24.55249) (xy 84.508829 -24.513781)
			(xy 84.554187 -24.48133) (xy 84.603787 -24.455829) (xy 84.656571 -24.437822) (xy 84.711414 -24.427692)
			(xy 84.767148 -24.425655) (xy 84.822585 -24.431755) (xy 84.876542 -24.445861) (xy 84.927871 -24.467673)
			(xy 84.975477 -24.496727) (xy 85.018345 -24.532402) (xy 85.055562 -24.573939) (xy 85.086335 -24.620452)
			(xy 85.110007 -24.670949) (xy 85.126075 -24.724356) (xy 85.134195 -24.779532) (xy 85.134704 -24.807418)
			(xy 85.134195 -24.835304) (xy 85.126075 -24.89048) (xy 85.110007 -24.943887) (xy 85.086335 -24.994384)
			(xy 85.055562 -25.040897) (xy 85.018345 -25.082434) (xy 84.975477 -25.118109) (xy 84.927871 -25.147163)
			(xy 84.876542 -25.168975) (xy 84.822585 -25.183081) (xy 84.767148 -25.189181) (xy 84.711414 -25.187144)
			(xy 84.656571 -25.177014) (xy 84.603787 -25.159007) (xy 84.554187 -25.133506) (xy 84.508829 -25.101055)
			(xy 84.46868 -25.062346) (xy 84.434594 -25.018203) (xy 84.407298 -24.969568) (xy 84.387375 -24.917477)
			(xy 84.375249 -24.86304) (xy 84.371178 -24.807418) (xy 77.325728 -24.807418) (xy 77.325728 -25.91562)
			(xy 77.32599 -25.923264) (xy 77.330518 -25.937865) (xy 77.334618 -25.944322) (xy 77.338682 -25.950418)
			(xy 77.350874 -25.959816) (xy 77.358748 -25.962864) (xy 77.387704 -25.97531) (xy 77.41547 -25.98913)
			(xy 77.466493 -26.024385) (xy 77.47619 -26.03373) (xy 83.267802 -26.03373) (xy 83.271873 -25.978108)
			(xy 83.283999 -25.923671) (xy 83.303922 -25.87158) (xy 83.331218 -25.822945) (xy 83.365304 -25.778802)
			(xy 83.405453 -25.740093) (xy 83.450811 -25.707642) (xy 83.500411 -25.682141) (xy 83.553195 -25.664134)
			(xy 83.608038 -25.654004) (xy 83.663772 -25.651967) (xy 83.719209 -25.658067) (xy 83.773166 -25.672173)
			(xy 83.824495 -25.693985) (xy 83.872101 -25.723039) (xy 83.914969 -25.758714) (xy 83.952186 -25.800251)
			(xy 83.982959 -25.846764) (xy 84.006631 -25.897261) (xy 84.022699 -25.950668) (xy 84.030819 -26.005844)
			(xy 84.031328 -26.03373) (xy 84.030819 -26.061616) (xy 84.022699 -26.116792) (xy 84.006631 -26.170199)
			(xy 83.982959 -26.220696) (xy 83.952186 -26.267209) (xy 83.914969 -26.308746) (xy 83.872101 -26.344421)
			(xy 83.824495 -26.373475) (xy 83.773166 -26.395287) (xy 83.719209 -26.409393) (xy 83.663772 -26.415493)
			(xy 83.608038 -26.413456) (xy 83.553195 -26.403326) (xy 83.500411 -26.385319) (xy 83.450811 -26.359818)
			(xy 83.405453 -26.327367) (xy 83.365304 -26.288658) (xy 83.331218 -26.244515) (xy 83.303922 -26.19588)
			(xy 83.283999 -26.143789) (xy 83.271873 -26.089352) (xy 83.267802 -26.03373) (xy 77.47619 -26.03373)
			(xy 77.51115 -26.067419) (xy 77.530198 -26.091896) (xy 77.530198 -26.092404) (xy 77.53477 -26.0985)
			(xy 77.539342 -26.105104) (xy 77.554833 -26.128746) (xy 77.579439 -26.179631) (xy 77.588364 -26.20645)
			(xy 77.589126 -26.208736) (xy 77.589126 -26.20899) (xy 77.589634 -26.210006) (xy 77.591623 -26.214795)
			(xy 77.597257 -26.223501) (xy 77.60081 -26.227278) (xy 79.021178 -27.647646) (xy 79.039292 -27.666426)
			(xy 79.069978 -27.708623) (xy 79.093679 -27.755104) (xy 79.10981 -27.804722) (xy 79.117973 -27.856255)
			(xy 79.11846 -27.882342) (xy 79.11846 -28.139136) (xy 80.397856 -28.139136) (xy 80.401927 -28.083514)
			(xy 80.414053 -28.029077) (xy 80.433976 -27.976986) (xy 80.461272 -27.928351) (xy 80.495358 -27.884208)
			(xy 80.535507 -27.845499) (xy 80.580865 -27.813048) (xy 80.630465 -27.787547) (xy 80.683249 -27.76954)
			(xy 80.738092 -27.75941) (xy 80.793826 -27.757373) (xy 80.849263 -27.763473) (xy 80.90322 -27.777579)
			(xy 80.954549 -27.799391) (xy 81.002155 -27.828445) (xy 81.045023 -27.86412) (xy 81.08224 -27.905657)
			(xy 81.113013 -27.95217) (xy 81.136685 -28.002667) (xy 81.152753 -28.056074) (xy 81.160873 -28.11125)
			(xy 81.161382 -28.139136) (xy 81.667856 -28.139136) (xy 81.671927 -28.083514) (xy 81.684053 -28.029077)
			(xy 81.703976 -27.976986) (xy 81.731272 -27.928351) (xy 81.765358 -27.884208) (xy 81.805507 -27.845499)
			(xy 81.850865 -27.813048) (xy 81.900465 -27.787547) (xy 81.953249 -27.76954) (xy 82.008092 -27.75941)
			(xy 82.063826 -27.757373) (xy 82.119263 -27.763473) (xy 82.17322 -27.777579) (xy 82.224549 -27.799391)
			(xy 82.272155 -27.828445) (xy 82.315023 -27.86412) (xy 82.35224 -27.905657) (xy 82.383013 -27.95217)
			(xy 82.406685 -28.002667) (xy 82.422753 -28.056074) (xy 82.430873 -28.11125) (xy 82.431382 -28.139136)
			(xy 82.430873 -28.167022) (xy 82.422753 -28.222198) (xy 82.406685 -28.275605) (xy 82.383013 -28.326102)
			(xy 82.35224 -28.372615) (xy 82.315023 -28.414152) (xy 82.272155 -28.449827) (xy 82.224549 -28.478881)
			(xy 82.17322 -28.500693) (xy 82.119263 -28.514799) (xy 82.063826 -28.520899) (xy 82.008092 -28.518862)
			(xy 81.953249 -28.508732) (xy 81.900465 -28.490725) (xy 81.850865 -28.465224) (xy 81.805507 -28.432773)
			(xy 81.765358 -28.394064) (xy 81.731272 -28.349921) (xy 81.703976 -28.301286) (xy 81.684053 -28.249195)
			(xy 81.671927 -28.194758) (xy 81.667856 -28.139136) (xy 81.161382 -28.139136) (xy 81.160873 -28.167022)
			(xy 81.152753 -28.222198) (xy 81.136685 -28.275605) (xy 81.113013 -28.326102) (xy 81.08224 -28.372615)
			(xy 81.045023 -28.414152) (xy 81.002155 -28.449827) (xy 80.954549 -28.478881) (xy 80.90322 -28.500693)
			(xy 80.849263 -28.514799) (xy 80.793826 -28.520899) (xy 80.738092 -28.518862) (xy 80.683249 -28.508732)
			(xy 80.630465 -28.490725) (xy 80.580865 -28.465224) (xy 80.535507 -28.432773) (xy 80.495358 -28.394064)
			(xy 80.461272 -28.349921) (xy 80.433976 -28.301286) (xy 80.414053 -28.249195) (xy 80.401927 -28.194758)
			(xy 80.397856 -28.139136) (xy 79.11846 -28.139136) (xy 79.11846 -29.134054) (xy 79.118932 -29.143685)
			(xy 79.126118 -29.161562) (xy 79.13243 -29.168852) (xy 79.134716 -29.171138) (xy 79.191104 -29.222192)
			(xy 79.19847 -29.22778) (xy 79.204576 -29.231281) (xy 79.218106 -29.235147) (xy 79.22514 -29.2354)
			(xy 79.229966 -29.2354) (xy 79.232252 -29.235146) (xy 79.269082 -29.233368) (xy 79.26959 -29.233368)
			(xy 79.270352 -29.233368) (xy 79.298089 -29.233869) (xy 79.352977 -29.241908) (xy 79.406123 -29.25781)
			(xy 79.456407 -29.281238) (xy 79.502769 -29.3117) (xy 79.544232 -29.348553) (xy 79.579923 -29.391021)
			(xy 79.609089 -29.438209) (xy 79.631115 -29.489123) (xy 79.645539 -29.542689) (xy 79.64932 -29.570172)
			(xy 79.650844 -29.58465) (xy 79.652114 -29.614876) (xy 79.652114 -29.635704) (xy 79.65059 -29.64815)
			(xy 79.647936 -29.673634) (xy 79.636669 -29.723618) (xy 79.618822 -29.771647) (xy 79.594716 -29.81686)
			(xy 79.564783 -29.858446) (xy 79.529561 -29.895657) (xy 79.509874 -29.912056) (xy 79.507334 -29.914088)
			(xy 79.498444 -29.923232) (xy 79.493489 -29.929117) (xy 79.487044 -29.94308) (xy 79.485744 -29.950664)
			(xy 79.485744 -29.951172) (xy 79.485236 -29.957522) (xy 79.485236 -30.02026) (xy 79.48549 -30.023562)
			(xy 79.487268 -30.040326) (xy 79.491332 -30.048708) (xy 79.496666 -30.059376) (xy 79.497174 -30.060392)
			(xy 79.498444 -30.063186) (xy 79.5004 -30.06724) (xy 79.505511 -30.074648) (xy 79.508604 -30.077918)
			(xy 79.513176 -30.08249) (xy 79.514954 -30.084014) (xy 79.535983 -30.102251) (xy 79.573051 -30.143776)
			(xy 79.603699 -30.190241) (xy 79.627276 -30.240664) (xy 79.643284 -30.293975) (xy 79.651382 -30.349045)
			(xy 79.65186 -30.376876) (xy 79.651398 -30.404129) (xy 79.643644 -30.45808) (xy 79.628289 -30.510378)
			(xy 79.605648 -30.559958) (xy 79.576179 -30.60581) (xy 79.540485 -30.647002) (xy 79.499291 -30.682694)
			(xy 79.453437 -30.712159) (xy 79.403855 -30.734798) (xy 79.351556 -30.750149) (xy 79.297605 -30.7579)
			(xy 79.270352 -30.758384) (xy 79.26959 -30.758384) (xy 79.269082 -30.758384) (xy 79.259031 -30.758339)
			(xy 79.238954 -30.757325) (xy 79.22895 -30.756352) (xy 79.219044 -30.755844) (xy 79.212694 -30.757876)
			(xy 79.2099 -30.758638) (xy 79.204806 -30.760418) (xy 79.195455 -30.765795) (xy 79.191358 -30.769306)
			(xy 79.178912 -30.780482) (xy 79.17815 -30.781244) (xy 79.133192 -30.821884) (xy 79.12878 -30.826748)
			(xy 79.122341 -30.838189) (xy 79.120492 -30.84449) (xy 79.11846 -30.854396) (xy 79.11846 -31.112206)
			(xy 79.118714 -31.116016) (xy 79.118714 -31.116524) (xy 79.120018 -31.126739) (xy 79.129592 -31.14495)
			(xy 79.137256 -31.15183) (xy 79.203804 -31.199074) (xy 79.212186 -31.204916) (xy 79.219044 -31.207456)
			(xy 79.227241 -31.210203) (xy 79.244513 -31.21059) (xy 79.252826 -31.208218) (xy 79.260954 -31.205424)
			(xy 79.290048 -31.19648) (xy 79.350155 -31.1869) (xy 79.380588 -31.186374) (xy 79.407843 -31.186836)
			(xy 79.461798 -31.194592) (xy 79.514099 -31.209948) (xy 79.563683 -31.232591) (xy 79.60954 -31.26206)
			(xy 79.650736 -31.297755) (xy 79.686433 -31.33895) (xy 79.715904 -31.384806) (xy 79.738548 -31.434389)
			(xy 79.753905 -31.486691) (xy 79.761663 -31.540645) (xy 79.761663 -31.595155) (xy 79.753905 -31.649109)
			(xy 79.738548 -31.701411) (xy 79.730394 -31.719266) (xy 80.285334 -31.719266) (xy 80.289405 -31.663644)
			(xy 80.301531 -31.609207) (xy 80.321454 -31.557116) (xy 80.34875 -31.508481) (xy 80.382836 -31.464338)
			(xy 80.422985 -31.425629) (xy 80.468343 -31.393178) (xy 80.517943 -31.367677) (xy 80.570727 -31.34967)
			(xy 80.62557 -31.33954) (xy 80.681304 -31.337503) (xy 80.736741 -31.343603) (xy 80.790698 -31.357709)
			(xy 80.842027 -31.379521) (xy 80.889633 -31.408575) (xy 80.932501 -31.44425) (xy 80.969718 -31.485787)
			(xy 81.000491 -31.5323) (xy 81.024163 -31.582797) (xy 81.040231 -31.636204) (xy 81.044381 -31.664402)
			(xy 81.560922 -31.664402) (xy 81.564993 -31.60878) (xy 81.577119 -31.554343) (xy 81.597042 -31.502252)
			(xy 81.624338 -31.453617) (xy 81.658424 -31.409474) (xy 81.698573 -31.370765) (xy 81.743931 -31.338314)
			(xy 81.793531 -31.312813) (xy 81.846315 -31.294806) (xy 81.901158 -31.284676) (xy 81.956892 -31.282639)
			(xy 82.012329 -31.288739) (xy 82.066286 -31.302845) (xy 82.117615 -31.324657) (xy 82.165221 -31.353711)
			(xy 82.208089 -31.389386) (xy 82.245306 -31.430923) (xy 82.276079 -31.477436) (xy 82.299751 -31.527933)
			(xy 82.315819 -31.58134) (xy 82.323939 -31.636516) (xy 82.324448 -31.664402) (xy 82.323939 -31.692288)
			(xy 82.315819 -31.747464) (xy 82.299751 -31.800871) (xy 82.276079 -31.851368) (xy 82.245306 -31.897881)
			(xy 82.208089 -31.939418) (xy 82.165221 -31.975093) (xy 82.117615 -32.004147) (xy 82.066286 -32.025959)
			(xy 82.012329 -32.040065) (xy 81.956892 -32.046165) (xy 81.901158 -32.044128) (xy 81.846315 -32.033998)
			(xy 81.793531 -32.015991) (xy 81.743931 -31.99049) (xy 81.698573 -31.958039) (xy 81.658424 -31.91933)
			(xy 81.624338 -31.875187) (xy 81.597042 -31.826552) (xy 81.577119 -31.774461) (xy 81.564993 -31.720024)
			(xy 81.560922 -31.664402) (xy 81.044381 -31.664402) (xy 81.048351 -31.69138) (xy 81.04886 -31.719266)
			(xy 81.048351 -31.747152) (xy 81.040231 -31.802328) (xy 81.024163 -31.855735) (xy 81.000491 -31.906232)
			(xy 80.969718 -31.952745) (xy 80.932501 -31.994282) (xy 80.889633 -32.029957) (xy 80.842027 -32.059011)
			(xy 80.790698 -32.080823) (xy 80.736741 -32.094929) (xy 80.681304 -32.101029) (xy 80.62557 -32.098992)
			(xy 80.570727 -32.088862) (xy 80.517943 -32.070855) (xy 80.468343 -32.045354) (xy 80.422985 -32.012903)
			(xy 80.382836 -31.974194) (xy 80.34875 -31.930051) (xy 80.321454 -31.881416) (xy 80.301531 -31.829325)
			(xy 80.289405 -31.774888) (xy 80.285334 -31.719266) (xy 79.730394 -31.719266) (xy 79.715904 -31.750994)
			(xy 79.686433 -31.79685) (xy 79.650736 -31.838045) (xy 79.60954 -31.87374) (xy 79.563683 -31.903209)
			(xy 79.514099 -31.925852) (xy 79.461798 -31.941208) (xy 79.407843 -31.948964) (xy 79.380588 -31.94939)
			(xy 79.379826 -31.94939) (xy 79.349587 -31.948787) (xy 79.28987 -31.939211) (xy 79.260954 -31.93034)
			(xy 79.253334 -31.9278) (xy 79.23276 -31.9278) (xy 79.224887 -31.928096) (xy 79.209887 -31.932881)
			(xy 79.203296 -31.937198) (xy 79.185262 -31.949898) (xy 79.13751 -31.983934) (xy 79.129008 -31.99157)
			(xy 79.119138 -32.012148) (xy 79.11846 -32.023558) (xy 79.11846 -33.239964) (xy 79.119476 -33.249616)
			(xy 79.121101 -33.256861) (xy 79.12794 -33.270033) (xy 79.132938 -33.275524) (xy 81.122266 -35.264852)
			(xy 81.902298 -35.264852) (xy 81.906369 -35.20923) (xy 81.918495 -35.154793) (xy 81.938418 -35.102702)
			(xy 81.965714 -35.054067) (xy 81.9998 -35.009924) (xy 82.039949 -34.971215) (xy 82.085307 -34.938764)
			(xy 82.134907 -34.913263) (xy 82.187691 -34.895256) (xy 82.242534 -34.885126) (xy 82.298268 -34.883089)
			(xy 82.353705 -34.889189) (xy 82.407662 -34.903295) (xy 82.458991 -34.925107) (xy 82.506597 -34.954161)
			(xy 82.549465 -34.989836) (xy 82.586682 -35.031373) (xy 82.617455 -35.077886) (xy 82.641127 -35.128383)
			(xy 82.657195 -35.18179) (xy 82.665315 -35.236966) (xy 82.665824 -35.264852) (xy 82.665315 -35.292738)
			(xy 82.657195 -35.347914) (xy 82.641127 -35.401321) (xy 82.617455 -35.451818) (xy 82.586682 -35.498331)
			(xy 82.549465 -35.539868) (xy 82.506597 -35.575543) (xy 82.458991 -35.604597) (xy 82.407662 -35.626409)
			(xy 82.353705 -35.640515) (xy 82.298268 -35.646615) (xy 82.242534 -35.644578) (xy 82.187691 -35.634448)
			(xy 82.134907 -35.616441) (xy 82.085307 -35.59094) (xy 82.039949 -35.558489) (xy 81.9998 -35.51978)
			(xy 81.965714 -35.475637) (xy 81.938418 -35.427002) (xy 81.918495 -35.374911) (xy 81.906369 -35.320474)
			(xy 81.902298 -35.264852) (xy 81.122266 -35.264852) (xy 82.144362 -36.286948) (xy 83.200238 -36.286948)
			(xy 83.204309 -36.231326) (xy 83.216435 -36.176889) (xy 83.236358 -36.124798) (xy 83.263654 -36.076163)
			(xy 83.29774 -36.03202) (xy 83.337889 -35.993311) (xy 83.383247 -35.96086) (xy 83.432847 -35.935359)
			(xy 83.485631 -35.917352) (xy 83.540474 -35.907222) (xy 83.596208 -35.905185) (xy 83.651645 -35.911285)
			(xy 83.705602 -35.925391) (xy 83.756931 -35.947203) (xy 83.804537 -35.976257) (xy 83.847405 -36.011932)
			(xy 83.884622 -36.053469) (xy 83.915395 -36.099982) (xy 83.939067 -36.150479) (xy 83.955135 -36.203886)
			(xy 83.963255 -36.259062) (xy 83.963764 -36.286948) (xy 83.963255 -36.314834) (xy 83.955135 -36.37001)
			(xy 83.939067 -36.423417) (xy 83.915395 -36.473914) (xy 83.884622 -36.520427) (xy 83.847405 -36.561964)
			(xy 83.804537 -36.597639) (xy 83.756931 -36.626693) (xy 83.705602 -36.648505) (xy 83.651645 -36.662611)
			(xy 83.596208 -36.668711) (xy 83.540474 -36.666674) (xy 83.485631 -36.656544) (xy 83.432847 -36.638537)
			(xy 83.383247 -36.613036) (xy 83.337889 -36.580585) (xy 83.29774 -36.541876) (xy 83.263654 -36.497733)
			(xy 83.236358 -36.449098) (xy 83.216435 -36.397007) (xy 83.204309 -36.34257) (xy 83.200238 -36.286948)
			(xy 82.144362 -36.286948) (xy 83.399376 -37.541962) (xy 83.407344 -37.549087) (xy 83.427294 -37.556689)
			(xy 83.437984 -37.556694) (xy 83.513422 -37.55263) (xy 83.518703 -37.55223) (xy 83.528947 -37.549545)
			(xy 83.533742 -37.547296) (xy 83.54314 -37.54247) (xy 83.549998 -37.533834) (xy 83.568229 -37.512187)
			(xy 83.60999 -37.473991) (xy 83.65693 -37.442376) (xy 83.708022 -37.418036) (xy 83.762147 -37.401502)
			(xy 83.818119 -37.393137) (xy 83.846416 -37.39261) (xy 83.84667 -37.39261) (xy 83.874407 -37.393112)
			(xy 83.929297 -37.401153) (xy 83.982444 -37.417055) (xy 84.032729 -37.440484) (xy 84.079093 -37.470945)
			(xy 84.120558 -37.507797) (xy 84.156253 -37.550263) (xy 84.185423 -37.597449) (xy 84.207456 -37.648362)
			(xy 84.221886 -37.701927) (xy 84.225638 -37.729414) (xy 84.227162 -37.74313) (xy 84.228859 -37.769576)
			(xy 84.225812 -37.82248) (xy 84.215479 -37.874455) (xy 84.198057 -37.924502) (xy 84.173881 -37.971659)
			(xy 84.143417 -38.015019) (xy 84.10725 -38.05375) (xy 84.086954 -38.07079) (xy 84.078572 -38.077648)
			(xy 84.073746 -38.0873) (xy 84.071386 -38.092133) (xy 84.068569 -38.102511) (xy 84.068158 -38.107874)
			(xy 84.064094 -38.18509) (xy 84.064301 -38.19398) (xy 84.07017 -38.210754) (xy 84.075524 -38.217856)
			(xy 84.077302 -38.219888) (xy 84.078826 -38.221412) (xy 84.379308 -38.521894) (xy 84.989162 -39.132002)
			(xy 84.996594 -39.138536) (xy 85.014949 -39.14588) (xy 85.034718 -39.145749) (xy 85.052974 -39.138163)
			(xy 85.060282 -39.131494) (xy 85.060536 -39.13124) (xy 85.067901 -39.123115) (xy 85.075533 -39.102579)
			(xy 85.075268 -39.091616) (xy 85.075268 -39.091362) (xy 85.074252 -39.064946) (xy 85.074252 -36.741354)
			(xy 85.07222 -36.727384) (xy 85.06714 -36.709096) (xy 85.065108 -36.705286) (xy 85.05444 -36.685982)
			(xy 85.05444 -36.685474) (xy 85.04766 -36.671677) (xy 85.036093 -36.643193) (xy 85.031326 -36.628578)
			(xy 85.029548 -36.622736) (xy 85.023198 -36.612068) (xy 83.528662 -35.117532) (xy 83.510552 -35.09875)
			(xy 83.479874 -35.056551) (xy 83.456181 -35.01007) (xy 83.440056 -34.960452) (xy 83.431899 -34.908922)
			(xy 83.43138 -34.882836) (xy 83.43138 -32.410654) (xy 83.427062 -32.405574) (xy 83.374484 -32.362394)
			(xy 83.363308 -32.35325) (xy 83.360449 -32.350961) (xy 83.354199 -32.347142) (xy 83.350862 -32.34563)
			(xy 83.32978 -32.350202) (xy 83.299722 -32.356215) (xy 83.238764 -32.362708) (xy 83.208114 -32.363156)
			(xy 83.1727 -32.362643) (xy 83.102388 -32.354107) (xy 83.033618 -32.337158) (xy 82.967392 -32.312042)
			(xy 82.904676 -32.279127) (xy 82.846386 -32.238892) (xy 82.79337 -32.191924) (xy 82.746403 -32.138908)
			(xy 82.706169 -32.080617) (xy 82.673254 -32.017901) (xy 82.64814 -31.951675) (xy 82.631191 -31.882904)
			(xy 82.622656 -31.812592) (xy 82.622136 -31.777178) (xy 82.622136 -30.776164) (xy 82.619719 -30.773073)
			(xy 82.614105 -30.76759) (xy 82.61096 -30.765242) (xy 82.576162 -30.743906) (xy 82.53857 -30.720792)
			(xy 82.528156 -30.715966) (xy 82.52587 -30.715204) (xy 82.516619 -30.712951) (xy 82.49768 -30.714764)
			(xy 82.48904 -30.71876) (xy 82.488786 -30.71876) (xy 82.478118 -30.724094) (xy 82.451888 -30.736183)
			(xy 82.396713 -30.75325) (xy 82.339609 -30.761897) (xy 82.310732 -30.762448) (xy 82.310478 -30.762448)
			(xy 82.282936 -30.761978) (xy 82.228415 -30.754136) (xy 82.175564 -30.738614) (xy 82.12546 -30.715729)
			(xy 82.079122 -30.685946) (xy 82.037496 -30.649872) (xy 82.001426 -30.608241) (xy 81.971649 -30.5619)
			(xy 81.94877 -30.511793) (xy 81.933254 -30.45894) (xy 81.925418 -30.404418) (xy 81.924906 -30.376876)
			(xy 81.92543 -30.347907) (xy 81.934106 -30.290621) (xy 81.95126 -30.23528) (xy 81.976505 -30.183131)
			(xy 82.009271 -30.135348) (xy 82.048821 -30.093008) (xy 82.07121 -30.074616) (xy 82.075578 -30.07096)
			(xy 82.082757 -30.062118) (xy 82.085434 -30.05709) (xy 82.090006 -30.047692) (xy 82.09026 -30.047184)
			(xy 82.092725 -30.041859) (xy 82.095426 -30.030443) (xy 82.095594 -30.024578) (xy 82.095594 -29.967682)
			(xy 82.095452 -29.962242) (xy 82.093147 -29.951609) (xy 82.091022 -29.9466) (xy 82.08772 -29.939742)
			(xy 82.08772 -29.939234) (xy 82.080862 -29.925518) (xy 82.07248 -29.914088) (xy 82.067654 -29.909262)
			(xy 82.065876 -29.907738) (xy 82.044848 -29.8895) (xy 82.007782 -29.847976) (xy 81.977138 -29.80151)
			(xy 81.953566 -29.751087) (xy 81.937563 -29.697776) (xy 81.929471 -29.642706) (xy 81.92897 -29.614876)
			(xy 81.929457 -29.587625) (xy 81.937217 -29.533679) (xy 81.952574 -29.481386) (xy 81.975216 -29.43181)
			(xy 82.004682 -29.385961) (xy 82.040374 -29.344772) (xy 82.081563 -29.309081) (xy 82.127412 -29.279615)
			(xy 82.176988 -29.256973) (xy 82.229281 -29.241616) (xy 82.283227 -29.233857) (xy 82.310478 -29.233368)
			(xy 82.335847 -29.233783) (xy 82.386138 -29.240505) (xy 82.435095 -29.253834) (xy 82.481853 -29.273534)
			(xy 82.525587 -29.299257) (xy 82.565526 -29.330551) (xy 82.583528 -29.34843) (xy 82.58556 -29.350462)
			(xy 82.596482 -29.358082) (xy 82.627724 -29.372052) (xy 82.639408 -29.37129) (xy 82.639662 -29.37129)
			(xy 82.652108 -29.370782) (xy 82.658325 -29.370272) (xy 82.670265 -29.366677) (xy 82.67573 -29.36367)
			(xy 82.705702 -29.345636) (xy 82.707988 -29.34208) (xy 82.72653 -29.312598) (xy 82.769573 -29.257842)
			(xy 82.79384 -29.23286) (xy 85.23478 -26.79192) (xy 85.238082 -26.787856) (xy 85.242218 -26.781346)
			(xy 85.246749 -26.766609) (xy 85.246972 -26.7589) (xy 85.246972 -24.158194) (xy 85.247467 -24.124108)
			(xy 85.255382 -24.056398) (xy 85.271103 -23.990064) (xy 85.294419 -23.926004) (xy 85.325014 -23.865084)
			(xy 85.362475 -23.808127) (xy 85.406295 -23.755905) (xy 85.455881 -23.709123) (xy 85.510563 -23.668414)
			(xy 85.569601 -23.634328) (xy 85.632197 -23.607327) (xy 85.697504 -23.587775) (xy 85.76464 -23.575937)
			(xy 85.832696 -23.571974) (xy 85.900752 -23.575937) (xy 85.967888 -23.587775) (xy 86.033195 -23.607327)
			(xy 86.095791 -23.634328) (xy 86.154829 -23.668414) (xy 86.209511 -23.709123) (xy 86.259097 -23.755905)
			(xy 86.302917 -23.808127) (xy 86.340378 -23.865084) (xy 86.370973 -23.926004) (xy 86.394289 -23.990064)
			(xy 86.41001 -24.056398) (xy 86.417925 -24.124108) (xy 86.41842 -24.158194) (xy 86.41842 -24.807418)
			(xy 86.620094 -24.807418) (xy 86.624165 -24.751796) (xy 86.636291 -24.697359) (xy 86.656214 -24.645268)
			(xy 86.68351 -24.596633) (xy 86.717596 -24.55249) (xy 86.757745 -24.513781) (xy 86.803103 -24.48133)
			(xy 86.852703 -24.455829) (xy 86.905487 -24.437822) (xy 86.96033 -24.427692) (xy 87.016064 -24.425655)
			(xy 87.071501 -24.431755) (xy 87.125458 -24.445861) (xy 87.176787 -24.467673) (xy 87.224393 -24.496727)
			(xy 87.267261 -24.532402) (xy 87.304478 -24.573939) (xy 87.335251 -24.620452) (xy 87.358923 -24.670949)
			(xy 87.374991 -24.724356) (xy 87.383111 -24.779532) (xy 87.38362 -24.807418) (xy 87.383111 -24.835304)
			(xy 87.374991 -24.89048) (xy 87.358923 -24.943887) (xy 87.335251 -24.994384) (xy 87.304478 -25.040897)
			(xy 87.267261 -25.082434) (xy 87.224393 -25.118109) (xy 87.176787 -25.147163) (xy 87.125458 -25.168975)
			(xy 87.071501 -25.183081) (xy 87.016064 -25.189181) (xy 86.96033 -25.187144) (xy 86.905487 -25.177014)
			(xy 86.852703 -25.159007) (xy 86.803103 -25.133506) (xy 86.757745 -25.101055) (xy 86.717596 -25.062346)
			(xy 86.68351 -25.018203) (xy 86.656214 -24.969568) (xy 86.636291 -24.917477) (xy 86.624165 -24.86304)
			(xy 86.620094 -24.807418) (xy 86.41842 -24.807418) (xy 86.41842 -26.724356) (xy 86.420632 -26.727205)
			(xy 86.425727 -26.73231) (xy 86.42858 -26.734516) (xy 86.741508 -26.734516) (xy 86.7537 -26.732992)
			(xy 86.756748 -26.731214) (xy 86.761077 -26.728717) (xy 86.768758 -26.722327) (xy 86.771988 -26.718514)
			(xy 86.78799 -26.698194) (xy 86.789006 -26.695146) (xy 86.778846 -26.649934) (xy 86.775782 -26.64001)
			(xy 86.763058 -26.623621) (xy 86.754208 -26.618184) (xy 86.750144 -26.616406) (xy 86.724926 -26.604921)
			(xy 86.677823 -26.575739) (xy 86.635438 -26.540048) (xy 86.598663 -26.4986) (xy 86.568272 -26.452267)
			(xy 86.544905 -26.402024) (xy 86.529053 -26.348929) (xy 86.521051 -26.294099) (xy 86.520528 -26.266394)
			(xy 86.521014 -26.239143) (xy 86.52877 -26.185195) (xy 86.544125 -26.1329) (xy 86.566767 -26.083323)
			(xy 86.596233 -26.037473) (xy 86.631924 -25.996282) (xy 86.673115 -25.960591) (xy 86.718965 -25.931125)
			(xy 86.768542 -25.908483) (xy 86.820837 -25.893128) (xy 86.874785 -25.885372) (xy 86.929287 -25.885372)
			(xy 86.983235 -25.893128) (xy 87.03553 -25.908483) (xy 87.085107 -25.931125) (xy 87.130957 -25.960591)
			(xy 87.172148 -25.996282) (xy 87.207839 -26.037473) (xy 87.237305 -26.083323) (xy 87.259947 -26.1329)
			(xy 87.275302 -26.185195) (xy 87.283058 -26.239143) (xy 87.283544 -26.266394) (xy 87.283006 -26.295372)
			(xy 87.274247 -26.352661) (xy 87.256928 -26.407968) (xy 87.231448 -26.460022) (xy 87.198393 -26.507626)
			(xy 87.158522 -26.549687) (xy 87.13597 -26.567892) (xy 87.13216 -26.57094) (xy 87.116412 -26.58872)
			(xy 87.113364 -26.598626) (xy 87.110316 -26.607516) (xy 87.110824 -26.617422) (xy 87.112348 -26.648156)
			(xy 87.112348 -26.648664) (xy 87.114888 -26.688034) (xy 87.115142 -26.690828) (xy 87.115886 -26.695979)
			(xy 87.119213 -26.705839) (xy 87.121746 -26.710386) (xy 87.12581 -26.717244) (xy 87.13089 -26.725372)
			(xy 87.138256 -26.73477) (xy 87.143844 -26.740358) (xy 87.167295 -26.755429) (xy 87.20998 -26.791282)
			(xy 87.24702 -26.83294) (xy 87.277633 -26.879526) (xy 87.301173 -26.930056) (xy 87.317143 -26.983464)
			(xy 87.325206 -27.038622) (xy 87.325708 -27.066494) (xy 87.32522 -27.093873) (xy 87.317428 -27.148074)
			(xy 87.302002 -27.200614) (xy 87.279256 -27.250425) (xy 87.249653 -27.296491) (xy 87.213796 -27.337876)
			(xy 87.172414 -27.373736) (xy 87.126349 -27.403343) (xy 87.076541 -27.426093) (xy 87.024001 -27.441522)
			(xy 86.969801 -27.449318) (xy 86.942422 -27.44978) (xy 86.911062 -27.449156) (xy 86.849177 -27.438947)
			(xy 86.78978 -27.418799) (xy 86.761828 -27.404568) (xy 86.756199 -27.401745) (xy 86.743993 -27.398663)
			(xy 86.737698 -27.398472) (xy 86.578186 -27.398472) (xy 86.57336 -27.403552) (xy 86.571582 -27.405076)
			(xy 86.570312 -27.406092) (xy 84.854034 -29.12237) (xy 86.606888 -29.12237) (xy 86.606888 -28.25877)
			(xy 86.607378 -28.228802) (xy 86.615201 -28.16938) (xy 86.630714 -28.111487) (xy 86.65365 -28.056114)
			(xy 86.683617 -28.004208) (xy 86.720104 -27.956658) (xy 86.762484 -27.914278) (xy 86.810034 -27.877791)
			(xy 86.86194 -27.847824) (xy 86.917313 -27.824888) (xy 86.975206 -27.809375) (xy 87.034628 -27.801552)
			(xy 87.094564 -27.801552) (xy 87.153986 -27.809375) (xy 87.211879 -27.824888) (xy 87.267252 -27.847824)
			(xy 87.319158 -27.877791) (xy 87.366708 -27.914278) (xy 87.409088 -27.956658) (xy 87.445575 -28.004208)
			(xy 87.475542 -28.056114) (xy 87.498478 -28.111487) (xy 87.513991 -28.16938) (xy 87.521814 -28.228802)
			(xy 87.522304 -28.25877) (xy 87.522304 -29.12237) (xy 87.521814 -29.152338) (xy 87.513991 -29.21176)
			(xy 87.498478 -29.269653) (xy 87.475542 -29.325026) (xy 87.445575 -29.376932) (xy 87.409088 -29.424482)
			(xy 87.366708 -29.466862) (xy 87.319158 -29.503349) (xy 87.267252 -29.533316) (xy 87.211879 -29.556252)
			(xy 87.153986 -29.571765) (xy 87.094564 -29.579588) (xy 87.034628 -29.579588) (xy 86.975206 -29.571765)
			(xy 86.917313 -29.556252) (xy 86.86194 -29.533316) (xy 86.810034 -29.503349) (xy 86.762484 -29.466862)
			(xy 86.720104 -29.424482) (xy 86.683617 -29.376932) (xy 86.65365 -29.325026) (xy 86.630714 -29.269653)
			(xy 86.615201 -29.21176) (xy 86.607378 -29.152338) (xy 86.606888 -29.12237) (xy 84.854034 -29.12237)
			(xy 84.097114 -29.87929) (xy 84.095336 -29.881576) (xy 84.095336 -30.922468) (xy 84.752688 -30.922468)
			(xy 84.752688 -30.058868) (xy 84.753178 -30.0289) (xy 84.761001 -29.969478) (xy 84.776514 -29.911585)
			(xy 84.79945 -29.856212) (xy 84.829417 -29.804306) (xy 84.865904 -29.756756) (xy 84.908284 -29.714376)
			(xy 84.955834 -29.677889) (xy 85.00774 -29.647922) (xy 85.063113 -29.624986) (xy 85.121006 -29.609473)
			(xy 85.180428 -29.60165) (xy 85.240364 -29.60165) (xy 85.299786 -29.609473) (xy 85.357679 -29.624986)
			(xy 85.413052 -29.647922) (xy 85.464958 -29.677889) (xy 85.512508 -29.714376) (xy 85.554888 -29.756756)
			(xy 85.591375 -29.804306) (xy 85.621342 -29.856212) (xy 85.644278 -29.911585) (xy 85.659791 -29.969478)
			(xy 85.667614 -30.0289) (xy 85.668104 -30.058868) (xy 85.668104 -30.92069) (xy 99.48926 -30.92069)
			(xy 99.48926 -30.05709) (xy 99.48975 -30.027106) (xy 99.497578 -29.96765) (xy 99.513099 -29.909725)
			(xy 99.536048 -29.854321) (xy 99.566032 -29.802387) (xy 99.602538 -29.754811) (xy 99.644943 -29.712406)
			(xy 99.692519 -29.6759) (xy 99.744453 -29.645916) (xy 99.799857 -29.622967) (xy 99.857782 -29.607446)
			(xy 99.917238 -29.599618) (xy 99.977206 -29.599618) (xy 100.036662 -29.607446) (xy 100.094587 -29.622967)
			(xy 100.149991 -29.645916) (xy 100.201925 -29.6759) (xy 100.249501 -29.712406) (xy 100.291906 -29.754811)
			(xy 100.328412 -29.802387) (xy 100.358396 -29.854321) (xy 100.381345 -29.909725) (xy 100.396866 -29.96765)
			(xy 100.404694 -30.027106) (xy 100.405184 -30.05709) (xy 100.405184 -30.92069) (xy 100.404694 -30.950674)
			(xy 100.396866 -31.01013) (xy 100.381345 -31.068055) (xy 100.358396 -31.123459) (xy 100.328412 -31.175393)
			(xy 100.291906 -31.222969) (xy 100.249501 -31.265374) (xy 100.201925 -31.30188) (xy 100.149991 -31.331864)
			(xy 100.094587 -31.354813) (xy 100.036662 -31.370334) (xy 99.977206 -31.378162) (xy 99.917238 -31.378162)
			(xy 99.857782 -31.370334) (xy 99.799857 -31.354813) (xy 99.744453 -31.331864) (xy 99.692519 -31.30188)
			(xy 99.644943 -31.265374) (xy 99.602538 -31.222969) (xy 99.566032 -31.175393) (xy 99.536048 -31.123459)
			(xy 99.513099 -31.068055) (xy 99.497578 -31.01013) (xy 99.48975 -30.950674) (xy 99.48926 -30.92069)
			(xy 85.668104 -30.92069) (xy 85.668104 -30.922468) (xy 85.667614 -30.952436) (xy 85.659791 -31.011858)
			(xy 85.644278 -31.069751) (xy 85.621342 -31.125124) (xy 85.591375 -31.17703) (xy 85.554888 -31.22458)
			(xy 85.512508 -31.26696) (xy 85.464958 -31.303447) (xy 85.413052 -31.333414) (xy 85.357679 -31.35635)
			(xy 85.299786 -31.371863) (xy 85.240364 -31.379686) (xy 85.180428 -31.379686) (xy 85.121006 -31.371863)
			(xy 85.063113 -31.35635) (xy 85.00774 -31.333414) (xy 84.955834 -31.303447) (xy 84.908284 -31.26696)
			(xy 84.865904 -31.22458) (xy 84.829417 -31.17703) (xy 84.79945 -31.125124) (xy 84.776514 -31.069751)
			(xy 84.761001 -31.011858) (xy 84.753178 -30.952436) (xy 84.752688 -30.922468) (xy 84.095336 -30.922468)
			(xy 84.095336 -32.722312) (xy 86.606888 -32.722312) (xy 86.606888 -31.858712) (xy 86.607378 -31.828744)
			(xy 86.615201 -31.769322) (xy 86.630714 -31.711429) (xy 86.65365 -31.656056) (xy 86.683617 -31.60415)
			(xy 86.720104 -31.5566) (xy 86.762484 -31.51422) (xy 86.810034 -31.477733) (xy 86.86194 -31.447766)
			(xy 86.917313 -31.42483) (xy 86.975206 -31.409317) (xy 87.034628 -31.401494) (xy 87.094564 -31.401494)
			(xy 87.153986 -31.409317) (xy 87.211879 -31.42483) (xy 87.267252 -31.447766) (xy 87.319158 -31.477733)
			(xy 87.366708 -31.51422) (xy 87.409088 -31.5566) (xy 87.445575 -31.60415) (xy 87.475542 -31.656056)
			(xy 87.498478 -31.711429) (xy 87.513991 -31.769322) (xy 87.521814 -31.828744) (xy 87.522304 -31.858712)
			(xy 87.522304 -32.714184) (xy 96.847152 -32.714184) (xy 96.847152 -31.850584) (xy 96.847642 -31.8206)
			(xy 96.85547 -31.761144) (xy 96.870991 -31.703219) (xy 96.89394 -31.647815) (xy 96.923924 -31.595881)
			(xy 96.96043 -31.548305) (xy 97.002835 -31.5059) (xy 97.050411 -31.469394) (xy 97.102345 -31.43941)
			(xy 97.157749 -31.416461) (xy 97.215674 -31.40094) (xy 97.27513 -31.393112) (xy 97.335098 -31.393112)
			(xy 97.394554 -31.40094) (xy 97.452479 -31.416461) (xy 97.507883 -31.43941) (xy 97.559817 -31.469394)
			(xy 97.607393 -31.5059) (xy 97.649798 -31.548305) (xy 97.686304 -31.595881) (xy 97.716288 -31.647815)
			(xy 97.739237 -31.703219) (xy 97.754758 -31.761144) (xy 97.762586 -31.8206) (xy 97.763076 -31.850584)
			(xy 97.763076 -32.714184) (xy 97.762586 -32.744168) (xy 97.754758 -32.803624) (xy 97.739237 -32.861549)
			(xy 97.716288 -32.916953) (xy 97.686304 -32.968887) (xy 97.649798 -33.016463) (xy 97.607393 -33.058868)
			(xy 97.559817 -33.095374) (xy 97.507883 -33.125358) (xy 97.452479 -33.148307) (xy 97.394554 -33.163828)
			(xy 97.335098 -33.171656) (xy 97.27513 -33.171656) (xy 97.215674 -33.163828) (xy 97.157749 -33.148307)
			(xy 97.102345 -33.125358) (xy 97.050411 -33.095374) (xy 97.002835 -33.058868) (xy 96.96043 -33.016463)
			(xy 96.923924 -32.968887) (xy 96.89394 -32.916953) (xy 96.870991 -32.861549) (xy 96.85547 -32.803624)
			(xy 96.847642 -32.744168) (xy 96.847152 -32.714184) (xy 87.522304 -32.714184) (xy 87.522304 -32.722312)
			(xy 87.521814 -32.75228) (xy 87.513991 -32.811702) (xy 87.498478 -32.869595) (xy 87.475542 -32.924968)
			(xy 87.445575 -32.976874) (xy 87.409088 -33.024424) (xy 87.366708 -33.066804) (xy 87.319158 -33.103291)
			(xy 87.267252 -33.133258) (xy 87.211879 -33.156194) (xy 87.153986 -33.171707) (xy 87.094564 -33.17953)
			(xy 87.034628 -33.17953) (xy 86.975206 -33.171707) (xy 86.917313 -33.156194) (xy 86.86194 -33.133258)
			(xy 86.810034 -33.103291) (xy 86.762484 -33.066804) (xy 86.720104 -33.024424) (xy 86.683617 -32.976874)
			(xy 86.65365 -32.924968) (xy 86.630714 -32.869595) (xy 86.615201 -32.811702) (xy 86.607378 -32.75228)
			(xy 86.606888 -32.722312) (xy 84.095336 -32.722312) (xy 84.095336 -34.52241) (xy 84.752688 -34.52241)
			(xy 84.752688 -33.65881) (xy 84.753178 -33.628842) (xy 84.761001 -33.56942) (xy 84.776514 -33.511527)
			(xy 84.79945 -33.456154) (xy 84.829417 -33.404248) (xy 84.865904 -33.356698) (xy 84.908284 -33.314318)
			(xy 84.955834 -33.277831) (xy 85.00774 -33.247864) (xy 85.063113 -33.224928) (xy 85.121006 -33.209415)
			(xy 85.180428 -33.201592) (xy 85.240364 -33.201592) (xy 85.299786 -33.209415) (xy 85.357679 -33.224928)
			(xy 85.413052 -33.247864) (xy 85.464958 -33.277831) (xy 85.512508 -33.314318) (xy 85.554888 -33.356698)
			(xy 85.591375 -33.404248) (xy 85.621342 -33.456154) (xy 85.644278 -33.511527) (xy 85.659791 -33.56942)
			(xy 85.667614 -33.628842) (xy 85.668104 -33.65881) (xy 85.668104 -34.520886) (xy 99.48926 -34.520886)
			(xy 99.48926 -33.657286) (xy 99.48975 -33.627302) (xy 99.497578 -33.567846) (xy 99.513099 -33.509921)
			(xy 99.536048 -33.454517) (xy 99.566032 -33.402583) (xy 99.602538 -33.355007) (xy 99.644943 -33.312602)
			(xy 99.692519 -33.276096) (xy 99.744453 -33.246112) (xy 99.799857 -33.223163) (xy 99.857782 -33.207642)
			(xy 99.917238 -33.199814) (xy 99.977206 -33.199814) (xy 100.036662 -33.207642) (xy 100.094587 -33.223163)
			(xy 100.149991 -33.246112) (xy 100.201925 -33.276096) (xy 100.249501 -33.312602) (xy 100.291906 -33.355007)
			(xy 100.328412 -33.402583) (xy 100.358396 -33.454517) (xy 100.381345 -33.509921) (xy 100.396866 -33.567846)
			(xy 100.404694 -33.627302) (xy 100.405184 -33.657286) (xy 100.405184 -34.520886) (xy 100.404694 -34.55087)
			(xy 100.396866 -34.610326) (xy 100.381345 -34.668251) (xy 100.358396 -34.723655) (xy 100.328412 -34.775589)
			(xy 100.291906 -34.823165) (xy 100.249501 -34.86557) (xy 100.201925 -34.902076) (xy 100.149991 -34.93206)
			(xy 100.094587 -34.955009) (xy 100.036662 -34.97053) (xy 99.977206 -34.978358) (xy 99.917238 -34.978358)
			(xy 99.857782 -34.97053) (xy 99.799857 -34.955009) (xy 99.744453 -34.93206) (xy 99.692519 -34.902076)
			(xy 99.644943 -34.86557) (xy 99.602538 -34.823165) (xy 99.566032 -34.775589) (xy 99.536048 -34.723655)
			(xy 99.513099 -34.668251) (xy 99.497578 -34.610326) (xy 99.48975 -34.55087) (xy 99.48926 -34.520886)
			(xy 85.668104 -34.520886) (xy 85.668104 -34.52241) (xy 85.667614 -34.552378) (xy 85.659791 -34.6118)
			(xy 85.644278 -34.669693) (xy 85.621342 -34.725066) (xy 85.591375 -34.776972) (xy 85.554888 -34.824522)
			(xy 85.512508 -34.866902) (xy 85.464958 -34.903389) (xy 85.413052 -34.933356) (xy 85.357679 -34.956292)
			(xy 85.299786 -34.971805) (xy 85.240364 -34.979628) (xy 85.180428 -34.979628) (xy 85.121006 -34.971805)
			(xy 85.063113 -34.956292) (xy 85.00774 -34.933356) (xy 84.955834 -34.903389) (xy 84.908284 -34.866902)
			(xy 84.865904 -34.824522) (xy 84.829417 -34.776972) (xy 84.79945 -34.725066) (xy 84.776514 -34.669693)
			(xy 84.761001 -34.6118) (xy 84.753178 -34.552378) (xy 84.752688 -34.52241) (xy 84.095336 -34.52241)
			(xy 84.095336 -34.72434) (xy 84.096352 -34.733992) (xy 84.097985 -34.741233) (xy 84.104836 -34.754393)
			(xy 84.109814 -34.7599) (xy 85.497416 -36.147502) (xy 85.50402 -36.149534) (xy 85.529833 -36.157633)
			(xy 85.579043 -36.180104) (xy 85.624585 -36.209303) (xy 85.665544 -36.244644) (xy 85.701099 -36.285418)
			(xy 85.730535 -36.330807) (xy 85.753264 -36.379899) (xy 85.768827 -36.431711) (xy 85.776914 -36.485201)
			(xy 85.777578 -36.512246) (xy 85.777578 -36.519104) (xy 85.777 -36.543004) (xy 85.770636 -36.590388)
			(xy 85.768219 -36.60013) (xy 89.998049 -36.60013) (xy 90.002054 -36.512222) (xy 90.014037 -36.425042)
			(xy 90.033897 -36.339313) (xy 90.061472 -36.255745) (xy 90.096531 -36.175031) (xy 90.138784 -36.097839)
			(xy 90.187882 -36.02481) (xy 90.243418 -35.956548) (xy 90.30493 -35.893618) (xy 90.371911 -35.836544)
			(xy 90.443804 -35.785796) (xy 90.520013 -35.741796) (xy 90.599908 -35.704909) (xy 90.682827 -35.67544)
			(xy 90.768082 -35.653633) (xy 90.854966 -35.639669) (xy 90.94276 -35.633663) (xy 91.030737 -35.635667)
			(xy 91.118167 -35.645662) (xy 91.204326 -35.663566) (xy 91.2885 -35.68923) (xy 91.369991 -35.722443)
			(xy 91.448125 -35.762929) (xy 91.522253 -35.810351) (xy 91.591761 -35.864318) (xy 91.656075 -35.924383)
			(xy 91.714659 -35.990047) (xy 91.76703 -36.060766) (xy 91.812753 -36.135954) (xy 91.85145 -36.214989)
			(xy 91.882799 -36.297215) (xy 91.906541 -36.381951) (xy 91.922479 -36.468495) (xy 91.930481 -36.55613)
			(xy 91.930982 -36.60013) (xy 91.930481 -36.64413) (xy 91.922479 -36.731765) (xy 91.906541 -36.818309)
			(xy 91.882799 -36.903045) (xy 91.85145 -36.985271) (xy 91.812753 -37.064306) (xy 91.76703 -37.139494)
			(xy 91.714659 -37.210213) (xy 91.656075 -37.275877) (xy 91.591761 -37.335942) (xy 91.522253 -37.389909)
			(xy 91.448125 -37.437331) (xy 91.369991 -37.477817) (xy 91.2885 -37.51103) (xy 91.204326 -37.536694)
			(xy 91.118167 -37.554598) (xy 91.030737 -37.564593) (xy 90.94276 -37.566597) (xy 90.854966 -37.560591)
			(xy 90.768082 -37.546627) (xy 90.682827 -37.52482) (xy 90.599908 -37.495351) (xy 90.520013 -37.458464)
			(xy 90.443804 -37.414464) (xy 90.371911 -37.363716) (xy 90.30493 -37.306642) (xy 90.243418 -37.243712)
			(xy 90.187882 -37.17545) (xy 90.138784 -37.102421) (xy 90.096531 -37.025229) (xy 90.061472 -36.944515)
			(xy 90.033897 -36.860947) (xy 90.014037 -36.775218) (xy 90.002054 -36.688038) (xy 89.998049 -36.60013)
			(xy 85.768219 -36.60013) (xy 85.764878 -36.613592) (xy 85.753448 -36.64966) (xy 85.7504 -36.657788)
			(xy 85.744812 -36.67125) (xy 85.74278 -36.675822) (xy 85.741764 -36.678108) (xy 85.739986 -36.681664)
			(xy 85.7377 -36.691824) (xy 85.7377 -38.90645) (xy 85.737776 -38.91066) (xy 85.739173 -38.918962)
			(xy 85.740494 -38.92296) (xy 85.742512 -38.928322) (xy 85.748532 -38.938067) (xy 85.752432 -38.942264)
			(xy 88.079021 -41.268751) (xy 93.84385 -41.268751) (xy 93.84385 -41.214249) (xy 93.851606 -41.160301)
			(xy 93.86696 -41.108006) (xy 93.889599 -41.058428) (xy 93.919064 -41.012576) (xy 93.954753 -40.971384)
			(xy 93.995941 -40.93569) (xy 94.041789 -40.90622) (xy 94.091365 -40.883575) (xy 94.143658 -40.868215)
			(xy 94.197605 -40.860453) (xy 94.224856 -40.859964) (xy 94.253596 -40.860463) (xy 94.310424 -40.869093)
			(xy 94.365314 -40.88615) (xy 94.417026 -40.911246) (xy 94.464387 -40.943816) (xy 94.485714 -40.963088)
			(xy 94.492572 -40.969692) (xy 94.510606 -40.976804) (xy 94.599506 -40.976804) (xy 94.61754 -40.969692)
			(xy 94.624398 -40.963088) (xy 94.645709 -40.943799) (xy 94.693075 -40.911233) (xy 94.74479 -40.886143)
			(xy 94.799685 -40.869097) (xy 94.856516 -40.860481) (xy 94.885256 -40.859964) (xy 94.912509 -40.86048)
			(xy 94.966461 -40.868232) (xy 95.01876 -40.883583) (xy 95.068342 -40.906221) (xy 95.114197 -40.935686)
			(xy 95.155392 -40.971377) (xy 95.191088 -41.012567) (xy 95.220558 -41.058419) (xy 95.243202 -41.107999)
			(xy 95.258559 -41.160296) (xy 95.266317 -41.214247) (xy 95.266317 -41.268753) (xy 95.258559 -41.322704)
			(xy 95.243202 -41.375001) (xy 95.220558 -41.424581) (xy 95.191088 -41.470433) (xy 95.155392 -41.511623)
			(xy 95.114197 -41.547314) (xy 95.068342 -41.576779) (xy 95.01876 -41.599417) (xy 94.966461 -41.614768)
			(xy 94.912509 -41.62252) (xy 94.885256 -41.62298) (xy 94.856517 -41.622462) (xy 94.79969 -41.613834)
			(xy 94.744801 -41.596782) (xy 94.693089 -41.57169) (xy 94.645726 -41.539126) (xy 94.624398 -41.519856)
			(xy 94.61754 -41.513252) (xy 94.599506 -41.50614) (xy 94.510606 -41.50614) (xy 94.492572 -41.513252)
			(xy 94.485714 -41.519856) (xy 94.464404 -41.539147) (xy 94.417038 -41.57171) (xy 94.365322 -41.596799)
			(xy 94.310427 -41.613845) (xy 94.253596 -41.622462) (xy 94.224856 -41.62298) (xy 94.197605 -41.622547)
			(xy 94.143658 -41.614785) (xy 94.091365 -41.599425) (xy 94.041789 -41.57678) (xy 93.995941 -41.54731)
			(xy 93.954753 -41.511616) (xy 93.919064 -41.470424) (xy 93.889599 -41.424572) (xy 93.86696 -41.374994)
			(xy 93.851606 -41.322699) (xy 93.84385 -41.268751) (xy 88.079021 -41.268751) (xy 90.115581 -43.305222)
			(xy 96.307148 -43.305222) (xy 96.307615 -43.277852) (xy 96.315431 -43.223672) (xy 96.330919 -43.171169)
			(xy 96.353761 -43.121422) (xy 96.383486 -43.075455) (xy 96.401128 -43.054524) (xy 96.401382 -43.05427)
			(xy 96.406943 -43.047166) (xy 96.413205 -43.030263) (xy 96.413574 -43.02125) (xy 96.413574 -42.954194)
			(xy 96.413226 -42.945176) (xy 96.406973 -42.928259) (xy 96.401382 -42.921174) (xy 96.401128 -42.921174)
			(xy 96.401128 -42.92092) (xy 96.383489 -42.899988) (xy 96.353776 -42.854015) (xy 96.33094 -42.804268)
			(xy 96.315449 -42.751767) (xy 96.307621 -42.697591) (xy 96.307148 -42.670222) (xy 96.307699 -42.641484)
			(xy 96.316317 -42.584659) (xy 96.333362 -42.529769) (xy 96.358447 -42.478057) (xy 96.391005 -42.430692)
			(xy 96.410272 -42.409364) (xy 96.416876 -42.402506) (xy 96.423988 -42.384472) (xy 96.423988 -42.295572)
			(xy 96.416876 -42.277538) (xy 96.410272 -42.27068) (xy 96.391025 -42.249333) (xy 96.358464 -42.201973)
			(xy 96.333374 -42.150264) (xy 96.316325 -42.095377) (xy 96.307702 -42.038553) (xy 96.307699 -41.981079)
			(xy 96.316318 -41.924255) (xy 96.333363 -41.869366) (xy 96.358448 -41.817655) (xy 96.391005 -41.770292)
			(xy 96.410272 -41.748964) (xy 96.416876 -41.742106) (xy 96.423988 -41.724072) (xy 96.423988 -41.635172)
			(xy 96.416876 -41.617138) (xy 96.410272 -41.61028) (xy 96.391017 -41.588939) (xy 96.358448 -41.541581)
			(xy 96.333351 -41.489873) (xy 96.316297 -41.434985) (xy 96.307671 -41.37816) (xy 96.307148 -41.349422)
			(xy 96.307634 -41.322171) (xy 96.31539 -41.268223) (xy 96.330745 -41.215928) (xy 96.353387 -41.166351)
			(xy 96.382853 -41.120501) (xy 96.418544 -41.07931) (xy 96.459735 -41.043619) (xy 96.505585 -41.014153)
			(xy 96.555162 -40.991511) (xy 96.607457 -40.976156) (xy 96.661405 -40.9684) (xy 96.715907 -40.9684)
			(xy 96.769855 -40.976156) (xy 96.82215 -40.991511) (xy 96.871727 -41.014153) (xy 96.917577 -41.043619)
			(xy 96.958768 -41.07931) (xy 96.994459 -41.120501) (xy 97.023925 -41.166351) (xy 97.046567 -41.215928)
			(xy 97.061922 -41.268223) (xy 97.069678 -41.322171) (xy 97.070164 -41.349422) (xy 97.069637 -41.378161)
			(xy 97.061012 -41.434987) (xy 97.043962 -41.489877) (xy 97.018872 -41.541589) (xy 96.986309 -41.588952)
			(xy 96.96704 -41.61028) (xy 96.960436 -41.617138) (xy 96.953324 -41.635172) (xy 96.953324 -41.724072)
			(xy 96.960436 -41.742106) (xy 96.96704 -41.748964) (xy 96.986334 -41.770271) (xy 97.018902 -41.817636)
			(xy 97.043995 -41.869351) (xy 97.061045 -41.924245) (xy 97.069666 -41.981076) (xy 97.069664 -42.038557)
			(xy 97.061037 -42.095387) (xy 97.043983 -42.150279) (xy 97.018886 -42.201992) (xy 96.986314 -42.249354)
			(xy 96.96704 -42.27068) (xy 96.960436 -42.277538) (xy 96.953324 -42.295572) (xy 96.953324 -42.384472)
			(xy 96.960436 -42.402506) (xy 96.96704 -42.409364) (xy 96.986318 -42.430685) (xy 97.018884 -42.478048)
			(xy 97.043975 -42.529761) (xy 97.061024 -42.584654) (xy 97.069645 -42.641483) (xy 97.070164 -42.670222)
			(xy 97.06972 -42.697593) (xy 97.061898 -42.751773) (xy 97.046404 -42.804277) (xy 97.025847 -42.849038)
			(xy 98.89185 -42.849038) (xy 98.895921 -42.793416) (xy 98.908047 -42.738979) (xy 98.92797 -42.686888)
			(xy 98.955266 -42.638253) (xy 98.989352 -42.59411) (xy 99.029501 -42.555401) (xy 99.074859 -42.52295)
			(xy 99.124459 -42.497449) (xy 99.177243 -42.479442) (xy 99.232086 -42.469312) (xy 99.28782 -42.467275)
			(xy 99.343257 -42.473375) (xy 99.397214 -42.487481) (xy 99.448543 -42.509293) (xy 99.496149 -42.538347)
			(xy 99.539017 -42.574022) (xy 99.576234 -42.615559) (xy 99.607007 -42.662072) (xy 99.630679 -42.712569)
			(xy 99.646747 -42.765976) (xy 99.654867 -42.821152) (xy 99.655228 -42.84091) (xy 104.932986 -42.84091)
			(xy 104.937057 -42.785288) (xy 104.949183 -42.730851) (xy 104.969106 -42.67876) (xy 104.996402 -42.630125)
			(xy 105.030488 -42.585982) (xy 105.070637 -42.547273) (xy 105.115995 -42.514822) (xy 105.165595 -42.489321)
			(xy 105.218379 -42.471314) (xy 105.273222 -42.461184) (xy 105.328956 -42.459147) (xy 105.384393 -42.465247)
			(xy 105.43835 -42.479353) (xy 105.489679 -42.501165) (xy 105.537285 -42.530219) (xy 105.580153 -42.565894)
			(xy 105.61737 -42.607431) (xy 105.648143 -42.653944) (xy 105.671815 -42.704441) (xy 105.687883 -42.757848)
			(xy 105.696003 -42.813024) (xy 105.696512 -42.84091) (xy 105.696003 -42.868796) (xy 105.687883 -42.923972)
			(xy 105.671815 -42.977379) (xy 105.648143 -43.027876) (xy 105.61737 -43.074389) (xy 105.580153 -43.115926)
			(xy 105.537285 -43.151601) (xy 105.489679 -43.180655) (xy 105.43835 -43.202467) (xy 105.384393 -43.216573)
			(xy 105.328956 -43.222673) (xy 105.273222 -43.220636) (xy 105.218379 -43.210506) (xy 105.165595 -43.192499)
			(xy 105.115995 -43.166998) (xy 105.070637 -43.134547) (xy 105.030488 -43.095838) (xy 104.996402 -43.051695)
			(xy 104.969106 -43.00306) (xy 104.949183 -42.950969) (xy 104.937057 -42.896532) (xy 104.932986 -42.84091)
			(xy 99.655228 -42.84091) (xy 99.655376 -42.849038) (xy 99.654867 -42.876924) (xy 99.646747 -42.9321)
			(xy 99.630679 -42.985507) (xy 99.607007 -43.036004) (xy 99.576234 -43.082517) (xy 99.539017 -43.124054)
			(xy 99.496149 -43.159729) (xy 99.448543 -43.188783) (xy 99.397214 -43.210595) (xy 99.343257 -43.224701)
			(xy 99.28782 -43.230801) (xy 99.232086 -43.228764) (xy 99.177243 -43.218634) (xy 99.124459 -43.200627)
			(xy 99.074859 -43.175126) (xy 99.029501 -43.142675) (xy 98.989352 -43.103966) (xy 98.955266 -43.059823)
			(xy 98.92797 -43.011188) (xy 98.908047 -42.959097) (xy 98.895921 -42.90466) (xy 98.89185 -42.849038)
			(xy 97.025847 -42.849038) (xy 97.023557 -42.854024) (xy 96.993828 -42.899989) (xy 96.976184 -42.92092)
			(xy 96.97593 -42.921174) (xy 96.97034 -42.928258) (xy 96.964097 -42.945177) (xy 96.963738 -42.954194)
			(xy 96.963738 -43.02125) (xy 96.964111 -43.030265) (xy 96.970346 -43.047183) (xy 96.97593 -43.05427)
			(xy 96.976184 -43.05427) (xy 96.976184 -43.054524) (xy 96.993798 -43.075476) (xy 97.023515 -43.121443)
			(xy 97.046355 -43.171185) (xy 97.061852 -43.223682) (xy 97.069687 -43.277854) (xy 97.070164 -43.305222)
			(xy 97.069678 -43.332473) (xy 97.061922 -43.386421) (xy 97.046567 -43.438716) (xy 97.023925 -43.488293)
			(xy 96.994459 -43.534143) (xy 96.958768 -43.575334) (xy 96.917577 -43.611025) (xy 96.871727 -43.640491)
			(xy 96.82215 -43.663133) (xy 96.769855 -43.678488) (xy 96.715907 -43.686244) (xy 96.661405 -43.686244)
			(xy 96.607457 -43.678488) (xy 96.555162 -43.663133) (xy 96.505585 -43.640491) (xy 96.459735 -43.611025)
			(xy 96.418544 -43.575334) (xy 96.382853 -43.534143) (xy 96.353387 -43.488293) (xy 96.330745 -43.438716)
			(xy 96.31539 -43.386421) (xy 96.307634 -43.332473) (xy 96.307148 -43.305222) (xy 90.115581 -43.305222)
			(xy 90.546638 -43.73626) (xy 98.212908 -43.73626) (xy 98.216979 -43.680638) (xy 98.229105 -43.626201)
			(xy 98.249028 -43.57411) (xy 98.276324 -43.525475) (xy 98.31041 -43.481332) (xy 98.350559 -43.442623)
			(xy 98.395917 -43.410172) (xy 98.445517 -43.384671) (xy 98.498301 -43.366664) (xy 98.553144 -43.356534)
			(xy 98.608878 -43.354497) (xy 98.664315 -43.360597) (xy 98.718272 -43.374703) (xy 98.769601 -43.396515)
			(xy 98.817207 -43.425569) (xy 98.860075 -43.461244) (xy 98.897292 -43.502781) (xy 98.928065 -43.549294)
			(xy 98.951737 -43.599791) (xy 98.967805 -43.653198) (xy 98.975925 -43.708374) (xy 98.976434 -43.73626)
			(xy 98.975925 -43.764146) (xy 98.967805 -43.819322) (xy 98.956496 -43.85691) (xy 102.71963 -43.85691)
			(xy 102.723701 -43.801288) (xy 102.735827 -43.746851) (xy 102.75575 -43.69476) (xy 102.783046 -43.646125)
			(xy 102.817132 -43.601982) (xy 102.857281 -43.563273) (xy 102.902639 -43.530822) (xy 102.952239 -43.505321)
			(xy 103.005023 -43.487314) (xy 103.059866 -43.477184) (xy 103.1156 -43.475147) (xy 103.171037 -43.481247)
			(xy 103.224994 -43.495353) (xy 103.276323 -43.517165) (xy 103.323929 -43.546219) (xy 103.366797 -43.581894)
			(xy 103.404014 -43.623431) (xy 103.434787 -43.669944) (xy 103.458459 -43.720441) (xy 103.474527 -43.773848)
			(xy 103.482647 -43.829024) (xy 103.483156 -43.85691) (xy 103.482647 -43.884796) (xy 103.474527 -43.939972)
			(xy 103.458459 -43.993379) (xy 103.434787 -44.043876) (xy 103.404014 -44.090389) (xy 103.366797 -44.131926)
			(xy 103.323929 -44.167601) (xy 103.276323 -44.196655) (xy 103.224994 -44.218467) (xy 103.171037 -44.232573)
			(xy 103.1156 -44.238673) (xy 103.059866 -44.236636) (xy 103.005023 -44.226506) (xy 102.952239 -44.208499)
			(xy 102.902639 -44.182998) (xy 102.857281 -44.150547) (xy 102.817132 -44.111838) (xy 102.783046 -44.067695)
			(xy 102.75575 -44.01906) (xy 102.735827 -43.966969) (xy 102.723701 -43.912532) (xy 102.71963 -43.85691)
			(xy 98.956496 -43.85691) (xy 98.951737 -43.872729) (xy 98.928065 -43.923226) (xy 98.897292 -43.969739)
			(xy 98.860075 -44.011276) (xy 98.817207 -44.046951) (xy 98.769601 -44.076005) (xy 98.718272 -44.097817)
			(xy 98.664315 -44.111923) (xy 98.608878 -44.118023) (xy 98.553144 -44.115986) (xy 98.498301 -44.105856)
			(xy 98.445517 -44.087849) (xy 98.395917 -44.062348) (xy 98.350559 -44.029897) (xy 98.31041 -43.991188)
			(xy 98.276324 -43.947045) (xy 98.249028 -43.89841) (xy 98.229105 -43.846319) (xy 98.216979 -43.791882)
			(xy 98.212908 -43.73626) (xy 90.546638 -43.73626) (xy 91.573096 -44.762674) (xy 91.591128 -44.781445)
			(xy 91.621707 -44.823562) (xy 91.645334 -44.869938) (xy 91.661427 -44.919435) (xy 91.669593 -44.970839)
			(xy 91.670124 -44.996862) (xy 91.670124 -45.114464) (xy 98.065334 -45.114464) (xy 98.069405 -45.058842)
			(xy 98.081531 -45.004405) (xy 98.101454 -44.952314) (xy 98.12875 -44.903679) (xy 98.162836 -44.859536)
			(xy 98.202985 -44.820827) (xy 98.248343 -44.788376) (xy 98.297943 -44.762875) (xy 98.350727 -44.744868)
			(xy 98.40557 -44.734738) (xy 98.461304 -44.732701) (xy 98.516741 -44.738801) (xy 98.570698 -44.752907)
			(xy 98.622027 -44.774719) (xy 98.669633 -44.803773) (xy 98.712501 -44.839448) (xy 98.742483 -44.87291)
			(xy 104.932986 -44.87291) (xy 104.937057 -44.817288) (xy 104.949183 -44.762851) (xy 104.969106 -44.71076)
			(xy 104.996402 -44.662125) (xy 105.030488 -44.617982) (xy 105.070637 -44.579273) (xy 105.115995 -44.546822)
			(xy 105.165595 -44.521321) (xy 105.218379 -44.503314) (xy 105.273222 -44.493184) (xy 105.328956 -44.491147)
			(xy 105.384393 -44.497247) (xy 105.43835 -44.511353) (xy 105.489679 -44.533165) (xy 105.537285 -44.562219)
			(xy 105.580153 -44.597894) (xy 105.61737 -44.639431) (xy 105.648143 -44.685944) (xy 105.671815 -44.736441)
			(xy 105.687883 -44.789848) (xy 105.696003 -44.845024) (xy 105.696512 -44.87291) (xy 105.696003 -44.900796)
			(xy 105.687883 -44.955972) (xy 105.671815 -45.009379) (xy 105.648143 -45.059876) (xy 105.61737 -45.106389)
			(xy 105.580153 -45.147926) (xy 105.537285 -45.183601) (xy 105.489679 -45.212655) (xy 105.43835 -45.234467)
			(xy 105.384393 -45.248573) (xy 105.328956 -45.254673) (xy 105.273222 -45.252636) (xy 105.218379 -45.242506)
			(xy 105.165595 -45.224499) (xy 105.115995 -45.198998) (xy 105.070637 -45.166547) (xy 105.030488 -45.127838)
			(xy 104.996402 -45.083695) (xy 104.969106 -45.03506) (xy 104.949183 -44.982969) (xy 104.937057 -44.928532)
			(xy 104.932986 -44.87291) (xy 98.742483 -44.87291) (xy 98.749718 -44.880985) (xy 98.780491 -44.927498)
			(xy 98.804163 -44.977995) (xy 98.820231 -45.031402) (xy 98.828351 -45.086578) (xy 98.82886 -45.114464)
			(xy 98.828351 -45.14235) (xy 98.820231 -45.197526) (xy 98.804163 -45.250933) (xy 98.780491 -45.30143)
			(xy 98.749718 -45.347943) (xy 98.744076 -45.35424) (xy 102.703628 -45.35424) (xy 102.707699 -45.298618)
			(xy 102.719825 -45.244181) (xy 102.739748 -45.19209) (xy 102.767044 -45.143455) (xy 102.80113 -45.099312)
			(xy 102.841279 -45.060603) (xy 102.886637 -45.028152) (xy 102.936237 -45.002651) (xy 102.989021 -44.984644)
			(xy 103.043864 -44.974514) (xy 103.099598 -44.972477) (xy 103.155035 -44.978577) (xy 103.208992 -44.992683)
			(xy 103.260321 -45.014495) (xy 103.307927 -45.043549) (xy 103.350795 -45.079224) (xy 103.388012 -45.120761)
			(xy 103.418785 -45.167274) (xy 103.442457 -45.217771) (xy 103.458525 -45.271178) (xy 103.466645 -45.326354)
			(xy 103.467154 -45.35424) (xy 103.466645 -45.382126) (xy 103.458525 -45.437302) (xy 103.442457 -45.490709)
			(xy 103.418785 -45.541206) (xy 103.388012 -45.587719) (xy 103.350795 -45.629256) (xy 103.307927 -45.664931)
			(xy 103.260321 -45.693985) (xy 103.208992 -45.715797) (xy 103.155035 -45.729903) (xy 103.099598 -45.736003)
			(xy 103.043864 -45.733966) (xy 102.989021 -45.723836) (xy 102.936237 -45.705829) (xy 102.886637 -45.680328)
			(xy 102.841279 -45.647877) (xy 102.80113 -45.609168) (xy 102.767044 -45.565025) (xy 102.739748 -45.51639)
			(xy 102.719825 -45.464299) (xy 102.707699 -45.409862) (xy 102.703628 -45.35424) (xy 98.744076 -45.35424)
			(xy 98.712501 -45.38948) (xy 98.669633 -45.425155) (xy 98.622027 -45.454209) (xy 98.570698 -45.476021)
			(xy 98.516741 -45.490127) (xy 98.461304 -45.496227) (xy 98.40557 -45.49419) (xy 98.350727 -45.48406)
			(xy 98.297943 -45.466053) (xy 98.248343 -45.440552) (xy 98.202985 -45.408101) (xy 98.162836 -45.369392)
			(xy 98.12875 -45.325249) (xy 98.101454 -45.276614) (xy 98.081531 -45.224523) (xy 98.069405 -45.170086)
			(xy 98.065334 -45.114464) (xy 91.670124 -45.114464) (xy 91.670124 -46.082204) (xy 96.052386 -46.082204)
			(xy 96.052881 -46.054953) (xy 96.060637 -46.001006) (xy 96.075992 -45.948712) (xy 96.098632 -45.899135)
			(xy 96.128097 -45.853285) (xy 96.163788 -45.812095) (xy 96.204977 -45.776403) (xy 96.250826 -45.746937)
			(xy 96.300402 -45.724295) (xy 96.352696 -45.708939) (xy 96.406643 -45.701182) (xy 96.433894 -45.700696)
			(xy 96.460796 -45.701163) (xy 96.514066 -45.708734) (xy 96.565744 -45.723712) (xy 96.614806 -45.745802)
			(xy 96.660279 -45.774563) (xy 96.70126 -45.809427) (xy 96.736938 -45.849702) (xy 96.752156 -45.871892)
			(xy 96.759268 -45.882814) (xy 96.782128 -45.894752) (xy 96.894396 -45.89272) (xy 96.916748 -45.879766)
			(xy 96.923606 -45.86859) (xy 96.938537 -45.844995) (xy 96.974214 -45.802043) (xy 97.015771 -45.76475)
			(xy 97.06232 -45.733912) (xy 97.112865 -45.710187) (xy 97.166329 -45.694083) (xy 97.22157 -45.685943)
			(xy 97.249488 -45.685456) (xy 97.276481 -45.685924) (xy 97.329929 -45.693528) (xy 97.381772 -45.708587)
			(xy 97.430977 -45.730799) (xy 97.476561 -45.759723) (xy 97.497392 -45.776896) (xy 97.50552 -45.784008)
			(xy 97.526094 -45.790104) (xy 97.611438 -45.779182) (xy 97.621978 -45.777387) (xy 97.640263 -45.766348)
			(xy 97.646744 -45.757846) (xy 97.662076 -45.7366) (xy 97.697667 -45.698147) (xy 97.738188 -45.66493)
			(xy 97.782874 -45.637573) (xy 97.830886 -45.616592) (xy 97.881318 -45.602382) (xy 97.93322 -45.595211)
			(xy 97.959418 -45.594778) (xy 97.986667 -45.595293) (xy 98.040611 -45.603052) (xy 98.092902 -45.618408)
			(xy 98.142475 -45.641049) (xy 98.188321 -45.670515) (xy 98.229508 -45.706205) (xy 98.265196 -45.747393)
			(xy 98.294659 -45.793241) (xy 98.317298 -45.842815) (xy 98.332652 -45.895106) (xy 98.340408 -45.949051)
			(xy 98.340408 -46.003549) (xy 98.332652 -46.057493) (xy 98.317298 -46.109785) (xy 98.294659 -46.159359)
			(xy 98.265196 -46.205207) (xy 98.229508 -46.246395) (xy 98.188321 -46.282085) (xy 98.142475 -46.311551)
			(xy 98.092902 -46.334192) (xy 98.040611 -46.349548) (xy 97.986667 -46.357307) (xy 97.959418 -46.357794)
			(xy 97.932426 -46.357311) (xy 97.878979 -46.349708) (xy 97.827136 -46.334653) (xy 97.777931 -46.312444)
			(xy 97.732346 -46.283525) (xy 97.711514 -46.266354) (xy 97.703386 -46.259242) (xy 97.682812 -46.253146)
			(xy 97.597468 -46.264068) (xy 97.586922 -46.265834) (xy 97.568641 -46.276896) (xy 97.562162 -46.285404)
			(xy 97.544551 -46.309706) (xy 97.502954 -46.352964) (xy 97.479358 -46.37151) (xy 97.471484 -46.377352)
			(xy 97.46107 -46.394878) (xy 97.447862 -46.485302) (xy 97.452688 -46.504606) (xy 97.45853 -46.51248)
			(xy 97.45853 -46.512734) (xy 97.476028 -46.537482) (xy 97.503833 -46.591333) (xy 97.522771 -46.648904)
			(xy 97.529974 -46.693836) (xy 102.676198 -46.693836) (xy 102.676684 -46.666585) (xy 102.68444 -46.612637)
			(xy 102.699795 -46.560342) (xy 102.722437 -46.510765) (xy 102.751903 -46.464915) (xy 102.787594 -46.423724)
			(xy 102.828785 -46.388033) (xy 102.874635 -46.358567) (xy 102.924212 -46.335925) (xy 102.976507 -46.32057)
			(xy 103.030455 -46.312814) (xy 103.084957 -46.312814) (xy 103.138905 -46.32057) (xy 103.1912 -46.335925)
			(xy 103.240777 -46.358567) (xy 103.286627 -46.388033) (xy 103.327818 -46.423724) (xy 103.363509 -46.464915)
			(xy 103.392975 -46.510765) (xy 103.415617 -46.560342) (xy 103.430972 -46.612637) (xy 103.438728 -46.666585)
			(xy 103.439214 -46.693836) (xy 103.438739 -46.720263) (xy 103.43143 -46.772611) (xy 103.416957 -46.823446)
			(xy 103.395598 -46.871793) (xy 103.382064 -46.894496) (xy 103.38181 -46.89475) (xy 103.376473 -46.904768)
			(xy 103.374218 -46.927318) (xy 103.377492 -46.938184) (xy 103.403654 -47.01286) (xy 103.408037 -47.023376)
			(xy 103.424126 -47.039464) (xy 103.434642 -47.043848) (xy 103.434896 -47.043848) (xy 103.459415 -47.052889)
			(xy 103.505867 -47.076838) (xy 103.548617 -47.106899) (xy 103.586867 -47.14251) (xy 103.619902 -47.183006)
			(xy 103.647104 -47.22763) (xy 103.667965 -47.275548) (xy 103.682094 -47.325863) (xy 103.689227 -47.377635)
			(xy 103.689658 -47.403766) (xy 103.689172 -47.431017) (xy 103.687649 -47.441612) (xy 104.961688 -47.441612)
			(xy 104.965759 -47.38599) (xy 104.977885 -47.331553) (xy 104.997808 -47.279462) (xy 105.025104 -47.230827)
			(xy 105.05919 -47.186684) (xy 105.099339 -47.147975) (xy 105.144697 -47.115524) (xy 105.194297 -47.090023)
			(xy 105.247081 -47.072016) (xy 105.301924 -47.061886) (xy 105.357658 -47.059849) (xy 105.413095 -47.065949)
			(xy 105.467052 -47.080055) (xy 105.518381 -47.101867) (xy 105.565987 -47.130921) (xy 105.608855 -47.166596)
			(xy 105.646072 -47.208133) (xy 105.676845 -47.254646) (xy 105.700517 -47.305143) (xy 105.716585 -47.35855)
			(xy 105.724705 -47.413726) (xy 105.725214 -47.441612) (xy 105.724705 -47.469498) (xy 105.716585 -47.524674)
			(xy 105.700517 -47.578081) (xy 105.676845 -47.628578) (xy 105.646072 -47.675091) (xy 105.608855 -47.716628)
			(xy 105.565987 -47.752303) (xy 105.518381 -47.781357) (xy 105.467052 -47.803169) (xy 105.413095 -47.817275)
			(xy 105.357658 -47.823375) (xy 105.301924 -47.821338) (xy 105.247081 -47.811208) (xy 105.194297 -47.793201)
			(xy 105.144697 -47.7677) (xy 105.099339 -47.735249) (xy 105.05919 -47.69654) (xy 105.025104 -47.652397)
			(xy 104.997808 -47.603762) (xy 104.977885 -47.551671) (xy 104.965759 -47.497234) (xy 104.961688 -47.441612)
			(xy 103.687649 -47.441612) (xy 103.681416 -47.484965) (xy 103.666061 -47.53726) (xy 103.643419 -47.586837)
			(xy 103.613953 -47.632687) (xy 103.578262 -47.673878) (xy 103.537071 -47.709569) (xy 103.491221 -47.739035)
			(xy 103.441644 -47.761677) (xy 103.389349 -47.777032) (xy 103.335401 -47.784788) (xy 103.280899 -47.784788)
			(xy 103.226951 -47.777032) (xy 103.174656 -47.761677) (xy 103.125079 -47.739035) (xy 103.079229 -47.709569)
			(xy 103.038038 -47.673878) (xy 103.002347 -47.632687) (xy 102.972881 -47.586837) (xy 102.950239 -47.53726)
			(xy 102.934884 -47.484965) (xy 102.927128 -47.431017) (xy 102.926642 -47.403766) (xy 102.92711 -47.377338)
			(xy 102.93442 -47.32499) (xy 102.948895 -47.274155) (xy 102.970256 -47.225809) (xy 102.983792 -47.203106)
			(xy 102.984046 -47.202852) (xy 102.989381 -47.192833) (xy 102.99164 -47.170284) (xy 102.988364 -47.159418)
			(xy 102.962202 -47.084742) (xy 102.957838 -47.074216) (xy 102.941736 -47.058132) (xy 102.931214 -47.053754)
			(xy 102.93096 -47.053754) (xy 102.906453 -47.044679) (xy 102.860001 -47.020738) (xy 102.817249 -46.990683)
			(xy 102.778996 -46.955076) (xy 102.74596 -46.914584) (xy 102.718756 -46.869963) (xy 102.697894 -46.822049)
			(xy 102.683763 -46.771736) (xy 102.676629 -46.719966) (xy 102.676198 -46.693836) (xy 97.529974 -46.693836)
			(xy 97.532364 -46.708745) (xy 97.532952 -46.739048) (xy 97.532467 -46.766298) (xy 97.524705 -46.820244)
			(xy 97.509346 -46.872536) (xy 97.486703 -46.92211) (xy 97.457235 -46.967958) (xy 97.421544 -47.009147)
			(xy 97.380355 -47.044838) (xy 97.334507 -47.074304) (xy 97.284932 -47.096947) (xy 97.23264 -47.112306)
			(xy 97.178694 -47.120067) (xy 97.151444 -47.120556) (xy 97.12541 -47.120133) (xy 97.073826 -47.113039)
			(xy 97.023684 -47.099004) (xy 96.975913 -47.078288) (xy 96.9314 -47.051275) (xy 96.910906 -47.035212)
			(xy 96.903154 -47.029462) (xy 96.884739 -47.023726) (xy 96.875092 -47.024036) (xy 96.795336 -47.030386)
			(xy 96.777556 -47.039022) (xy 96.771206 -47.046388) (xy 96.753045 -47.066053) (xy 96.712133 -47.100573)
			(xy 96.6668 -47.12904) (xy 96.617935 -47.150894) (xy 96.566495 -47.165708) (xy 96.513491 -47.173189)
			(xy 96.486726 -47.173642) (xy 96.459477 -47.173098) (xy 96.405533 -47.165346) (xy 96.353242 -47.149995)
			(xy 96.303667 -47.12736) (xy 96.257818 -47.0979) (xy 96.216628 -47.062214) (xy 96.180936 -47.02103)
			(xy 96.151469 -46.975186) (xy 96.128826 -46.925615) (xy 96.113467 -46.873326) (xy 96.105707 -46.819383)
			(xy 96.105218 -46.792134) (xy 96.105738 -46.76336) (xy 96.114389 -46.706465) (xy 96.131486 -46.651514)
			(xy 96.156641 -46.599754) (xy 96.189283 -46.552359) (xy 96.208596 -46.531022) (xy 96.215962 -46.523148)
			(xy 96.223074 -46.503336) (xy 96.215708 -46.40707) (xy 96.205802 -46.388274) (xy 96.19742 -46.38167)
			(xy 96.175235 -46.363445) (xy 96.136025 -46.32151) (xy 96.10354 -46.274174) (xy 96.078511 -46.222506)
			(xy 96.061505 -46.167672) (xy 96.052904 -46.110909) (xy 96.052386 -46.082204) (xy 91.670124 -46.082204)
			(xy 91.670124 -48.30699) (xy 102.553768 -48.30699) (xy 102.557839 -48.251368) (xy 102.569965 -48.196931)
			(xy 102.589888 -48.14484) (xy 102.617184 -48.096205) (xy 102.65127 -48.052062) (xy 102.691419 -48.013353)
			(xy 102.736777 -47.980902) (xy 102.786377 -47.955401) (xy 102.839161 -47.937394) (xy 102.894004 -47.927264)
			(xy 102.949738 -47.925227) (xy 103.005175 -47.931327) (xy 103.059132 -47.945433) (xy 103.110461 -47.967245)
			(xy 103.158067 -47.996299) (xy 103.200935 -48.031974) (xy 103.238152 -48.073511) (xy 103.268925 -48.120024)
			(xy 103.292597 -48.170521) (xy 103.308665 -48.223928) (xy 103.316785 -48.279104) (xy 103.317294 -48.30699)
			(xy 103.316785 -48.334876) (xy 103.308665 -48.390052) (xy 103.292597 -48.443459) (xy 103.268925 -48.493956)
			(xy 103.238152 -48.540469) (xy 103.200935 -48.582006) (xy 103.158067 -48.617681) (xy 103.110461 -48.646735)
			(xy 103.059132 -48.668547) (xy 103.005175 -48.682653) (xy 102.949738 -48.688753) (xy 102.894004 -48.686716)
			(xy 102.839161 -48.676586) (xy 102.786377 -48.658579) (xy 102.736777 -48.633078) (xy 102.691419 -48.600627)
			(xy 102.65127 -48.561918) (xy 102.617184 -48.517775) (xy 102.589888 -48.46914) (xy 102.569965 -48.417049)
			(xy 102.557839 -48.362612) (xy 102.553768 -48.30699) (xy 91.670124 -48.30699) (xy 91.670124 -48.753014)
			(xy 99.168202 -48.753014) (xy 99.172273 -48.697392) (xy 99.184399 -48.642955) (xy 99.204322 -48.590864)
			(xy 99.231618 -48.542229) (xy 99.265704 -48.498086) (xy 99.305853 -48.459377) (xy 99.351211 -48.426926)
			(xy 99.400811 -48.401425) (xy 99.453595 -48.383418) (xy 99.508438 -48.373288) (xy 99.564172 -48.371251)
			(xy 99.619609 -48.377351) (xy 99.673566 -48.391457) (xy 99.724895 -48.413269) (xy 99.772501 -48.442323)
			(xy 99.815369 -48.477998) (xy 99.852586 -48.519535) (xy 99.883359 -48.566048) (xy 99.907031 -48.616545)
			(xy 99.923099 -48.669952) (xy 99.931219 -48.725128) (xy 99.931728 -48.753014) (xy 99.931219 -48.7809)
			(xy 99.923099 -48.836076) (xy 99.920655 -48.8442) (xy 100.18725 -48.8442) (xy 100.191321 -48.788578)
			(xy 100.203447 -48.734141) (xy 100.22337 -48.68205) (xy 100.250666 -48.633415) (xy 100.284752 -48.589272)
			(xy 100.324901 -48.550563) (xy 100.370259 -48.518112) (xy 100.419859 -48.492611) (xy 100.472643 -48.474604)
			(xy 100.527486 -48.464474) (xy 100.58322 -48.462437) (xy 100.638657 -48.468537) (xy 100.692614 -48.482643)
			(xy 100.743943 -48.504455) (xy 100.791549 -48.533509) (xy 100.834417 -48.569184) (xy 100.871634 -48.610721)
			(xy 100.902407 -48.657234) (xy 100.926079 -48.707731) (xy 100.942147 -48.761138) (xy 100.950267 -48.816314)
			(xy 100.950776 -48.8442) (xy 100.950267 -48.872086) (xy 100.947269 -48.89246) (xy 101.213918 -48.89246)
			(xy 101.217989 -48.836838) (xy 101.230115 -48.782401) (xy 101.250038 -48.73031) (xy 101.277334 -48.681675)
			(xy 101.31142 -48.637532) (xy 101.351569 -48.598823) (xy 101.396927 -48.566372) (xy 101.446527 -48.540871)
			(xy 101.499311 -48.522864) (xy 101.554154 -48.512734) (xy 101.609888 -48.510697) (xy 101.665325 -48.516797)
			(xy 101.719282 -48.530903) (xy 101.770611 -48.552715) (xy 101.818217 -48.581769) (xy 101.861085 -48.617444)
			(xy 101.898302 -48.658981) (xy 101.929075 -48.705494) (xy 101.952747 -48.755991) (xy 101.968815 -48.809398)
			(xy 101.976935 -48.864574) (xy 101.977444 -48.89246) (xy 101.976935 -48.920346) (xy 101.974497 -48.93691)
			(xy 104.932986 -48.93691) (xy 104.937057 -48.881288) (xy 104.949183 -48.826851) (xy 104.969106 -48.77476)
			(xy 104.996402 -48.726125) (xy 105.030488 -48.681982) (xy 105.070637 -48.643273) (xy 105.115995 -48.610822)
			(xy 105.165595 -48.585321) (xy 105.218379 -48.567314) (xy 105.273222 -48.557184) (xy 105.328956 -48.555147)
			(xy 105.384393 -48.561247) (xy 105.43835 -48.575353) (xy 105.489679 -48.597165) (xy 105.537285 -48.626219)
			(xy 105.580153 -48.661894) (xy 105.61737 -48.703431) (xy 105.648143 -48.749944) (xy 105.671815 -48.800441)
			(xy 105.687883 -48.853848) (xy 105.696003 -48.909024) (xy 105.696512 -48.93691) (xy 105.696003 -48.964796)
			(xy 105.687883 -49.019972) (xy 105.671815 -49.073379) (xy 105.648143 -49.123876) (xy 105.61737 -49.170389)
			(xy 105.580153 -49.211926) (xy 105.537285 -49.247601) (xy 105.489679 -49.276655) (xy 105.43835 -49.298467)
			(xy 105.384393 -49.312573) (xy 105.328956 -49.318673) (xy 105.273222 -49.316636) (xy 105.218379 -49.306506)
			(xy 105.165595 -49.288499) (xy 105.115995 -49.262998) (xy 105.070637 -49.230547) (xy 105.030488 -49.191838)
			(xy 104.996402 -49.147695) (xy 104.969106 -49.09906) (xy 104.949183 -49.046969) (xy 104.937057 -48.992532)
			(xy 104.932986 -48.93691) (xy 101.974497 -48.93691) (xy 101.968815 -48.975522) (xy 101.952747 -49.028929)
			(xy 101.929075 -49.079426) (xy 101.898302 -49.125939) (xy 101.861085 -49.167476) (xy 101.818217 -49.203151)
			(xy 101.770611 -49.232205) (xy 101.719282 -49.254017) (xy 101.665325 -49.268123) (xy 101.609888 -49.274223)
			(xy 101.554154 -49.272186) (xy 101.499311 -49.262056) (xy 101.446527 -49.244049) (xy 101.396927 -49.218548)
			(xy 101.351569 -49.186097) (xy 101.31142 -49.147388) (xy 101.277334 -49.103245) (xy 101.250038 -49.05461)
			(xy 101.230115 -49.002519) (xy 101.217989 -48.948082) (xy 101.213918 -48.89246) (xy 100.947269 -48.89246)
			(xy 100.942147 -48.927262) (xy 100.926079 -48.980669) (xy 100.902407 -49.031166) (xy 100.871634 -49.077679)
			(xy 100.834417 -49.119216) (xy 100.791549 -49.154891) (xy 100.743943 -49.183945) (xy 100.692614 -49.205757)
			(xy 100.638657 -49.219863) (xy 100.58322 -49.225963) (xy 100.527486 -49.223926) (xy 100.472643 -49.213796)
			(xy 100.419859 -49.195789) (xy 100.370259 -49.170288) (xy 100.324901 -49.137837) (xy 100.284752 -49.099128)
			(xy 100.250666 -49.054985) (xy 100.22337 -49.00635) (xy 100.203447 -48.954259) (xy 100.191321 -48.899822)
			(xy 100.18725 -48.8442) (xy 99.920655 -48.8442) (xy 99.907031 -48.889483) (xy 99.883359 -48.93998)
			(xy 99.852586 -48.986493) (xy 99.815369 -49.02803) (xy 99.772501 -49.063705) (xy 99.724895 -49.092759)
			(xy 99.673566 -49.114571) (xy 99.619609 -49.128677) (xy 99.564172 -49.134777) (xy 99.508438 -49.13274)
			(xy 99.453595 -49.12261) (xy 99.400811 -49.104603) (xy 99.351211 -49.079102) (xy 99.305853 -49.046651)
			(xy 99.265704 -49.007942) (xy 99.231618 -48.963799) (xy 99.204322 -48.915164) (xy 99.184399 -48.863073)
			(xy 99.172273 -48.808636) (xy 99.168202 -48.753014) (xy 91.670124 -48.753014) (xy 91.670124 -49.95291)
			(xy 104.932986 -49.95291) (xy 104.937057 -49.897288) (xy 104.949183 -49.842851) (xy 104.969106 -49.79076)
			(xy 104.996402 -49.742125) (xy 105.030488 -49.697982) (xy 105.070637 -49.659273) (xy 105.115995 -49.626822)
			(xy 105.165595 -49.601321) (xy 105.218379 -49.583314) (xy 105.273222 -49.573184) (xy 105.328956 -49.571147)
			(xy 105.384393 -49.577247) (xy 105.43835 -49.591353) (xy 105.489679 -49.613165) (xy 105.537285 -49.642219)
			(xy 105.580153 -49.677894) (xy 105.61737 -49.719431) (xy 105.648143 -49.765944) (xy 105.671815 -49.816441)
			(xy 105.687883 -49.869848) (xy 105.696003 -49.925024) (xy 105.696512 -49.95291) (xy 105.696003 -49.980796)
			(xy 105.687883 -50.035972) (xy 105.671815 -50.089379) (xy 105.648143 -50.139876) (xy 105.61737 -50.186389)
			(xy 105.580153 -50.227926) (xy 105.537285 -50.263601) (xy 105.489679 -50.292655) (xy 105.43835 -50.314467)
			(xy 105.384393 -50.328573) (xy 105.328956 -50.334673) (xy 105.273222 -50.332636) (xy 105.218379 -50.322506)
			(xy 105.165595 -50.304499) (xy 105.115995 -50.278998) (xy 105.070637 -50.246547) (xy 105.030488 -50.207838)
			(xy 104.996402 -50.163695) (xy 104.969106 -50.11506) (xy 104.949183 -50.062969) (xy 104.937057 -50.008532)
			(xy 104.932986 -49.95291) (xy 91.670124 -49.95291) (xy 91.670124 -51.019456) (xy 102.749348 -51.019456)
			(xy 102.753419 -50.963834) (xy 102.765545 -50.909397) (xy 102.785468 -50.857306) (xy 102.812764 -50.808671)
			(xy 102.84685 -50.764528) (xy 102.886999 -50.725819) (xy 102.932357 -50.693368) (xy 102.981957 -50.667867)
			(xy 103.034741 -50.64986) (xy 103.089584 -50.63973) (xy 103.145318 -50.637693) (xy 103.200755 -50.643793)
			(xy 103.254712 -50.657899) (xy 103.306041 -50.679711) (xy 103.353647 -50.708765) (xy 103.396515 -50.74444)
			(xy 103.433732 -50.785977) (xy 103.464505 -50.83249) (xy 103.488177 -50.882987) (xy 103.504245 -50.936394)
			(xy 103.512365 -50.99157) (xy 103.512874 -51.019456) (xy 103.512365 -51.047342) (xy 103.504245 -51.102518)
			(xy 103.488177 -51.155925) (xy 103.464505 -51.206422) (xy 103.433732 -51.252935) (xy 103.396515 -51.294472)
			(xy 103.353647 -51.330147) (xy 103.306041 -51.359201) (xy 103.254712 -51.381013) (xy 103.200755 -51.395119)
			(xy 103.145318 -51.401219) (xy 103.089584 -51.399182) (xy 103.034741 -51.389052) (xy 102.981957 -51.371045)
			(xy 102.932357 -51.345544) (xy 102.886999 -51.313093) (xy 102.84685 -51.274384) (xy 102.812764 -51.230241)
			(xy 102.785468 -51.181606) (xy 102.765545 -51.129515) (xy 102.753419 -51.075078) (xy 102.749348 -51.019456)
			(xy 91.670124 -51.019456) (xy 91.670124 -52.035456) (xy 104.941114 -52.035456) (xy 104.945185 -51.979834)
			(xy 104.957311 -51.925397) (xy 104.977234 -51.873306) (xy 105.00453 -51.824671) (xy 105.038616 -51.780528)
			(xy 105.078765 -51.741819) (xy 105.124123 -51.709368) (xy 105.173723 -51.683867) (xy 105.226507 -51.66586)
			(xy 105.28135 -51.65573) (xy 105.337084 -51.653693) (xy 105.392521 -51.659793) (xy 105.446478 -51.673899)
			(xy 105.497807 -51.695711) (xy 105.545413 -51.724765) (xy 105.588281 -51.76044) (xy 105.625498 -51.801977)
			(xy 105.656271 -51.84849) (xy 105.679943 -51.898987) (xy 105.696011 -51.952394) (xy 105.704131 -52.00757)
			(xy 105.70464 -52.035456) (xy 105.704131 -52.063342) (xy 105.696011 -52.118518) (xy 105.679943 -52.171925)
			(xy 105.656271 -52.222422) (xy 105.625498 -52.268935) (xy 105.588281 -52.310472) (xy 105.545413 -52.346147)
			(xy 105.497807 -52.375201) (xy 105.446478 -52.397013) (xy 105.392521 -52.411119) (xy 105.337084 -52.417219)
			(xy 105.28135 -52.415182) (xy 105.226507 -52.405052) (xy 105.173723 -52.387045) (xy 105.124123 -52.361544)
			(xy 105.078765 -52.329093) (xy 105.038616 -52.290384) (xy 105.00453 -52.246241) (xy 104.977234 -52.197606)
			(xy 104.957311 -52.145515) (xy 104.945185 -52.091078) (xy 104.941114 -52.035456) (xy 91.670124 -52.035456)
			(xy 91.670124 -52.359306) (xy 91.670124 -52.359814) (xy 91.670858 -52.371193) (xy 91.680879 -52.39164)
			(xy 91.689428 -52.399184) (xy 91.756484 -52.449984) (xy 91.76576 -52.455714) (xy 91.787205 -52.459536)
			(xy 91.797886 -52.45735) (xy 91.823278 -52.450708) (xy 91.875275 -52.443567) (xy 91.901518 -52.443126)
			(xy 91.902026 -52.443126) (xy 91.929403 -52.443616) (xy 91.983598 -52.451412) (xy 92.036133 -52.466841)
			(xy 92.085937 -52.489589) (xy 92.131997 -52.519194) (xy 92.173375 -52.555052) (xy 92.209229 -52.596433)
			(xy 92.238829 -52.642496) (xy 92.261572 -52.692303) (xy 92.276996 -52.744839) (xy 92.284787 -52.799035)
			(xy 92.285312 -52.826412) (xy 92.285312 -52.826666) (xy 92.28488 -52.852608) (xy 92.277885 -52.904018)
			(xy 92.264032 -52.954019) (xy 92.243572 -53.001699) (xy 92.216879 -53.04619) (xy 92.200984 -53.066696)
			(xy 92.197936 -53.070506) (xy 92.197428 -53.071014) (xy 92.195396 -53.073808) (xy 92.192602 -53.081428)
			(xy 92.19119 -53.085606) (xy 92.189653 -53.094291) (xy 92.189554 -53.0987) (xy 92.189554 -53.117242)
			(xy 92.189488 -53.120847) (xy 92.188464 -53.127985) (xy 92.187522 -53.131466) (xy 92.18676 -53.135022)
			(xy 92.18676 -53.197506) (xy 92.192348 -53.213762) (xy 92.195904 -53.21808) (xy 92.202526 -53.226158)
			(xy 92.214979 -53.242932) (xy 92.220796 -53.251608) (xy 92.226892 -53.260752) (xy 92.22994 -53.266086)
			(xy 92.239327 -53.282258) (xy 92.255236 -53.3161) (xy 92.26169 -53.33365) (xy 92.261944 -53.334412)
			(xy 92.262198 -53.335428) (xy 92.262706 -53.336698) (xy 92.263214 -53.338222) (xy 92.271265 -53.363247)
			(xy 92.281202 -53.414867) (xy 92.283026 -53.441092) (xy 92.283534 -53.46065) (xy 92.283534 -53.461412)
			(xy 92.28328 -53.477414) (xy 92.283026 -53.481732) (xy 92.28088 -53.511139) (xy 92.268675 -53.568823)
			(xy 92.247754 -53.623947) (xy 92.218613 -53.675203) (xy 92.20073 -53.698648) (xy 92.200476 -53.698902)
			(xy 92.197936 -53.70195) (xy 92.194204 -53.70806) (xy 92.18995 -53.721725) (xy 92.189554 -53.728874)
			(xy 92.189554 -53.752242) (xy 92.189488 -53.755847) (xy 92.188464 -53.762985) (xy 92.187522 -53.766466)
			(xy 92.18676 -53.770022) (xy 92.18676 -53.832506) (xy 92.192348 -53.848762) (xy 92.195904 -53.85308)
			(xy 92.202526 -53.861158) (xy 92.214979 -53.877932) (xy 92.220796 -53.886608) (xy 92.226892 -53.895752)
			(xy 92.22994 -53.901086) (xy 92.239327 -53.917258) (xy 92.255236 -53.9511) (xy 92.26169 -53.96865)
			(xy 92.261944 -53.969412) (xy 92.262198 -53.970428) (xy 92.262706 -53.971698) (xy 92.263214 -53.973222)
			(xy 92.271265 -53.998247) (xy 92.281202 -54.049867) (xy 92.283026 -54.076092) (xy 92.283534 -54.09565)
			(xy 92.283534 -54.096412) (xy 92.28328 -54.112414) (xy 92.283026 -54.116732) (xy 92.28088 -54.146139)
			(xy 92.268675 -54.203823) (xy 92.247754 -54.258947) (xy 92.218613 -54.310203) (xy 92.20073 -54.333648)
			(xy 92.200476 -54.333902) (xy 92.197936 -54.33695) (xy 92.194204 -54.34306) (xy 92.18995 -54.356725)
			(xy 92.189554 -54.363874) (xy 92.189554 -54.387242) (xy 92.189409 -54.392681) (xy 92.187098 -54.403311)
			(xy 92.184982 -54.408324) (xy 92.178632 -54.42204) (xy 92.176566 -54.426744) (xy 92.17413 -54.436724)
			(xy 92.173806 -54.441852) (xy 92.174314 -54.450488) (xy 92.175598 -54.457773) (xy 92.181802 -54.471194)
			(xy 92.186506 -54.476904) (xy 92.18676 -54.477158) (xy 92.204868 -54.498228) (xy 92.235429 -54.544622)
			(xy 92.258945 -54.594955) (xy 92.274918 -54.648164) (xy 92.283012 -54.703127) (xy 92.283534 -54.730904)
			(xy 92.283534 -54.731412) (xy 92.283047 -54.758663) (xy 92.278383 -54.791102) (xy 94.176342 -54.791102)
			(xy 94.176799 -54.763731) (xy 94.184617 -54.709551) (xy 94.200108 -54.657048) (xy 94.222952 -54.607301)
			(xy 94.252679 -54.561335) (xy 94.270322 -54.540404) (xy 94.270576 -54.54015) (xy 94.276157 -54.53306)
			(xy 94.282405 -54.516146) (xy 94.282768 -54.50713) (xy 94.282768 -54.440074) (xy 94.28243 -54.431055)
			(xy 94.27617 -54.414138) (xy 94.270576 -54.407054) (xy 94.270322 -54.407054) (xy 94.270322 -54.4068)
			(xy 94.252683 -54.385866) (xy 94.222959 -54.339898) (xy 94.200114 -54.290152) (xy 94.184618 -54.23765)
			(xy 94.176789 -54.183472) (xy 94.176789 -54.128731) (xy 94.184617 -54.074553) (xy 94.200113 -54.022051)
			(xy 94.222958 -53.972305) (xy 94.252682 -53.926337) (xy 94.270322 -53.905404) (xy 94.270576 -53.90515)
			(xy 94.276157 -53.89806) (xy 94.282405 -53.881146) (xy 94.282768 -53.87213) (xy 94.282768 -53.805074)
			(xy 94.28243 -53.796055) (xy 94.27617 -53.779138) (xy 94.270576 -53.772054) (xy 94.270322 -53.772054)
			(xy 94.270322 -53.7718) (xy 94.252683 -53.750866) (xy 94.222959 -53.704898) (xy 94.200114 -53.655152)
			(xy 94.184618 -53.60265) (xy 94.176789 -53.548472) (xy 94.176789 -53.493731) (xy 94.184617 -53.439553)
			(xy 94.200113 -53.387051) (xy 94.222958 -53.337305) (xy 94.252682 -53.291337) (xy 94.270322 -53.270404)
			(xy 94.270576 -53.27015) (xy 94.276157 -53.26306) (xy 94.282405 -53.246146) (xy 94.282768 -53.23713)
			(xy 94.282768 -53.170074) (xy 94.28243 -53.161055) (xy 94.27617 -53.144138) (xy 94.270576 -53.137054)
			(xy 94.270322 -53.137054) (xy 94.270322 -53.1368) (xy 94.252673 -53.115876) (xy 94.222962 -53.069901)
			(xy 94.200127 -53.020152) (xy 94.184639 -52.967649) (xy 94.176814 -52.913472) (xy 94.176342 -52.886102)
			(xy 94.176828 -52.858851) (xy 94.184584 -52.804903) (xy 94.199939 -52.752608) (xy 94.222581 -52.703031)
			(xy 94.252047 -52.657181) (xy 94.287738 -52.61599) (xy 94.328929 -52.580299) (xy 94.374779 -52.550833)
			(xy 94.424356 -52.528191) (xy 94.476651 -52.512836) (xy 94.530599 -52.50508) (xy 94.585101 -52.50508)
			(xy 94.639049 -52.512836) (xy 94.691344 -52.528191) (xy 94.730453 -52.546052) (xy 99.679473 -52.546052)
			(xy 99.679473 -52.491548) (xy 99.68723 -52.437599) (xy 99.702586 -52.385303) (xy 99.725228 -52.335725)
			(xy 99.754695 -52.289874) (xy 99.790387 -52.248683) (xy 99.831579 -52.212991) (xy 99.87743 -52.183525)
			(xy 99.927009 -52.160884) (xy 99.979305 -52.145529) (xy 100.033254 -52.137773) (xy 100.060506 -52.13731)
			(xy 100.087876 -52.13777) (xy 100.142056 -52.145589) (xy 100.194559 -52.161079) (xy 100.244306 -52.183922)
			(xy 100.290273 -52.213648) (xy 100.311204 -52.23129) (xy 100.311458 -52.231544) (xy 100.318549 -52.237124)
			(xy 100.335462 -52.243374) (xy 100.344478 -52.243736) (xy 100.411534 -52.243736) (xy 100.420552 -52.243388)
			(xy 100.437468 -52.237133) (xy 100.444554 -52.231544) (xy 100.444554 -52.23129) (xy 100.444808 -52.23129)
			(xy 100.465741 -52.213649) (xy 100.511709 -52.183925) (xy 100.561455 -52.161079) (xy 100.613957 -52.145583)
			(xy 100.668135 -52.137754) (xy 100.722877 -52.137754) (xy 100.777055 -52.145583) (xy 100.829557 -52.161079)
			(xy 100.879303 -52.183925) (xy 100.925271 -52.213649) (xy 100.946204 -52.23129) (xy 100.946458 -52.231544)
			(xy 100.953549 -52.237124) (xy 100.970462 -52.243374) (xy 100.979478 -52.243736) (xy 101.046534 -52.243736)
			(xy 101.055552 -52.243388) (xy 101.072468 -52.237133) (xy 101.079554 -52.231544) (xy 101.079554 -52.23129)
			(xy 101.079808 -52.23129) (xy 101.100725 -52.213632) (xy 101.146702 -52.183923) (xy 101.196453 -52.161091)
			(xy 101.248957 -52.145605) (xy 101.303136 -52.137781) (xy 101.330506 -52.13731) (xy 101.357758 -52.13776)
			(xy 101.411708 -52.145518) (xy 101.464004 -52.160874) (xy 101.513583 -52.183517) (xy 101.559435 -52.212985)
			(xy 101.600626 -52.248678) (xy 101.636319 -52.28987) (xy 101.665786 -52.335722) (xy 101.688428 -52.385301)
			(xy 101.703783 -52.437598) (xy 101.71154 -52.491548) (xy 101.71154 -52.546052) (xy 101.705595 -52.587398)
			(xy 102.75519 -52.587398) (xy 102.759261 -52.531776) (xy 102.771387 -52.477339) (xy 102.79131 -52.425248)
			(xy 102.818606 -52.376613) (xy 102.852692 -52.33247) (xy 102.892841 -52.293761) (xy 102.938199 -52.26131)
			(xy 102.987799 -52.235809) (xy 103.040583 -52.217802) (xy 103.095426 -52.207672) (xy 103.15116 -52.205635)
			(xy 103.206597 -52.211735) (xy 103.260554 -52.225841) (xy 103.311883 -52.247653) (xy 103.359489 -52.276707)
			(xy 103.402357 -52.312382) (xy 103.439574 -52.353919) (xy 103.470347 -52.400432) (xy 103.494019 -52.450929)
			(xy 103.510087 -52.504336) (xy 103.518207 -52.559512) (xy 103.518716 -52.587398) (xy 103.518207 -52.615284)
			(xy 103.510087 -52.67046) (xy 103.494019 -52.723867) (xy 103.470347 -52.774364) (xy 103.439574 -52.820877)
			(xy 103.402357 -52.862414) (xy 103.359489 -52.898089) (xy 103.311883 -52.927143) (xy 103.260554 -52.948955)
			(xy 103.206597 -52.963061) (xy 103.15116 -52.969161) (xy 103.095426 -52.967124) (xy 103.040583 -52.956994)
			(xy 102.987799 -52.938987) (xy 102.938199 -52.913486) (xy 102.892841 -52.881035) (xy 102.852692 -52.842326)
			(xy 102.818606 -52.798183) (xy 102.79131 -52.749548) (xy 102.771387 -52.697457) (xy 102.759261 -52.64302)
			(xy 102.75519 -52.587398) (xy 101.705595 -52.587398) (xy 101.703783 -52.600002) (xy 101.688428 -52.652299)
			(xy 101.665786 -52.701878) (xy 101.636319 -52.74773) (xy 101.600626 -52.788922) (xy 101.559435 -52.824615)
			(xy 101.513583 -52.854083) (xy 101.464004 -52.876726) (xy 101.411708 -52.892082) (xy 101.357758 -52.89984)
			(xy 101.330506 -52.900326) (xy 101.303135 -52.899874) (xy 101.248955 -52.892056) (xy 101.196451 -52.876564)
			(xy 101.146704 -52.853719) (xy 101.100738 -52.82399) (xy 101.079808 -52.806346) (xy 101.079554 -52.806092)
			(xy 101.072457 -52.800521) (xy 101.055548 -52.794265) (xy 101.046534 -52.7939) (xy 100.979478 -52.7939)
			(xy 100.97046 -52.794247) (xy 100.953543 -52.800501) (xy 100.946458 -52.806092) (xy 100.946204 -52.806346)
			(xy 100.925271 -52.823987) (xy 100.879303 -52.853711) (xy 100.829557 -52.876557) (xy 100.777055 -52.892053)
			(xy 100.722877 -52.899882) (xy 100.668135 -52.899882) (xy 100.613957 -52.892053) (xy 100.561455 -52.876557)
			(xy 100.511709 -52.853711) (xy 100.465741 -52.823987) (xy 100.444808 -52.806346) (xy 100.444554 -52.806092)
			(xy 100.437457 -52.800521) (xy 100.420548 -52.794265) (xy 100.411534 -52.7939) (xy 100.344478 -52.7939)
			(xy 100.33546 -52.794247) (xy 100.318543 -52.800501) (xy 100.311458 -52.806092) (xy 100.311458 -52.806346)
			(xy 100.311204 -52.806346) (xy 100.290274 -52.823988) (xy 100.244302 -52.853701) (xy 100.194554 -52.876538)
			(xy 100.142052 -52.892028) (xy 100.087875 -52.899854) (xy 100.060506 -52.900326) (xy 100.033254 -52.899827)
			(xy 99.979305 -52.892071) (xy 99.927009 -52.876716) (xy 99.87743 -52.854075) (xy 99.831579 -52.824609)
			(xy 99.790387 -52.788917) (xy 99.754695 -52.747726) (xy 99.725228 -52.701875) (xy 99.702586 -52.652297)
			(xy 99.68723 -52.600001) (xy 99.679473 -52.546052) (xy 94.730453 -52.546052) (xy 94.740921 -52.550833)
			(xy 94.786771 -52.580299) (xy 94.827962 -52.61599) (xy 94.863653 -52.657181) (xy 94.893119 -52.703031)
			(xy 94.915761 -52.752608) (xy 94.931116 -52.804903) (xy 94.938872 -52.858851) (xy 94.939358 -52.886102)
			(xy 94.938903 -52.913473) (xy 94.931084 -52.967653) (xy 94.915593 -53.020156) (xy 94.892749 -53.069903)
			(xy 94.863021 -53.115869) (xy 94.845378 -53.1368) (xy 94.845124 -53.137054) (xy 94.839542 -53.144143)
			(xy 94.833294 -53.161058) (xy 94.832932 -53.170074) (xy 94.832932 -53.23713) (xy 94.833268 -53.246149)
			(xy 94.839529 -53.263066) (xy 94.845124 -53.27015) (xy 94.845378 -53.27015) (xy 94.845378 -53.270404)
			(xy 94.86302 -53.291335) (xy 94.892745 -53.337303) (xy 94.91559 -53.38705) (xy 94.931086 -53.439552)
			(xy 94.938914 -53.493731) (xy 94.938914 -53.548472) (xy 94.931085 -53.602651) (xy 94.915589 -53.655153)
			(xy 94.892743 -53.704899) (xy 94.863019 -53.750867) (xy 94.846448 -53.77053) (xy 95.21063 -53.77053)
			(xy 95.211158 -53.741613) (xy 95.219884 -53.684442) (xy 95.237139 -53.629243) (xy 95.262529 -53.577281)
			(xy 95.295471 -53.529747) (xy 95.335211 -53.48773) (xy 95.357696 -53.46954) (xy 95.366475 -53.461905)
			(xy 95.376674 -53.441026) (xy 95.377254 -53.429408) (xy 95.377254 -53.349652) (xy 95.376744 -53.338016)
			(xy 95.366536 -53.317106) (xy 95.357696 -53.30952) (xy 95.335221 -53.291319) (xy 95.295486 -53.249301)
			(xy 95.262546 -53.201768) (xy 95.237156 -53.149809) (xy 95.219898 -53.094613) (xy 95.211166 -53.037445)
			(xy 95.21063 -53.00853) (xy 95.211083 -52.981276) (xy 95.218837 -52.927323) (xy 95.234191 -52.875023)
			(xy 95.256833 -52.82544) (xy 95.286302 -52.779585) (xy 95.321997 -52.738391) (xy 95.363191 -52.702697)
			(xy 95.409047 -52.673229) (xy 95.45863 -52.650589) (xy 95.510931 -52.635236) (xy 95.564884 -52.627483)
			(xy 95.592138 -52.627022) (xy 95.618453 -52.627457) (xy 95.670583 -52.634698) (xy 95.721227 -52.649023)
			(xy 95.769426 -52.670161) (xy 95.814269 -52.697713) (xy 95.854907 -52.731158) (xy 95.873062 -52.750212)
			(xy 95.880594 -52.757601) (xy 95.899866 -52.766132) (xy 95.9104 -52.766722) (xy 95.985076 -52.766722)
			(xy 95.995625 -52.766187) (xy 96.01492 -52.757655) (xy 96.022414 -52.750212) (xy 96.040572 -52.731159)
			(xy 96.081201 -52.697701) (xy 96.126041 -52.670141) (xy 96.174241 -52.649002) (xy 96.224888 -52.634685)
			(xy 96.277022 -52.62746) (xy 96.303338 -52.627022) (xy 96.330592 -52.627443) (xy 96.384543 -52.635205)
			(xy 96.436841 -52.650566) (xy 96.48642 -52.673214) (xy 96.532272 -52.702687) (xy 96.573463 -52.738386)
			(xy 96.609154 -52.779583) (xy 96.638618 -52.825439) (xy 96.661257 -52.875023) (xy 96.676609 -52.927323)
			(xy 96.684362 -52.981276) (xy 96.684846 -53.00853) (xy 96.684382 -53.036197) (xy 96.676377 -53.09095)
			(xy 96.660554 -53.143973) (xy 96.637244 -53.194158) (xy 96.606934 -53.240454) (xy 96.570261 -53.28189)
			(xy 96.527991 -53.317599) (xy 96.50476 -53.332634) (xy 96.495071 -53.339256) (xy 96.482633 -53.359128)
			(xy 96.480884 -53.370734) (xy 96.47301 -53.450744) (xy 96.47237 -53.462382) (xy 96.480457 -53.484219)
			(xy 96.488504 -53.492654) (xy 96.488758 -53.492908) (xy 96.507317 -53.511011) (xy 96.5399 -53.551337)
			(xy 96.566716 -53.595706) (xy 96.587273 -53.643301) (xy 96.601191 -53.693242) (xy 96.608212 -53.744608)
			(xy 96.608646 -53.77053) (xy 96.60815 -53.79778) (xy 96.600391 -53.851726) (xy 96.585034 -53.904018)
			(xy 96.562392 -53.953593) (xy 96.532926 -53.999441) (xy 96.497236 -54.04063) (xy 96.456048 -54.076321)
			(xy 96.4102 -54.105788) (xy 96.360625 -54.128431) (xy 96.308333 -54.143789) (xy 96.254388 -54.15155)
			(xy 96.227138 -54.152038) (xy 96.199768 -54.151565) (xy 96.145588 -54.143751) (xy 96.093085 -54.128264)
			(xy 96.043338 -54.105424) (xy 95.997371 -54.075699) (xy 95.97644 -54.058058) (xy 95.976186 -54.057804)
			(xy 95.969107 -54.052206) (xy 95.952185 -54.045966) (xy 95.943166 -54.045612) (xy 95.87611 -54.045612)
			(xy 95.867093 -54.045971) (xy 95.850176 -54.052217) (xy 95.84309 -54.057804) (xy 95.84309 -54.058058)
			(xy 95.842836 -54.058058) (xy 95.821896 -54.075687) (xy 95.775926 -54.105402) (xy 95.726181 -54.12824)
			(xy 95.673681 -54.143734) (xy 95.619507 -54.151563) (xy 95.592138 -54.152038) (xy 95.564887 -54.151509)
			(xy 95.51094 -54.143758) (xy 95.458646 -54.128409) (xy 95.409068 -54.105773) (xy 95.363216 -54.076312)
			(xy 95.322023 -54.040625) (xy 95.286329 -53.999439) (xy 95.25686 -53.953592) (xy 95.234215 -53.904018)
			(xy 95.218856 -53.851726) (xy 95.211095 -53.79778) (xy 95.21063 -53.77053) (xy 94.846448 -53.77053)
			(xy 94.845378 -53.7718) (xy 94.845124 -53.772054) (xy 94.839542 -53.779143) (xy 94.833294 -53.796058)
			(xy 94.832932 -53.805074) (xy 94.832932 -53.87213) (xy 94.833268 -53.881149) (xy 94.839529 -53.898066)
			(xy 94.845124 -53.90515) (xy 94.845378 -53.90515) (xy 94.845378 -53.905404) (xy 94.86302 -53.926335)
			(xy 94.892745 -53.972303) (xy 94.91559 -54.02205) (xy 94.931086 -54.074552) (xy 94.938914 -54.128731)
			(xy 94.938914 -54.183472) (xy 94.931085 -54.237651) (xy 94.915589 -54.290153) (xy 94.901796 -54.320186)
			(xy 97.130362 -54.320186) (xy 97.130805 -54.292815) (xy 97.138626 -54.238634) (xy 97.15412 -54.18613)
			(xy 97.176967 -54.136384) (xy 97.206698 -54.090418) (xy 97.224342 -54.069488) (xy 97.224596 -54.069234)
			(xy 97.230174 -54.062142) (xy 97.236426 -54.045229) (xy 97.236788 -54.036214) (xy 97.236788 -53.969158)
			(xy 97.236406 -53.960144) (xy 97.230176 -53.943226) (xy 97.224596 -53.936138) (xy 97.224342 -53.936138)
			(xy 97.224342 -53.935884) (xy 97.206735 -53.914926) (xy 97.177017 -53.868961) (xy 97.154174 -53.81922)
			(xy 97.138676 -53.766725) (xy 97.13084 -53.712553) (xy 97.130362 -53.685186) (xy 97.130848 -53.657935)
			(xy 97.138604 -53.603987) (xy 97.153959 -53.551692) (xy 97.176601 -53.502115) (xy 97.206067 -53.456265)
			(xy 97.241758 -53.415074) (xy 97.282949 -53.379383) (xy 97.328799 -53.349917) (xy 97.378376 -53.327275)
			(xy 97.430671 -53.31192) (xy 97.484619 -53.304164) (xy 97.539121 -53.304164) (xy 97.593069 -53.31192)
			(xy 97.645364 -53.327275) (xy 97.694941 -53.349917) (xy 97.740791 -53.379383) (xy 97.781982 -53.415074)
			(xy 97.817673 -53.456265) (xy 97.847139 -53.502115) (xy 97.869781 -53.551692) (xy 97.885136 -53.603987)
			(xy 97.892892 -53.657935) (xy 97.893378 -53.685186) (xy 97.892909 -53.712556) (xy 97.885093 -53.766735)
			(xy 97.869605 -53.819239) (xy 97.846763 -53.868986) (xy 97.817039 -53.914952) (xy 97.799398 -53.935884)
			(xy 97.799144 -53.936138) (xy 97.793571 -53.943233) (xy 97.787317 -53.960144) (xy 97.786952 -53.969158)
			(xy 97.786952 -54.036214) (xy 97.787291 -54.045233) (xy 97.79355 -54.06215) (xy 97.799144 -54.069234)
			(xy 97.799398 -54.069234) (xy 97.799398 -54.069488) (xy 97.817045 -54.090414) (xy 97.846755 -54.136388)
			(xy 97.86959 -54.186137) (xy 97.885079 -54.23864) (xy 97.892905 -54.292816) (xy 97.893378 -54.320186)
			(xy 97.892892 -54.347437) (xy 97.885136 -54.401385) (xy 97.869781 -54.45368) (xy 97.847139 -54.503257)
			(xy 97.817673 -54.549107) (xy 97.781982 -54.590298) (xy 97.740791 -54.625989) (xy 97.694941 -54.655455)
			(xy 97.645364 -54.678097) (xy 97.593069 -54.693452) (xy 97.539121 -54.701208) (xy 97.484619 -54.701208)
			(xy 97.430671 -54.693452) (xy 97.378376 -54.678097) (xy 97.328799 -54.655455) (xy 97.282949 -54.625989)
			(xy 97.241758 -54.590298) (xy 97.206067 -54.549107) (xy 97.176601 -54.503257) (xy 97.153959 -54.45368)
			(xy 97.138604 -54.401385) (xy 97.130848 -54.347437) (xy 97.130362 -54.320186) (xy 94.901796 -54.320186)
			(xy 94.892743 -54.339899) (xy 94.863019 -54.385867) (xy 94.845378 -54.4068) (xy 94.845124 -54.407054)
			(xy 94.839542 -54.414143) (xy 94.833294 -54.431058) (xy 94.832932 -54.440074) (xy 94.832932 -54.50713)
			(xy 94.833268 -54.516149) (xy 94.839529 -54.533066) (xy 94.845124 -54.54015) (xy 94.845378 -54.54015)
			(xy 94.845378 -54.540404) (xy 94.863029 -54.561327) (xy 94.89274 -54.607302) (xy 94.915574 -54.657052)
			(xy 94.931062 -54.709554) (xy 94.938886 -54.763732) (xy 94.939003 -54.770528) (xy 98.070924 -54.770528)
			(xy 98.071401 -54.743158) (xy 98.079215 -54.688979) (xy 98.094701 -54.636476) (xy 98.117541 -54.586729)
			(xy 98.147264 -54.540762) (xy 98.164904 -54.51983) (xy 98.165158 -54.519576) (xy 98.170768 -54.512505)
			(xy 98.176999 -54.495576) (xy 98.17735 -54.486556) (xy 98.17735 -54.4195) (xy 98.177004 -54.410482)
			(xy 98.17075 -54.393564) (xy 98.165158 -54.38648) (xy 98.164904 -54.38648) (xy 98.164904 -54.386226)
			(xy 98.147264 -54.365294) (xy 98.117552 -54.319322) (xy 98.094716 -54.269574) (xy 98.079226 -54.217073)
			(xy 98.071398 -54.162897) (xy 98.070924 -54.135528) (xy 98.07141 -54.108277) (xy 98.079166 -54.054329)
			(xy 98.094521 -54.002034) (xy 98.117163 -53.952457) (xy 98.146629 -53.906607) (xy 98.18232 -53.865416)
			(xy 98.223511 -53.829725) (xy 98.269361 -53.800259) (xy 98.318938 -53.777617) (xy 98.371233 -53.762262)
			(xy 98.425181 -53.754506) (xy 98.479683 -53.754506) (xy 98.533631 -53.762262) (xy 98.585926 -53.777617)
			(xy 98.635503 -53.800259) (xy 98.681353 -53.829725) (xy 98.722544 -53.865416) (xy 98.758235 -53.906607)
			(xy 98.787701 -53.952457) (xy 98.810343 -54.002034) (xy 98.825698 -54.054329) (xy 98.833454 -54.108277)
			(xy 98.83394 -54.135528) (xy 98.833505 -54.1629) (xy 98.825682 -54.217081) (xy 98.810186 -54.269585)
			(xy 98.787337 -54.319331) (xy 98.757605 -54.365296) (xy 98.73996 -54.386226) (xy 98.739706 -54.38648)
			(xy 98.734122 -54.393569) (xy 98.727874 -54.410484) (xy 98.727514 -54.4195) (xy 98.727514 -54.486556)
			(xy 98.727889 -54.495571) (xy 98.734124 -54.512488) (xy 98.739706 -54.519576) (xy 98.73996 -54.519576)
			(xy 98.73996 -54.51983) (xy 98.757574 -54.540783) (xy 98.787291 -54.586749) (xy 98.810132 -54.636491)
			(xy 98.825629 -54.688988) (xy 98.833463 -54.74316) (xy 98.83394 -54.770528) (xy 98.833454 -54.797779)
			(xy 98.825698 -54.851727) (xy 98.810343 -54.904022) (xy 98.787701 -54.953599) (xy 98.758235 -54.999449)
			(xy 98.722544 -55.04064) (xy 98.681353 -55.076331) (xy 98.635503 -55.105797) (xy 98.585926 -55.128439)
			(xy 98.533631 -55.143794) (xy 98.479683 -55.15155) (xy 98.425181 -55.15155) (xy 98.371233 -55.143794)
			(xy 98.318938 -55.128439) (xy 98.269361 -55.105797) (xy 98.223511 -55.076331) (xy 98.18232 -55.04064)
			(xy 98.146629 -54.999449) (xy 98.117163 -54.953599) (xy 98.094521 -54.904022) (xy 98.079166 -54.851727)
			(xy 98.07141 -54.797779) (xy 98.070924 -54.770528) (xy 94.939003 -54.770528) (xy 94.939358 -54.791102)
			(xy 94.938872 -54.818353) (xy 94.931116 -54.872301) (xy 94.915761 -54.924596) (xy 94.893119 -54.974173)
			(xy 94.863653 -55.020023) (xy 94.827962 -55.061214) (xy 94.786771 -55.096905) (xy 94.740921 -55.126371)
			(xy 94.691344 -55.149013) (xy 94.639049 -55.164368) (xy 94.585101 -55.172124) (xy 94.530599 -55.172124)
			(xy 94.476651 -55.164368) (xy 94.424356 -55.149013) (xy 94.374779 -55.126371) (xy 94.328929 -55.096905)
			(xy 94.287738 -55.061214) (xy 94.252047 -55.020023) (xy 94.222581 -54.974173) (xy 94.199939 -54.924596)
			(xy 94.184584 -54.872301) (xy 94.176828 -54.818353) (xy 94.176342 -54.791102) (xy 92.278383 -54.791102)
			(xy 92.27529 -54.812611) (xy 92.259934 -54.864906) (xy 92.237292 -54.914483) (xy 92.207826 -54.960334)
			(xy 92.172135 -55.001525) (xy 92.130945 -55.037218) (xy 92.085096 -55.066686) (xy 92.035519 -55.089329)
			(xy 91.983225 -55.104687) (xy 91.929277 -55.112446) (xy 91.902026 -55.11292) (xy 91.875982 -55.112509)
			(xy 91.824368 -55.105497) (xy 91.799156 -55.09895) (xy 91.787472 -55.095648) (xy 91.776296 -55.09768)
			(xy 91.770608 -55.098953) (xy 91.759965 -55.103701) (xy 91.755214 -55.107078) (xy 91.69019 -55.156354)
			(xy 91.685872 -55.15991) (xy 91.679564 -55.166414) (xy 91.671627 -55.182686) (xy 91.670378 -55.19166)
			(xy 91.670124 -55.19674) (xy 91.670124 -57.002934) (xy 99.563428 -57.002934) (xy 99.563927 -56.974842)
			(xy 99.572151 -56.919264) (xy 99.58844 -56.865494) (xy 99.612441 -56.814696) (xy 99.643636 -56.767969)
			(xy 99.681348 -56.726324) (xy 99.724763 -56.690664) (xy 99.748594 -56.675782) (xy 99.757484 -56.670448)
			(xy 99.769676 -56.65343) (xy 99.789996 -56.560212) (xy 99.785678 -56.539638) (xy 99.779836 -56.531002)
			(xy 99.763839 -56.506936) (xy 99.738494 -56.455006) (xy 99.721268 -56.399848) (xy 99.712552 -56.342724)
			(xy 99.712018 -56.313832) (xy 99.712485 -56.286579) (xy 99.720238 -56.232627) (xy 99.735592 -56.180327)
			(xy 99.758232 -56.130746) (xy 99.787699 -56.084891) (xy 99.823393 -56.043697) (xy 99.864586 -56.008003)
			(xy 99.91044 -55.978535) (xy 99.960022 -55.955894) (xy 100.012321 -55.94054) (xy 100.066273 -55.932786)
			(xy 100.093526 -55.932324) (xy 100.120897 -55.932769) (xy 100.175077 -55.940591) (xy 100.227581 -55.956085)
			(xy 100.277327 -55.978931) (xy 100.323293 -56.00866) (xy 100.344224 -56.026304) (xy 100.344478 -56.026558)
			(xy 100.351562 -56.032148) (xy 100.368481 -56.038391) (xy 100.377498 -56.03875) (xy 100.444554 -56.03875)
			(xy 100.45357 -56.038382) (xy 100.470488 -56.032143) (xy 100.477574 -56.026558) (xy 100.477574 -56.026304)
			(xy 100.477828 -56.026304) (xy 100.498761 -56.008663) (xy 100.544729 -55.978939) (xy 100.594475 -55.956093)
			(xy 100.646977 -55.940597) (xy 100.701155 -55.932768) (xy 100.755897 -55.932768) (xy 100.810075 -55.940597)
			(xy 100.862577 -55.956093) (xy 100.912323 -55.978939) (xy 100.958291 -56.008663) (xy 100.979224 -56.026304)
			(xy 100.979478 -56.026558) (xy 100.986562 -56.032148) (xy 101.003481 -56.038391) (xy 101.012498 -56.03875)
			(xy 101.079554 -56.03875) (xy 101.08857 -56.038382) (xy 101.105488 -56.032143) (xy 101.112574 -56.026558)
			(xy 101.112574 -56.026304) (xy 101.112828 -56.026304) (xy 101.133777 -56.008686) (xy 101.179745 -55.978971)
			(xy 101.229488 -55.956131) (xy 101.281985 -55.940635) (xy 101.336158 -55.932801) (xy 101.363526 -55.932324)
			(xy 101.390778 -55.932748) (xy 101.444728 -55.940508) (xy 101.497024 -55.955866) (xy 101.546602 -55.978511)
			(xy 101.592453 -56.00798) (xy 101.633643 -56.043675) (xy 101.669335 -56.084868) (xy 101.698801 -56.130721)
			(xy 101.721443 -56.180301) (xy 101.736798 -56.232598) (xy 101.744554 -56.286548) (xy 101.744554 -56.297068)
			(xy 102.086408 -56.297068) (xy 102.090479 -56.241446) (xy 102.102605 -56.187009) (xy 102.122528 -56.134918)
			(xy 102.149824 -56.086283) (xy 102.18391 -56.04214) (xy 102.224059 -56.003431) (xy 102.269417 -55.97098)
			(xy 102.319017 -55.945479) (xy 102.371801 -55.927472) (xy 102.426644 -55.917342) (xy 102.482378 -55.915305)
			(xy 102.537815 -55.921405) (xy 102.591772 -55.935511) (xy 102.643101 -55.957323) (xy 102.690707 -55.986377)
			(xy 102.733575 -56.022052) (xy 102.770792 -56.063589) (xy 102.801565 -56.110102) (xy 102.825237 -56.160599)
			(xy 102.841305 -56.214006) (xy 102.849425 -56.269182) (xy 102.849934 -56.297068) (xy 102.849425 -56.324954)
			(xy 102.841305 -56.38013) (xy 102.825237 -56.433537) (xy 102.801565 -56.484034) (xy 102.770792 -56.530547)
			(xy 102.733575 -56.572084) (xy 102.690707 -56.607759) (xy 102.643101 -56.636813) (xy 102.591772 -56.658625)
			(xy 102.537815 -56.672731) (xy 102.482378 -56.678831) (xy 102.426644 -56.676794) (xy 102.371801 -56.666664)
			(xy 102.319017 -56.648657) (xy 102.269417 -56.623156) (xy 102.224059 -56.590705) (xy 102.18391 -56.551996)
			(xy 102.149824 -56.507853) (xy 102.122528 -56.459218) (xy 102.102605 -56.407127) (xy 102.090479 -56.35269)
			(xy 102.086408 -56.297068) (xy 101.744554 -56.297068) (xy 101.744554 -56.341052) (xy 101.736798 -56.395002)
			(xy 101.721443 -56.447299) (xy 101.698801 -56.496879) (xy 101.669335 -56.542732) (xy 101.633643 -56.583925)
			(xy 101.592453 -56.61962) (xy 101.546602 -56.649089) (xy 101.497024 -56.671734) (xy 101.444728 -56.687092)
			(xy 101.390778 -56.694852) (xy 101.363526 -56.69534) (xy 101.336156 -56.694873) (xy 101.281976 -56.687058)
			(xy 101.229472 -56.67157) (xy 101.179725 -56.648728) (xy 101.133759 -56.619002) (xy 101.112828 -56.60136)
			(xy 101.112574 -56.601106) (xy 101.10547 -56.595545) (xy 101.088567 -56.589283) (xy 101.079554 -56.588914)
			(xy 101.012498 -56.588914) (xy 101.003481 -56.589267) (xy 100.986564 -56.595517) (xy 100.979478 -56.601106)
			(xy 100.979478 -56.60136) (xy 100.979224 -56.60136) (xy 100.958291 -56.619001) (xy 100.912323 -56.648725)
			(xy 100.862577 -56.671571) (xy 100.810075 -56.687067) (xy 100.755897 -56.694896) (xy 100.701155 -56.694896)
			(xy 100.646977 -56.687067) (xy 100.594475 -56.671571) (xy 100.544729 -56.648725) (xy 100.498761 -56.619001)
			(xy 100.477828 -56.60136) (xy 100.477574 -56.601106) (xy 100.47047 -56.595545) (xy 100.453567 -56.589283)
			(xy 100.444554 -56.588914) (xy 100.377498 -56.588914) (xy 100.368481 -56.589267) (xy 100.351564 -56.595517)
			(xy 100.344478 -56.601106) (xy 100.34397 -56.60136) (xy 100.331235 -56.612303) (xy 100.304144 -56.632145)
			(xy 100.289868 -56.640984) (xy 100.280978 -56.646318) (xy 100.268786 -56.663336) (xy 100.248466 -56.756554)
			(xy 100.252784 -56.777128) (xy 100.258626 -56.785764) (xy 100.274616 -56.809834) (xy 100.29996 -56.861764)
			(xy 100.317188 -56.91692) (xy 100.325907 -56.974042) (xy 100.326444 -57.002934) (xy 100.325958 -57.030185)
			(xy 100.318202 -57.084133) (xy 100.302847 -57.136428) (xy 100.280205 -57.186005) (xy 100.250739 -57.231855)
			(xy 100.215048 -57.273046) (xy 100.173857 -57.308737) (xy 100.128007 -57.338203) (xy 100.07843 -57.360845)
			(xy 100.026135 -57.3762) (xy 99.972187 -57.383956) (xy 99.917685 -57.383956) (xy 99.863737 -57.3762)
			(xy 99.811442 -57.360845) (xy 99.761865 -57.338203) (xy 99.716015 -57.308737) (xy 99.674824 -57.273046)
			(xy 99.639133 -57.231855) (xy 99.609667 -57.186005) (xy 99.587025 -57.136428) (xy 99.57167 -57.084133)
			(xy 99.563914 -57.030185) (xy 99.563428 -57.002934) (xy 91.670124 -57.002934) (xy 91.670124 -58.679334)
			(xy 99.995228 -58.679334) (xy 99.995642 -58.653018) (xy 100.002887 -58.600887) (xy 100.017216 -58.550243)
			(xy 100.038358 -58.502044) (xy 100.065914 -58.457202) (xy 100.099362 -58.416565) (xy 100.118418 -58.39841)
			(xy 100.12582 -58.390889) (xy 100.134344 -58.371608) (xy 100.134928 -58.361072) (xy 100.134928 -58.286396)
			(xy 100.134406 -58.275846) (xy 100.125865 -58.256551) (xy 100.118418 -58.249058) (xy 100.099353 -58.230912)
			(xy 100.065896 -58.190281) (xy 100.038337 -58.145439) (xy 100.017201 -58.097236) (xy 100.002886 -58.046586)
			(xy 99.995664 -57.994451) (xy 99.995228 -57.968134) (xy 99.995714 -57.940883) (xy 100.00347 -57.886935)
			(xy 100.018825 -57.83464) (xy 100.041467 -57.785063) (xy 100.070933 -57.739213) (xy 100.106624 -57.698022)
			(xy 100.147815 -57.662331) (xy 100.193665 -57.632865) (xy 100.243242 -57.610223) (xy 100.295537 -57.594868)
			(xy 100.349485 -57.587112) (xy 100.403987 -57.587112) (xy 100.457935 -57.594868) (xy 100.51023 -57.610223)
			(xy 100.559807 -57.632865) (xy 100.605657 -57.662331) (xy 100.646848 -57.698022) (xy 100.682539 -57.739213)
			(xy 100.712005 -57.785063) (xy 100.734647 -57.83464) (xy 100.750002 -57.886935) (xy 100.757758 -57.940883)
			(xy 100.758244 -57.968134) (xy 100.757817 -57.99445) (xy 100.750577 -58.046581) (xy 100.736251 -58.097225)
			(xy 100.715111 -58.145424) (xy 100.687557 -58.190266) (xy 100.65411 -58.230903) (xy 100.635054 -58.249058)
			(xy 100.627677 -58.256601) (xy 100.619137 -58.275864) (xy 100.618544 -58.286396) (xy 100.618544 -58.361072)
			(xy 100.619062 -58.371623) (xy 100.627604 -58.390919) (xy 100.635054 -58.39841) (xy 100.654118 -58.416557)
			(xy 100.687572 -58.45719) (xy 100.715129 -58.502032) (xy 100.736265 -58.550234) (xy 100.750581 -58.600883)
			(xy 100.757806 -58.653018) (xy 100.758244 -58.679334) (xy 100.757758 -58.706585) (xy 100.750002 -58.760533)
			(xy 100.734647 -58.812828) (xy 100.712005 -58.862405) (xy 100.682539 -58.908255) (xy 100.646848 -58.949446)
			(xy 100.605657 -58.985137) (xy 100.559807 -59.014603) (xy 100.51023 -59.037245) (xy 100.457935 -59.0526)
			(xy 100.403987 -59.060356) (xy 100.349485 -59.060356) (xy 100.295537 -59.0526) (xy 100.243242 -59.037245)
			(xy 100.193665 -59.014603) (xy 100.147815 -58.985137) (xy 100.106624 -58.949446) (xy 100.070933 -58.908255)
			(xy 100.041467 -58.862405) (xy 100.018825 -58.812828) (xy 100.00347 -58.760533) (xy 99.995714 -58.706585)
			(xy 99.995228 -58.679334) (xy 91.670124 -58.679334) (xy 91.670124 -60.01925) (xy 100.135684 -60.01925)
			(xy 100.135684 -59.96475) (xy 100.14344 -59.910804) (xy 100.158794 -59.85851) (xy 100.181434 -59.808935)
			(xy 100.210899 -59.763086) (xy 100.246589 -59.721896) (xy 100.287777 -59.686205) (xy 100.333626 -59.656739)
			(xy 100.383201 -59.634098) (xy 100.435494 -59.618742) (xy 100.48944 -59.610984) (xy 100.51669 -59.610498)
			(xy 100.54406 -59.61097) (xy 100.598239 -59.618787) (xy 100.650742 -59.634274) (xy 100.700489 -59.657115)
			(xy 100.746456 -59.686838) (xy 100.767388 -59.704478) (xy 100.767642 -59.704732) (xy 100.774738 -59.710304)
			(xy 100.791648 -59.716558) (xy 100.800662 -59.716924) (xy 100.867718 -59.716924) (xy 100.876735 -59.716571)
			(xy 100.893652 -59.71032) (xy 100.900738 -59.704732) (xy 100.900738 -59.704478) (xy 100.900992 -59.704478)
			(xy 100.921925 -59.686837) (xy 100.967893 -59.657113) (xy 101.017639 -59.634267) (xy 101.070141 -59.618771)
			(xy 101.124319 -59.610942) (xy 101.179061 -59.610942) (xy 101.233239 -59.618771) (xy 101.285741 -59.634267)
			(xy 101.335487 -59.657113) (xy 101.381455 -59.686837) (xy 101.402388 -59.704478) (xy 101.402642 -59.704732)
			(xy 101.409738 -59.710304) (xy 101.426648 -59.716558) (xy 101.435662 -59.716924) (xy 101.502718 -59.716924)
			(xy 101.511735 -59.716571) (xy 101.528652 -59.71032) (xy 101.535738 -59.704732) (xy 101.535738 -59.704478)
			(xy 101.535992 -59.704478) (xy 101.556913 -59.686826) (xy 101.60289 -59.657117) (xy 101.65264 -59.634284)
			(xy 101.705143 -59.618796) (xy 101.75932 -59.61097) (xy 101.78669 -59.610498) (xy 101.813944 -59.610949)
			(xy 101.867897 -59.618705) (xy 101.920196 -59.63406) (xy 101.969779 -59.656702) (xy 102.015634 -59.68617)
			(xy 102.056828 -59.721865) (xy 102.092524 -59.763058) (xy 102.121993 -59.808913) (xy 102.144636 -59.858494)
			(xy 102.159993 -59.910794) (xy 102.167751 -59.964746) (xy 102.167751 -60.019254) (xy 102.159993 -60.073206)
			(xy 102.144636 -60.125506) (xy 102.121993 -60.175087) (xy 102.092524 -60.220942) (xy 102.056828 -60.262135)
			(xy 102.015634 -60.29783) (xy 101.969779 -60.327298) (xy 101.920196 -60.34994) (xy 101.867897 -60.365295)
			(xy 101.813944 -60.373051) (xy 101.78669 -60.373514) (xy 101.75932 -60.37305) (xy 101.705141 -60.365231)
			(xy 101.652638 -60.349742) (xy 101.602891 -60.326899) (xy 101.556924 -60.297175) (xy 101.535992 -60.279534)
			(xy 101.535738 -60.27928) (xy 101.528646 -60.273701) (xy 101.511733 -60.26745) (xy 101.502718 -60.267088)
			(xy 101.435662 -60.267088) (xy 101.426644 -60.267429) (xy 101.409727 -60.273688) (xy 101.402642 -60.27928)
			(xy 101.402388 -60.279534) (xy 101.381455 -60.297175) (xy 101.335487 -60.326899) (xy 101.285741 -60.349745)
			(xy 101.233239 -60.365241) (xy 101.179061 -60.37307) (xy 101.124319 -60.37307) (xy 101.070141 -60.365241)
			(xy 101.017639 -60.349745) (xy 100.967893 -60.326899) (xy 100.921925 -60.297175) (xy 100.900992 -60.279534)
			(xy 100.900738 -60.27928) (xy 100.893646 -60.273701) (xy 100.876733 -60.26745) (xy 100.867718 -60.267088)
			(xy 100.800662 -60.267088) (xy 100.791644 -60.267429) (xy 100.774727 -60.273688) (xy 100.767642 -60.27928)
			(xy 100.767642 -60.279534) (xy 100.767388 -60.279534) (xy 100.746438 -60.297151) (xy 100.70047 -60.326865)
			(xy 100.650727 -60.349704) (xy 100.59823 -60.365201) (xy 100.544058 -60.373036) (xy 100.51669 -60.373514)
			(xy 100.48944 -60.373016) (xy 100.435494 -60.365258) (xy 100.383201 -60.349902) (xy 100.333626 -60.327261)
			(xy 100.287777 -60.297795) (xy 100.246589 -60.262104) (xy 100.210899 -60.220914) (xy 100.181434 -60.175065)
			(xy 100.158794 -60.12549) (xy 100.14344 -60.073196) (xy 100.135684 -60.01925) (xy 91.670124 -60.01925)
			(xy 91.670124 -63.213552) (xy 100.120665 -63.213552) (xy 100.120665 -63.159048) (xy 100.128422 -63.105098)
			(xy 100.143778 -63.052801) (xy 100.16642 -63.003222) (xy 100.195888 -62.95737) (xy 100.231581 -62.916178)
			(xy 100.272773 -62.880485) (xy 100.318625 -62.851018) (xy 100.368205 -62.828377) (xy 100.420502 -62.813021)
			(xy 100.474452 -62.805265) (xy 100.501704 -62.804802) (xy 100.529074 -62.805265) (xy 100.583254 -62.813084)
			(xy 100.635757 -62.828573) (xy 100.685504 -62.851416) (xy 100.73147 -62.881141) (xy 100.752402 -62.898782)
			(xy 100.752656 -62.899036) (xy 100.759748 -62.904614) (xy 100.776661 -62.910865) (xy 100.785676 -62.911228)
			(xy 100.852732 -62.911228) (xy 100.86175 -62.91088) (xy 100.878666 -62.904626) (xy 100.885752 -62.899036)
			(xy 100.885752 -62.898782) (xy 100.886006 -62.898782) (xy 100.906939 -62.881141) (xy 100.952907 -62.851417)
			(xy 101.002653 -62.828571) (xy 101.055155 -62.813075) (xy 101.109333 -62.805246) (xy 101.164075 -62.805246)
			(xy 101.218253 -62.813075) (xy 101.270755 -62.828571) (xy 101.320501 -62.851417) (xy 101.366469 -62.881141)
			(xy 101.387402 -62.898782) (xy 101.387656 -62.899036) (xy 101.394748 -62.904614) (xy 101.411661 -62.910865)
			(xy 101.420676 -62.911228) (xy 101.487732 -62.911228) (xy 101.49675 -62.91088) (xy 101.513666 -62.904626)
			(xy 101.520752 -62.899036) (xy 101.520752 -62.898782) (xy 101.521006 -62.898782) (xy 101.541923 -62.881124)
			(xy 101.5879 -62.851415) (xy 101.637651 -62.828583) (xy 101.690155 -62.813097) (xy 101.744334 -62.805273)
			(xy 101.771704 -62.804802) (xy 101.798956 -62.805268) (xy 101.852904 -62.813025) (xy 101.9052 -62.828381)
			(xy 101.954778 -62.851023) (xy 102.000629 -62.88049) (xy 102.04182 -62.916183) (xy 102.077512 -62.957374)
			(xy 102.106979 -63.003225) (xy 102.12962 -63.052804) (xy 102.144976 -63.105099) (xy 102.152732 -63.159048)
			(xy 102.152732 -63.213552) (xy 102.144976 -63.267501) (xy 102.12962 -63.319796) (xy 102.106979 -63.369375)
			(xy 102.077512 -63.415226) (xy 102.04182 -63.456417) (xy 102.000629 -63.49211) (xy 101.954778 -63.521577)
			(xy 101.9052 -63.544219) (xy 101.852904 -63.559575) (xy 101.798956 -63.567332) (xy 101.771704 -63.567818)
			(xy 101.744333 -63.56737) (xy 101.690152 -63.559551) (xy 101.637648 -63.544058) (xy 101.587902 -63.521212)
			(xy 101.541936 -63.491482) (xy 101.521006 -63.473838) (xy 101.520752 -63.473584) (xy 101.513656 -63.468011)
			(xy 101.496746 -63.461757) (xy 101.487732 -63.461392) (xy 101.420676 -63.461392) (xy 101.411658 -63.461739)
			(xy 101.394741 -63.467994) (xy 101.387656 -63.473584) (xy 101.387402 -63.473838) (xy 101.366469 -63.491479)
			(xy 101.320501 -63.521203) (xy 101.270755 -63.544049) (xy 101.218253 -63.559545) (xy 101.164075 -63.567374)
			(xy 101.109333 -63.567374) (xy 101.055155 -63.559545) (xy 101.002653 -63.544049) (xy 100.952907 -63.521203)
			(xy 100.906939 -63.491479) (xy 100.886006 -63.473838) (xy 100.885752 -63.473584) (xy 100.878656 -63.468011)
			(xy 100.861746 -63.461757) (xy 100.852732 -63.461392) (xy 100.785676 -63.461392) (xy 100.776658 -63.461739)
			(xy 100.759741 -63.467994) (xy 100.752656 -63.473584) (xy 100.752656 -63.473838) (xy 100.752402 -63.473838)
			(xy 100.731485 -63.491496) (xy 100.685508 -63.521204) (xy 100.635756 -63.544036) (xy 100.583252 -63.559522)
			(xy 100.529074 -63.567346) (xy 100.501704 -63.567818) (xy 100.474452 -63.567335) (xy 100.420502 -63.559579)
			(xy 100.368205 -63.544223) (xy 100.318625 -63.521582) (xy 100.272773 -63.492115) (xy 100.231581 -63.456422)
			(xy 100.195888 -63.41523) (xy 100.16642 -63.369378) (xy 100.143778 -63.319799) (xy 100.128422 -63.267502)
			(xy 100.120665 -63.213552) (xy 91.670124 -63.213552) (xy 91.670124 -67.128949) (xy 92.366598 -67.128949)
			(xy 92.366598 -67.074451) (xy 92.374354 -67.020506) (xy 92.389708 -66.968215) (xy 92.412347 -66.918641)
			(xy 92.441811 -66.872794) (xy 92.4775 -66.831606) (xy 92.518687 -66.795916) (xy 92.564534 -66.766451)
			(xy 92.614108 -66.743811) (xy 92.666399 -66.728456) (xy 92.720343 -66.720699) (xy 92.747592 -66.720212)
			(xy 92.774962 -66.72068) (xy 92.829141 -66.728497) (xy 92.881645 -66.743985) (xy 92.931391 -66.766827)
			(xy 92.977358 -66.796551) (xy 92.99829 -66.814192) (xy 92.998544 -66.814446) (xy 93.005638 -66.820021)
			(xy 93.022549 -66.826273) (xy 93.031564 -66.826638) (xy 93.09862 -66.826638) (xy 93.107637 -66.826282)
			(xy 93.124553 -66.820033) (xy 93.13164 -66.814446) (xy 93.13164 -66.814192) (xy 93.131894 -66.814192)
			(xy 93.152816 -66.796541) (xy 93.198792 -66.766831) (xy 93.248542 -66.743998) (xy 93.301045 -66.728509)
			(xy 93.355222 -66.720684) (xy 93.382592 -66.720212) (xy 93.409847 -66.720634) (xy 93.463801 -66.728391)
			(xy 93.516103 -66.743747) (xy 93.565687 -66.76639) (xy 93.611543 -66.79586) (xy 93.652739 -66.831555)
			(xy 93.688436 -66.87275) (xy 93.717906 -66.918606) (xy 93.74055 -66.96819) (xy 93.755907 -67.020491)
			(xy 93.763665 -67.074445) (xy 93.763665 -67.128955) (xy 93.755907 -67.182909) (xy 93.74055 -67.23521)
			(xy 93.717906 -67.284794) (xy 93.688436 -67.33065) (xy 93.652739 -67.371845) (xy 93.611543 -67.40754)
			(xy 93.565687 -67.43701) (xy 93.516103 -67.459653) (xy 93.463801 -67.475009) (xy 93.409847 -67.482766)
			(xy 93.382592 -67.483228) (xy 93.355221 -67.482784) (xy 93.30104 -67.474964) (xy 93.248536 -67.45947)
			(xy 93.198789 -67.436623) (xy 93.152824 -67.406892) (xy 93.131894 -67.389248) (xy 93.13164 -67.388994)
			(xy 93.124547 -67.383417) (xy 93.107635 -67.377165) (xy 93.09862 -67.376802) (xy 93.031564 -67.376802)
			(xy 93.022545 -67.377142) (xy 93.005629 -67.383401) (xy 92.998544 -67.388994) (xy 92.998544 -67.389248)
			(xy 92.99829 -67.389248) (xy 92.977366 -67.406897) (xy 92.931392 -67.436609) (xy 92.881642 -67.459444)
			(xy 92.82914 -67.474933) (xy 92.774962 -67.482757) (xy 92.747592 -67.483228) (xy 92.720343 -67.482701)
			(xy 92.666399 -67.474944) (xy 92.614108 -67.459589) (xy 92.564534 -67.436949) (xy 92.518687 -67.407484)
			(xy 92.4775 -67.371794) (xy 92.441811 -67.330606) (xy 92.412347 -67.284759) (xy 92.389708 -67.235185)
			(xy 92.374354 -67.182894) (xy 92.366598 -67.128949) (xy 91.670124 -67.128949) (xy 91.670124 -67.488054)
			(xy 96.779078 -67.488054) (xy 96.783149 -67.432432) (xy 96.795275 -67.377995) (xy 96.815198 -67.325904)
			(xy 96.842494 -67.277269) (xy 96.87658 -67.233126) (xy 96.916729 -67.194417) (xy 96.962087 -67.161966)
			(xy 97.011687 -67.136465) (xy 97.064471 -67.118458) (xy 97.119314 -67.108328) (xy 97.175048 -67.106291)
			(xy 97.230485 -67.112391) (xy 97.284442 -67.126497) (xy 97.335771 -67.148309) (xy 97.383377 -67.177363)
			(xy 97.426245 -67.213038) (xy 97.463462 -67.254575) (xy 97.494235 -67.301088) (xy 97.517907 -67.351585)
			(xy 97.533975 -67.404992) (xy 97.542095 -67.460168) (xy 97.542604 -67.488054) (xy 97.542095 -67.51594)
			(xy 97.53891 -67.537584) (xy 98.071176 -67.537584) (xy 98.075247 -67.481962) (xy 98.087373 -67.427525)
			(xy 98.107296 -67.375434) (xy 98.134592 -67.326799) (xy 98.168678 -67.282656) (xy 98.208827 -67.243947)
			(xy 98.254185 -67.211496) (xy 98.303785 -67.185995) (xy 98.356569 -67.167988) (xy 98.411412 -67.157858)
			(xy 98.467146 -67.155821) (xy 98.522583 -67.161921) (xy 98.57654 -67.176027) (xy 98.627869 -67.197839)
			(xy 98.675475 -67.226893) (xy 98.718343 -67.262568) (xy 98.75556 -67.304105) (xy 98.786333 -67.350618)
			(xy 98.810005 -67.401115) (xy 98.826073 -67.454522) (xy 98.834193 -67.509698) (xy 98.834702 -67.537584)
			(xy 98.834193 -67.56547) (xy 98.830148 -67.592956) (xy 99.34524 -67.592956) (xy 99.349311 -67.537334)
			(xy 99.361437 -67.482897) (xy 99.38136 -67.430806) (xy 99.408656 -67.382171) (xy 99.442742 -67.338028)
			(xy 99.482891 -67.299319) (xy 99.528249 -67.266868) (xy 99.577849 -67.241367) (xy 99.630633 -67.22336)
			(xy 99.685476 -67.21323) (xy 99.74121 -67.211193) (xy 99.796647 -67.217293) (xy 99.850604 -67.231399)
			(xy 99.901933 -67.253211) (xy 99.949539 -67.282265) (xy 99.992407 -67.31794) (xy 100.029624 -67.359477)
			(xy 100.060397 -67.40599) (xy 100.084069 -67.456487) (xy 100.100137 -67.509894) (xy 100.108254 -67.565048)
			(xy 102.446616 -67.565048) (xy 102.446616 -67.510552) (xy 102.454371 -67.456612) (xy 102.469724 -67.404324)
			(xy 102.492362 -67.354753) (xy 102.521823 -67.308908) (xy 102.557509 -67.267722) (xy 102.598693 -67.232034)
			(xy 102.644537 -67.20257) (xy 102.694107 -67.17993) (xy 102.746394 -67.164575) (xy 102.800334 -67.156817)
			(xy 102.827582 -67.15633) (xy 102.854952 -67.156799) (xy 102.909131 -67.164615) (xy 102.961635 -67.180103)
			(xy 103.011382 -67.202944) (xy 103.057348 -67.232669) (xy 103.07828 -67.25031) (xy 103.078534 -67.250564)
			(xy 103.08563 -67.256137) (xy 103.10254 -67.26239) (xy 103.111554 -67.262756) (xy 103.17861 -67.262756)
			(xy 103.187629 -67.262414) (xy 103.204546 -67.256157) (xy 103.21163 -67.250564) (xy 103.21163 -67.25031)
			(xy 103.211884 -67.25031) (xy 103.232813 -67.232667) (xy 103.278786 -67.202955) (xy 103.328535 -67.18012)
			(xy 103.381036 -67.16463) (xy 103.435213 -67.156803) (xy 103.462582 -67.15633) (xy 103.489838 -67.156716)
			(xy 103.543797 -67.164471) (xy 103.596102 -67.179827) (xy 103.645689 -67.202471) (xy 103.691549 -67.231942)
			(xy 103.732748 -67.267639) (xy 103.768448 -67.308836) (xy 103.79792 -67.354695) (xy 103.820566 -67.404281)
			(xy 103.835925 -67.456586) (xy 103.843683 -67.510544) (xy 103.843683 -67.565056) (xy 103.835925 -67.619014)
			(xy 103.820566 -67.671319) (xy 103.79792 -67.720905) (xy 103.768448 -67.766764) (xy 103.732748 -67.807961)
			(xy 103.691549 -67.843658) (xy 103.645689 -67.873129) (xy 103.596102 -67.895773) (xy 103.543797 -67.911129)
			(xy 103.489838 -67.918884) (xy 103.462582 -67.919346) (xy 103.435211 -67.918904) (xy 103.38103 -67.911082)
			(xy 103.328526 -67.895588) (xy 103.27878 -67.872741) (xy 103.232814 -67.84301) (xy 103.211884 -67.825366)
			(xy 103.21163 -67.825112) (xy 103.204538 -67.819533) (xy 103.187625 -67.813281) (xy 103.17861 -67.81292)
			(xy 103.111554 -67.81292) (xy 103.102539 -67.813299) (xy 103.085622 -67.819531) (xy 103.078534 -67.825112)
			(xy 103.078534 -67.825366) (xy 103.07828 -67.825366) (xy 103.057324 -67.842976) (xy 103.011358 -67.872693)
			(xy 102.961617 -67.895535) (xy 102.909121 -67.911033) (xy 102.85495 -67.918868) (xy 102.827582 -67.919346)
			(xy 102.800334 -67.918783) (xy 102.746394 -67.911025) (xy 102.694107 -67.89567) (xy 102.644537 -67.87303)
			(xy 102.598693 -67.843566) (xy 102.557509 -67.807878) (xy 102.521823 -67.766692) (xy 102.492362 -67.720847)
			(xy 102.469724 -67.671276) (xy 102.454371 -67.618988) (xy 102.446616 -67.565048) (xy 100.108254 -67.565048)
			(xy 100.108257 -67.56507) (xy 100.108766 -67.592956) (xy 100.108257 -67.620842) (xy 100.100137 -67.676018)
			(xy 100.084069 -67.729425) (xy 100.060397 -67.779922) (xy 100.029624 -67.826435) (xy 99.992407 -67.867972)
			(xy 99.949539 -67.903647) (xy 99.901933 -67.932701) (xy 99.850604 -67.954513) (xy 99.796647 -67.968619)
			(xy 99.74121 -67.974719) (xy 99.685476 -67.972682) (xy 99.630633 -67.962552) (xy 99.577849 -67.944545)
			(xy 99.528249 -67.919044) (xy 99.482891 -67.886593) (xy 99.442742 -67.847884) (xy 99.408656 -67.803741)
			(xy 99.38136 -67.755106) (xy 99.361437 -67.703015) (xy 99.349311 -67.648578) (xy 99.34524 -67.592956)
			(xy 98.830148 -67.592956) (xy 98.826073 -67.620646) (xy 98.810005 -67.674053) (xy 98.786333 -67.72455)
			(xy 98.75556 -67.771063) (xy 98.718343 -67.8126) (xy 98.675475 -67.848275) (xy 98.627869 -67.877329)
			(xy 98.57654 -67.899141) (xy 98.522583 -67.913247) (xy 98.467146 -67.919347) (xy 98.411412 -67.91731)
			(xy 98.356569 -67.90718) (xy 98.303785 -67.889173) (xy 98.254185 -67.863672) (xy 98.208827 -67.831221)
			(xy 98.168678 -67.792512) (xy 98.134592 -67.748369) (xy 98.107296 -67.699734) (xy 98.087373 -67.647643)
			(xy 98.075247 -67.593206) (xy 98.071176 -67.537584) (xy 97.53891 -67.537584) (xy 97.533975 -67.571116)
			(xy 97.517907 -67.624523) (xy 97.494235 -67.67502) (xy 97.463462 -67.721533) (xy 97.426245 -67.76307)
			(xy 97.383377 -67.798745) (xy 97.335771 -67.827799) (xy 97.284442 -67.849611) (xy 97.230485 -67.863717)
			(xy 97.175048 -67.869817) (xy 97.119314 -67.86778) (xy 97.064471 -67.85765) (xy 97.011687 -67.839643)
			(xy 96.962087 -67.814142) (xy 96.916729 -67.781691) (xy 96.87658 -67.742982) (xy 96.842494 -67.698839)
			(xy 96.815198 -67.650204) (xy 96.795275 -67.598113) (xy 96.783149 -67.543676) (xy 96.779078 -67.488054)
			(xy 91.670124 -67.488054) (xy 91.670124 -68.586604) (xy 94.62516 -68.586604) (xy 94.625614 -68.559233)
			(xy 94.633432 -68.505053) (xy 94.648923 -68.452549) (xy 94.671768 -68.402802) (xy 94.701497 -68.356837)
			(xy 94.71914 -68.335906) (xy 94.719394 -68.335652) (xy 94.724964 -68.328554) (xy 94.731221 -68.311646)
			(xy 94.731586 -68.302632) (xy 94.731586 -68.235576) (xy 94.731243 -68.226558) (xy 94.724986 -68.209641)
			(xy 94.719394 -68.202556) (xy 94.71914 -68.202556) (xy 94.71914 -68.202302) (xy 94.701495 -68.181375)
			(xy 94.671782 -68.135401) (xy 94.648947 -68.085653) (xy 94.633458 -68.033151) (xy 94.625632 -67.978974)
			(xy 94.62516 -67.951604) (xy 94.625681 -67.924354) (xy 94.633437 -67.87041) (xy 94.64879 -67.818117)
			(xy 94.671428 -67.768542) (xy 94.700891 -67.722693) (xy 94.736578 -67.681504) (xy 94.777765 -67.645812)
			(xy 94.823611 -67.616345) (xy 94.873184 -67.593702) (xy 94.925474 -67.578344) (xy 94.979418 -67.570584)
			(xy 95.006668 -67.570096) (xy 95.032983 -67.570519) (xy 95.085114 -67.577763) (xy 95.135757 -67.592091)
			(xy 95.183956 -67.613232) (xy 95.228799 -67.640786) (xy 95.269436 -67.674231) (xy 95.287592 -67.693286)
			(xy 95.295117 -67.700684) (xy 95.314394 -67.709211) (xy 95.32493 -67.709796) (xy 95.399606 -67.709796)
			(xy 95.410158 -67.709285) (xy 95.429453 -67.700737) (xy 95.436944 -67.693286) (xy 95.455082 -67.674213)
			(xy 95.495716 -67.640758) (xy 95.54056 -67.613202) (xy 95.588764 -67.592067) (xy 95.639415 -67.577753)
			(xy 95.691551 -67.570532) (xy 95.717868 -67.570096) (xy 95.745238 -67.570582) (xy 95.799416 -67.578395)
			(xy 95.851919 -67.59388) (xy 95.901666 -67.616717) (xy 95.947634 -67.646437) (xy 95.968566 -67.664076)
			(xy 95.96882 -67.66433) (xy 95.975894 -67.669934) (xy 95.992821 -67.676169) (xy 96.00184 -67.676522)
			(xy 96.068896 -67.676522) (xy 96.077912 -67.676158) (xy 96.094829 -67.669915) (xy 96.101916 -67.66433)
			(xy 96.101916 -67.664076) (xy 96.10217 -67.664076) (xy 96.123099 -67.646434) (xy 96.169073 -67.616723)
			(xy 96.218822 -67.593888) (xy 96.271323 -67.578398) (xy 96.325499 -67.57057) (xy 96.352868 -67.570096)
			(xy 96.38012 -67.570585) (xy 96.43407 -67.578338) (xy 96.486368 -67.59369) (xy 96.535948 -67.616329)
			(xy 96.581802 -67.645794) (xy 96.622995 -67.681485) (xy 96.658689 -67.722676) (xy 96.688158 -67.768527)
			(xy 96.7108 -67.818106) (xy 96.726156 -67.870402) (xy 96.733913 -67.924352) (xy 96.734376 -67.951604)
			(xy 96.733918 -67.978975) (xy 96.726099 -68.033154) (xy 96.710609 -68.085658) (xy 96.687765 -68.135404)
			(xy 96.658038 -68.181371) (xy 96.640396 -68.202302) (xy 96.640142 -68.202556) (xy 96.634561 -68.209646)
			(xy 96.628312 -68.22656) (xy 96.62795 -68.235576) (xy 96.62795 -68.302632) (xy 96.628281 -68.311652)
			(xy 96.634545 -68.328569) (xy 96.640142 -68.335652) (xy 96.640396 -68.335652) (xy 96.640396 -68.335906)
			(xy 96.658051 -68.356825) (xy 96.68776 -68.402802) (xy 96.710593 -68.452552) (xy 96.726081 -68.505056)
			(xy 96.733904 -68.559234) (xy 96.734376 -68.586604) (xy 96.733948 -68.613858) (xy 96.72619 -68.667812)
			(xy 96.710832 -68.720113) (xy 96.694199 -68.75653) (xy 100.170234 -68.75653) (xy 100.170709 -68.72916)
			(xy 100.178524 -68.674981) (xy 100.19401 -68.622478) (xy 100.21685 -68.572731) (xy 100.246573 -68.526764)
			(xy 100.264214 -68.505832) (xy 100.264468 -68.505578) (xy 100.270078 -68.498508) (xy 100.276309 -68.481578)
			(xy 100.27666 -68.472558) (xy 100.27666 -68.405502) (xy 100.27631 -68.396484) (xy 100.270059 -68.379567)
			(xy 100.264468 -68.372482) (xy 100.264214 -68.372482) (xy 100.264214 -68.372228) (xy 100.246577 -68.351294)
			(xy 100.216864 -68.305322) (xy 100.194028 -68.255575) (xy 100.178536 -68.203075) (xy 100.170708 -68.148899)
			(xy 100.170234 -68.12153) (xy 100.170683 -68.094276) (xy 100.178437 -68.040322) (xy 100.193792 -67.988022)
			(xy 100.216434 -67.938439) (xy 100.245903 -67.892584) (xy 100.281598 -67.851389) (xy 100.322793 -67.815695)
			(xy 100.368649 -67.786228) (xy 100.418233 -67.763587) (xy 100.470534 -67.748235) (xy 100.524488 -67.740482)
			(xy 100.551742 -67.740022) (xy 100.579111 -67.740517) (xy 100.633289 -67.748327) (xy 100.685792 -67.763809)
			(xy 100.73554 -67.786644) (xy 100.781508 -67.816363) (xy 100.80244 -67.834002) (xy 100.802694 -67.834256)
			(xy 100.809773 -67.839853) (xy 100.826696 -67.846092) (xy 100.835714 -67.846448) (xy 100.90277 -67.846448)
			(xy 100.911787 -67.846088) (xy 100.928704 -67.839844) (xy 100.93579 -67.834256) (xy 100.93579 -67.834002)
			(xy 100.936044 -67.834002) (xy 100.956987 -67.816376) (xy 101.002956 -67.786662) (xy 101.052701 -67.763824)
			(xy 101.1052 -67.74833) (xy 101.159374 -67.740498) (xy 101.186742 -67.740022) (xy 101.213057 -67.740454)
			(xy 101.265188 -67.747695) (xy 101.315831 -67.762021) (xy 101.36403 -67.78316) (xy 101.408873 -67.810712)
			(xy 101.449511 -67.844157) (xy 101.467666 -67.863212) (xy 101.475197 -67.870603) (xy 101.49447 -67.879133)
			(xy 101.505004 -67.879722) (xy 101.57968 -67.879722) (xy 101.590229 -67.879189) (xy 101.609524 -67.870656)
			(xy 101.617018 -67.863212) (xy 101.635174 -67.844157) (xy 101.675803 -67.810699) (xy 101.720644 -67.78314)
			(xy 101.768844 -67.762001) (xy 101.819492 -67.747684) (xy 101.871626 -67.74046) (xy 101.897942 -67.740022)
			(xy 101.925196 -67.740439) (xy 101.979147 -67.748202) (xy 102.031445 -67.763564) (xy 102.081025 -67.786212)
			(xy 102.126876 -67.815685) (xy 102.168067 -67.851384) (xy 102.203758 -67.892581) (xy 102.233223 -67.938439)
			(xy 102.255861 -67.988022) (xy 102.271213 -68.040323) (xy 102.278966 -68.094276) (xy 102.27945 -68.12153)
			(xy 102.279014 -68.148901) (xy 102.271191 -68.203082) (xy 102.255695 -68.255586) (xy 102.232847 -68.305333)
			(xy 102.203115 -68.351298) (xy 102.18547 -68.372228) (xy 102.185216 -68.372482) (xy 102.179633 -68.379571)
			(xy 102.173384 -68.396486) (xy 102.173024 -68.405502) (xy 102.173024 -68.472558) (xy 102.173396 -68.481573)
			(xy 102.179633 -68.498491) (xy 102.185216 -68.505578) (xy 102.18547 -68.505578) (xy 102.18547 -68.505832)
			(xy 102.203086 -68.526783) (xy 102.232802 -68.57275) (xy 102.255643 -68.622493) (xy 102.27114 -68.674989)
			(xy 102.278973 -68.729162) (xy 102.27945 -68.75653) (xy 102.27895 -68.78378) (xy 102.271191 -68.837725)
			(xy 102.255834 -68.890017) (xy 102.233192 -68.939592) (xy 102.203727 -68.98544) (xy 102.168037 -69.026629)
			(xy 102.126849 -69.06232) (xy 102.081002 -69.091787) (xy 102.031428 -69.11443) (xy 101.979137 -69.129788)
			(xy 101.925192 -69.137549) (xy 101.897942 -69.138038) (xy 101.871626 -69.137629) (xy 101.819494 -69.130385)
			(xy 101.768849 -69.116056) (xy 101.72065 -69.094913) (xy 101.675808 -69.067355) (xy 101.635172 -69.033905)
			(xy 101.617018 -69.014848) (xy 101.609485 -69.00746) (xy 101.590214 -68.998926) (xy 101.57968 -68.998338)
			(xy 101.505004 -68.998338) (xy 101.494451 -68.998844) (xy 101.475156 -69.007394) (xy 101.467666 -69.014848)
			(xy 101.449529 -69.033922) (xy 101.408895 -69.067376) (xy 101.36405 -69.094931) (xy 101.315846 -69.116066)
			(xy 101.265195 -69.13038) (xy 101.213059 -69.137601) (xy 101.186742 -69.138038) (xy 101.159372 -69.137562)
			(xy 101.105193 -69.129749) (xy 101.052689 -69.114263) (xy 101.002942 -69.091423) (xy 100.956975 -69.061699)
			(xy 100.936044 -69.044058) (xy 100.93579 -69.043804) (xy 100.92871 -69.038208) (xy 100.911788 -69.031967)
			(xy 100.90277 -69.031612) (xy 100.835714 -69.031612) (xy 100.826697 -69.031973) (xy 100.80978 -69.038217)
			(xy 100.802694 -69.043804) (xy 100.802694 -69.044058) (xy 100.80244 -69.044058) (xy 100.781498 -69.061685)
			(xy 100.735529 -69.0914) (xy 100.685784 -69.114239) (xy 100.633285 -69.129733) (xy 100.579111 -69.137563)
			(xy 100.551742 -69.138038) (xy 100.524492 -69.137506) (xy 100.470545 -69.129755) (xy 100.41825 -69.114406)
			(xy 100.368672 -69.091771) (xy 100.32282 -69.06231) (xy 100.281628 -69.026623) (xy 100.245933 -68.985438)
			(xy 100.216464 -68.939591) (xy 100.193819 -68.890018) (xy 100.17846 -68.837726) (xy 100.170699 -68.78378)
			(xy 100.170234 -68.75653) (xy 96.694199 -68.75653) (xy 96.688186 -68.769695) (xy 96.658715 -68.81555)
			(xy 96.623018 -68.856743) (xy 96.581821 -68.892437) (xy 96.535963 -68.921904) (xy 96.486379 -68.944544)
			(xy 96.434077 -68.959898) (xy 96.380122 -68.967651) (xy 96.352868 -68.968112) (xy 96.325497 -68.967662)
			(xy 96.271318 -68.95984) (xy 96.218814 -68.944347) (xy 96.169068 -68.921502) (xy 96.123101 -68.891774)
			(xy 96.10217 -68.874132) (xy 96.101916 -68.873878) (xy 96.094831 -68.86829) (xy 96.077913 -68.862045)
			(xy 96.068896 -68.861686) (xy 96.00184 -68.861686) (xy 95.992825 -68.862065) (xy 95.975908 -68.868298)
			(xy 95.96882 -68.873878) (xy 95.96882 -68.874132) (xy 95.968566 -68.874132) (xy 95.947624 -68.891759)
			(xy 95.901653 -68.921471) (xy 95.851908 -68.944309) (xy 95.79941 -68.959803) (xy 95.745236 -68.967636)
			(xy 95.717868 -68.968112) (xy 95.691553 -68.967662) (xy 95.639424 -68.960423) (xy 95.588781 -68.9461)
			(xy 95.540583 -68.924965) (xy 95.49574 -68.897416) (xy 95.4551 -68.863975) (xy 95.436944 -68.844922)
			(xy 95.429405 -68.837541) (xy 95.410138 -68.829004) (xy 95.399606 -68.828412) (xy 95.32493 -68.828412)
			(xy 95.31438 -68.82894) (xy 95.295085 -68.837476) (xy 95.287592 -68.844922) (xy 95.269438 -68.863979)
			(xy 95.228807 -68.897435) (xy 95.183966 -68.924993) (xy 95.135766 -68.946131) (xy 95.085118 -68.960448)
			(xy 95.032984 -68.967673) (xy 95.006668 -68.968112) (xy 94.979416 -68.967652) (xy 94.925468 -68.959891)
			(xy 94.873173 -68.944532) (xy 94.823596 -68.921888) (xy 94.777746 -68.892418) (xy 94.736556 -68.856724)
			(xy 94.700865 -68.815532) (xy 94.671399 -68.76968) (xy 94.648758 -68.720101) (xy 94.633403 -68.667805)
			(xy 94.625646 -68.613856) (xy 94.62516 -68.586604) (xy 91.670124 -68.586604) (xy 91.670124 -71.555864)
			(xy 97.194368 -71.555864) (xy 97.198439 -71.500242) (xy 97.210565 -71.445805) (xy 97.230488 -71.393714)
			(xy 97.257784 -71.345079) (xy 97.29187 -71.300936) (xy 97.332019 -71.262227) (xy 97.377377 -71.229776)
			(xy 97.426977 -71.204275) (xy 97.479761 -71.186268) (xy 97.534604 -71.176138) (xy 97.590338 -71.174101)
			(xy 97.645775 -71.180201) (xy 97.699732 -71.194307) (xy 97.751061 -71.216119) (xy 97.798667 -71.245173)
			(xy 97.841535 -71.280848) (xy 97.878752 -71.322385) (xy 97.909525 -71.368898) (xy 97.933197 -71.419395)
			(xy 97.949265 -71.472802) (xy 97.957385 -71.527978) (xy 97.957894 -71.555864) (xy 97.957385 -71.58375)
			(xy 97.951546 -71.623428) (xy 98.703382 -71.623428) (xy 98.707453 -71.567806) (xy 98.719579 -71.513369)
			(xy 98.739502 -71.461278) (xy 98.766798 -71.412643) (xy 98.800884 -71.3685) (xy 98.841033 -71.329791)
			(xy 98.886391 -71.29734) (xy 98.935991 -71.271839) (xy 98.988775 -71.253832) (xy 99.043618 -71.243702)
			(xy 99.099352 -71.241665) (xy 99.154789 -71.247765) (xy 99.208746 -71.261871) (xy 99.260075 -71.283683)
			(xy 99.307681 -71.312737) (xy 99.350549 -71.348412) (xy 99.387766 -71.389949) (xy 99.418539 -71.436462)
			(xy 99.442211 -71.486959) (xy 99.458279 -71.540366) (xy 99.466399 -71.595542) (xy 99.466908 -71.623428)
			(xy 99.466399 -71.651314) (xy 99.458279 -71.70649) (xy 99.442211 -71.759897) (xy 99.418539 -71.810394)
			(xy 99.387766 -71.856907) (xy 99.350549 -71.898444) (xy 99.307681 -71.934119) (xy 99.260075 -71.963173)
			(xy 99.208746 -71.984985) (xy 99.154789 -71.999091) (xy 99.099352 -72.005191) (xy 99.043618 -72.003154)
			(xy 98.988775 -71.993024) (xy 98.935991 -71.975017) (xy 98.886391 -71.949516) (xy 98.841033 -71.917065)
			(xy 98.800884 -71.878356) (xy 98.766798 -71.834213) (xy 98.739502 -71.785578) (xy 98.719579 -71.733487)
			(xy 98.707453 -71.67905) (xy 98.703382 -71.623428) (xy 97.951546 -71.623428) (xy 97.949265 -71.638926)
			(xy 97.933197 -71.692333) (xy 97.909525 -71.74283) (xy 97.878752 -71.789343) (xy 97.841535 -71.83088)
			(xy 97.798667 -71.866555) (xy 97.751061 -71.895609) (xy 97.699732 -71.917421) (xy 97.645775 -71.931527)
			(xy 97.590338 -71.937627) (xy 97.534604 -71.93559) (xy 97.479761 -71.92546) (xy 97.426977 -71.907453)
			(xy 97.377377 -71.881952) (xy 97.332019 -71.849501) (xy 97.29187 -71.810792) (xy 97.257784 -71.766649)
			(xy 97.230488 -71.718014) (xy 97.210565 -71.665923) (xy 97.198439 -71.611486) (xy 97.194368 -71.555864)
			(xy 91.670124 -71.555864) (xy 91.670124 -73.023984) (xy 91.670378 -73.02881) (xy 91.671529 -73.037302)
			(xy 91.678671 -73.05287) (xy 91.684348 -73.05929) (xy 92.00007 -73.374758) (xy 92.018183 -73.393538)
			(xy 92.048869 -73.435735) (xy 92.072569 -73.482216) (xy 92.088698 -73.531834) (xy 92.096859 -73.583367)
			(xy 92.097352 -73.609454) (xy 92.097352 -75.875896) (xy 92.098368 -75.885548) (xy 92.099997 -75.892791)
			(xy 92.106841 -75.905958) (xy 92.11183 -75.911456) (xy 93.565741 -77.365367) (xy 105.150162 -77.365367)
			(xy 105.150162 -77.305433) (xy 105.157985 -77.246011) (xy 105.173496 -77.188119) (xy 105.19643 -77.132746)
			(xy 105.226396 -77.08084) (xy 105.26288 -77.03329) (xy 105.305258 -76.990908) (xy 105.352805 -76.954419)
			(xy 105.404708 -76.924449) (xy 105.460079 -76.901509) (xy 105.51797 -76.885993) (xy 105.577391 -76.878165)
			(xy 105.607358 -76.877672) (xy 106.470958 -76.877672) (xy 106.500928 -76.878178) (xy 106.560354 -76.885997)
			(xy 106.618252 -76.901506) (xy 106.67363 -76.92444) (xy 106.72554 -76.954406) (xy 106.773095 -76.990892)
			(xy 106.81548 -77.033273) (xy 106.851971 -77.080825) (xy 106.881942 -77.132732) (xy 106.904881 -77.188108)
			(xy 106.920395 -77.246004) (xy 106.928219 -77.305431) (xy 106.928219 -77.365367) (xy 109.150162 -77.365367)
			(xy 109.150162 -77.305433) (xy 109.157984 -77.246012) (xy 109.173495 -77.18812) (xy 109.196429 -77.132748)
			(xy 109.226394 -77.080843) (xy 109.262878 -77.033292) (xy 109.305255 -76.990911) (xy 109.352801 -76.954422)
			(xy 109.404703 -76.924452) (xy 109.460073 -76.901511) (xy 109.517963 -76.885994) (xy 109.577383 -76.878165)
			(xy 109.60735 -76.877672) (xy 110.47095 -76.877672) (xy 110.50092 -76.878178) (xy 110.560347 -76.885996)
			(xy 110.618246 -76.901504) (xy 110.673625 -76.924437) (xy 110.725536 -76.954403) (xy 110.773092 -76.990889)
			(xy 110.815478 -77.03327) (xy 110.851969 -77.080822) (xy 110.881941 -77.13273) (xy 110.90488 -77.188107)
			(xy 110.920395 -77.246003) (xy 110.928219 -77.30543) (xy 110.928219 -77.36537) (xy 110.920395 -77.424797)
			(xy 110.90488 -77.482693) (xy 110.881941 -77.53807) (xy 110.851969 -77.589978) (xy 110.815478 -77.63753)
			(xy 110.773092 -77.679911) (xy 110.725536 -77.716397) (xy 110.673625 -77.746363) (xy 110.618246 -77.769296)
			(xy 110.560347 -77.784804) (xy 110.50092 -77.792622) (xy 110.47095 -77.793088) (xy 109.60735 -77.793088)
			(xy 109.577383 -77.792635) (xy 109.517963 -77.784806) (xy 109.460073 -77.769289) (xy 109.404703 -77.746348)
			(xy 109.352801 -77.716378) (xy 109.305255 -77.679889) (xy 109.262878 -77.637508) (xy 109.226394 -77.589957)
			(xy 109.196429 -77.538052) (xy 109.173495 -77.48268) (xy 109.157984 -77.424788) (xy 109.150162 -77.365367)
			(xy 106.928219 -77.365367) (xy 106.928219 -77.365369) (xy 106.920395 -77.424796) (xy 106.904881 -77.482692)
			(xy 106.881942 -77.538068) (xy 106.851971 -77.589975) (xy 106.81548 -77.637527) (xy 106.773095 -77.679908)
			(xy 106.72554 -77.716394) (xy 106.67363 -77.74636) (xy 106.618252 -77.769294) (xy 106.560354 -77.784803)
			(xy 106.500928 -77.792622) (xy 106.470958 -77.793088) (xy 105.607358 -77.793088) (xy 105.577391 -77.792635)
			(xy 105.51797 -77.784807) (xy 105.460079 -77.769291) (xy 105.404708 -77.746351) (xy 105.352805 -77.716381)
			(xy 105.305258 -77.679892) (xy 105.26288 -77.63751) (xy 105.226396 -77.58996) (xy 105.19643 -77.538054)
			(xy 105.173496 -77.482681) (xy 105.157985 -77.424789) (xy 105.150162 -77.365367) (xy 93.565741 -77.365367)
			(xy 93.686884 -77.48651) (xy 93.692381 -77.491501) (xy 93.705546 -77.498355) (xy 93.712792 -77.499972)
			(xy 93.722444 -77.500988) (xy 104.389682 -77.500988) (xy 104.408327 -77.501199) (xy 104.445376 -77.505405)
			(xy 104.463596 -77.50937) (xy 104.487472 -77.515974) (xy 104.488488 -77.516228) (xy 104.490266 -77.51699)
			(xy 104.4956 -77.518514) (xy 104.498394 -77.51953) (xy 104.500426 -77.520546) (xy 104.502204 -77.521054)
			(xy 104.531271 -77.53267) (xy 104.584612 -77.565411) (xy 104.608122 -77.586078) (xy 104.608376 -77.586332)
			(xy 104.611424 -77.589126) (xy 104.617012 -77.594714) (xy 105.149665 -78.127367) (xy 107.150162 -78.127367)
			(xy 107.150162 -78.067433) (xy 107.157984 -78.008012) (xy 107.173496 -77.950119) (xy 107.19643 -77.894747)
			(xy 107.226395 -77.842842) (xy 107.262879 -77.795291) (xy 107.305256 -77.752909) (xy 107.352803 -77.716421)
			(xy 107.404706 -77.68645) (xy 107.460076 -77.66351) (xy 107.517966 -77.647993) (xy 107.577387 -77.640165)
			(xy 107.607354 -77.639672) (xy 108.470954 -77.639672) (xy 108.500924 -77.640178) (xy 108.560351 -77.647996)
			(xy 108.618249 -77.663505) (xy 108.673627 -77.686438) (xy 108.725538 -77.716405) (xy 108.773094 -77.752891)
			(xy 108.815479 -77.795272) (xy 108.85197 -77.842823) (xy 108.881941 -77.894731) (xy 108.90488 -77.950107)
			(xy 108.920395 -78.008004) (xy 108.928219 -78.06743) (xy 108.928219 -78.12737) (xy 108.920395 -78.186796)
			(xy 108.90488 -78.244693) (xy 108.881941 -78.300069) (xy 108.85197 -78.351977) (xy 108.815479 -78.399528)
			(xy 108.773093 -78.441909) (xy 108.725538 -78.478395) (xy 108.673627 -78.508362) (xy 108.618249 -78.531295)
			(xy 108.560351 -78.546804) (xy 108.500924 -78.554622) (xy 108.470954 -78.555088) (xy 107.607354 -78.555088)
			(xy 107.577387 -78.554635) (xy 107.517966 -78.546807) (xy 107.460076 -78.53129) (xy 107.404706 -78.50835)
			(xy 107.352803 -78.478379) (xy 107.305256 -78.441891) (xy 107.262879 -78.399509) (xy 107.226395 -78.351958)
			(xy 107.19643 -78.300053) (xy 107.173496 -78.244681) (xy 107.157984 -78.186788) (xy 107.150162 -78.127367)
			(xy 105.149665 -78.127367) (xy 105.262172 -78.239874) (xy 105.26776 -78.2447) (xy 105.274501 -78.249366)
			(xy 105.290047 -78.25454) (xy 105.29824 -78.25486) (xy 105.34269 -78.25486) (xy 105.368712 -78.25539)
			(xy 105.420112 -78.263563) (xy 105.469605 -78.279662) (xy 105.515977 -78.303293) (xy 105.55809 -78.333875)
			(xy 105.576878 -78.351888) (xy 106.162856 -78.937866) (xy 106.168359 -78.942845) (xy 106.181529 -78.949673)
			(xy 106.188764 -78.951328) (xy 106.198416 -78.952344) (xy 111.916718 -78.952344) (xy 111.926786 -78.952772)
			(xy 111.945381 -78.960496) (xy 111.952786 -78.96733) (xy 112.173512 -79.188056) (xy 112.176363 -79.190762)
			(xy 112.182742 -79.195354) (xy 112.186212 -79.1972) (xy 112.191638 -79.199786) (xy 112.203318 -79.202617)
			(xy 112.209326 -79.202788) (xy 113.627154 -79.202788) (xy 113.636679 -79.202399) (xy 113.654416 -79.195449)
			(xy 113.668383 -79.182495) (xy 113.672874 -79.174086) (xy 113.674144 -79.171038) (xy 113.67685 -79.163867)
			(xy 113.678266 -79.148614) (xy 113.676938 -79.141066) (xy 113.675668 -79.134462) (xy 113.66881 -79.121762)
			(xy 109.194854 -74.647806) (xy 109.176741 -74.629025) (xy 109.146054 -74.586828) (xy 109.12235 -74.540348)
			(xy 109.106215 -74.49073) (xy 109.098046 -74.439198) (xy 109.097572 -74.41311) (xy 109.097572 -71.120762)
			(xy 109.097406 -71.114752) (xy 109.094583 -71.103069) (xy 109.091984 -71.097648) (xy 109.090142 -71.094176)
			(xy 109.085544 -71.087801) (xy 109.08284 -71.084948) (xy 104.639618 -66.641726) (xy 104.621506 -66.622945)
			(xy 104.590824 -66.580748) (xy 104.567127 -66.534267) (xy 104.551 -66.484648) (xy 104.542842 -66.433117)
			(xy 104.542336 -66.40703) (xy 104.542336 -64.714628) (xy 104.541871 -64.703941) (xy 104.533186 -64.684411)
			(xy 104.517307 -64.670104) (xy 104.507284 -64.666368) (xy 104.483916 -64.658748) (xy 104.480082 -64.657586)
			(xy 104.472173 -64.656309) (xy 104.468168 -64.656208) (xy 104.430322 -64.672972) (xy 104.42956 -64.673734)
			(xy 104.417876 -64.68618) (xy 103.78567 -65.318386) (xy 103.76689 -65.3365) (xy 103.724694 -65.367188)
			(xy 103.678213 -65.390891) (xy 103.628594 -65.407023) (xy 103.577062 -65.415188) (xy 103.550974 -65.415668)
			(xy 100.449888 -65.415668) (xy 100.443877 -65.415831) (xy 100.43219 -65.418645) (xy 100.426774 -65.421256)
			(xy 100.423301 -65.423098) (xy 100.416927 -65.427696) (xy 100.414074 -65.4304) (xy 99.966018 -65.878456)
			(xy 99.947248 -65.896489) (xy 99.905132 -65.927071) (xy 99.858755 -65.9507) (xy 99.809258 -65.966794)
			(xy 99.757854 -65.974959) (xy 99.73183 -65.975484) (xy 99.056698 -65.975484) (xy 99.030676 -65.974953)
			(xy 98.979276 -65.966779) (xy 98.929783 -65.950681) (xy 98.88341 -65.927051) (xy 98.841296 -65.896471)
			(xy 98.82251 -65.878456) (xy 98.421698 -65.477644) (xy 98.417837 -65.473918) (xy 98.408869 -65.46803)
			(xy 98.403918 -65.46596) (xy 98.401124 -65.465198) (xy 98.375565 -65.456763) (xy 98.326929 -65.433711)
			(xy 98.282014 -65.404054) (xy 98.241712 -65.36838) (xy 98.206822 -65.327398) (xy 98.178036 -65.28192)
			(xy 98.155926 -65.232849) (xy 98.14093 -65.181158) (xy 98.133345 -65.127873) (xy 98.1329 -65.100962)
			(xy 98.132953 -65.090974) (xy 98.13397 -65.071025) (xy 98.134932 -65.061084) (xy 98.135948 -65.05067)
			(xy 98.132646 -65.040256) (xy 98.130901 -65.035245) (xy 98.125648 -65.026028) (xy 98.122232 -65.021968)
			(xy 98.07194 -64.965834) (xy 98.068198 -64.961857) (xy 98.059359 -64.95545) (xy 98.054414 -64.953134)
			(xy 98.050886 -64.951622) (xy 98.043487 -64.949578) (xy 98.039682 -64.94907) (xy 98.03384 -64.948816)
			(xy 97.514918 -64.948816) (xy 97.505774 -64.949578) (xy 97.498285 -64.951212) (xy 97.484717 -64.958327)
			(xy 97.479104 -64.963548) (xy 96.45269 -65.990216) (xy 96.43392 -66.008249) (xy 96.391804 -66.038831)
			(xy 96.345428 -66.062458) (xy 96.29593 -66.078551) (xy 96.244526 -66.086713) (xy 96.218502 -66.087244)
			(xy 92.92971 -66.087244) (xy 92.923622 -66.087448) (xy 92.911806 -66.090394) (xy 92.906342 -66.093086)
			(xy 92.906088 -66.093086) (xy 92.87856 -66.10692) (xy 92.820146 -66.126497) (xy 92.759345 -66.136426)
			(xy 92.728542 -66.137028) (xy 92.701286 -66.136568) (xy 92.647327 -66.128815) (xy 92.595022 -66.113462)
			(xy 92.545434 -66.090821) (xy 92.499573 -66.061352) (xy 92.458373 -66.025657) (xy 92.422673 -65.984461)
			(xy 92.393199 -65.938603) (xy 92.370552 -65.889018) (xy 92.355193 -65.836714) (xy 92.347435 -65.782756)
			(xy 92.347435 -65.728244) (xy 92.355193 -65.674286) (xy 92.370552 -65.621982) (xy 92.393199 -65.572397)
			(xy 92.422673 -65.526539) (xy 92.458373 -65.485343) (xy 92.499573 -65.449648) (xy 92.545434 -65.420179)
			(xy 92.595022 -65.397538) (xy 92.647327 -65.382185) (xy 92.701286 -65.374432) (xy 92.728542 -65.374012)
			(xy 92.759343 -65.374628) (xy 92.820137 -65.384573) (xy 92.878546 -65.40415) (xy 92.906088 -65.417954)
			(xy 92.906342 -65.417954) (xy 92.911812 -65.420634) (xy 92.923623 -65.423599) (xy 92.92971 -65.423796)
			(xy 96.059498 -65.423796) (xy 96.068642 -65.423034) (xy 96.07613 -65.421399) (xy 96.089697 -65.414282)
			(xy 96.095312 -65.409064) (xy 97.121726 -64.382396) (xy 97.140498 -64.364368) (xy 97.182617 -64.333796)
			(xy 97.228994 -64.310177) (xy 97.278491 -64.294092) (xy 97.329892 -64.285934) (xy 97.355914 -64.285368)
			(xy 103.208836 -64.285368) (xy 103.214846 -64.285202) (xy 103.226529 -64.28238) (xy 103.23195 -64.27978)
			(xy 103.235422 -64.277938) (xy 103.241797 -64.27334) (xy 103.24465 -64.270636) (xy 103.38562 -64.129666)
			(xy 103.388322 -64.126812) (xy 103.392907 -64.12043) (xy 103.394764 -64.116966) (xy 103.39735 -64.11154)
			(xy 103.400178 -64.09986) (xy 103.400352 -64.093852) (xy 103.400352 -54.424326) (xy 103.400304 -54.420455)
			(xy 103.399155 -54.412801) (xy 103.398066 -54.409086) (xy 103.395339 -54.401485) (xy 103.385888 -54.388402)
			(xy 103.379524 -54.383432) (xy 103.313484 -54.335172) (xy 103.308531 -54.331655) (xy 103.297354 -54.326906)
			(xy 103.291386 -54.325774) (xy 103.279448 -54.323996) (xy 103.273352 -54.326028) (xy 103.244381 -54.334942)
			(xy 103.184532 -54.344521) (xy 103.154226 -54.345078) (xy 103.153972 -54.345078) (xy 103.126724 -54.34459)
			(xy 103.072784 -54.336831) (xy 103.020497 -54.321474) (xy 102.970927 -54.298833) (xy 102.925084 -54.269369)
			(xy 102.8839 -54.23368) (xy 102.848214 -54.192494) (xy 102.818753 -54.146649) (xy 102.796116 -54.097077)
			(xy 102.780763 -54.044789) (xy 102.773008 -53.990848) (xy 102.773008 -53.936352) (xy 102.780763 -53.882411)
			(xy 102.796116 -53.830123) (xy 102.818753 -53.780551) (xy 102.848214 -53.734706) (xy 102.8839 -53.69352)
			(xy 102.925084 -53.657831) (xy 102.970927 -53.628367) (xy 103.020497 -53.605726) (xy 103.072784 -53.590369)
			(xy 103.126724 -53.58261) (xy 103.153972 -53.582062) (xy 103.154226 -53.582062) (xy 103.18453 -53.582643)
			(xy 103.24438 -53.592206) (xy 103.273352 -53.601112) (xy 103.279448 -53.603144) (xy 103.291386 -53.601366)
			(xy 103.29734 -53.600189) (xy 103.308509 -53.595445) (xy 103.313484 -53.591968) (xy 103.379524 -53.543708)
			(xy 103.388789 -53.536105) (xy 103.399656 -53.514778) (xy 103.400352 -53.502814) (xy 103.400352 -53.493416)
			(xy 103.400882 -53.467393) (xy 103.409053 -53.415993) (xy 103.425152 -53.366499) (xy 103.448781 -53.320126)
			(xy 103.479363 -53.278012) (xy 103.49738 -53.259228) (xy 103.939848 -52.81676) (xy 103.958617 -52.798724)
			(xy 104.000732 -52.768136) (xy 104.047108 -52.744502) (xy 104.096606 -52.728402) (xy 104.148011 -52.720231)
			(xy 104.174036 -52.719732) (xy 105.121964 -52.719732) (xy 105.12805 -52.719519) (xy 105.139857 -52.716557)
			(xy 105.145332 -52.71389) (xy 105.145586 -52.71389) (xy 105.173113 -52.700052) (xy 105.231526 -52.680467)
			(xy 105.292328 -52.670532) (xy 105.323132 -52.669948) (xy 105.350383 -52.670436) (xy 105.40433 -52.678196)
			(xy 105.456623 -52.693553) (xy 105.506199 -52.716196) (xy 105.552048 -52.745662) (xy 105.593238 -52.781353)
			(xy 105.628931 -52.822542) (xy 105.658399 -52.868391) (xy 105.681042 -52.917966) (xy 105.696402 -52.970259)
			(xy 105.704163 -53.024205) (xy 105.70464 -53.051456) (xy 105.704175 -53.078355) (xy 105.696611 -53.131618)
			(xy 105.681639 -53.18329) (xy 105.659557 -53.232347) (xy 105.630803 -53.277816) (xy 105.595947 -53.318794)
			(xy 105.55568 -53.35447) (xy 105.510801 -53.384136) (xy 105.462199 -53.407204) (xy 105.43667 -53.415692)
			(xy 105.436416 -53.415692) (xy 105.433622 -53.416454) (xy 105.428682 -53.418541) (xy 105.419727 -53.424439)
			(xy 105.415842 -53.428138) (xy 105.310432 -53.533548) (xy 105.095802 -53.747924) (xy 105.090029 -53.754301)
			(xy 105.082767 -53.769883) (xy 105.081578 -53.778404) (xy 105.081324 -53.783484) (xy 105.081324 -57.606692)
			(xy 105.081825 -57.616502) (xy 105.089274 -57.634658) (xy 105.095802 -57.641998) (xy 105.576116 -58.122312)
			(xy 105.594149 -58.141082) (xy 105.624731 -58.183198) (xy 105.648358 -58.229574) (xy 105.66445 -58.279072)
			(xy 105.672612 -58.330476) (xy 105.673144 -58.3565) (xy 105.673144 -66.070226) (xy 105.673188 -66.074097)
			(xy 105.67433 -66.081754) (xy 105.67543 -66.085466) (xy 105.677417 -66.091213) (xy 105.683705 -66.101616)
			(xy 105.687876 -66.10604) (xy 110.06963 -70.48754) (xy 110.087742 -70.506321) (xy 110.118424 -70.548519)
			(xy 110.142122 -70.595) (xy 110.158251 -70.644618) (xy 110.166413 -70.696149) (xy 110.166912 -70.722236)
			(xy 110.166912 -74.03846) (xy 110.167928 -74.049128) (xy 110.169648 -74.056111) (xy 110.176495 -74.068751)
			(xy 110.18139 -74.07402) (xy 114.497612 -78.390496) (xy 114.502048 -78.394652) (xy 114.512444 -78.400946)
			(xy 114.518186 -78.402942) (xy 114.521905 -78.404009) (xy 114.529557 -78.405155) (xy 114.533426 -78.405228)
			(xy 117.612668 -78.405228) (xy 117.638691 -78.405757) (xy 117.690094 -78.413926) (xy 117.73959 -78.430021)
			(xy 117.785965 -78.453648) (xy 117.828083 -78.484227) (xy 117.846856 -78.502256) (xy 124.270262 -84.925662)
			(xy 124.288376 -84.944442) (xy 124.319061 -84.986638) (xy 124.342761 -85.03312) (xy 124.35889 -85.082738)
			(xy 124.367051 -85.134271) (xy 124.367544 -85.160358) (xy 124.367544 -88.660478) (xy 134.653526 -88.660478)
			(xy 134.657597 -88.604856) (xy 134.669723 -88.550419) (xy 134.689646 -88.498328) (xy 134.716942 -88.449693)
			(xy 134.751028 -88.40555) (xy 134.791177 -88.366841) (xy 134.836535 -88.33439) (xy 134.886135 -88.308889)
			(xy 134.938919 -88.290882) (xy 134.993762 -88.280752) (xy 135.049496 -88.278715) (xy 135.104933 -88.284815)
			(xy 135.15889 -88.298921) (xy 135.210219 -88.320733) (xy 135.257825 -88.349787) (xy 135.300693 -88.385462)
			(xy 135.33791 -88.426999) (xy 135.368683 -88.473512) (xy 135.392355 -88.524009) (xy 135.408423 -88.577416)
			(xy 135.416543 -88.632592) (xy 135.417052 -88.660478) (xy 135.416543 -88.688364) (xy 135.408423 -88.74354)
			(xy 135.392355 -88.796947) (xy 135.368683 -88.847444) (xy 135.33791 -88.893957) (xy 135.300693 -88.935494)
			(xy 135.257825 -88.971169) (xy 135.210219 -89.000223) (xy 135.15889 -89.022035) (xy 135.104933 -89.036141)
			(xy 135.049496 -89.042241) (xy 134.993762 -89.040204) (xy 134.938919 -89.030074) (xy 134.886135 -89.012067)
			(xy 134.836535 -88.986566) (xy 134.791177 -88.954115) (xy 134.751028 -88.915406) (xy 134.716942 -88.871263)
			(xy 134.689646 -88.822628) (xy 134.669723 -88.770537) (xy 134.657597 -88.7161) (xy 134.653526 -88.660478)
			(xy 124.367544 -88.660478) (xy 124.367544 -89.176606) (xy 124.546104 -89.176606) (xy 124.550175 -89.120984)
			(xy 124.562301 -89.066547) (xy 124.582224 -89.014456) (xy 124.60952 -88.965821) (xy 124.643606 -88.921678)
			(xy 124.683755 -88.882969) (xy 124.729113 -88.850518) (xy 124.778713 -88.825017) (xy 124.831497 -88.80701)
			(xy 124.88634 -88.79688) (xy 124.942074 -88.794843) (xy 124.997511 -88.800943) (xy 125.051468 -88.815049)
			(xy 125.102797 -88.836861) (xy 125.150403 -88.865915) (xy 125.193271 -88.90159) (xy 125.230488 -88.943127)
			(xy 125.261261 -88.98964) (xy 125.284933 -89.040137) (xy 125.301001 -89.093544) (xy 125.309121 -89.14872)
			(xy 125.30963 -89.176606) (xy 125.309121 -89.204492) (xy 125.3053 -89.230454) (xy 133.320534 -89.230454)
			(xy 133.324605 -89.174832) (xy 133.336731 -89.120395) (xy 133.356654 -89.068304) (xy 133.38395 -89.019669)
			(xy 133.418036 -88.975526) (xy 133.458185 -88.936817) (xy 133.503543 -88.904366) (xy 133.553143 -88.878865)
			(xy 133.605927 -88.860858) (xy 133.66077 -88.850728) (xy 133.716504 -88.848691) (xy 133.771941 -88.854791)
			(xy 133.825898 -88.868897) (xy 133.877227 -88.890709) (xy 133.924833 -88.919763) (xy 133.967701 -88.955438)
			(xy 134.004918 -88.996975) (xy 134.035691 -89.043488) (xy 134.059363 -89.093985) (xy 134.075431 -89.147392)
			(xy 134.083551 -89.202568) (xy 134.08406 -89.230454) (xy 134.083551 -89.25834) (xy 134.075431 -89.313516)
			(xy 134.059363 -89.366923) (xy 134.035691 -89.41742) (xy 134.004918 -89.463933) (xy 133.967701 -89.50547)
			(xy 133.924833 -89.541145) (xy 133.877227 -89.570199) (xy 133.825898 -89.592011) (xy 133.771941 -89.606117)
			(xy 133.716504 -89.612217) (xy 133.66077 -89.61018) (xy 133.605927 -89.60005) (xy 133.553143 -89.582043)
			(xy 133.503543 -89.556542) (xy 133.458185 -89.524091) (xy 133.418036 -89.485382) (xy 133.38395 -89.441239)
			(xy 133.356654 -89.392604) (xy 133.336731 -89.340513) (xy 133.324605 -89.286076) (xy 133.320534 -89.230454)
			(xy 125.3053 -89.230454) (xy 125.301001 -89.259668) (xy 125.284933 -89.313075) (xy 125.261261 -89.363572)
			(xy 125.230488 -89.410085) (xy 125.193271 -89.451622) (xy 125.150403 -89.487297) (xy 125.102797 -89.516351)
			(xy 125.051468 -89.538163) (xy 124.997511 -89.552269) (xy 124.942074 -89.558369) (xy 124.88634 -89.556332)
			(xy 124.831497 -89.546202) (xy 124.778713 -89.528195) (xy 124.729113 -89.502694) (xy 124.683755 -89.470243)
			(xy 124.643606 -89.431534) (xy 124.60952 -89.387391) (xy 124.582224 -89.338756) (xy 124.562301 -89.286665)
			(xy 124.550175 -89.232228) (xy 124.546104 -89.176606) (xy 124.367544 -89.176606) (xy 124.367544 -89.985088)
			(xy 134.64743 -89.985088) (xy 134.651501 -89.929466) (xy 134.663627 -89.875029) (xy 134.68355 -89.822938)
			(xy 134.710846 -89.774303) (xy 134.744932 -89.73016) (xy 134.785081 -89.691451) (xy 134.830439 -89.659)
			(xy 134.880039 -89.633499) (xy 134.932823 -89.615492) (xy 134.987666 -89.605362) (xy 135.0434 -89.603325)
			(xy 135.098837 -89.609425) (xy 135.152794 -89.623531) (xy 135.204123 -89.645343) (xy 135.251729 -89.674397)
			(xy 135.294597 -89.710072) (xy 135.331814 -89.751609) (xy 135.362587 -89.798122) (xy 135.386259 -89.848619)
			(xy 135.402327 -89.902026) (xy 135.410447 -89.957202) (xy 135.410956 -89.985088) (xy 135.410447 -90.012974)
			(xy 135.402327 -90.06815) (xy 135.386259 -90.121557) (xy 135.362587 -90.172054) (xy 135.331814 -90.218567)
			(xy 135.294597 -90.260104) (xy 135.251729 -90.295779) (xy 135.204123 -90.324833) (xy 135.152794 -90.346645)
			(xy 135.098837 -90.360751) (xy 135.0434 -90.366851) (xy 134.987666 -90.364814) (xy 134.932823 -90.354684)
			(xy 134.880039 -90.336677) (xy 134.830439 -90.311176) (xy 134.785081 -90.278725) (xy 134.744932 -90.240016)
			(xy 134.710846 -90.195873) (xy 134.68355 -90.147238) (xy 134.663627 -90.095147) (xy 134.651501 -90.04071)
			(xy 134.64743 -89.985088) (xy 124.367544 -89.985088) (xy 124.367544 -90.706194) (xy 124.7935 -90.706194)
			(xy 124.797571 -90.650572) (xy 124.809697 -90.596135) (xy 124.82962 -90.544044) (xy 124.856916 -90.495409)
			(xy 124.891002 -90.451266) (xy 124.931151 -90.412557) (xy 124.976509 -90.380106) (xy 125.026109 -90.354605)
			(xy 125.078893 -90.336598) (xy 125.133736 -90.326468) (xy 125.18947 -90.324431) (xy 125.244907 -90.330531)
			(xy 125.298864 -90.344637) (xy 125.350193 -90.366449) (xy 125.397799 -90.395503) (xy 125.440667 -90.431178)
			(xy 125.477884 -90.472715) (xy 125.508657 -90.519228) (xy 125.532329 -90.569725) (xy 125.548397 -90.623132)
			(xy 125.556517 -90.678308) (xy 125.557026 -90.706194) (xy 125.556517 -90.73408) (xy 125.548397 -90.789256)
			(xy 125.532329 -90.842663) (xy 125.508657 -90.89316) (xy 125.477884 -90.939673) (xy 125.440667 -90.98121)
			(xy 125.397799 -91.016885) (xy 125.350193 -91.045939) (xy 125.298864 -91.067751) (xy 125.244907 -91.081857)
			(xy 125.18947 -91.087957) (xy 125.133736 -91.08592) (xy 125.078893 -91.07579) (xy 125.026109 -91.057783)
			(xy 124.976509 -91.032282) (xy 124.931151 -90.999831) (xy 124.891002 -90.961122) (xy 124.856916 -90.916979)
			(xy 124.82962 -90.868344) (xy 124.809697 -90.816253) (xy 124.797571 -90.761816) (xy 124.7935 -90.706194)
			(xy 124.367544 -90.706194) (xy 124.367544 -91.327478) (xy 134.913368 -91.327478) (xy 134.917439 -91.271856)
			(xy 134.929565 -91.217419) (xy 134.949488 -91.165328) (xy 134.976784 -91.116693) (xy 135.01087 -91.07255)
			(xy 135.051019 -91.033841) (xy 135.096377 -91.00139) (xy 135.145977 -90.975889) (xy 135.198761 -90.957882)
			(xy 135.253604 -90.947752) (xy 135.309338 -90.945715) (xy 135.364775 -90.951815) (xy 135.418732 -90.965921)
			(xy 135.470061 -90.987733) (xy 135.517667 -91.016787) (xy 135.560535 -91.052462) (xy 135.597752 -91.093999)
			(xy 135.628525 -91.140512) (xy 135.652197 -91.191009) (xy 135.668265 -91.244416) (xy 135.676385 -91.299592)
			(xy 135.676894 -91.327478) (xy 135.676385 -91.355364) (xy 135.668265 -91.41054) (xy 135.652197 -91.463947)
			(xy 135.628525 -91.514444) (xy 135.597752 -91.560957) (xy 135.560535 -91.602494) (xy 135.517667 -91.638169)
			(xy 135.470061 -91.667223) (xy 135.418732 -91.689035) (xy 135.364775 -91.703141) (xy 135.309338 -91.709241)
			(xy 135.253604 -91.707204) (xy 135.198761 -91.697074) (xy 135.145977 -91.679067) (xy 135.096377 -91.653566)
			(xy 135.051019 -91.621115) (xy 135.01087 -91.582406) (xy 134.976784 -91.538263) (xy 134.949488 -91.489628)
			(xy 134.929565 -91.437537) (xy 134.917439 -91.3831) (xy 134.913368 -91.327478) (xy 124.367544 -91.327478)
			(xy 124.367544 -92.179902) (xy 125.607824 -92.179902) (xy 125.611895 -92.12428) (xy 125.624021 -92.069843)
			(xy 125.643944 -92.017752) (xy 125.67124 -91.969117) (xy 125.705326 -91.924974) (xy 125.745475 -91.886265)
			(xy 125.790833 -91.853814) (xy 125.840433 -91.828313) (xy 125.893217 -91.810306) (xy 125.94806 -91.800176)
			(xy 126.003794 -91.798139) (xy 126.059231 -91.804239) (xy 126.113188 -91.818345) (xy 126.164517 -91.840157)
			(xy 126.212123 -91.869211) (xy 126.254991 -91.904886) (xy 126.292208 -91.946423) (xy 126.322981 -91.992936)
			(xy 126.346653 -92.043433) (xy 126.362721 -92.09684) (xy 126.370841 -92.152016) (xy 126.37135 -92.179902)
			(xy 126.370841 -92.207788) (xy 126.362721 -92.262964) (xy 126.346653 -92.316371) (xy 126.322981 -92.366868)
			(xy 126.292208 -92.413381) (xy 126.254991 -92.454918) (xy 126.212123 -92.490593) (xy 126.164517 -92.519647)
			(xy 126.113188 -92.541459) (xy 126.059231 -92.555565) (xy 126.003794 -92.561665) (xy 125.94806 -92.559628)
			(xy 125.893217 -92.549498) (xy 125.840433 -92.531491) (xy 125.790833 -92.50599) (xy 125.745475 -92.473539)
			(xy 125.705326 -92.43483) (xy 125.67124 -92.390687) (xy 125.643944 -92.342052) (xy 125.624021 -92.289961)
			(xy 125.611895 -92.235524) (xy 125.607824 -92.179902) (xy 124.367544 -92.179902) (xy 124.367544 -92.446094)
			(xy 124.37491 -92.453968) (xy 124.375418 -92.454476) (xy 124.381768 -92.459048) (xy 124.41555 -92.47759)
			(xy 124.416058 -92.47759) (xy 124.447554 -92.494354) (xy 124.450348 -92.495878) (xy 124.454699 -92.497773)
			(xy 124.463905 -92.500077) (xy 124.468636 -92.50045) (xy 124.499878 -92.50045) (xy 124.505745 -92.500296)
			(xy 124.517164 -92.497595) (xy 124.522484 -92.495116) (xy 124.525532 -92.493592) (xy 124.528072 -92.492068)
			(xy 124.53239 -92.489528) (xy 124.534168 -92.488512) (xy 124.556331 -92.475954) (xy 124.603297 -92.456229)
			(xy 124.652477 -92.44295) (xy 124.677678 -92.439236) (xy 124.689752 -92.43774) (xy 124.714027 -92.436091)
			(xy 124.726192 -92.435934) (xy 124.727462 -92.435934) (xy 124.754714 -92.436395) (xy 124.808663 -92.444146)
			(xy 124.860959 -92.459497) (xy 124.910539 -92.482135) (xy 124.956392 -92.511599) (xy 124.997584 -92.547289)
			(xy 125.033278 -92.588478) (xy 125.062747 -92.634328) (xy 125.067842 -92.645484) (xy 135.053576 -92.645484)
			(xy 135.057647 -92.589862) (xy 135.069773 -92.535425) (xy 135.089696 -92.483334) (xy 135.116992 -92.434699)
			(xy 135.151078 -92.390556) (xy 135.191227 -92.351847) (xy 135.236585 -92.319396) (xy 135.286185 -92.293895)
			(xy 135.338969 -92.275888) (xy 135.393812 -92.265758) (xy 135.449546 -92.263721) (xy 135.504983 -92.269821)
			(xy 135.55894 -92.283927) (xy 135.610269 -92.305739) (xy 135.657875 -92.334793) (xy 135.700743 -92.370468)
			(xy 135.73796 -92.412005) (xy 135.768733 -92.458518) (xy 135.792405 -92.509015) (xy 135.808473 -92.562422)
			(xy 135.816593 -92.617598) (xy 135.817102 -92.645484) (xy 135.816593 -92.67337) (xy 135.808473 -92.728546)
			(xy 135.792405 -92.781953) (xy 135.768733 -92.83245) (xy 135.73796 -92.878963) (xy 135.700743 -92.9205)
			(xy 135.657875 -92.956175) (xy 135.610269 -92.985229) (xy 135.55894 -93.007041) (xy 135.504983 -93.021147)
			(xy 135.449546 -93.027247) (xy 135.393812 -93.02521) (xy 135.338969 -93.01508) (xy 135.286185 -92.997073)
			(xy 135.236585 -92.971572) (xy 135.191227 -92.939121) (xy 135.151078 -92.900412) (xy 135.116992 -92.856269)
			(xy 135.089696 -92.807634) (xy 135.069773 -92.755543) (xy 135.057647 -92.701106) (xy 135.053576 -92.645484)
			(xy 125.067842 -92.645484) (xy 125.085389 -92.683905) (xy 125.100746 -92.7362) (xy 125.108503 -92.790148)
			(xy 125.108503 -92.844652) (xy 125.100746 -92.8986) (xy 125.085389 -92.950895) (xy 125.062747 -93.000472)
			(xy 125.033278 -93.046322) (xy 124.997584 -93.087511) (xy 124.956392 -93.123201) (xy 124.910539 -93.152665)
			(xy 124.860959 -93.175303) (xy 124.808663 -93.190654) (xy 124.754714 -93.198405) (xy 124.727462 -93.19895)
			(xy 124.727208 -93.19895) (xy 124.700178 -93.198484) (xy 124.64666 -93.190851) (xy 124.59476 -93.175722)
			(xy 124.545523 -93.153404) (xy 124.522484 -93.13926) (xy 124.521976 -93.139006) (xy 124.517404 -93.136212)
			(xy 124.508768 -93.132402) (xy 124.4981 -93.1291) (xy 124.494242 -93.128119) (xy 124.486332 -93.127222)
			(xy 124.482352 -93.127322) (xy 124.482098 -93.127322) (xy 124.478404 -93.127557) (xy 124.471138 -93.128964)
			(xy 124.46762 -93.130116) (xy 124.462794 -93.131894) (xy 124.461778 -93.132402) (xy 124.380752 -93.176598)
			(xy 124.376991 -93.179109) (xy 124.370344 -93.18524) (xy 124.367544 -93.18879) (xy 124.367544 -93.8403)
			(xy 125.868174 -93.8403) (xy 125.872245 -93.784678) (xy 125.884371 -93.730241) (xy 125.904294 -93.67815)
			(xy 125.93159 -93.629515) (xy 125.965676 -93.585372) (xy 126.005825 -93.546663) (xy 126.051183 -93.514212)
			(xy 126.100783 -93.488711) (xy 126.153567 -93.470704) (xy 126.20841 -93.460574) (xy 126.264144 -93.458537)
			(xy 126.319581 -93.464637) (xy 126.373538 -93.478743) (xy 126.424867 -93.500555) (xy 126.472473 -93.529609)
			(xy 126.515341 -93.565284) (xy 126.552558 -93.606821) (xy 126.583331 -93.653334) (xy 126.607003 -93.703831)
			(xy 126.623071 -93.757238) (xy 126.624604 -93.767656) (xy 133.93623 -93.767656) (xy 133.940301 -93.712034)
			(xy 133.952427 -93.657597) (xy 133.97235 -93.605506) (xy 133.999646 -93.556871) (xy 134.033732 -93.512728)
			(xy 134.073881 -93.474019) (xy 134.119239 -93.441568) (xy 134.168839 -93.416067) (xy 134.221623 -93.39806)
			(xy 134.276466 -93.38793) (xy 134.3322 -93.385893) (xy 134.387637 -93.391993) (xy 134.441594 -93.406099)
			(xy 134.492923 -93.427911) (xy 134.540529 -93.456965) (xy 134.583397 -93.49264) (xy 134.620614 -93.534177)
			(xy 134.651387 -93.58069) (xy 134.675059 -93.631187) (xy 134.691127 -93.684594) (xy 134.699247 -93.73977)
			(xy 134.699756 -93.767656) (xy 134.699247 -93.795542) (xy 134.691127 -93.850718) (xy 134.675059 -93.904125)
			(xy 134.651387 -93.954622) (xy 134.620614 -94.001135) (xy 134.583397 -94.042672) (xy 134.540529 -94.078347)
			(xy 134.492923 -94.107401) (xy 134.441594 -94.129213) (xy 134.387637 -94.143319) (xy 134.3322 -94.149419)
			(xy 134.276466 -94.147382) (xy 134.221623 -94.137252) (xy 134.168839 -94.119245) (xy 134.119239 -94.093744)
			(xy 134.073881 -94.061293) (xy 134.033732 -94.022584) (xy 133.999646 -93.978441) (xy 133.97235 -93.929806)
			(xy 133.952427 -93.877715) (xy 133.940301 -93.823278) (xy 133.93623 -93.767656) (xy 126.624604 -93.767656)
			(xy 126.631191 -93.812414) (xy 126.6317 -93.8403) (xy 126.631191 -93.868186) (xy 126.623071 -93.923362)
			(xy 126.607003 -93.976769) (xy 126.583331 -94.027266) (xy 126.552558 -94.073779) (xy 126.515341 -94.115316)
			(xy 126.472473 -94.150991) (xy 126.424867 -94.180045) (xy 126.373538 -94.201857) (xy 126.319581 -94.215963)
			(xy 126.264144 -94.222063) (xy 126.20841 -94.220026) (xy 126.153567 -94.209896) (xy 126.100783 -94.191889)
			(xy 126.051183 -94.166388) (xy 126.005825 -94.133937) (xy 125.965676 -94.095228) (xy 125.93159 -94.051085)
			(xy 125.904294 -94.00245) (xy 125.884371 -93.950359) (xy 125.872245 -93.895922) (xy 125.868174 -93.8403)
			(xy 124.367544 -93.8403) (xy 124.367544 -94.451424) (xy 135.029192 -94.451424) (xy 135.033263 -94.395802)
			(xy 135.045389 -94.341365) (xy 135.065312 -94.289274) (xy 135.092608 -94.240639) (xy 135.126694 -94.196496)
			(xy 135.166843 -94.157787) (xy 135.212201 -94.125336) (xy 135.261801 -94.099835) (xy 135.314585 -94.081828)
			(xy 135.369428 -94.071698) (xy 135.425162 -94.069661) (xy 135.480599 -94.075761) (xy 135.534556 -94.089867)
			(xy 135.585885 -94.111679) (xy 135.633491 -94.140733) (xy 135.676359 -94.176408) (xy 135.713576 -94.217945)
			(xy 135.744349 -94.264458) (xy 135.768021 -94.314955) (xy 135.784089 -94.368362) (xy 135.792209 -94.423538)
			(xy 135.792718 -94.451424) (xy 135.792209 -94.47931) (xy 135.784089 -94.534486) (xy 135.768021 -94.587893)
			(xy 135.744349 -94.63839) (xy 135.713576 -94.684903) (xy 135.676359 -94.72644) (xy 135.633491 -94.762115)
			(xy 135.585885 -94.791169) (xy 135.534556 -94.812981) (xy 135.480599 -94.827087) (xy 135.425162 -94.833187)
			(xy 135.369428 -94.83115) (xy 135.314585 -94.82102) (xy 135.261801 -94.803013) (xy 135.212201 -94.777512)
			(xy 135.166843 -94.745061) (xy 135.126694 -94.706352) (xy 135.092608 -94.662209) (xy 135.065312 -94.613574)
			(xy 135.045389 -94.561483) (xy 135.033263 -94.507046) (xy 135.029192 -94.451424) (xy 124.367544 -94.451424)
			(xy 124.367544 -94.49308) (xy 124.37237 -94.498668) (xy 124.377196 -94.503494) (xy 124.384308 -94.509336)
			(xy 124.428504 -94.53626) (xy 124.428758 -94.536514) (xy 124.451872 -94.550484) (xy 124.457403 -94.553182)
			(xy 124.469344 -94.556139) (xy 124.475494 -94.556326) (xy 124.490226 -94.556326) (xy 124.496094 -94.556178)
			(xy 124.507518 -94.553486) (xy 124.512832 -94.550992) (xy 124.51334 -94.550738) (xy 124.540041 -94.537929)
			(xy 124.596422 -94.519817) (xy 124.654927 -94.510653) (xy 124.684536 -94.510098) (xy 124.6886 -94.510098)
			(xy 124.716139 -94.510863) (xy 124.770575 -94.519342) (xy 124.823225 -94.53556) (xy 124.872996 -94.55918)
			(xy 124.918854 -94.589711) (xy 124.959844 -94.626519) (xy 124.995116 -94.668839) (xy 125.023936 -94.715791)
			(xy 125.045706 -94.7664) (xy 125.059971 -94.819612) (xy 125.063758 -94.846902) (xy 125.064774 -94.855538)
			(xy 125.065282 -94.86138) (xy 125.066552 -94.891606) (xy 125.06606 -94.919274) (xy 125.058071 -94.974032)
			(xy 125.042263 -95.027063) (xy 125.018965 -95.077256) (xy 124.988666 -95.123561) (xy 124.952 -95.165008)
			(xy 124.909736 -95.200728) (xy 124.862758 -95.229973) (xy 124.812052 -95.252131) (xy 124.758677 -95.266738)
			(xy 124.731272 -95.270574) (xy 124.715016 -95.272098) (xy 124.685552 -95.273368) (xy 124.678694 -95.273368)
			(xy 124.649693 -95.272362) (xy 124.592484 -95.262658) (xy 124.537404 -95.244403) (xy 124.511308 -95.231712)
			(xy 124.50953 -95.230696) (xy 124.50572 -95.228918) (xy 124.49302 -95.225616) (xy 124.48794 -95.2246)
			(xy 124.479244 -95.223639) (xy 124.462091 -95.227013) (xy 124.454412 -95.231204) (xy 124.454158 -95.231458)
			(xy 124.380244 -95.276162) (xy 124.376638 -95.278652) (xy 124.370256 -95.284657) (xy 124.367544 -95.2881)
			(xy 124.367544 -95.892874) (xy 125.538482 -95.892874) (xy 125.542553 -95.837252) (xy 125.554679 -95.782815)
			(xy 125.574602 -95.730724) (xy 125.601898 -95.682089) (xy 125.635984 -95.637946) (xy 125.676133 -95.599237)
			(xy 125.721491 -95.566786) (xy 125.771091 -95.541285) (xy 125.823875 -95.523278) (xy 125.878718 -95.513148)
			(xy 125.934452 -95.511111) (xy 125.989889 -95.517211) (xy 125.999593 -95.519748) (xy 134.274558 -95.519748)
			(xy 134.278629 -95.464126) (xy 134.290755 -95.409689) (xy 134.310678 -95.357598) (xy 134.337974 -95.308963)
			(xy 134.37206 -95.26482) (xy 134.412209 -95.226111) (xy 134.457567 -95.19366) (xy 134.507167 -95.168159)
			(xy 134.559951 -95.150152) (xy 134.614794 -95.140022) (xy 134.670528 -95.137985) (xy 134.725965 -95.144085)
			(xy 134.779922 -95.158191) (xy 134.831251 -95.180003) (xy 134.878857 -95.209057) (xy 134.921725 -95.244732)
			(xy 134.958942 -95.286269) (xy 134.989715 -95.332782) (xy 135.013387 -95.383279) (xy 135.029455 -95.436686)
			(xy 135.037575 -95.491862) (xy 135.038084 -95.519748) (xy 135.037575 -95.547634) (xy 135.029455 -95.60281)
			(xy 135.013387 -95.656217) (xy 134.989715 -95.706714) (xy 134.958942 -95.753227) (xy 134.921725 -95.794764)
			(xy 134.878857 -95.830439) (xy 134.831251 -95.859493) (xy 134.779922 -95.881305) (xy 134.725965 -95.895411)
			(xy 134.670528 -95.901511) (xy 134.614794 -95.899474) (xy 134.559951 -95.889344) (xy 134.507167 -95.871337)
			(xy 134.457567 -95.845836) (xy 134.412209 -95.813385) (xy 134.37206 -95.774676) (xy 134.337974 -95.730533)
			(xy 134.310678 -95.681898) (xy 134.290755 -95.629807) (xy 134.278629 -95.57537) (xy 134.274558 -95.519748)
			(xy 125.999593 -95.519748) (xy 126.043846 -95.531317) (xy 126.095175 -95.553129) (xy 126.142781 -95.582183)
			(xy 126.185649 -95.617858) (xy 126.222866 -95.659395) (xy 126.253639 -95.705908) (xy 126.277311 -95.756405)
			(xy 126.293379 -95.809812) (xy 126.301499 -95.864988) (xy 126.302008 -95.892874) (xy 126.301499 -95.92076)
			(xy 126.293379 -95.975936) (xy 126.277311 -96.029343) (xy 126.253639 -96.07984) (xy 126.222866 -96.126353)
			(xy 126.185649 -96.16789) (xy 126.142781 -96.203565) (xy 126.095175 -96.232619) (xy 126.043846 -96.254431)
			(xy 125.989889 -96.268537) (xy 125.934452 -96.274637) (xy 125.878718 -96.2726) (xy 125.823875 -96.26247)
			(xy 125.771091 -96.244463) (xy 125.721491 -96.218962) (xy 125.676133 -96.186511) (xy 125.635984 -96.147802)
			(xy 125.601898 -96.103659) (xy 125.574602 -96.055024) (xy 125.554679 -96.002933) (xy 125.542553 -95.948496)
			(xy 125.538482 -95.892874) (xy 124.367544 -95.892874) (xy 124.367544 -96.440498) (xy 128.268982 -96.440498)
			(xy 128.273053 -96.384876) (xy 128.285179 -96.330439) (xy 128.305102 -96.278348) (xy 128.332398 -96.229713)
			(xy 128.366484 -96.18557) (xy 128.406633 -96.146861) (xy 128.451991 -96.11441) (xy 128.501591 -96.088909)
			(xy 128.554375 -96.070902) (xy 128.609218 -96.060772) (xy 128.664952 -96.058735) (xy 128.720389 -96.064835)
			(xy 128.774346 -96.078941) (xy 128.825675 -96.100753) (xy 128.873281 -96.129807) (xy 128.916149 -96.165482)
			(xy 128.953366 -96.207019) (xy 128.984139 -96.253532) (xy 129.007811 -96.304029) (xy 129.023879 -96.357436)
			(xy 129.031999 -96.412612) (xy 129.032508 -96.440498) (xy 129.031999 -96.468384) (xy 129.023879 -96.52356)
			(xy 129.007811 -96.576967) (xy 128.984139 -96.627464) (xy 128.953366 -96.673977) (xy 128.920869 -96.710246)
			(xy 134.734044 -96.710246) (xy 134.738115 -96.654624) (xy 134.750241 -96.600187) (xy 134.770164 -96.548096)
			(xy 134.79746 -96.499461) (xy 134.831546 -96.455318) (xy 134.871695 -96.416609) (xy 134.917053 -96.384158)
			(xy 134.966653 -96.358657) (xy 135.019437 -96.34065) (xy 135.07428 -96.33052) (xy 135.130014 -96.328483)
			(xy 135.185451 -96.334583) (xy 135.239408 -96.348689) (xy 135.290737 -96.370501) (xy 135.338343 -96.399555)
			(xy 135.381211 -96.43523) (xy 135.418428 -96.476767) (xy 135.449201 -96.52328) (xy 135.472873 -96.573777)
			(xy 135.488941 -96.627184) (xy 135.497061 -96.68236) (xy 135.49757 -96.710246) (xy 135.497061 -96.738132)
			(xy 135.488941 -96.793308) (xy 135.472873 -96.846715) (xy 135.449201 -96.897212) (xy 135.418428 -96.943725)
			(xy 135.381211 -96.985262) (xy 135.338343 -97.020937) (xy 135.290737 -97.049991) (xy 135.239408 -97.071803)
			(xy 135.185451 -97.085909) (xy 135.130014 -97.092009) (xy 135.07428 -97.089972) (xy 135.019437 -97.079842)
			(xy 134.966653 -97.061835) (xy 134.917053 -97.036334) (xy 134.871695 -97.003883) (xy 134.831546 -96.965174)
			(xy 134.79746 -96.921031) (xy 134.770164 -96.872396) (xy 134.750241 -96.820305) (xy 134.738115 -96.765868)
			(xy 134.734044 -96.710246) (xy 128.920869 -96.710246) (xy 128.916149 -96.715514) (xy 128.873281 -96.751189)
			(xy 128.825675 -96.780243) (xy 128.774346 -96.802055) (xy 128.720389 -96.816161) (xy 128.664952 -96.822261)
			(xy 128.609218 -96.820224) (xy 128.554375 -96.810094) (xy 128.501591 -96.792087) (xy 128.451991 -96.766586)
			(xy 128.406633 -96.734135) (xy 128.366484 -96.695426) (xy 128.332398 -96.651283) (xy 128.305102 -96.602648)
			(xy 128.285179 -96.550557) (xy 128.273053 -96.49612) (xy 128.268982 -96.440498) (xy 124.367544 -96.440498)
			(xy 124.367544 -96.774254) (xy 124.37237 -96.779842) (xy 124.377196 -96.784668) (xy 124.384308 -96.79051)
			(xy 124.428504 -96.817434) (xy 124.428758 -96.817688) (xy 124.451872 -96.831658) (xy 124.457402 -96.834357)
			(xy 124.469343 -96.837316) (xy 124.475494 -96.8375) (xy 124.490226 -96.8375) (xy 124.496093 -96.837339)
			(xy 124.507515 -96.834651) (xy 124.512832 -96.832166) (xy 124.51334 -96.831912) (xy 124.54004 -96.819101)
			(xy 124.596421 -96.800985) (xy 124.654926 -96.791819) (xy 124.684536 -96.791272) (xy 124.6886 -96.791272)
			(xy 124.71614 -96.792037) (xy 124.770577 -96.800515) (xy 124.823228 -96.816733) (xy 124.873001 -96.840353)
			(xy 124.91886 -96.870883) (xy 124.959853 -96.907691) (xy 124.995128 -96.95001) (xy 125.023951 -96.996962)
			(xy 125.045723 -97.04757) (xy 125.059992 -97.100783) (xy 125.063758 -97.128076) (xy 125.064774 -97.136712)
			(xy 125.065282 -97.142554) (xy 125.066552 -97.17278) (xy 125.066055 -97.200445) (xy 125.058057 -97.255195)
			(xy 125.042242 -97.308217) (xy 125.01894 -97.358401) (xy 124.988639 -97.404697) (xy 124.951973 -97.446134)
			(xy 124.90971 -97.481846) (xy 124.862736 -97.511085) (xy 124.812034 -97.533237) (xy 124.758665 -97.54784)
			(xy 124.731272 -97.551748) (xy 124.715016 -97.553272) (xy 124.685552 -97.554542) (xy 124.678694 -97.554542)
			(xy 124.649693 -97.553536) (xy 124.592485 -97.543832) (xy 124.537405 -97.525575) (xy 124.511308 -97.512886)
			(xy 124.50953 -97.51187) (xy 124.50572 -97.510092) (xy 124.49302 -97.50679) (xy 124.48794 -97.505774)
			(xy 124.479245 -97.504813) (xy 124.462093 -97.508191) (xy 124.454412 -97.512378) (xy 124.454158 -97.512632)
			(xy 124.380244 -97.557336) (xy 124.376637 -97.559825) (xy 124.370252 -97.565828) (xy 124.367544 -97.569274)
			(xy 124.367544 -98.27006) (xy 125.399544 -98.27006) (xy 125.403615 -98.214438) (xy 125.415741 -98.160001)
			(xy 125.435664 -98.10791) (xy 125.46296 -98.059275) (xy 125.497046 -98.015132) (xy 125.537195 -97.976423)
			(xy 125.582553 -97.943972) (xy 125.632153 -97.918471) (xy 125.684937 -97.900464) (xy 125.73978 -97.890334)
			(xy 125.795514 -97.888297) (xy 125.850951 -97.894397) (xy 125.904908 -97.908503) (xy 125.956237 -97.930315)
			(xy 126.003843 -97.959369) (xy 126.028929 -97.980246) (xy 134.734044 -97.980246) (xy 134.738115 -97.924624)
			(xy 134.750241 -97.870187) (xy 134.770164 -97.818096) (xy 134.79746 -97.769461) (xy 134.831546 -97.725318)
			(xy 134.871695 -97.686609) (xy 134.917053 -97.654158) (xy 134.966653 -97.628657) (xy 135.019437 -97.61065)
			(xy 135.07428 -97.60052) (xy 135.130014 -97.598483) (xy 135.185451 -97.604583) (xy 135.239408 -97.618689)
			(xy 135.290737 -97.640501) (xy 135.338343 -97.669555) (xy 135.381211 -97.70523) (xy 135.418428 -97.746767)
			(xy 135.449201 -97.79328) (xy 135.472873 -97.843777) (xy 135.488941 -97.897184) (xy 135.497061 -97.95236)
			(xy 135.49757 -97.980246) (xy 135.497061 -98.008132) (xy 135.488941 -98.063308) (xy 135.472873 -98.116715)
			(xy 135.449201 -98.167212) (xy 135.418428 -98.213725) (xy 135.381211 -98.255262) (xy 135.338343 -98.290937)
			(xy 135.290737 -98.319991) (xy 135.239408 -98.341803) (xy 135.185451 -98.355909) (xy 135.130014 -98.362009)
			(xy 135.07428 -98.359972) (xy 135.019437 -98.349842) (xy 134.966653 -98.331835) (xy 134.917053 -98.306334)
			(xy 134.871695 -98.273883) (xy 134.831546 -98.235174) (xy 134.79746 -98.191031) (xy 134.770164 -98.142396)
			(xy 134.750241 -98.090305) (xy 134.738115 -98.035868) (xy 134.734044 -97.980246) (xy 126.028929 -97.980246)
			(xy 126.046711 -97.995044) (xy 126.083928 -98.036581) (xy 126.114701 -98.083094) (xy 126.138373 -98.133591)
			(xy 126.154441 -98.186998) (xy 126.162561 -98.242174) (xy 126.16307 -98.27006) (xy 126.162561 -98.297946)
			(xy 126.154441 -98.353122) (xy 126.138373 -98.406529) (xy 126.114701 -98.457026) (xy 126.083928 -98.503539)
			(xy 126.046711 -98.545076) (xy 126.003843 -98.580751) (xy 125.956237 -98.609805) (xy 125.904908 -98.631617)
			(xy 125.850951 -98.645723) (xy 125.795514 -98.651823) (xy 125.73978 -98.649786) (xy 125.684937 -98.639656)
			(xy 125.632153 -98.621649) (xy 125.582553 -98.596148) (xy 125.537195 -98.563697) (xy 125.497046 -98.524988)
			(xy 125.46296 -98.480845) (xy 125.435664 -98.43221) (xy 125.415741 -98.380119) (xy 125.403615 -98.325682)
			(xy 125.399544 -98.27006) (xy 124.367544 -98.27006) (xy 124.367544 -99.139756) (xy 124.370823 -99.143876)
			(xy 124.378762 -99.150789) (xy 124.383292 -99.153472) (xy 124.408692 -99.164902) (xy 124.4092 -99.16541)
			(xy 124.474986 -99.194112) (xy 124.481519 -99.196421) (xy 124.495297 -99.197834) (xy 124.502164 -99.196906)
			(xy 124.509022 -99.195636) (xy 124.521976 -99.18954) (xy 124.527818 -99.183952) (xy 124.549121 -99.164925)
			(xy 124.596322 -99.132763) (xy 124.647787 -99.107991) (xy 124.702368 -99.091163) (xy 124.758848 -99.082655)
			(xy 124.787406 -99.082098) (xy 124.814657 -99.082584) (xy 124.868603 -99.090341) (xy 124.920896 -99.105697)
			(xy 124.970472 -99.128338) (xy 125.016321 -99.157804) (xy 125.057509 -99.193495) (xy 125.0932 -99.234684)
			(xy 125.098957 -99.243642) (xy 135.047988 -99.243642) (xy 135.052059 -99.18802) (xy 135.064185 -99.133583)
			(xy 135.084108 -99.081492) (xy 135.111404 -99.032857) (xy 135.14549 -98.988714) (xy 135.185639 -98.950005)
			(xy 135.230997 -98.917554) (xy 135.280597 -98.892053) (xy 135.333381 -98.874046) (xy 135.388224 -98.863916)
			(xy 135.443958 -98.861879) (xy 135.499395 -98.867979) (xy 135.553352 -98.882085) (xy 135.604681 -98.903897)
			(xy 135.652287 -98.932951) (xy 135.695155 -98.968626) (xy 135.732372 -99.010163) (xy 135.763145 -99.056676)
			(xy 135.786817 -99.107173) (xy 135.802885 -99.16058) (xy 135.811005 -99.215756) (xy 135.811514 -99.243642)
			(xy 135.811005 -99.271528) (xy 135.802885 -99.326704) (xy 135.786817 -99.380111) (xy 135.763145 -99.430608)
			(xy 135.732372 -99.477121) (xy 135.695155 -99.518658) (xy 135.652287 -99.554333) (xy 135.604681 -99.583387)
			(xy 135.553352 -99.605199) (xy 135.499395 -99.619305) (xy 135.443958 -99.625405) (xy 135.388224 -99.623368)
			(xy 135.333381 -99.613238) (xy 135.280597 -99.595231) (xy 135.230997 -99.56973) (xy 135.185639 -99.537279)
			(xy 135.14549 -99.49857) (xy 135.111404 -99.454427) (xy 135.084108 -99.405792) (xy 135.064185 -99.353701)
			(xy 135.052059 -99.299264) (xy 135.047988 -99.243642) (xy 125.098957 -99.243642) (xy 125.122665 -99.280534)
			(xy 125.145305 -99.33011) (xy 125.16066 -99.382403) (xy 125.168416 -99.436349) (xy 125.168416 -99.490851)
			(xy 125.16066 -99.544797) (xy 125.145305 -99.59709) (xy 125.122665 -99.646666) (xy 125.0932 -99.692516)
			(xy 125.057509 -99.733705) (xy 125.016321 -99.769396) (xy 124.970472 -99.798862) (xy 124.920896 -99.821503)
			(xy 124.868603 -99.836859) (xy 124.814657 -99.844616) (xy 124.787406 -99.845114) (xy 124.772674 -99.845114)
			(xy 124.74631 -99.843652) (xy 124.694333 -99.834361) (xy 124.644135 -99.817984) (xy 124.59668 -99.794833)
			(xy 124.552875 -99.765353) (xy 124.532898 -99.748086) (xy 124.527564 -99.74326) (xy 124.513086 -99.736148)
			(xy 124.504958 -99.7331) (xy 124.499365 -99.731628) (xy 124.48782 -99.730984) (xy 124.482098 -99.73183)
			(xy 124.470668 -99.735132) (xy 124.41682 -99.7585) (xy 124.387864 -99.7712) (xy 124.380498 -99.774502)
			(xy 124.374656 -99.777042) (xy 124.373894 -99.777296) (xy 124.371608 -99.780598) (xy 124.369576 -99.78771)
			(xy 124.36863 -99.79119) (xy 124.367616 -99.798329) (xy 124.367544 -99.801934) (xy 124.367544 -100.978208)
			(xy 134.74395 -100.978208) (xy 134.748021 -100.922586) (xy 134.760147 -100.868149) (xy 134.78007 -100.816058)
			(xy 134.807366 -100.767423) (xy 134.841452 -100.72328) (xy 134.881601 -100.684571) (xy 134.926959 -100.65212)
			(xy 134.976559 -100.626619) (xy 135.029343 -100.608612) (xy 135.084186 -100.598482) (xy 135.13992 -100.596445)
			(xy 135.195357 -100.602545) (xy 135.249314 -100.616651) (xy 135.300643 -100.638463) (xy 135.348249 -100.667517)
			(xy 135.391117 -100.703192) (xy 135.428334 -100.744729) (xy 135.459107 -100.791242) (xy 135.482779 -100.841739)
			(xy 135.498847 -100.895146) (xy 135.506967 -100.950322) (xy 135.507476 -100.978208) (xy 135.506967 -101.006094)
			(xy 135.498847 -101.06127) (xy 135.482779 -101.114677) (xy 135.459107 -101.165174) (xy 135.428334 -101.211687)
			(xy 135.391117 -101.253224) (xy 135.348249 -101.288899) (xy 135.300643 -101.317953) (xy 135.249314 -101.339765)
			(xy 135.195357 -101.353871) (xy 135.13992 -101.359971) (xy 135.084186 -101.357934) (xy 135.029343 -101.347804)
			(xy 134.976559 -101.329797) (xy 134.926959 -101.304296) (xy 134.881601 -101.271845) (xy 134.841452 -101.233136)
			(xy 134.807366 -101.188993) (xy 134.78007 -101.140358) (xy 134.760147 -101.088267) (xy 134.748021 -101.03383)
			(xy 134.74395 -100.978208) (xy 124.367544 -100.978208) (xy 124.367544 -102.639368) (xy 124.36706 -102.665456)
			(xy 124.358898 -102.71699) (xy 124.342769 -102.766611) (xy 124.319071 -102.813095) (xy 124.288389 -102.855296)
			(xy 124.270262 -102.874064) (xy 124.228352 -102.915974) (xy 124.227844 -102.923086) (xy 124.227844 -104.439466)
			(xy 124.229186 -104.451876) (xy 124.241811 -104.473362) (xy 124.251974 -104.480614) (xy 124.261372 -104.484932)
			(xy 124.281438 -104.492298) (xy 124.281946 -104.492298) (xy 124.355352 -104.517952) (xy 124.362464 -104.519476)
			(xy 124.366274 -104.51973) (xy 124.370645 -104.519882) (xy 124.379331 -104.518865) (xy 124.383546 -104.517698)
			(xy 124.391166 -104.515412) (xy 124.40412 -104.506776) (xy 124.4092 -104.500172) (xy 124.427392 -104.477732)
			(xy 124.469396 -104.438077) (xy 124.516897 -104.405205) (xy 124.56881 -104.379868) (xy 124.623949 -104.362644)
			(xy 124.681053 -104.353928) (xy 124.709936 -104.35336) (xy 124.715778 -104.35336) (xy 124.742767 -104.354223)
			(xy 124.796109 -104.362619) (xy 124.847734 -104.378452) (xy 124.89661 -104.401407) (xy 124.94176 -104.431025)
			(xy 124.982283 -104.466714) (xy 125.017369 -104.507761) (xy 125.046315 -104.553345) (xy 125.068544 -104.602555)
			(xy 125.083612 -104.654409) (xy 125.091217 -104.707869) (xy 125.091698 -104.734868) (xy 125.091196 -104.762606)
			(xy 125.083155 -104.817495) (xy 125.067253 -104.870643) (xy 125.043825 -104.920929) (xy 125.013365 -104.967294)
			(xy 124.976513 -105.00876) (xy 124.934046 -105.044455) (xy 124.88686 -105.073627) (xy 124.835948 -105.095661)
			(xy 124.782382 -105.110092) (xy 124.754894 -105.113836) (xy 124.741178 -105.11536) (xy 124.719842 -105.116376)
			(xy 124.718826 -105.116376) (xy 124.710698 -105.11663) (xy 124.709682 -105.11663) (xy 124.681665 -105.1161)
			(xy 124.626241 -105.107839) (xy 124.572619 -105.091571) (xy 124.521949 -105.067644) (xy 124.475317 -105.036571)
			(xy 124.433725 -104.99902) (xy 124.41555 -104.977692) (xy 124.411994 -104.973628) (xy 124.406152 -104.968802)
			(xy 124.398278 -104.963976) (xy 124.394976 -104.962452) (xy 124.381006 -104.955848) (xy 124.373233 -104.95309)
			(xy 124.356774 -104.952174) (xy 124.348748 -104.95407) (xy 124.307092 -104.968548) (xy 124.306584 -104.968548)
			(xy 124.26569 -104.983026) (xy 124.254768 -104.986836) (xy 124.242576 -104.999028) (xy 124.239056 -105.002759)
			(xy 124.23343 -105.011335) (xy 124.2314 -105.016046) (xy 124.227844 -105.024682) (xy 124.227844 -105.903268)
			(xy 124.228395 -105.913623) (xy 124.236661 -105.93262) (xy 124.243846 -105.940098) (xy 124.24918 -105.94467)
			(xy 124.271466 -105.957586) (xy 124.312666 -105.988503) (xy 124.349332 -106.024682) (xy 124.380798 -106.065464)
			(xy 124.406491 -106.110109) (xy 124.425945 -106.157804) (xy 124.438805 -106.207683) (xy 124.44222 -106.233214)
			(xy 124.443744 -106.246676) (xy 124.445014 -106.277664) (xy 124.445014 -106.277918) (xy 124.444511 -106.306047)
			(xy 124.436246 -106.361695) (xy 124.419899 -106.415526) (xy 124.395825 -106.466372) (xy 124.364544 -106.513132)
			(xy 124.326735 -106.554791) (xy 124.283218 -106.590447) (xy 124.25934 -106.605324) (xy 124.258832 -106.605832)
			(xy 124.249688 -106.61142) (xy 124.244354 -106.615484) (xy 124.239528 -106.620056) (xy 124.234194 -106.628946)
			(xy 124.231756 -106.633572) (xy 124.228671 -106.643561) (xy 124.228098 -106.648758) (xy 124.228098 -106.649266)
			(xy 124.227844 -106.65333) (xy 124.227844 -107.693206) (xy 124.228383 -107.703566) (xy 124.236634 -107.72258)
			(xy 124.243846 -107.730036) (xy 124.24918 -107.734608) (xy 124.271465 -107.747525) (xy 124.312662 -107.778443)
			(xy 124.349324 -107.814623) (xy 124.380786 -107.855406) (xy 124.406475 -107.900051) (xy 124.425924 -107.947747)
			(xy 124.438779 -107.997625) (xy 124.44222 -108.023152) (xy 124.443744 -108.036614) (xy 124.445014 -108.067602)
			(xy 124.445014 -108.067856) (xy 124.444515 -108.095987) (xy 124.436259 -108.151641) (xy 124.419918 -108.205478)
			(xy 124.395848 -108.256332) (xy 124.36457 -108.303099) (xy 124.326763 -108.344765) (xy 124.283246 -108.380427)
			(xy 124.25934 -108.395262) (xy 124.258832 -108.39577) (xy 124.249688 -108.401358) (xy 124.244354 -108.405422)
			(xy 124.239528 -108.409994) (xy 124.234194 -108.418884) (xy 124.23176 -108.423511) (xy 124.228682 -108.433501)
			(xy 124.228098 -108.438696) (xy 124.228098 -108.439204) (xy 124.227844 -108.443268) (xy 124.227844 -109.09681)
			(xy 124.22886 -109.106208) (xy 124.22886 -109.106716) (xy 124.230567 -109.113874) (xy 124.237402 -109.126898)
			(xy 124.242322 -109.13237) (xy 124.293376 -109.183424) (xy 124.296499 -109.186333) (xy 124.303517 -109.191191)
			(xy 124.307346 -109.193076) (xy 124.319284 -109.198156) (xy 124.32538 -109.19841) (xy 124.353979 -109.198641)
			(xy 124.410611 -109.206622) (xy 124.465418 -109.222962) (xy 124.517174 -109.247296) (xy 124.56472 -109.27908)
			(xy 124.606993 -109.317601) (xy 124.643045 -109.361998) (xy 124.67207 -109.411276) (xy 124.693419 -109.464334)
			(xy 124.700538 -109.492034) (xy 124.701046 -109.49432) (xy 124.705568 -109.515301) (xy 124.71041 -109.557949)
			(xy 124.710698 -109.57941) (xy 124.710698 -109.579918) (xy 124.71024 -109.606454) (xy 124.702883 -109.659014)
			(xy 124.688314 -109.710047) (xy 124.666813 -109.758569) (xy 124.638796 -109.803644) (xy 124.604803 -109.844401)
			(xy 124.56549 -109.880054) (xy 124.521616 -109.909916) (xy 124.474027 -109.93341) (xy 124.423642 -109.950082)
			(xy 124.371432 -109.959612) (xy 124.344938 -109.961172) (xy 124.334524 -109.961426) (xy 124.328428 -109.961426)
			(xy 124.315474 -109.964728) (xy 124.308616 -109.966506) (xy 124.303028 -109.969554) (xy 124.301758 -109.970316)
			(xy 124.291598 -109.97819) (xy 124.242576 -110.027212) (xy 124.239869 -110.030062) (xy 124.235274 -110.03644)
			(xy 124.233432 -110.039912) (xy 124.230844 -110.045338) (xy 124.228012 -110.057017) (xy 124.227844 -110.063026)
			(xy 124.227844 -111.252254) (xy 124.22886 -111.261652) (xy 124.22886 -111.26216) (xy 124.23056 -111.269322)
			(xy 124.237385 -111.282356) (xy 124.242322 -111.287814) (xy 124.293376 -111.338868) (xy 124.296501 -111.341775)
			(xy 124.30352 -111.346629) (xy 124.307346 -111.34852) (xy 124.319284 -111.3536) (xy 124.32538 -111.353854)
			(xy 124.353978 -111.354085) (xy 124.410608 -111.362066) (xy 124.465413 -111.378407) (xy 124.517167 -111.402743)
			(xy 124.56471 -111.434528) (xy 124.606979 -111.47305) (xy 124.643026 -111.517448) (xy 124.672047 -111.566728)
			(xy 124.693389 -111.619785) (xy 124.700538 -111.647478) (xy 124.701046 -111.649764) (xy 124.705566 -111.670745)
			(xy 124.710402 -111.713393) (xy 124.710698 -111.734854) (xy 124.710698 -111.735362) (xy 124.710627 -111.739426)
			(xy 127.565148 -111.739426) (xy 127.569219 -111.683804) (xy 127.581345 -111.629367) (xy 127.601268 -111.577276)
			(xy 127.628564 -111.528641) (xy 127.66265 -111.484498) (xy 127.702799 -111.445789) (xy 127.748157 -111.413338)
			(xy 127.797757 -111.387837) (xy 127.850541 -111.36983) (xy 127.905384 -111.3597) (xy 127.961118 -111.357663)
			(xy 128.016555 -111.363763) (xy 128.070512 -111.377869) (xy 128.121841 -111.399681) (xy 128.169447 -111.428735)
			(xy 128.212315 -111.46441) (xy 128.249532 -111.505947) (xy 128.280305 -111.55246) (xy 128.303977 -111.602957)
			(xy 128.320045 -111.656364) (xy 128.328165 -111.71154) (xy 128.328674 -111.739426) (xy 128.328165 -111.767312)
			(xy 128.320045 -111.822488) (xy 128.303977 -111.875895) (xy 128.280305 -111.926392) (xy 128.249532 -111.972905)
			(xy 128.212315 -112.014442) (xy 128.169447 -112.050117) (xy 128.121841 -112.079171) (xy 128.070512 -112.100983)
			(xy 128.016555 -112.115089) (xy 127.961118 -112.121189) (xy 127.905384 -112.119152) (xy 127.850541 -112.109022)
			(xy 127.797757 -112.091015) (xy 127.748157 -112.065514) (xy 127.702799 -112.033063) (xy 127.66265 -111.994354)
			(xy 127.628564 -111.950211) (xy 127.601268 -111.901576) (xy 127.581345 -111.849485) (xy 127.569219 -111.795048)
			(xy 127.565148 -111.739426) (xy 124.710627 -111.739426) (xy 124.710237 -111.761896) (xy 124.702875 -111.814451)
			(xy 124.688302 -111.86548) (xy 124.666799 -111.913996) (xy 124.63878 -111.959065) (xy 124.604787 -111.999817)
			(xy 124.565475 -112.035466) (xy 124.521603 -112.065323) (xy 124.474017 -112.088814) (xy 124.423634 -112.105484)
			(xy 124.371428 -112.115012) (xy 124.344938 -112.116616) (xy 124.334524 -112.11687) (xy 124.328428 -112.11687)
			(xy 124.315474 -112.120172) (xy 124.308616 -112.12195) (xy 124.303028 -112.124998) (xy 124.301758 -112.12576)
			(xy 124.291598 -112.133634) (xy 124.242576 -112.182656) (xy 124.239866 -112.185504) (xy 124.235265 -112.191879)
			(xy 124.233432 -112.195356) (xy 124.230849 -112.200783) (xy 124.228026 -112.212462) (xy 124.227844 -112.21847)
			(xy 124.227844 -112.540034) (xy 129.905504 -112.540034) (xy 129.909575 -112.484412) (xy 129.921701 -112.429975)
			(xy 129.941624 -112.377884) (xy 129.96892 -112.329249) (xy 130.003006 -112.285106) (xy 130.043155 -112.246397)
			(xy 130.088513 -112.213946) (xy 130.138113 -112.188445) (xy 130.190897 -112.170438) (xy 130.24574 -112.160308)
			(xy 130.301474 -112.158271) (xy 130.356911 -112.164371) (xy 130.410868 -112.178477) (xy 130.462197 -112.200289)
			(xy 130.509803 -112.229343) (xy 130.552671 -112.265018) (xy 130.589888 -112.306555) (xy 130.620661 -112.353068)
			(xy 130.644333 -112.403565) (xy 130.649627 -112.421162) (xy 131.907024 -112.421162) (xy 131.911095 -112.36554)
			(xy 131.923221 -112.311103) (xy 131.943144 -112.259012) (xy 131.97044 -112.210377) (xy 132.004526 -112.166234)
			(xy 132.044675 -112.127525) (xy 132.090033 -112.095074) (xy 132.139633 -112.069573) (xy 132.192417 -112.051566)
			(xy 132.24726 -112.041436) (xy 132.302994 -112.039399) (xy 132.358431 -112.045499) (xy 132.412388 -112.059605)
			(xy 132.463717 -112.081417) (xy 132.511323 -112.110471) (xy 132.554191 -112.146146) (xy 132.591408 -112.187683)
			(xy 132.622181 -112.234196) (xy 132.645853 -112.284693) (xy 132.661921 -112.3381) (xy 132.670041 -112.393276)
			(xy 132.67055 -112.421162) (xy 132.670041 -112.449048) (xy 132.661921 -112.504224) (xy 132.645853 -112.557631)
			(xy 132.622181 -112.608128) (xy 132.591408 -112.654641) (xy 132.554191 -112.696178) (xy 132.511323 -112.731853)
			(xy 132.463717 -112.760907) (xy 132.412388 -112.782719) (xy 132.358431 -112.796825) (xy 132.302994 -112.802925)
			(xy 132.24726 -112.800888) (xy 132.192417 -112.790758) (xy 132.139633 -112.772751) (xy 132.090033 -112.74725)
			(xy 132.044675 -112.714799) (xy 132.004526 -112.67609) (xy 131.97044 -112.631947) (xy 131.943144 -112.583312)
			(xy 131.923221 -112.531221) (xy 131.911095 -112.476784) (xy 131.907024 -112.421162) (xy 130.649627 -112.421162)
			(xy 130.660401 -112.456972) (xy 130.668521 -112.512148) (xy 130.66903 -112.540034) (xy 130.668521 -112.56792)
			(xy 130.660401 -112.623096) (xy 130.644333 -112.676503) (xy 130.620661 -112.727) (xy 130.589888 -112.773513)
			(xy 130.552671 -112.81505) (xy 130.509803 -112.850725) (xy 130.462197 -112.879779) (xy 130.410868 -112.901591)
			(xy 130.356911 -112.915697) (xy 130.301474 -112.921797) (xy 130.24574 -112.91976) (xy 130.190897 -112.90963)
			(xy 130.138113 -112.891623) (xy 130.088513 -112.866122) (xy 130.043155 -112.833671) (xy 130.003006 -112.794962)
			(xy 129.96892 -112.750819) (xy 129.941624 -112.702184) (xy 129.921701 -112.650093) (xy 129.909575 -112.595656)
			(xy 129.905504 -112.540034) (xy 124.227844 -112.540034) (xy 124.227844 -113.898426) (xy 127.55321 -113.898426)
			(xy 127.557281 -113.842804) (xy 127.569407 -113.788367) (xy 127.58933 -113.736276) (xy 127.616626 -113.687641)
			(xy 127.650712 -113.643498) (xy 127.690861 -113.604789) (xy 127.736219 -113.572338) (xy 127.785819 -113.546837)
			(xy 127.838603 -113.52883) (xy 127.893446 -113.5187) (xy 127.94918 -113.516663) (xy 128.004617 -113.522763)
			(xy 128.058574 -113.536869) (xy 128.109903 -113.558681) (xy 128.157509 -113.587735) (xy 128.200377 -113.62341)
			(xy 128.237594 -113.664947) (xy 128.268367 -113.71146) (xy 128.292039 -113.761957) (xy 128.308107 -113.815364)
			(xy 128.316227 -113.87054) (xy 128.316736 -113.898426) (xy 128.316227 -113.926312) (xy 128.308107 -113.981488)
			(xy 128.292039 -114.034895) (xy 128.268367 -114.085392) (xy 128.237594 -114.131905) (xy 128.200377 -114.173442)
			(xy 128.157509 -114.209117) (xy 128.109903 -114.238171) (xy 128.058574 -114.259983) (xy 128.004617 -114.274089)
			(xy 127.94918 -114.280189) (xy 127.893446 -114.278152) (xy 127.838603 -114.268022) (xy 127.785819 -114.250015)
			(xy 127.736219 -114.224514) (xy 127.690861 -114.192063) (xy 127.650712 -114.153354) (xy 127.616626 -114.109211)
			(xy 127.58933 -114.060576) (xy 127.569407 -114.008485) (xy 127.557281 -113.954048) (xy 127.55321 -113.898426)
			(xy 124.227844 -113.898426) (xy 124.227844 -116.937028) (xy 124.22886 -116.946426) (xy 124.22886 -116.946934)
			(xy 124.230569 -116.954091) (xy 124.237407 -116.967111) (xy 124.242322 -116.972588) (xy 124.60986 -117.340126)
			(xy 124.615537 -117.345324) (xy 124.629241 -117.352315) (xy 124.636784 -117.353842) (xy 124.637292 -117.353842)
			(xy 124.64542 -117.354604) (xy 125.7173 -117.354604) (xy 125.726847 -117.35416) (xy 125.744602 -117.347123)
			(xy 125.751844 -117.340888) (xy 125.76429 -117.32895) (xy 125.77064 -117.322854) (xy 125.771402 -117.322092)
			(xy 125.774839 -117.318477) (xy 125.780347 -117.310162) (xy 125.782324 -117.305582) (xy 125.78969 -117.28831)
			(xy 125.790452 -117.281452) (xy 125.794277 -117.254042) (xy 125.808814 -117.200644) (xy 125.830914 -117.149906)
			(xy 125.860114 -117.102895) (xy 125.8958 -117.060596) (xy 125.937224 -117.023897) (xy 125.983515 -116.993568)
			(xy 126.033703 -116.970247) (xy 126.086734 -116.954422) (xy 126.141495 -116.946425) (xy 126.196837 -116.946425)
			(xy 126.251598 -116.954422) (xy 126.304629 -116.970247) (xy 126.354817 -116.993568) (xy 126.401108 -117.023897)
			(xy 126.442532 -117.060596) (xy 126.478218 -117.102895) (xy 126.507418 -117.149906) (xy 126.529518 -117.200644)
			(xy 126.544055 -117.254042) (xy 126.54788 -117.281452) (xy 126.548642 -117.28831) (xy 126.553976 -117.30101)
			(xy 126.557532 -117.309392) (xy 126.565406 -117.320822) (xy 126.58598 -117.340126) (xy 126.587504 -117.34165)
			(xy 126.594642 -117.347485) (xy 126.611825 -117.354128) (xy 126.621032 -117.354604) (xy 127.720852 -117.354604)
			(xy 127.73025 -117.353588) (xy 127.730758 -117.353588) (xy 127.737919 -117.351886) (xy 127.750948 -117.345057)
			(xy 127.756412 -117.340126) (xy 127.758698 -117.33784) (xy 127.809498 -117.280944) (xy 127.812892 -117.27694)
			(xy 127.818139 -117.26785) (xy 127.819912 -117.26291) (xy 127.823214 -117.25275) (xy 127.821944 -117.241828)
			(xy 127.820882 -117.23151) (xy 127.819737 -117.210798) (xy 127.819658 -117.200426) (xy 127.820144 -117.173175)
			(xy 127.8279 -117.119227) (xy 127.843255 -117.066932) (xy 127.865897 -117.017355) (xy 127.895363 -116.971505)
			(xy 127.931054 -116.930314) (xy 127.972245 -116.894623) (xy 128.018095 -116.865157) (xy 128.067672 -116.842515)
			(xy 128.119967 -116.82716) (xy 128.173915 -116.819404) (xy 128.228417 -116.819404) (xy 128.282365 -116.82716)
			(xy 128.33466 -116.842515) (xy 128.384237 -116.865157) (xy 128.430087 -116.894623) (xy 128.471278 -116.930314)
			(xy 128.506969 -116.971505) (xy 128.536435 -117.017355) (xy 128.559077 -117.066932) (xy 128.574432 -117.119227)
			(xy 128.582188 -117.173175) (xy 128.582674 -117.200426) (xy 128.582597 -117.210798) (xy 128.581453 -117.231511)
			(xy 128.580388 -117.241828) (xy 128.579372 -117.253004) (xy 128.58242 -117.262656) (xy 128.583993 -117.266985)
			(xy 128.588464 -117.275036) (xy 128.59131 -117.278658) (xy 128.642872 -117.337332) (xy 128.644396 -117.338602)
			(xy 128.64592 -117.340126) (xy 128.65135 -117.345108) (xy 128.664388 -117.351957) (xy 128.671574 -117.353588)
			(xy 128.672082 -117.353588) (xy 128.68148 -117.354604) (xy 129.949702 -117.354604) (xy 129.960487 -117.354117)
			(xy 129.98017 -117.345292) (xy 129.994519 -117.329186) (xy 129.998216 -117.319044) (xy 130.001264 -117.309392)
			(xy 130.001772 -117.304058) (xy 130.003026 -117.294015) (xy 130.006458 -117.274066) (xy 130.00863 -117.26418)
			(xy 130.012652 -117.247398) (xy 130.023334 -117.21458) (xy 130.029966 -117.198648) (xy 130.031998 -117.194076)
			(xy 130.034284 -117.183662) (xy 130.034284 -117.161564) (xy 130.032252 -117.154706) (xy 130.029458 -117.147594)
			(xy 130.010662 -117.115844) (xy 130.010662 -117.115336) (xy 129.986278 -117.074696) (xy 129.983184 -117.070113)
			(xy 129.975365 -117.062299) (xy 129.970784 -117.059202) (xy 129.960878 -117.053106) (xy 129.948686 -117.051836)
			(xy 129.931371 -117.049974) (xy 129.897154 -117.043488) (xy 129.88036 -117.038882) (xy 129.879852 -117.038882)
			(xy 129.870454 -117.036088) (xy 129.869184 -117.03558) (xy 129.867152 -117.035072) (xy 129.866136 -117.034564)
			(xy 129.834237 -117.023334) (xy 129.774705 -116.991262) (xy 129.747772 -116.97081) (xy 129.747518 -116.970556)
			(xy 129.740406 -116.965222) (xy 129.73177 -116.962174) (xy 129.727935 -116.961015) (xy 129.720027 -116.959744)
			(xy 129.716022 -116.959634) (xy 129.694432 -116.959634) (xy 129.688994 -116.959486) (xy 129.678366 -116.957169)
			(xy 129.67335 -116.955062) (xy 129.659634 -116.948712) (xy 129.65493 -116.946645) (xy 129.64495 -116.944211)
			(xy 129.639822 -116.943886) (xy 129.631186 -116.944394) (xy 129.623902 -116.945681) (xy 129.610484 -116.951888)
			(xy 129.60477 -116.956586) (xy 129.604516 -116.95684) (xy 129.583446 -116.974947) (xy 129.537052 -117.005507)
			(xy 129.486719 -117.02902) (xy 129.433509 -117.044991) (xy 129.378547 -117.053081) (xy 129.35077 -117.053614)
			(xy 129.350262 -117.053614) (xy 129.323012 -117.053126) (xy 129.269068 -117.045365) (xy 129.216778 -117.030006)
			(xy 129.167205 -117.007363) (xy 129.121359 -116.977896) (xy 129.080173 -116.942205) (xy 129.044485 -116.901015)
			(xy 129.015021 -116.855167) (xy 128.992382 -116.805592) (xy 128.977028 -116.7533) (xy 128.969272 -116.699356)
			(xy 128.968754 -116.672106) (xy 128.968754 -116.671598) (xy 128.969185 -116.645972) (xy 128.976085 -116.595188)
			(xy 128.989734 -116.545787) (xy 129.009885 -116.498663) (xy 129.036173 -116.454667) (xy 129.051812 -116.434362)
			(xy 129.056892 -116.427758) (xy 129.060702 -116.416582) (xy 129.062734 -116.40312) (xy 129.062734 -116.381276)
			(xy 129.062798 -116.37767) (xy 129.06382 -116.370532) (xy 129.064766 -116.367052) (xy 129.065528 -116.363496)
			(xy 129.065528 -116.301012) (xy 129.05994 -116.284756) (xy 129.056384 -116.280438) (xy 129.049761 -116.27236)
			(xy 129.037309 -116.255586) (xy 129.031492 -116.24691) (xy 129.019129 -116.227536) (xy 128.998633 -116.1864)
			(xy 128.990598 -116.164868) (xy 128.990344 -116.164106) (xy 128.99009 -116.16309) (xy 128.989074 -116.160296)
			(xy 128.979579 -116.130453) (xy 128.969363 -116.068671) (xy 128.968754 -116.03736) (xy 128.968754 -116.037106)
			(xy 128.969163 -116.011488) (xy 128.976014 -115.960713) (xy 128.989608 -115.911314) (xy 129.009698 -115.864182)
			(xy 129.035923 -115.820167) (xy 129.051558 -115.79987) (xy 129.051812 -115.799616) (xy 129.054352 -115.796568)
			(xy 129.058087 -115.790458) (xy 129.062347 -115.776794) (xy 129.062734 -115.769644) (xy 129.062734 -115.746276)
			(xy 129.062876 -115.740836) (xy 129.065184 -115.730205) (xy 129.067306 -115.725194) (xy 129.073656 -115.711478)
			(xy 129.075715 -115.706772) (xy 129.078136 -115.696791) (xy 129.078482 -115.691666) (xy 129.077974 -115.68303)
			(xy 129.076695 -115.675742) (xy 129.070503 -115.662311) (xy 129.065782 -115.656614) (xy 129.065528 -115.65636)
			(xy 129.04742 -115.63529) (xy 129.016857 -115.588896) (xy 128.99334 -115.538564) (xy 128.977365 -115.485354)
			(xy 128.969269 -115.430391) (xy 128.968754 -115.402614) (xy 128.968754 -115.402106) (xy 128.969239 -115.374853)
			(xy 128.976995 -115.320903) (xy 128.992349 -115.268605) (xy 129.014989 -115.219025) (xy 129.044455 -115.173171)
			(xy 129.080146 -115.131977) (xy 129.121336 -115.096281) (xy 129.167186 -115.066811) (xy 129.216764 -115.044165)
			(xy 129.26906 -115.028804) (xy 129.32301 -115.021042) (xy 129.350262 -115.020598) (xy 129.35077 -115.020598)
			(xy 129.376397 -115.021026) (xy 129.427184 -115.027922) (xy 129.476588 -115.041566) (xy 129.523716 -115.061711)
			(xy 129.567718 -115.087995) (xy 129.588006 -115.103656) (xy 129.59461 -115.108736) (xy 129.605786 -115.112546)
			(xy 129.619248 -115.114578) (xy 129.641092 -115.114578) (xy 129.646533 -115.114717) (xy 129.657168 -115.117016)
			(xy 129.662174 -115.11915) (xy 129.67589 -115.1255) (xy 129.680595 -115.127564) (xy 129.690575 -115.129994)
			(xy 129.695702 -115.130326) (xy 129.704338 -115.129818) (xy 129.711627 -115.128541) (xy 129.72506 -115.122351)
			(xy 129.730754 -115.117626) (xy 129.731008 -115.117372) (xy 129.752077 -115.09926) (xy 129.798468 -115.06869)
			(xy 129.848801 -115.045166) (xy 129.902011 -115.029184) (xy 129.956975 -115.021083) (xy 129.984754 -115.020598)
			(xy 129.985262 -115.020598) (xy 130.012516 -115.021059) (xy 130.066471 -115.028811) (xy 130.118773 -115.044164)
			(xy 130.168358 -115.066805) (xy 130.214215 -115.096272) (xy 130.255412 -115.131965) (xy 130.291109 -115.173159)
			(xy 130.32058 -115.219014) (xy 130.343225 -115.268597) (xy 130.358582 -115.320898) (xy 130.366339 -115.374852)
			(xy 130.36677 -115.402106) (xy 130.36636 -115.427723) (xy 130.359506 -115.478497) (xy 130.345909 -115.527893)
			(xy 130.325814 -115.575022) (xy 130.299585 -115.619033) (xy 130.283966 -115.639342) (xy 130.283712 -115.639596)
			(xy 130.281172 -115.642644) (xy 130.277437 -115.648753) (xy 130.273178 -115.662418) (xy 130.27279 -115.669568)
			(xy 130.27279 -115.692936) (xy 130.272725 -115.696541) (xy 130.271702 -115.70368) (xy 130.270758 -115.70716)
			(xy 130.269996 -115.710716) (xy 130.269996 -115.7732) (xy 130.275584 -115.789456) (xy 130.27914 -115.793774)
			(xy 130.285762 -115.801852) (xy 130.298214 -115.818627) (xy 130.304032 -115.827302) (xy 130.316401 -115.846673)
			(xy 130.33691 -115.887804) (xy 130.344926 -115.909344) (xy 130.34518 -115.910106) (xy 130.34645 -115.913916)
			(xy 130.354502 -115.938941) (xy 130.364438 -115.990561) (xy 130.366262 -116.016786) (xy 130.36677 -116.036344)
			(xy 130.36677 -116.037106) (xy 130.366516 -116.053108) (xy 130.366262 -116.057426) (xy 130.364118 -116.086834)
			(xy 130.351914 -116.144519) (xy 130.330995 -116.199645) (xy 130.301856 -116.250903) (xy 130.283966 -116.274342)
			(xy 130.283712 -116.274596) (xy 130.281172 -116.277644) (xy 130.277437 -116.283753) (xy 130.273178 -116.297418)
			(xy 130.27279 -116.304568) (xy 130.27279 -116.327936) (xy 130.272647 -116.333375) (xy 130.270338 -116.344007)
			(xy 130.268218 -116.349018) (xy 130.261868 -116.362734) (xy 130.2598 -116.367438) (xy 130.257361 -116.377418)
			(xy 130.257042 -116.382546) (xy 130.25755 -116.391182) (xy 130.258832 -116.398469) (xy 130.265028 -116.411896)
			(xy 130.269742 -116.417598) (xy 130.269996 -116.417852) (xy 130.288118 -116.438943) (xy 130.318699 -116.485384)
			(xy 130.342221 -116.535769) (xy 130.358187 -116.589033) (xy 130.366259 -116.644049) (xy 130.36677 -116.671852)
			(xy 130.36677 -116.672868) (xy 130.366641 -116.680234) (xy 131.250942 -116.680234) (xy 131.255013 -116.624612)
			(xy 131.267139 -116.570175) (xy 131.287062 -116.518084) (xy 131.314358 -116.469449) (xy 131.348444 -116.425306)
			(xy 131.388593 -116.386597) (xy 131.433951 -116.354146) (xy 131.483551 -116.328645) (xy 131.536335 -116.310638)
			(xy 131.591178 -116.300508) (xy 131.646912 -116.298471) (xy 131.702349 -116.304571) (xy 131.756306 -116.318677)
			(xy 131.807635 -116.340489) (xy 131.855241 -116.369543) (xy 131.898109 -116.405218) (xy 131.935326 -116.446755)
			(xy 131.966099 -116.493268) (xy 131.989771 -116.543765) (xy 132.005839 -116.597172) (xy 132.013959 -116.652348)
			(xy 132.014468 -116.680234) (xy 132.013959 -116.70812) (xy 132.005839 -116.763296) (xy 131.989771 -116.816703)
			(xy 131.966099 -116.8672) (xy 131.935326 -116.913713) (xy 131.898109 -116.95525) (xy 131.855241 -116.990925)
			(xy 131.807635 -117.019979) (xy 131.756306 -117.041791) (xy 131.702349 -117.055897) (xy 131.646912 -117.061997)
			(xy 131.591178 -117.05996) (xy 131.536335 -117.04983) (xy 131.483551 -117.031823) (xy 131.433951 -117.006322)
			(xy 131.388593 -116.973871) (xy 131.348444 -116.935162) (xy 131.314358 -116.891019) (xy 131.287062 -116.842384)
			(xy 131.267139 -116.790293) (xy 131.255013 -116.735856) (xy 131.250942 -116.680234) (xy 130.366641 -116.680234)
			(xy 130.36632 -116.698506) (xy 130.359393 -116.749313) (xy 130.34574 -116.798739) (xy 130.336036 -116.822474)
			(xy 130.334004 -116.827046) (xy 130.331718 -116.83746) (xy 130.331718 -116.837714) (xy 130.330419 -116.844703)
			(xy 130.331324 -116.858885) (xy 130.333496 -116.865654) (xy 130.336544 -116.873528) (xy 130.35534 -116.905278)
			(xy 130.35534 -116.905786) (xy 130.37947 -116.946426) (xy 130.380232 -116.947442) (xy 130.380232 -116.947696)
			(xy 130.38358 -116.952274) (xy 130.391908 -116.95997) (xy 130.396742 -116.962936) (xy 130.405632 -116.968016)
			(xy 130.417316 -116.969286) (xy 130.445181 -116.972475) (xy 130.499616 -116.985978) (xy 130.55149 -117.007299)
			(xy 130.599686 -117.03598) (xy 130.643168 -117.071404) (xy 130.680999 -117.112808) (xy 130.712366 -117.159302)
			(xy 130.736593 -117.209884) (xy 130.753159 -117.263466) (xy 130.75793 -117.291104) (xy 130.75793 -117.291358)
			(xy 130.7592 -117.29974) (xy 130.763264 -117.307614) (xy 130.765374 -117.311499) (xy 130.770743 -117.318522)
			(xy 130.773932 -117.321584) (xy 130.789426 -117.336062) (xy 130.78968 -117.336062) (xy 130.796792 -117.342666)
			(xy 130.803788 -117.348123) (xy 130.820438 -117.354225) (xy 130.829304 -117.354604) (xy 132.347716 -117.354604)
			(xy 132.357722 -117.354113) (xy 132.376209 -117.346451) (xy 132.390358 -117.332299) (xy 132.398015 -117.31381)
			(xy 132.398516 -117.303804) (xy 132.398516 -117.301772) (xy 132.399004 -117.274523) (xy 132.406764 -117.220579)
			(xy 132.422122 -117.168289) (xy 132.444765 -117.118717) (xy 132.474232 -117.072872) (xy 132.509924 -117.031687)
			(xy 132.551114 -116.996001) (xy 132.596963 -116.96654) (xy 132.646538 -116.943904) (xy 132.69883 -116.928553)
			(xy 132.752775 -116.9208) (xy 132.780024 -116.920264) (xy 132.807558 -116.920748) (xy 132.862053 -116.928667)
			(xy 132.914845 -116.944335) (xy 132.964836 -116.967428) (xy 133.010989 -116.997466) (xy 133.052346 -117.033826)
			(xy 133.088048 -117.075753) (xy 133.117353 -117.122375) (xy 133.139652 -117.172726) (xy 133.154484 -117.225758)
			(xy 133.158484 -117.253004) (xy 133.160262 -117.266212) (xy 133.184138 -117.297962) (xy 133.187774 -117.302351)
			(xy 133.196616 -117.30954) (xy 133.201664 -117.312186) (xy 133.204712 -117.313456) (xy 133.206744 -117.314472)
			(xy 133.208014 -117.31498) (xy 133.213799 -117.317097) (xy 133.226002 -117.318763) (xy 133.232144 -117.318282)
			(xy 133.24459 -117.316758) (xy 133.259068 -117.307106) (xy 133.267599 -117.299307) (xy 133.277129 -117.278276)
			(xy 133.277356 -117.26672) (xy 133.277356 -117.259354) (xy 133.277771 -117.233703) (xy 133.284651 -117.182864)
			(xy 133.298294 -117.133409) (xy 133.318452 -117.086233) (xy 133.34476 -117.04219) (xy 133.360414 -117.021864)
			(xy 133.365494 -117.01526) (xy 133.369304 -117.004084) (xy 133.371336 -116.990622) (xy 133.371336 -116.968778)
			(xy 133.3714 -116.965172) (xy 133.372422 -116.958034) (xy 133.373368 -116.954554) (xy 133.37413 -116.950998)
			(xy 133.37413 -116.888514) (xy 133.368542 -116.872258) (xy 133.364986 -116.86794) (xy 133.358363 -116.859862)
			(xy 133.345911 -116.843088) (xy 133.340094 -116.834412) (xy 133.333998 -116.825268) (xy 133.33095 -116.819934)
			(xy 133.321566 -116.803761) (xy 133.305665 -116.769916) (xy 133.2992 -116.75237) (xy 133.298946 -116.751608)
			(xy 133.298692 -116.750592) (xy 133.297676 -116.747798) (xy 133.288181 -116.717955) (xy 133.277964 -116.656173)
			(xy 133.277356 -116.624862) (xy 133.277356 -116.624608) (xy 133.277765 -116.59899) (xy 133.284616 -116.548215)
			(xy 133.298209 -116.498816) (xy 133.3183 -116.451683) (xy 133.344524 -116.407668) (xy 133.36016 -116.387372)
			(xy 133.360414 -116.387118) (xy 133.362954 -116.38407) (xy 133.366689 -116.37796) (xy 133.370949 -116.364296)
			(xy 133.371336 -116.357146) (xy 133.371336 -116.333778) (xy 133.371478 -116.328338) (xy 133.373785 -116.317706)
			(xy 133.375908 -116.312696) (xy 133.382258 -116.29898) (xy 133.384317 -116.294274) (xy 133.386738 -116.284293)
			(xy 133.387084 -116.279168) (xy 133.386576 -116.270532) (xy 133.385294 -116.263246) (xy 133.379094 -116.249822)
			(xy 133.374384 -116.244116) (xy 133.37413 -116.243862) (xy 133.356021 -116.222792) (xy 133.325458 -116.176399)
			(xy 133.301941 -116.126066) (xy 133.285965 -116.072856) (xy 133.277869 -116.017894) (xy 133.277356 -115.990116)
			(xy 133.277356 -115.989608) (xy 133.277841 -115.962355) (xy 133.285597 -115.908405) (xy 133.300951 -115.856107)
			(xy 133.323591 -115.806527) (xy 133.353056 -115.760673) (xy 133.388747 -115.719479) (xy 133.429937 -115.683783)
			(xy 133.475788 -115.654312) (xy 133.525366 -115.631666) (xy 133.577662 -115.616306) (xy 133.631611 -115.608544)
			(xy 133.658864 -115.6081) (xy 133.659372 -115.6081) (xy 133.684998 -115.608529) (xy 133.735786 -115.615425)
			(xy 133.78519 -115.629069) (xy 133.832318 -115.649214) (xy 133.876319 -115.675498) (xy 133.896608 -115.691158)
			(xy 133.903212 -115.696238) (xy 133.914388 -115.700048) (xy 133.92785 -115.70208) (xy 133.949694 -115.70208)
			(xy 133.955135 -115.702219) (xy 133.96577 -115.704518) (xy 133.970776 -115.706652) (xy 133.984492 -115.713002)
			(xy 133.989197 -115.715066) (xy 133.999177 -115.717495) (xy 134.004304 -115.717828) (xy 134.01294 -115.71732)
			(xy 134.020229 -115.716043) (xy 134.033661 -115.709852) (xy 134.039356 -115.705128) (xy 134.03961 -115.704874)
			(xy 134.060679 -115.686762) (xy 134.10707 -115.656192) (xy 134.157403 -115.632668) (xy 134.210613 -115.616687)
			(xy 134.265577 -115.608585) (xy 134.293356 -115.6081) (xy 134.293864 -115.6081) (xy 134.321118 -115.608561)
			(xy 134.375073 -115.616314) (xy 134.427374 -115.631667) (xy 134.476959 -115.654307) (xy 134.522816 -115.683774)
			(xy 134.564012 -115.719468) (xy 134.599709 -115.760662) (xy 134.629179 -115.806517) (xy 134.651823 -115.856099)
			(xy 134.66718 -115.9084) (xy 134.674937 -115.962354) (xy 134.675372 -115.989608) (xy 134.674962 -116.015225)
			(xy 134.668108 -116.065998) (xy 134.654511 -116.115395) (xy 134.634416 -116.162524) (xy 134.608186 -116.206534)
			(xy 134.592568 -116.226844) (xy 134.592314 -116.227098) (xy 134.589774 -116.230146) (xy 134.586039 -116.236256)
			(xy 134.581781 -116.24992) (xy 134.581392 -116.25707) (xy 134.581392 -116.280438) (xy 134.581327 -116.284043)
			(xy 134.580303 -116.291181) (xy 134.57936 -116.294662) (xy 134.578598 -116.298218) (xy 134.578598 -116.360702)
			(xy 134.584186 -116.376958) (xy 134.587742 -116.381276) (xy 134.594364 -116.389354) (xy 134.606815 -116.406129)
			(xy 134.612634 -116.414804) (xy 134.61873 -116.423948) (xy 134.621778 -116.429282) (xy 134.631165 -116.445454)
			(xy 134.647072 -116.479297) (xy 134.653528 -116.496846) (xy 134.653782 -116.497608) (xy 134.654036 -116.498624)
			(xy 134.654544 -116.499894) (xy 134.655052 -116.501418) (xy 134.661993 -116.52272) (xy 134.671414 -116.566522)
			(xy 134.673848 -116.588794) (xy 134.673848 -116.589302) (xy 134.674864 -116.60378) (xy 134.674864 -116.604542)
			(xy 134.675118 -116.608352) (xy 134.67588 -116.625116) (xy 134.675118 -116.637562) (xy 134.6735 -116.667929)
			(xy 134.661827 -116.727607) (xy 134.640829 -116.784675) (xy 134.611039 -116.837686) (xy 134.592568 -116.861844)
			(xy 134.592314 -116.862098) (xy 134.589774 -116.865146) (xy 134.586039 -116.871256) (xy 134.581781 -116.88492)
			(xy 134.581392 -116.89207) (xy 134.581392 -116.915438) (xy 134.581248 -116.920877) (xy 134.578939 -116.931508)
			(xy 134.57682 -116.93652) (xy 134.57047 -116.950236) (xy 134.568402 -116.95494) (xy 134.565964 -116.96492)
			(xy 134.565644 -116.970048) (xy 134.566152 -116.978684) (xy 134.567434 -116.985971) (xy 134.573631 -116.999397)
			(xy 134.578344 -117.0051) (xy 134.578598 -117.005354) (xy 134.597941 -117.027935) (xy 134.630086 -117.077953)
			(xy 134.642606 -117.104922) (xy 134.653569 -117.130826) (xy 134.668623 -117.185023) (xy 134.672578 -117.212872)
			(xy 134.672578 -117.214142) (xy 134.673086 -117.217698) (xy 134.67334 -117.219984) (xy 134.67334 -117.220238)
			(xy 134.673594 -117.222524) (xy 134.673594 -117.223032) (xy 134.673848 -117.224048) (xy 134.67461 -117.230398)
			(xy 134.675372 -117.249194) (xy 134.675372 -117.249702) (xy 134.675626 -117.254528) (xy 134.678166 -117.266466)
			(xy 134.68004 -117.273525) (xy 134.687144 -117.286279) (xy 134.692136 -117.291612) (xy 134.70509 -117.304312)
			(xy 134.737602 -117.336316) (xy 134.73811 -117.336824) (xy 134.741412 -117.340126) (xy 134.746841 -117.345109)
			(xy 134.75988 -117.35196) (xy 134.767066 -117.353588) (xy 134.767574 -117.353588) (xy 134.776972 -117.354604)
			(xy 137.952734 -117.354604) (xy 137.960862 -117.353842) (xy 137.96137 -117.353842) (xy 137.968887 -117.352238)
			(xy 137.982572 -117.345259) (xy 137.988294 -117.340126) (xy 138.93927 -116.38915) (xy 138.94425 -116.383647)
			(xy 138.951078 -116.370478) (xy 138.952732 -116.363242) (xy 138.953748 -116.35359) (xy 138.953748 -111.402368)
			(xy 138.953584 -111.396358) (xy 138.950766 -111.384672) (xy 138.94816 -111.379254) (xy 138.946318 -111.375782)
			(xy 138.941719 -111.369408) (xy 138.939016 -111.366554) (xy 138.057636 -110.485174) (xy 138.039606 -110.466403)
			(xy 138.00903 -110.424285) (xy 137.985408 -110.377908) (xy 137.969321 -110.328411) (xy 137.961163 -110.277009)
			(xy 137.960608 -110.250986) (xy 137.960608 -100.068634) (xy 137.959904 -100.056478) (xy 137.948756 -100.034871)
			(xy 137.939272 -100.027232) (xy 137.879074 -99.986846) (xy 137.867898 -99.979226) (xy 137.862574 -99.975895)
			(xy 137.850757 -99.971657) (xy 137.84453 -99.970844) (xy 137.832338 -99.969574) (xy 137.832084 -99.969574)
			(xy 137.820654 -99.9744) (xy 137.797705 -99.983325) (xy 137.750089 -99.995874) (xy 137.701257 -100.002203)
			(xy 137.676636 -100.002594) (xy 137.649382 -100.002133) (xy 137.595428 -99.99438) (xy 137.543126 -99.979027)
			(xy 137.493543 -99.956387) (xy 137.447686 -99.926919) (xy 137.40649 -99.891225) (xy 137.370794 -99.850032)
			(xy 137.341324 -99.804177) (xy 137.318681 -99.754594) (xy 137.303324 -99.702294) (xy 137.295568 -99.64834)
			(xy 137.295128 -99.621086) (xy 137.295633 -99.593351) (xy 137.30368 -99.538467) (xy 137.319586 -99.485327)
			(xy 137.343017 -99.435048) (xy 137.37348 -99.388691) (xy 137.410332 -99.347232) (xy 137.452798 -99.311544)
			(xy 137.499983 -99.28238) (xy 137.550892 -99.260353) (xy 137.604454 -99.245927) (xy 137.631932 -99.242118)
			(xy 137.645648 -99.240594) (xy 137.676636 -99.239324) (xy 137.701258 -99.239704) (xy 137.750093 -99.246028)
			(xy 137.79771 -99.258578) (xy 137.820654 -99.267518) (xy 137.832084 -99.272344) (xy 137.832338 -99.272344)
			(xy 137.84453 -99.271074) (xy 137.850769 -99.270311) (xy 137.862597 -99.266069) (xy 137.867898 -99.262692)
			(xy 137.879074 -99.255072) (xy 137.939272 -99.214686) (xy 137.94879 -99.207074) (xy 137.959955 -99.185452)
			(xy 137.960608 -99.173284) (xy 137.960608 -98.503994) (xy 137.959592 -98.494342) (xy 137.957609 -98.485635)
			(xy 137.948499 -98.470289) (xy 137.941812 -98.46437) (xy 137.933684 -98.459036) (xy 137.911078 -98.447098)
			(xy 137.85469 -98.416872) (xy 137.848477 -98.413803) (xy 137.834946 -98.410828) (xy 137.82802 -98.41103)
			(xy 137.814812 -98.411792) (xy 137.803128 -98.419412) (xy 137.802874 -98.419666) (xy 137.779412 -98.434466)
			(xy 137.729113 -98.457856) (xy 137.675955 -98.473706) (xy 137.62106 -98.481681) (xy 137.593324 -98.48215)
			(xy 137.57783 -98.481896) (xy 137.577322 -98.481896) (xy 137.550839 -98.480328) (xy 137.498653 -98.470782)
			(xy 137.448294 -98.454096) (xy 137.400733 -98.430592) (xy 137.356888 -98.400724) (xy 137.317606 -98.365068)
			(xy 137.283644 -98.324312) (xy 137.255657 -98.279243) (xy 137.234186 -98.230731) (xy 137.219645 -98.179711)
			(xy 137.212315 -98.127168) (xy 137.211816 -98.100642) (xy 137.212276 -98.073388) (xy 137.220029 -98.019434)
			(xy 137.235381 -97.967132) (xy 137.258022 -97.917548) (xy 137.287489 -97.871692) (xy 137.323183 -97.830496)
			(xy 137.364377 -97.7948) (xy 137.410232 -97.76533) (xy 137.459815 -97.742688) (xy 137.512116 -97.727333)
			(xy 137.56607 -97.719578) (xy 137.593324 -97.719134) (xy 137.593832 -97.719134) (xy 137.621502 -97.719649)
			(xy 137.676256 -97.727683) (xy 137.729277 -97.743534) (xy 137.779456 -97.766871) (xy 137.802874 -97.781618)
			(xy 137.803128 -97.781872) (xy 137.803382 -97.782126) (xy 137.809062 -97.785551) (xy 137.821668 -97.789658)
			(xy 137.828274 -97.790254) (xy 137.842244 -97.791016) (xy 137.911078 -97.754186) (xy 137.933684 -97.742248)
			(xy 137.941812 -97.736914) (xy 137.948461 -97.730964) (xy 137.957553 -97.715629) (xy 137.959592 -97.706942)
			(xy 137.960608 -97.69729) (xy 137.960608 -89.922604) (xy 137.960511 -89.917586) (xy 137.958583 -89.907737)
			(xy 137.956798 -89.903046) (xy 137.954761 -89.898556) (xy 137.94927 -89.890366) (xy 137.945876 -89.88679)
			(xy 123.554236 -75.495404) (xy 123.536204 -75.476633) (xy 123.505624 -75.434516) (xy 123.481999 -75.38814)
			(xy 123.465907 -75.338643) (xy 123.457744 -75.287239) (xy 123.457208 -75.261216) (xy 123.457208 -69.998082)
			(xy 123.455176 -69.984112) (xy 123.453262 -69.978009) (xy 123.446824 -69.966961) (xy 123.442476 -69.962268)
			(xy 121.837958 -68.35775) (xy 120.23344 -66.753486) (xy 120.226042 -66.74664) (xy 120.207443 -66.738914)
			(xy 120.197372 -66.7385) (xy 117.699536 -66.7385) (xy 117.674248 -66.738) (xy 117.624295 -66.730083)
			(xy 117.576194 -66.714453) (xy 117.531129 -66.691495) (xy 117.490207 -66.661774) (xy 117.471952 -66.644266)
			(xy 117.318282 -66.490596) (xy 117.313202 -66.487548) (xy 117.297344 -66.477356) (xy 117.267807 -66.453934)
			(xy 117.254274 -66.440812) (xy 117.253258 -66.439796) (xy 114.59337 -63.779908) (xy 114.575256 -63.761128)
			(xy 114.544567 -63.718931) (xy 114.520862 -63.672451) (xy 114.504726 -63.622833) (xy 114.496556 -63.5713)
			(xy 114.496088 -63.545212) (xy 114.496088 -61.047122) (xy 114.495917 -61.041113) (xy 114.493087 -61.029434)
			(xy 114.4905 -61.024008) (xy 114.488662 -61.020533) (xy 114.484071 -61.014151) (xy 114.481356 -61.011308)
			(xy 107.349544 -53.879496) (xy 107.331512 -53.860725) (xy 107.300933 -53.818608) (xy 107.277308 -53.772232)
			(xy 107.261216 -53.722735) (xy 107.253054 -53.671331) (xy 107.252516 -53.645308) (xy 107.252516 -42.271696)
			(xy 107.252435 -42.267487) (xy 107.251031 -42.259187) (xy 107.249722 -42.255186) (xy 107.247705 -42.249824)
			(xy 107.241683 -42.240079) (xy 107.237784 -42.235882) (xy 101.184202 -36.182554) (xy 101.166089 -36.163774)
			(xy 101.135405 -36.121576) (xy 101.111705 -36.075095) (xy 101.095575 -36.025477) (xy 101.087413 -35.973945)
			(xy 101.08692 -35.947858) (xy 101.08692 -29.1846) (xy 101.087406 -29.158513) (xy 101.095572 -29.106981)
			(xy 101.111704 -29.057362) (xy 101.135402 -29.01088) (xy 101.166084 -28.96868) (xy 101.184202 -28.949904)
			(xy 101.657912 -28.476194) (xy 101.65842 -28.469844) (xy 101.657658 -28.461716) (xy 101.613462 -28.41752)
			(xy 101.610609 -28.414817) (xy 101.604228 -28.410229) (xy 101.600762 -28.408376) (xy 101.595335 -28.405793)
			(xy 101.583655 -28.40297) (xy 101.577648 -28.402788) (xy 98.685096 -28.402788) (xy 98.659805 -28.402293)
			(xy 98.609846 -28.394385) (xy 98.561737 -28.378766) (xy 98.516661 -28.355818) (xy 98.475726 -28.326106)
			(xy 98.457512 -28.308554) (xy 97.95383 -27.804618) (xy 97.951251 -27.802167) (xy 97.945516 -27.797955)
			(xy 97.9424 -27.796236) (xy 97.936771 -27.793413) (xy 97.924565 -27.790334) (xy 97.91827 -27.79014)
			(xy 97.731072 -27.79014) (xy 97.722635 -27.791) (xy 97.706998 -27.79754) (xy 97.694333 -27.808804)
			(xy 97.689924 -27.816048) (xy 97.650046 -27.901392) (xy 97.647146 -27.909898) (xy 97.646888 -27.927856)
			(xy 97.649538 -27.936444) (xy 97.649538 -27.936698) (xy 97.656396 -27.95651) (xy 97.661984 -27.963622)
			(xy 97.662238 -27.963876) (xy 97.681233 -27.988346) (xy 97.713153 -28.041435) (xy 97.737619 -28.098345)
			(xy 97.754183 -28.158035) (xy 97.762542 -28.219415) (xy 97.763076 -28.250388) (xy 97.763076 -29.114242)
			(xy 97.762586 -29.144226) (xy 97.754758 -29.203682) (xy 97.739237 -29.261607) (xy 97.716288 -29.317011)
			(xy 97.686304 -29.368945) (xy 97.649798 -29.416521) (xy 97.607393 -29.458926) (xy 97.559817 -29.495432)
			(xy 97.507883 -29.525416) (xy 97.452479 -29.548365) (xy 97.394554 -29.563886) (xy 97.335098 -29.571714)
			(xy 97.27513 -29.571714) (xy 97.215674 -29.563886) (xy 97.157749 -29.548365) (xy 97.102345 -29.525416)
			(xy 97.050411 -29.495432) (xy 97.002835 -29.458926) (xy 96.96043 -29.416521) (xy 96.923924 -29.368945)
			(xy 96.89394 -29.317011) (xy 96.870991 -29.261607) (xy 96.85547 -29.203682) (xy 96.847642 -29.144226)
			(xy 96.847152 -29.114242) (xy 96.847152 -28.250642) (xy 96.847538 -28.223478) (xy 96.853971 -28.169531)
			(xy 96.866752 -28.116727) (xy 96.875854 -28.09113) (xy 96.876362 -28.08986) (xy 96.877632 -28.086304)
			(xy 96.87941 -28.081478) (xy 96.880172 -28.0797) (xy 96.892505 -28.050476) (xy 96.924071 -27.99546)
			(xy 96.962938 -27.945333) (xy 97.008358 -27.901058) (xy 97.033588 -27.881834) (xy 97.038414 -27.878278)
			(xy 97.04197 -27.874214) (xy 97.048828 -27.8638) (xy 97.054162 -27.853132) (xy 97.054162 -27.84094)
			(xy 97.053749 -27.830916) (xy 97.046085 -27.812392) (xy 97.03191 -27.798217) (xy 97.013386 -27.790552)
			(xy 97.003362 -27.79014) (xy 96.929448 -27.79014) (xy 96.91497 -27.790648) (xy 96.914462 -27.790648)
			(xy 96.891765 -27.790242) (xy 96.846826 -27.783833) (xy 96.803233 -27.771174) (xy 96.782382 -27.7622)
			(xy 96.779842 -27.76093) (xy 96.768666 -27.757374) (xy 96.766126 -27.756866) (xy 96.742726 -27.751516)
			(xy 96.697668 -27.734975) (xy 96.655469 -27.712104) (xy 96.617012 -27.683381) (xy 96.599756 -27.666696)
			(xy 95.525844 -26.592784) (xy 95.5167 -26.594562) (xy 95.503085 -26.598284) (xy 95.478463 -26.612065)
			(xy 95.468186 -26.62174) (xy 95.467678 -26.622248) (xy 95.458863 -26.631874) (xy 95.446011 -26.654583)
			(xy 95.439361 -26.679814) (xy 95.438976 -26.69286) (xy 95.438976 -27.342846) (xy 95.438486 -27.372814)
			(xy 95.430663 -27.432236) (xy 95.41515 -27.490129) (xy 95.392214 -27.545502) (xy 95.362247 -27.597408)
			(xy 95.32576 -27.644958) (xy 95.28338 -27.687338) (xy 95.23583 -27.723825) (xy 95.183924 -27.753792)
			(xy 95.128551 -27.776728) (xy 95.070658 -27.792241) (xy 95.011236 -27.800064) (xy 94.9513 -27.800064)
			(xy 94.891878 -27.792241) (xy 94.833985 -27.776728) (xy 94.778612 -27.753792) (xy 94.726706 -27.723825)
			(xy 94.679156 -27.687338) (xy 94.636776 -27.644958) (xy 94.600289 -27.597408) (xy 94.570322 -27.545502)
			(xy 94.547386 -27.490129) (xy 94.531873 -27.432236) (xy 94.52405 -27.372814) (xy 94.52356 -27.342846)
			(xy 94.52356 -26.734008) (xy 94.523306 -26.479246) (xy 94.523833 -26.447748) (xy 94.532472 -26.385347)
			(xy 94.549581 -26.324719) (xy 94.574835 -26.267007) (xy 94.60776 -26.2133) (xy 94.647733 -26.164611)
			(xy 94.694001 -26.121858) (xy 94.74569 -26.085849) (xy 94.801826 -26.057262) (xy 94.831408 -26.04643)
			(xy 94.831662 -26.04643) (xy 94.83217 -26.046176) (xy 94.838079 -26.043862) (xy 94.848617 -26.036797)
			(xy 94.852998 -26.032206) (xy 94.857316 -26.02738) (xy 94.86011 -26.022046) (xy 94.864682 -26.0096)
			(xy 94.870016 -25.98547) (xy 94.870016 -25.984962) (xy 94.873064 -25.972262) (xy 94.874737 -25.961359)
			(xy 94.869736 -25.939897) (xy 94.863412 -25.93086) (xy 94.862396 -25.92959) (xy 94.859348 -25.926288)
			(xy 94.669864 -25.736804) (xy 94.667011 -25.734101) (xy 94.660629 -25.729515) (xy 94.657164 -25.72766)
			(xy 94.651738 -25.725073) (xy 94.640058 -25.722245) (xy 94.63405 -25.722072) (xy 92.3798 -25.722072)
			(xy 92.373958 -25.72512) (xy 92.36837 -25.727914) (xy 92.34087 -25.741687) (xy 92.282534 -25.761164)
			(xy 92.221829 -25.771028) (xy 92.191078 -25.771602) (xy 92.163828 -25.771115) (xy 92.109883 -25.763356)
			(xy 92.057591 -25.747999) (xy 92.008017 -25.725356) (xy 91.96217 -25.695889) (xy 91.920983 -25.660197)
			(xy 91.885294 -25.619008) (xy 91.855831 -25.573158) (xy 91.833192 -25.523583) (xy 91.817838 -25.47129)
			(xy 91.810083 -25.417344) (xy 91.80957 -25.390094) (xy 91.810058 -25.362164) (xy 91.818204 -25.306901)
			(xy 91.834321 -25.253416) (xy 91.858065 -25.202853) (xy 91.888928 -25.156293) (xy 91.92625 -25.114731)
			(xy 91.969234 -25.079055) (xy 92.01696 -25.050028) (xy 92.068409 -25.028271) (xy 92.09532 -25.020778)
			(xy 92.102178 -25.019) (xy 92.108782 -25.01519) (xy 92.118942 -25.007316) (xy 92.12707 -24.999188)
			(xy 92.134977 -24.99034) (xy 92.142382 -24.967826) (xy 92.141294 -24.956008) (xy 91.789504 -24.604218)
			(xy 91.764322 -24.578274) (xy 91.719879 -24.521245) (xy 91.682788 -24.459182) (xy 91.653612 -24.393028)
			(xy 91.632794 -24.323787) (xy 91.626182 -24.288242) (xy 91.621864 -24.263604) (xy 91.617779 -24.25984)
			(xy 91.608287 -24.254075) (xy 91.603068 -24.252174) (xy 91.593924 -24.249126) (xy 91.525344 -24.22779)
			(xy 91.515692 -24.224742) (xy 91.510356 -24.223302) (xy 91.499333 -24.222538) (xy 91.493848 -24.223218)
			(xy 91.292426 -24.42464) (xy 91.273656 -24.442674) (xy 91.231541 -24.473259) (xy 91.185165 -24.496889)
			(xy 91.135667 -24.512986) (xy 91.084262 -24.521153) (xy 91.058238 -24.521668) (xy 89.869518 -24.521668)
			(xy 89.865708 -24.5237) (xy 89.837217 -24.538699) (xy 89.776455 -24.55998) (xy 89.712986 -24.570782)
			(xy 89.680796 -24.571452) (xy 89.653544 -24.570966) (xy 89.599594 -24.563209) (xy 89.547297 -24.547854)
			(xy 89.497718 -24.525213) (xy 89.451865 -24.495748) (xy 89.410671 -24.460057) (xy 89.374976 -24.418867)
			(xy 89.345506 -24.373017) (xy 89.32286 -24.32344) (xy 89.307499 -24.271145) (xy 89.299737 -24.217196)
			(xy 89.299288 -24.189944) (xy 89.299764 -24.162783) (xy 89.307463 -24.109009) (xy 89.322712 -24.056871)
			(xy 89.345202 -24.007423) (xy 89.374479 -23.961665) (xy 89.40995 -23.920523) (xy 89.450899 -23.884828)
			(xy 89.496496 -23.855302) (xy 89.54582 -23.832543) (xy 89.597875 -23.81701) (xy 89.651606 -23.809018)
			(xy 89.678764 -23.808436) (xy 89.681558 -23.808436) (xy 89.71362 -23.809162) (xy 89.776825 -23.820004)
			(xy 89.837333 -23.841242) (xy 89.865708 -23.856188) (xy 89.869518 -23.85822) (xy 90.899234 -23.85822)
			(xy 90.902536 -23.85822) (xy 90.911558 -23.857276) (xy 90.928098 -23.849861) (xy 90.934794 -23.843742)
			(xy 91.01455 -23.763732) (xy 91.053666 -23.724616) (xy 91.054217 -23.720241) (xy 91.053959 -23.711427)
			(xy 91.053158 -23.70709) (xy 91.048078 -23.69058) (xy 91.048078 -23.690072) (xy 91.024964 -23.616412)
			(xy 91.023094 -23.611065) (xy 91.01732 -23.601322) (xy 91.013534 -23.597108) (xy 91.010486 -23.5966)
			(xy 90.988896 -23.59279) (xy 90.956081 -23.586357) (xy 90.892068 -23.567009) (xy 90.830677 -23.540492)
			(xy 90.772708 -23.507152) (xy 90.718916 -23.467423) (xy 90.670002 -23.421823) (xy 90.626603 -23.370945)
			(xy 90.589285 -23.315453) (xy 90.558534 -23.25607) (xy 90.546174 -23.224998) (xy 90.537284 -23.201884)
			(xy 90.533474 -23.198582) (xy 90.438224 -23.178516) (xy 90.433144 -23.1775) (xy 90.42527 -23.175722)
			(xy 90.420952 -23.176992) (xy 90.15857 -23.439374) (xy 90.135006 -23.462272) (xy 90.083622 -23.503225)
			(xy 90.027979 -23.538173) (xy 89.968776 -23.566677) (xy 89.906756 -23.588378) (xy 89.842697 -23.603004)
			(xy 89.777404 -23.610372) (xy 89.74455 -23.610824) (xy 89.744296 -23.610824) (xy 89.708899 -23.61029)
			(xy 89.63862 -23.601756) (xy 89.569883 -23.584813) (xy 89.503689 -23.559709) (xy 89.441004 -23.526809)
			(xy 89.382741 -23.486592) (xy 89.329751 -23.439647) (xy 89.282805 -23.386656) (xy 89.242589 -23.328393)
			(xy 89.20969 -23.265707) (xy 89.184586 -23.199513) (xy 89.167643 -23.130776) (xy 89.15911 -23.060497)
			(xy 89.158572 -23.0251) (xy 89.158572 -23.024846) (xy 89.15903 -22.991991) (xy 89.166381 -22.926694)
			(xy 89.180997 -22.862631) (xy 89.202693 -22.800607) (xy 89.231197 -22.741402) (xy 89.266151 -22.68576)
			(xy 89.307114 -22.634381) (xy 89.330022 -22.610826) (xy 89.822782 -22.118066) (xy 89.846346 -22.095169)
			(xy 89.89773 -22.054218) (xy 89.953373 -22.019272) (xy 90.012577 -21.990772) (xy 90.074597 -21.969075)
			(xy 90.138656 -21.954453) (xy 90.203949 -21.94709) (xy 90.236802 -21.946616) (xy 94.0689 -21.946616)
			(xy 94.070424 -21.94433) (xy 94.07144 -21.942806) (xy 94.10192 -21.892514) (xy 94.10192 -21.892006)
			(xy 94.117414 -21.866098) (xy 94.12224 -21.85416) (xy 94.123764 -21.842476) (xy 94.124018 -21.830792)
			(xy 94.11843 -21.818854) (xy 94.117922 -21.817838) (xy 94.104022 -21.790283) (xy 94.084336 -21.731793)
			(xy 94.074335 -21.670894) (xy 94.073726 -21.640038) (xy 94.073726 -21.63572) (xy 94.074494 -21.607317)
			(xy 94.083405 -21.551204) (xy 94.100543 -21.497034) (xy 94.125527 -21.446006) (xy 94.157805 -21.399249)
			(xy 94.17685 -21.378164) (xy 94.183708 -21.371052) (xy 94.187264 -21.362162) (xy 94.189804 -21.353018)
			(xy 94.190566 -21.344128) (xy 94.190566 -21.27377) (xy 94.190502 -21.269636) (xy 94.189232 -21.261468)
			(xy 94.188026 -21.257514) (xy 94.187264 -21.255736) (xy 94.183962 -21.2471) (xy 94.17685 -21.23948)
			(xy 94.157576 -21.218154) (xy 94.125006 -21.170791) (xy 94.099909 -21.119079) (xy 94.082855 -21.064186)
			(xy 94.074229 -21.007356) (xy 94.074227 -20.949876) (xy 94.082848 -20.893045) (xy 94.099897 -20.838151)
			(xy 94.12499 -20.786436) (xy 94.157556 -20.739071) (xy 94.17685 -20.717764) (xy 94.183962 -20.710144)
			(xy 94.187264 -20.701508) (xy 94.188026 -20.69973) (xy 94.189258 -20.695781) (xy 94.190535 -20.68761)
			(xy 94.190566 -20.683474) (xy 94.190566 -20.61337) (xy 94.190502 -20.609236) (xy 94.189232 -20.601068)
			(xy 94.188026 -20.597114) (xy 94.187264 -20.595336) (xy 94.183962 -20.5867) (xy 94.17685 -20.57908)
			(xy 94.157576 -20.557754) (xy 94.125006 -20.510391) (xy 94.099909 -20.458679) (xy 94.082855 -20.403786)
			(xy 94.074229 -20.346956) (xy 94.074227 -20.289476) (xy 94.082848 -20.232645) (xy 94.099897 -20.177751)
			(xy 94.12499 -20.126036) (xy 94.157556 -20.078671) (xy 94.17685 -20.057364) (xy 94.183962 -20.049744)
			(xy 94.187264 -20.041108) (xy 94.188026 -20.03933) (xy 94.189258 -20.035381) (xy 94.190535 -20.02721)
			(xy 94.190566 -20.023074) (xy 94.190566 -19.95297) (xy 94.190502 -19.948836) (xy 94.189232 -19.940668)
			(xy 94.188026 -19.936714) (xy 94.187264 -19.934936) (xy 94.183962 -19.9263) (xy 94.17685 -19.91868)
			(xy 94.157576 -19.897354) (xy 94.125006 -19.849991) (xy 94.099909 -19.798279) (xy 94.082855 -19.743386)
			(xy 94.074229 -19.686556) (xy 94.074227 -19.629076) (xy 94.082848 -19.572245) (xy 94.099897 -19.517351)
			(xy 94.12499 -19.465636) (xy 94.157556 -19.418271) (xy 94.17685 -19.396964) (xy 94.183962 -19.389344)
			(xy 94.187264 -19.380708) (xy 94.188026 -19.37893) (xy 94.189258 -19.374981) (xy 94.190535 -19.36681)
			(xy 94.190566 -19.362674) (xy 94.190566 -19.29257) (xy 94.190502 -19.288436) (xy 94.189232 -19.280268)
			(xy 94.188026 -19.276314) (xy 94.187264 -19.274536) (xy 94.183962 -19.2659) (xy 94.17685 -19.25828)
			(xy 94.157581 -19.236952) (xy 94.125019 -19.189588) (xy 94.09993 -19.137877) (xy 94.08288 -19.082987)
			(xy 94.074256 -19.02616) (xy 94.073726 -18.997422) (xy 94.074212 -18.970171) (xy 94.081968 -18.916223)
			(xy 94.097323 -18.863928) (xy 94.119965 -18.814351) (xy 94.149431 -18.768501) (xy 94.185122 -18.72731)
			(xy 94.226313 -18.691619) (xy 94.272163 -18.662153) (xy 94.32174 -18.639511) (xy 94.374035 -18.624156)
			(xy 94.427983 -18.6164) (xy 94.482485 -18.6164) (xy 94.536433 -18.624156) (xy 94.588728 -18.639511)
			(xy 94.638305 -18.662153) (xy 94.684155 -18.691619) (xy 94.725346 -18.72731) (xy 94.761037 -18.768501)
			(xy 94.790503 -18.814351) (xy 94.813145 -18.863928) (xy 94.8285 -18.916223) (xy 94.836256 -18.970171)
			(xy 94.836742 -18.997422) (xy 94.836219 -19.02616) (xy 94.827593 -19.082985) (xy 94.810538 -19.137873)
			(xy 94.785441 -19.18958) (xy 94.752871 -19.236937) (xy 94.733618 -19.25828) (xy 94.726506 -19.2659)
			(xy 94.723204 -19.274536) (xy 94.722442 -19.276314) (xy 94.721212 -19.280263) (xy 94.719941 -19.288434)
			(xy 94.719902 -19.29257) (xy 94.719902 -19.362674) (xy 94.719969 -19.366807) (xy 94.721245 -19.374974)
			(xy 94.722442 -19.37893) (xy 94.723204 -19.380708) (xy 94.726506 -19.389344) (xy 94.733618 -19.396964)
			(xy 94.752885 -19.418292) (xy 94.785444 -19.465655) (xy 94.810529 -19.517366) (xy 94.827574 -19.572254)
			(xy 94.836193 -19.629079) (xy 94.836191 -19.686553) (xy 94.827567 -19.743377) (xy 94.810518 -19.798264)
			(xy 94.785428 -19.849973) (xy 94.752865 -19.897333) (xy 94.733618 -19.91868) (xy 94.726506 -19.9263)
			(xy 94.723204 -19.934936) (xy 94.722442 -19.936714) (xy 94.721212 -19.940663) (xy 94.719941 -19.948834)
			(xy 94.719902 -19.95297) (xy 94.719902 -20.023074) (xy 94.719969 -20.027207) (xy 94.721245 -20.035374)
			(xy 94.722442 -20.03933) (xy 94.723204 -20.041108) (xy 94.726506 -20.049744) (xy 94.733618 -20.057364)
			(xy 94.752885 -20.078692) (xy 94.785444 -20.126055) (xy 94.810529 -20.177766) (xy 94.827574 -20.232654)
			(xy 94.836193 -20.289479) (xy 94.836191 -20.346953) (xy 94.827567 -20.403777) (xy 94.810518 -20.458664)
			(xy 94.785428 -20.510373) (xy 94.752865 -20.557733) (xy 94.733618 -20.57908) (xy 94.726506 -20.5867)
			(xy 94.723204 -20.595336) (xy 94.722442 -20.597114) (xy 94.721212 -20.601063) (xy 94.719941 -20.609234)
			(xy 94.719902 -20.61337) (xy 94.719902 -20.683474) (xy 94.719969 -20.687607) (xy 94.721245 -20.695774)
			(xy 94.722442 -20.69973) (xy 94.723204 -20.701508) (xy 94.726506 -20.710144) (xy 94.733618 -20.717764)
			(xy 94.752885 -20.739092) (xy 94.785444 -20.786455) (xy 94.810529 -20.838166) (xy 94.827574 -20.893054)
			(xy 94.836193 -20.949879) (xy 94.836191 -21.007353) (xy 94.827567 -21.064177) (xy 94.810518 -21.119064)
			(xy 94.785428 -21.170773) (xy 94.752865 -21.218133) (xy 94.733618 -21.23948) (xy 94.726506 -21.2471)
			(xy 94.723204 -21.255736) (xy 94.722442 -21.257514) (xy 94.721212 -21.261463) (xy 94.719941 -21.269634)
			(xy 94.719902 -21.27377) (xy 94.719902 -21.343874) (xy 94.719969 -21.348007) (xy 94.721245 -21.356174)
			(xy 94.722442 -21.36013) (xy 94.723204 -21.361908) (xy 94.726506 -21.370544) (xy 94.733618 -21.378164)
			(xy 94.752886 -21.399492) (xy 94.785445 -21.446856) (xy 94.81053 -21.498568) (xy 94.827575 -21.553458)
			(xy 94.836194 -21.610284) (xy 94.836742 -21.639022) (xy 94.836742 -21.641308) (xy 94.835989 -21.671946)
			(xy 94.825918 -21.732396) (xy 94.806323 -21.790462) (xy 94.792546 -21.817838) (xy 94.791022 -21.820632)
			(xy 94.7889 -21.825769) (xy 94.786716 -21.836664) (xy 94.786704 -21.842222) (xy 94.786958 -21.855684)
			(xy 94.808548 -21.892006) (xy 94.808548 -21.892514) (xy 94.839028 -21.942552) (xy 94.841822 -21.946616)
			(xy 99.252532 -21.946616) (xy 99.260241 -21.946387) (xy 99.274978 -21.941862) (xy 99.281488 -21.937726)
			(xy 99.285552 -21.934424) (xy 99.628706 -21.59127) (xy 99.629214 -21.583904) (xy 99.629214 -21.567902)
			(xy 99.626166 -21.556218) (xy 99.621848 -21.547836) (xy 99.608316 -21.520574) (xy 99.589122 -21.462819)
			(xy 99.579336 -21.402751) (xy 99.578668 -21.372322) (xy 99.578668 -21.36394) (xy 99.579663 -21.337046)
			(xy 99.588283 -21.283923) (xy 99.604285 -21.232539) (xy 99.627351 -21.183916) (xy 99.657024 -21.139017)
			(xy 99.692713 -21.098735) (xy 99.73371 -21.063871) (xy 99.779201 -21.035115) (xy 99.828283 -21.01304)
			(xy 99.87998 -20.998084) (xy 99.933267 -20.990543) (xy 99.960176 -20.990052) (xy 99.963732 -20.990052)
			(xy 99.972622 -20.990306) (xy 99.977956 -20.99056) (xy 99.989386 -20.988274) (xy 99.996099 -20.98686)
			(xy 100.008467 -20.980941) (xy 100.01377 -20.97659) (xy 100.066856 -20.925536) (xy 100.072444 -20.919186)
			(xy 100.072444 -11.67003) (xy 100.072745 -11.64385) (xy 100.077453 -11.591701) (xy 100.081842 -11.56589)
			(xy 100.082604 -11.561318) (xy 100.082604 -11.47953) (xy 100.083074 -11.447264) (xy 100.090329 -11.383139)
			(xy 100.104705 -11.320228) (xy 100.126023 -11.259317) (xy 100.154016 -11.201171) (xy 100.188332 -11.146519)
			(xy 100.228543 -11.096044) (xy 100.251006 -11.072876) (xy 100.922582 -10.4013) (xy 100.94575 -10.378772)
			(xy 100.996274 -10.338477) (xy 101.050992 -10.304093) (xy 101.109215 -10.27605) (xy 101.170211 -10.254702)
			(xy 101.233214 -10.240317) (xy 101.297432 -10.233076) (xy 101.329744 -10.232644) (xy 102.055676 -10.232644)
			(xy 102.077738 -10.232883) (xy 102.121729 -10.236313) (xy 102.14356 -10.239502) (xy 102.144576 -10.239502)
			(xy 102.176124 -10.244148) (xy 102.23804 -10.259417) (xy 102.297931 -10.281321) (xy 102.355089 -10.309599)
			(xy 102.408838 -10.343918) (xy 102.458542 -10.383871) (xy 102.48138 -10.406126) (xy 102.658672 -10.583672)
			(xy 103.204518 -11.129518) (xy 103.227418 -11.153081) (xy 103.268376 -11.204463) (xy 103.303329 -11.260105)
			(xy 103.331836 -11.319308) (xy 103.353541 -11.381329) (xy 103.36817 -11.445389) (xy 103.37554 -11.510684)
			(xy 103.375968 -11.543538) (xy 103.375968 -11.543792) (xy 103.375434 -11.579191) (xy 103.366902 -11.649472)
			(xy 103.349961 -11.718213) (xy 103.324857 -11.78441) (xy 103.291958 -11.847099) (xy 103.251743 -11.905366)
			(xy 103.204798 -11.958361) (xy 103.151807 -12.005311) (xy 103.093544 -12.045531) (xy 103.030858 -12.078436)
			(xy 102.964663 -12.103545) (xy 102.895923 -12.120493) (xy 102.825643 -12.129031) (xy 102.790244 -12.129516)
			(xy 102.78999 -12.129516) (xy 102.757134 -12.129061) (xy 102.691835 -12.121714) (xy 102.627769 -12.107101)
			(xy 102.565742 -12.085408) (xy 102.506534 -12.056907) (xy 102.450889 -12.021955) (xy 102.399507 -11.980993)
			(xy 102.37597 -11.958066) (xy 102.328218 -11.910314) (xy 102.325678 -11.909806) (xy 102.242366 -11.912092)
			(xy 102.236778 -11.912854) (xy 102.222808 -11.928856) (xy 102.19563 -11.958066) (xy 101.827584 -12.326112)
			(xy 101.824881 -12.328965) (xy 101.820293 -12.335346) (xy 101.81844 -12.338812) (xy 101.815852 -12.344238)
			(xy 101.813019 -12.355917) (xy 101.812852 -12.361926) (xy 101.812852 -20.28063) (xy 101.81463 -20.283932)
			(xy 101.825044 -20.291044) (xy 101.82606 -20.291806) (xy 101.831394 -20.296124) (xy 101.862382 -20.309332)
			(xy 101.867208 -20.310348) (xy 101.871482 -20.311132) (xy 101.880167 -20.311388) (xy 101.88448 -20.310856)
			(xy 103.389684 -18.805652) (xy 103.392986 -18.801588) (xy 103.397113 -18.795075) (xy 103.401624 -18.780339)
			(xy 103.401876 -18.772632) (xy 103.401876 -12.570968) (xy 103.402332 -12.538113) (xy 103.409682 -12.472815)
			(xy 103.424296 -12.40875) (xy 103.44599 -12.346724) (xy 103.474493 -12.287518) (xy 103.509445 -12.231874)
			(xy 103.550408 -12.180494) (xy 103.573326 -12.156948) (xy 104.038654 -11.69162) (xy 104.043642 -11.686121)
			(xy 104.050491 -11.672956) (xy 104.052116 -11.665712) (xy 104.053132 -11.65606) (xy 104.053132 -9.95934)
			(xy 104.050783 -9.956307) (xy 104.045303 -9.950941) (xy 104.04221 -9.948672) (xy 104.008428 -9.924288)
			(xy 103.974646 -9.900158) (xy 103.971852 -9.898126) (xy 103.96211 -9.89284) (xy 103.940111 -9.890328)
			(xy 103.929434 -9.8933) (xy 103.921306 -9.896094) (xy 103.893092 -9.904511) (xy 103.834919 -9.913572)
			(xy 103.805482 -9.914128) (xy 103.80472 -9.914128) (xy 103.777465 -9.913666) (xy 103.723509 -9.905911)
			(xy 103.671206 -9.890556) (xy 103.62162 -9.867914) (xy 103.575762 -9.838445) (xy 103.534565 -9.802749)
			(xy 103.498867 -9.761554) (xy 103.469396 -9.715697) (xy 103.446751 -9.666113) (xy 103.431393 -9.613811)
			(xy 103.423635 -9.559855) (xy 103.423635 -9.505345) (xy 103.431393 -9.451389) (xy 103.446751 -9.399087)
			(xy 103.469396 -9.349503) (xy 103.498867 -9.303646) (xy 103.534565 -9.262451) (xy 103.575762 -9.226755)
			(xy 103.62162 -9.197286) (xy 103.671206 -9.174644) (xy 103.723509 -9.159289) (xy 103.777465 -9.151534)
			(xy 103.80472 -9.151112) (xy 103.805482 -9.151112) (xy 103.834784 -9.151626) (xy 103.892703 -9.160553)
			(xy 103.920798 -9.168892) (xy 103.921814 -9.1694) (xy 103.933244 -9.172702) (xy 103.937492 -9.173657)
			(xy 103.946175 -9.174304) (xy 103.950516 -9.173972) (xy 103.952802 -9.173718) (xy 103.954072 -9.173464)
			(xy 103.957882 -9.172702) (xy 103.962048 -9.171571) (xy 103.96996 -9.168118) (xy 103.97363 -9.165844)
			(xy 104.008174 -9.140952) (xy 104.008682 -9.140952) (xy 104.04475 -9.115298) (xy 104.053132 -9.106408)
			(xy 104.053132 -7.53491) (xy 104.053613 -7.502034) (xy 104.061011 -7.436698) (xy 104.075671 -7.3726)
			(xy 104.097408 -7.310544) (xy 104.12595 -7.251309) (xy 104.160939 -7.195638) (xy 104.201935 -7.144229)
			(xy 104.224836 -7.120636) (xy 104.547162 -6.798564) (xy 104.778556 -6.56717) (xy 104.802134 -6.54426)
			(xy 104.853547 -6.503286) (xy 104.909225 -6.468326) (xy 104.968466 -6.439818) (xy 105.030527 -6.418121)
			(xy 105.094626 -6.403508) (xy 105.159958 -6.396163) (xy 105.19283 -6.39572) (xy 105.205022 -6.395466)
			(xy 105.239949 -6.396717) (xy 105.30915 -6.406506) (xy 105.376698 -6.42445) (xy 105.441633 -6.450298)
			(xy 105.503036 -6.483681) (xy 105.560035 -6.524126) (xy 105.611822 -6.57106) (xy 105.657662 -6.623817)
			(xy 105.696906 -6.68165) (xy 105.726878 -6.739636) (xy 106.901994 -6.739636) (xy 106.906065 -6.684014)
			(xy 106.918191 -6.629577) (xy 106.938114 -6.577486) (xy 106.96541 -6.528851) (xy 106.999496 -6.484708)
			(xy 107.039645 -6.445999) (xy 107.085003 -6.413548) (xy 107.134603 -6.388047) (xy 107.187387 -6.37004)
			(xy 107.24223 -6.35991) (xy 107.297964 -6.357873) (xy 107.353401 -6.363973) (xy 107.407358 -6.378079)
			(xy 107.458687 -6.399891) (xy 107.506293 -6.428945) (xy 107.549161 -6.46462) (xy 107.586378 -6.506157)
			(xy 107.617151 -6.55267) (xy 107.640823 -6.603167) (xy 107.656891 -6.656574) (xy 107.665011 -6.71175)
			(xy 107.66552 -6.739636) (xy 107.665011 -6.767522) (xy 107.656891 -6.822698) (xy 107.640823 -6.876105)
			(xy 107.617151 -6.926602) (xy 107.586378 -6.973115) (xy 107.549161 -7.014652) (xy 107.506293 -7.050327)
			(xy 107.458687 -7.079381) (xy 107.407358 -7.101193) (xy 107.353401 -7.115299) (xy 107.297964 -7.121399)
			(xy 107.24223 -7.119362) (xy 107.187387 -7.109232) (xy 107.134603 -7.091225) (xy 107.085003 -7.065724)
			(xy 107.039645 -7.033273) (xy 106.999496 -6.994564) (xy 106.96541 -6.950421) (xy 106.938114 -6.901786)
			(xy 106.918191 -6.849695) (xy 106.906065 -6.795258) (xy 106.901994 -6.739636) (xy 105.726878 -6.739636)
			(xy 105.728998 -6.743737) (xy 105.753481 -6.809199) (xy 105.770009 -6.877107) (xy 105.778347 -6.946499)
			(xy 105.778808 -6.981444) (xy 105.778808 -6.982968) (xy 105.778094 -7.021547) (xy 105.767758 -7.098013)
			(xy 105.747459 -7.172456) (xy 105.733088 -7.208266) (xy 105.717864 -7.243011) (xy 105.679746 -7.308596)
			(xy 105.633491 -7.36872) (xy 105.607104 -7.395972) (xy 105.3846 -7.618222) (xy 105.381164 -7.621838)
			(xy 105.375658 -7.630154) (xy 105.373678 -7.634732) (xy 105.369868 -7.643876) (xy 105.369868 -7.652258)
			(xy 105.370376 -7.659624) (xy 105.380282 -7.729474) (xy 105.380859 -7.73308) (xy 105.382896 -7.740093)
			(xy 105.384016 -7.742682) (xy 106.920282 -7.742682) (xy 106.924353 -7.68706) (xy 106.936479 -7.632623)
			(xy 106.956402 -7.580532) (xy 106.983698 -7.531897) (xy 107.017784 -7.487754) (xy 107.057933 -7.449045)
			(xy 107.103291 -7.416594) (xy 107.152891 -7.391093) (xy 107.205675 -7.373086) (xy 107.260518 -7.362956)
			(xy 107.316252 -7.360919) (xy 107.371689 -7.367019) (xy 107.425646 -7.381125) (xy 107.476975 -7.402937)
			(xy 107.524581 -7.431991) (xy 107.567449 -7.467666) (xy 107.604666 -7.509203) (xy 107.635439 -7.555716)
			(xy 107.659111 -7.606213) (xy 107.675179 -7.65962) (xy 107.683299 -7.714796) (xy 107.683808 -7.742682)
			(xy 107.683299 -7.770568) (xy 107.675179 -7.825744) (xy 107.659111 -7.879151) (xy 107.635439 -7.929648)
			(xy 107.604666 -7.976161) (xy 107.567449 -8.017698) (xy 107.524581 -8.053373) (xy 107.476975 -8.082427)
			(xy 107.425646 -8.104239) (xy 107.371689 -8.118345) (xy 107.316252 -8.124445) (xy 107.260518 -8.122408)
			(xy 107.205675 -8.112278) (xy 107.152891 -8.094271) (xy 107.103291 -8.06877) (xy 107.057933 -8.036319)
			(xy 107.017784 -7.99761) (xy 106.983698 -7.953467) (xy 106.956402 -7.904832) (xy 106.936479 -7.852741)
			(xy 106.924353 -7.798304) (xy 106.920282 -7.742682) (xy 105.384016 -7.742682) (xy 105.384346 -7.743444)
			(xy 105.40492 -7.754366) (xy 105.435764 -7.771189) (xy 105.493571 -7.811126) (xy 105.546178 -7.857698)
			(xy 105.592829 -7.910235) (xy 105.632853 -7.967981) (xy 105.665673 -8.030105) (xy 105.678732 -8.062722)
			(xy 105.684066 -8.076692) (xy 105.684574 -8.0772) (xy 105.687081 -8.079762) (xy 105.692691 -8.084222)
			(xy 105.69575 -8.08609) (xy 105.751122 -8.113522) (xy 105.75163 -8.113776) (xy 105.760166 -8.117445)
			(xy 105.778664 -8.118999) (xy 105.787698 -8.116824) (xy 105.78846 -8.11657) (xy 105.813961 -8.109798)
			(xy 105.866219 -8.102531) (xy 105.8926 -8.102092) (xy 105.919851 -8.102578) (xy 105.973799 -8.110334)
			(xy 106.026094 -8.125689) (xy 106.075671 -8.148331) (xy 106.121521 -8.177797) (xy 106.162712 -8.213488)
			(xy 106.198403 -8.254679) (xy 106.227869 -8.300529) (xy 106.250511 -8.350106) (xy 106.265866 -8.402401)
			(xy 106.273622 -8.456349) (xy 106.273622 -8.510851) (xy 106.265866 -8.564799) (xy 106.250511 -8.617094)
			(xy 106.227869 -8.666671) (xy 106.198403 -8.712521) (xy 106.162712 -8.753712) (xy 106.121521 -8.789403)
			(xy 106.075671 -8.818869) (xy 106.026094 -8.841511) (xy 105.973799 -8.856866) (xy 105.919851 -8.864622)
			(xy 105.8926 -8.865108) (xy 105.892092 -8.865108) (xy 105.871804 -8.864825) (xy 105.83146 -8.860499)
			(xy 105.811574 -8.856472) (xy 105.800398 -8.854186) (xy 105.789222 -8.856726) (xy 105.783693 -8.858152)
			(xy 105.773434 -8.863158) (xy 105.768902 -8.866632) (xy 105.749344 -8.88238) (xy 105.707942 -8.915654)
			(xy 105.698544 -8.92556) (xy 105.698544 -12.362434) (xy 105.698087 -12.395289) (xy 105.690738 -12.460587)
			(xy 105.676124 -12.524652) (xy 105.65443 -12.586678) (xy 105.625928 -12.645886) (xy 105.590976 -12.70153)
			(xy 105.550015 -12.752911) (xy 105.527094 -12.776454) (xy 105.280714 -13.022834) (xy 105.276107 -13.02769)
			(xy 105.269414 -13.039278) (xy 105.267506 -13.045694) (xy 105.163874 -13.149326) (xy 105.157024 -13.156722)
			(xy 105.149287 -13.175321) (xy 105.148888 -13.185394) (xy 105.148888 -16.969994) (xy 129.848363 -16.969994)
			(xy 129.852368 -16.882086) (xy 129.864351 -16.794906) (xy 129.884211 -16.709177) (xy 129.911786 -16.625609)
			(xy 129.946845 -16.544895) (xy 129.989098 -16.467703) (xy 130.038196 -16.394674) (xy 130.093732 -16.326412)
			(xy 130.155244 -16.263482) (xy 130.222225 -16.206408) (xy 130.294118 -16.15566) (xy 130.370327 -16.11166)
			(xy 130.450222 -16.074773) (xy 130.533141 -16.045304) (xy 130.618396 -16.023497) (xy 130.70528 -16.009533)
			(xy 130.793074 -16.003527) (xy 130.881051 -16.005531) (xy 130.968481 -16.015526) (xy 131.05464 -16.03343)
			(xy 131.138814 -16.059094) (xy 131.220305 -16.092307) (xy 131.298439 -16.132793) (xy 131.372567 -16.180215)
			(xy 131.442075 -16.234182) (xy 131.506389 -16.294247) (xy 131.564973 -16.359911) (xy 131.617344 -16.43063)
			(xy 131.663067 -16.505818) (xy 131.701764 -16.584853) (xy 131.733113 -16.667079) (xy 131.756855 -16.751815)
			(xy 131.772793 -16.838359) (xy 131.780795 -16.925994) (xy 131.781296 -16.969994) (xy 131.780795 -17.013994)
			(xy 131.772793 -17.101629) (xy 131.756855 -17.188173) (xy 131.733113 -17.272909) (xy 131.701764 -17.355135)
			(xy 131.663067 -17.43417) (xy 131.617344 -17.509358) (xy 131.564973 -17.580077) (xy 131.506389 -17.645741)
			(xy 131.442075 -17.705806) (xy 131.372567 -17.759773) (xy 131.298439 -17.807195) (xy 131.220305 -17.847681)
			(xy 131.138814 -17.880894) (xy 131.05464 -17.906558) (xy 130.968481 -17.924462) (xy 130.881051 -17.934457)
			(xy 130.793074 -17.936461) (xy 130.70528 -17.930455) (xy 130.618396 -17.916491) (xy 130.533141 -17.894684)
			(xy 130.450222 -17.865215) (xy 130.370327 -17.828328) (xy 130.294118 -17.784328) (xy 130.222225 -17.73358)
			(xy 130.155244 -17.676506) (xy 130.093732 -17.613576) (xy 130.038196 -17.545314) (xy 129.989098 -17.472285)
			(xy 129.946845 -17.395093) (xy 129.911786 -17.314379) (xy 129.884211 -17.230811) (xy 129.864351 -17.145082)
			(xy 129.852368 -17.057902) (xy 129.848363 -16.969994) (xy 105.148888 -16.969994) (xy 105.148888 -19.28368)
			(xy 105.148407 -19.316557) (xy 105.14101 -19.381893) (xy 105.126352 -19.445992) (xy 105.104616 -19.508049)
			(xy 105.076075 -19.567286) (xy 105.041088 -19.622959) (xy 105.000094 -19.674369) (xy 104.977184 -19.697954)
			(xy 104.8766 -19.798538) (xy 104.8766 -19.798792) (xy 103.950413 -20.72513) (xy 121.28044 -20.72513)
			(xy 121.28441 -20.594996) (xy 121.296306 -20.465346) (xy 121.316085 -20.336663) (xy 121.343671 -20.209424)
			(xy 121.378964 -20.084105) (xy 121.42183 -19.961169) (xy 121.472112 -19.841076) (xy 121.529621 -19.724272)
			(xy 121.594145 -19.61119) (xy 121.665442 -19.502253) (xy 121.743247 -19.397865) (xy 121.827272 -19.298414)
			(xy 121.917204 -19.204271) (xy 122.012708 -19.115786) (xy 122.113428 -19.033287) (xy 122.21899 -18.957082)
			(xy 122.329002 -18.887455) (xy 122.443054 -18.824664) (xy 122.560722 -18.768942) (xy 122.681568 -18.720498)
			(xy 122.805143 -18.679511) (xy 122.930986 -18.646134) (xy 123.058631 -18.620491) (xy 123.187601 -18.602677)
			(xy 123.317417 -18.592759) (xy 123.447596 -18.590774) (xy 123.577655 -18.596728) (xy 123.707108 -18.610601)
			(xy 123.835475 -18.632339) (xy 123.962278 -18.661863) (xy 124.087045 -18.699062) (xy 124.209312 -18.743798)
			(xy 124.328625 -18.795906) (xy 124.444538 -18.855189) (xy 124.556623 -18.92143) (xy 124.66446 -18.99438)
			(xy 124.767649 -19.073768) (xy 124.865807 -19.1593) (xy 124.958568 -19.250657) (xy 125.045587 -19.347499)
			(xy 125.12654 -19.449466) (xy 125.201126 -19.556178) (xy 125.269067 -19.667239) (xy 125.330112 -19.782235)
			(xy 125.384033 -19.900739) (xy 125.430628 -20.02231) (xy 125.469726 -20.146495) (xy 125.50118 -20.272833)
			(xy 125.524874 -20.400854) (xy 125.540718 -20.53008) (xy 125.548656 -20.660033) (xy 125.549152 -20.72513)
			(xy 125.548656 -20.790227) (xy 125.540718 -20.92018) (xy 125.524874 -21.049406) (xy 125.50118 -21.177427)
			(xy 125.469726 -21.303765) (xy 125.430628 -21.42795) (xy 125.384033 -21.549521) (xy 125.330112 -21.668025)
			(xy 125.269067 -21.783021) (xy 125.201126 -21.894082) (xy 125.12654 -22.000794) (xy 125.045587 -22.102761)
			(xy 124.958568 -22.199603) (xy 124.865807 -22.29096) (xy 124.767649 -22.376492) (xy 124.66446 -22.45588)
			(xy 124.556623 -22.52883) (xy 124.444538 -22.595071) (xy 124.328625 -22.654354) (xy 124.209312 -22.706462)
			(xy 124.087045 -22.751198) (xy 123.962278 -22.788397) (xy 123.835475 -22.817921) (xy 123.707108 -22.839659)
			(xy 123.577655 -22.853532) (xy 123.447596 -22.859486) (xy 123.317417 -22.857501) (xy 123.187601 -22.847583)
			(xy 123.058631 -22.829769) (xy 122.930986 -22.804126) (xy 122.805143 -22.770749) (xy 122.681568 -22.729762)
			(xy 122.560722 -22.681318) (xy 122.443054 -22.625596) (xy 122.329002 -22.562805) (xy 122.21899 -22.493178)
			(xy 122.113428 -22.416973) (xy 122.012708 -22.334474) (xy 121.917204 -22.245989) (xy 121.827272 -22.151846)
			(xy 121.743247 -22.052395) (xy 121.665442 -21.948007) (xy 121.594145 -21.83907) (xy 121.529621 -21.725988)
			(xy 121.472112 -21.609184) (xy 121.42183 -21.489091) (xy 121.378964 -21.366155) (xy 121.343671 -21.240836)
			(xy 121.316085 -21.113597) (xy 121.296306 -20.984914) (xy 121.28441 -20.855264) (xy 121.28044 -20.72513)
			(xy 103.950413 -20.72513) (xy 103.313484 -21.362162) (xy 103.312976 -21.36902) (xy 103.312976 -24.807418)
			(xy 122.471432 -24.807418) (xy 122.475503 -24.751796) (xy 122.487629 -24.697359) (xy 122.507552 -24.645268)
			(xy 122.534848 -24.596633) (xy 122.568934 -24.55249) (xy 122.609083 -24.513781) (xy 122.654441 -24.48133)
			(xy 122.704041 -24.455829) (xy 122.756825 -24.437822) (xy 122.811668 -24.427692) (xy 122.867402 -24.425655)
			(xy 122.922839 -24.431755) (xy 122.976796 -24.445861) (xy 123.028125 -24.467673) (xy 123.075731 -24.496727)
			(xy 123.118599 -24.532402) (xy 123.155816 -24.573939) (xy 123.186589 -24.620452) (xy 123.210261 -24.670949)
			(xy 123.226329 -24.724356) (xy 123.234449 -24.779532) (xy 123.234958 -24.807418) (xy 123.234449 -24.835304)
			(xy 123.226329 -24.89048) (xy 123.210261 -24.943887) (xy 123.186589 -24.994384) (xy 123.155816 -25.040897)
			(xy 123.118599 -25.082434) (xy 123.075731 -25.118109) (xy 123.028125 -25.147163) (xy 122.976796 -25.168975)
			(xy 122.922839 -25.183081) (xy 122.867402 -25.189181) (xy 122.811668 -25.187144) (xy 122.756825 -25.177014)
			(xy 122.704041 -25.159007) (xy 122.654441 -25.133506) (xy 122.609083 -25.101055) (xy 122.568934 -25.062346)
			(xy 122.534848 -25.018203) (xy 122.507552 -24.969568) (xy 122.487629 -24.917477) (xy 122.475503 -24.86304)
			(xy 122.471432 -24.807418) (xy 103.312976 -24.807418) (xy 103.312976 -25.906222) (xy 103.313992 -25.91562)
			(xy 103.313992 -25.916128) (xy 103.315702 -25.923284) (xy 103.322542 -25.936303) (xy 103.327454 -25.941782)
			(xy 103.342694 -25.957022) (xy 103.353362 -25.960832) (xy 103.376128 -25.969498) (xy 103.419439 -25.991792)
			(xy 103.439722 -26.005282) (xy 103.460462 -26.02004) (xy 103.475603 -26.03373) (xy 121.368056 -26.03373)
			(xy 121.372127 -25.978108) (xy 121.384253 -25.923671) (xy 121.404176 -25.87158) (xy 121.431472 -25.822945)
			(xy 121.465558 -25.778802) (xy 121.505707 -25.740093) (xy 121.551065 -25.707642) (xy 121.600665 -25.682141)
			(xy 121.653449 -25.664134) (xy 121.708292 -25.654004) (xy 121.764026 -25.651967) (xy 121.819463 -25.658067)
			(xy 121.87342 -25.672173) (xy 121.924749 -25.693985) (xy 121.972355 -25.723039) (xy 122.015223 -25.758714)
			(xy 122.05244 -25.800251) (xy 122.083213 -25.846764) (xy 122.106885 -25.897261) (xy 122.122953 -25.950668)
			(xy 122.131073 -26.005844) (xy 122.131582 -26.03373) (xy 122.131073 -26.061616) (xy 122.122953 -26.116792)
			(xy 122.106885 -26.170199) (xy 122.083213 -26.220696) (xy 122.05244 -26.267209) (xy 122.015223 -26.308746)
			(xy 121.972355 -26.344421) (xy 121.924749 -26.373475) (xy 121.87342 -26.395287) (xy 121.819463 -26.409393)
			(xy 121.764026 -26.415493) (xy 121.708292 -26.413456) (xy 121.653449 -26.403326) (xy 121.600665 -26.385319)
			(xy 121.551065 -26.359818) (xy 121.505707 -26.327367) (xy 121.465558 -26.288658) (xy 121.431472 -26.244515)
			(xy 121.404176 -26.19588) (xy 121.384253 -26.143789) (xy 121.372127 -26.089352) (xy 121.368056 -26.03373)
			(xy 103.475603 -26.03373) (xy 103.498219 -26.054178) (xy 103.531112 -26.093025) (xy 103.558556 -26.135895)
			(xy 103.580067 -26.182028) (xy 103.588058 -26.206196) (xy 103.588058 -26.206704) (xy 103.590099 -26.212369)
			(xy 103.596379 -26.222639) (xy 103.600504 -26.227024) (xy 104.93502 -27.56154) (xy 104.936036 -27.562556)
			(xy 104.949164 -27.576084) (xy 104.972588 -27.605621) (xy 104.982772 -27.621484) (xy 104.98582 -27.626564)
			(xy 105.18521 -27.825954) (xy 105.202762 -27.84417) (xy 105.232494 -27.885095) (xy 105.255454 -27.930169)
			(xy 105.271074 -27.978281) (xy 105.278971 -28.028246) (xy 105.279444 -28.053538) (xy 105.279444 -28.139136)
			(xy 118.49811 -28.139136) (xy 118.502181 -28.083514) (xy 118.514307 -28.029077) (xy 118.53423 -27.976986)
			(xy 118.561526 -27.928351) (xy 118.595612 -27.884208) (xy 118.635761 -27.845499) (xy 118.681119 -27.813048)
			(xy 118.730719 -27.787547) (xy 118.783503 -27.76954) (xy 118.838346 -27.75941) (xy 118.89408 -27.757373)
			(xy 118.949517 -27.763473) (xy 119.003474 -27.777579) (xy 119.054803 -27.799391) (xy 119.102409 -27.828445)
			(xy 119.145277 -27.86412) (xy 119.182494 -27.905657) (xy 119.213267 -27.95217) (xy 119.236939 -28.002667)
			(xy 119.253007 -28.056074) (xy 119.261127 -28.11125) (xy 119.261636 -28.139136) (xy 119.76811 -28.139136)
			(xy 119.772181 -28.083514) (xy 119.784307 -28.029077) (xy 119.80423 -27.976986) (xy 119.831526 -27.928351)
			(xy 119.865612 -27.884208) (xy 119.905761 -27.845499) (xy 119.951119 -27.813048) (xy 120.000719 -27.787547)
			(xy 120.053503 -27.76954) (xy 120.108346 -27.75941) (xy 120.16408 -27.757373) (xy 120.219517 -27.763473)
			(xy 120.273474 -27.777579) (xy 120.324803 -27.799391) (xy 120.372409 -27.828445) (xy 120.415277 -27.86412)
			(xy 120.452494 -27.905657) (xy 120.483267 -27.95217) (xy 120.506939 -28.002667) (xy 120.523007 -28.056074)
			(xy 120.531127 -28.11125) (xy 120.531636 -28.139136) (xy 120.531127 -28.167022) (xy 120.523007 -28.222198)
			(xy 120.506939 -28.275605) (xy 120.483267 -28.326102) (xy 120.452494 -28.372615) (xy 120.415277 -28.414152)
			(xy 120.372409 -28.449827) (xy 120.324803 -28.478881) (xy 120.273474 -28.500693) (xy 120.219517 -28.514799)
			(xy 120.16408 -28.520899) (xy 120.108346 -28.518862) (xy 120.053503 -28.508732) (xy 120.000719 -28.490725)
			(xy 119.951119 -28.465224) (xy 119.905761 -28.432773) (xy 119.865612 -28.394064) (xy 119.831526 -28.349921)
			(xy 119.80423 -28.301286) (xy 119.784307 -28.249195) (xy 119.772181 -28.194758) (xy 119.76811 -28.139136)
			(xy 119.261636 -28.139136) (xy 119.261127 -28.167022) (xy 119.253007 -28.222198) (xy 119.236939 -28.275605)
			(xy 119.213267 -28.326102) (xy 119.182494 -28.372615) (xy 119.145277 -28.414152) (xy 119.102409 -28.449827)
			(xy 119.054803 -28.478881) (xy 119.003474 -28.500693) (xy 118.949517 -28.514799) (xy 118.89408 -28.520899)
			(xy 118.838346 -28.518862) (xy 118.783503 -28.508732) (xy 118.730719 -28.490725) (xy 118.681119 -28.465224)
			(xy 118.635761 -28.432773) (xy 118.595612 -28.394064) (xy 118.561526 -28.349921) (xy 118.53423 -28.301286)
			(xy 118.514307 -28.249195) (xy 118.502181 -28.194758) (xy 118.49811 -28.139136) (xy 105.279444 -28.139136)
			(xy 105.279444 -30.376876) (xy 116.989098 -30.376876) (xy 116.989672 -30.347961) (xy 116.998389 -30.290793)
			(xy 117.015636 -30.235595) (xy 117.041017 -30.183633) (xy 117.073951 -30.136098) (xy 117.113683 -30.094078)
			(xy 117.136164 -30.075886) (xy 117.144978 -30.068286) (xy 117.155155 -30.047379) (xy 117.155722 -30.035754)
			(xy 117.155722 -29.955998) (xy 117.155162 -29.944369) (xy 117.144987 -29.92346) (xy 117.136164 -29.915866)
			(xy 117.113657 -29.897703) (xy 117.073925 -29.855677) (xy 117.04099 -29.808135) (xy 117.015606 -29.756169)
			(xy 116.998354 -29.700967) (xy 116.98963 -29.643794) (xy 116.989098 -29.614876) (xy 116.989584 -29.587625)
			(xy 116.99734 -29.533677) (xy 117.012695 -29.481382) (xy 117.035337 -29.431805) (xy 117.064803 -29.385955)
			(xy 117.100494 -29.344764) (xy 117.141685 -29.309073) (xy 117.187535 -29.279607) (xy 117.237112 -29.256965)
			(xy 117.289407 -29.24161) (xy 117.343355 -29.233854) (xy 117.397857 -29.233854) (xy 117.451805 -29.24161)
			(xy 117.5041 -29.256965) (xy 117.553677 -29.279607) (xy 117.599527 -29.309073) (xy 117.640718 -29.344764)
			(xy 117.676409 -29.385955) (xy 117.705875 -29.431805) (xy 117.728517 -29.481382) (xy 117.743872 -29.533677)
			(xy 117.751628 -29.587625) (xy 117.752114 -29.614876) (xy 117.751611 -29.643794) (xy 117.742884 -29.700967)
			(xy 117.725625 -29.756168) (xy 117.70023 -29.80813) (xy 117.667282 -29.855663) (xy 117.627536 -29.897678)
			(xy 117.605048 -29.915866) (xy 117.596257 -29.923489) (xy 117.586067 -29.944378) (xy 117.58549 -29.955998)
			(xy 117.58549 -30.035754) (xy 117.586016 -30.047387) (xy 117.596215 -30.068296) (xy 117.605048 -30.075886)
			(xy 117.627535 -30.094073) (xy 117.667268 -30.136095) (xy 117.700205 -30.183631) (xy 117.725592 -30.235593)
			(xy 117.742848 -30.290791) (xy 117.751578 -30.34796) (xy 117.752114 -30.376876) (xy 117.751628 -30.404127)
			(xy 117.743872 -30.458075) (xy 117.728517 -30.51037) (xy 117.705875 -30.559947) (xy 117.676409 -30.605797)
			(xy 117.640718 -30.646988) (xy 117.599527 -30.682679) (xy 117.553677 -30.712145) (xy 117.5041 -30.734787)
			(xy 117.451805 -30.750142) (xy 117.397857 -30.757898) (xy 117.343355 -30.757898) (xy 117.289407 -30.750142)
			(xy 117.237112 -30.734787) (xy 117.187535 -30.712145) (xy 117.141685 -30.682679) (xy 117.100494 -30.646988)
			(xy 117.064803 -30.605797) (xy 117.035337 -30.559947) (xy 117.012695 -30.51037) (xy 116.99734 -30.458075)
			(xy 116.989584 -30.404127) (xy 116.989098 -30.376876) (xy 105.279444 -30.376876) (xy 105.279444 -31.36392)
			(xy 105.278947 -31.38921) (xy 105.271037 -31.439167) (xy 105.255414 -31.487273) (xy 105.232462 -31.532346)
			(xy 105.206663 -31.567882) (xy 117.098824 -31.567882) (xy 117.102895 -31.51226) (xy 117.115021 -31.457823)
			(xy 117.134944 -31.405732) (xy 117.16224 -31.357097) (xy 117.196326 -31.312954) (xy 117.236475 -31.274245)
			(xy 117.281833 -31.241794) (xy 117.331433 -31.216293) (xy 117.384217 -31.198286) (xy 117.43906 -31.188156)
			(xy 117.494794 -31.186119) (xy 117.550231 -31.192219) (xy 117.604188 -31.206325) (xy 117.655517 -31.228137)
			(xy 117.703123 -31.257191) (xy 117.745991 -31.292866) (xy 117.783208 -31.334403) (xy 117.813981 -31.380916)
			(xy 117.837653 -31.431413) (xy 117.853721 -31.48482) (xy 117.861841 -31.539996) (xy 117.86235 -31.567882)
			(xy 117.861841 -31.595768) (xy 117.853721 -31.650944) (xy 117.837653 -31.704351) (xy 117.830661 -31.719266)
			(xy 118.385588 -31.719266) (xy 118.389659 -31.663644) (xy 118.401785 -31.609207) (xy 118.421708 -31.557116)
			(xy 118.449004 -31.508481) (xy 118.48309 -31.464338) (xy 118.523239 -31.425629) (xy 118.568597 -31.393178)
			(xy 118.618197 -31.367677) (xy 118.670981 -31.34967) (xy 118.725824 -31.33954) (xy 118.781558 -31.337503)
			(xy 118.836995 -31.343603) (xy 118.890952 -31.357709) (xy 118.942281 -31.379521) (xy 118.989887 -31.408575)
			(xy 119.032755 -31.44425) (xy 119.069972 -31.485787) (xy 119.100745 -31.5323) (xy 119.124417 -31.582797)
			(xy 119.140485 -31.636204) (xy 119.144635 -31.664402) (xy 119.661176 -31.664402) (xy 119.665247 -31.60878)
			(xy 119.677373 -31.554343) (xy 119.697296 -31.502252) (xy 119.724592 -31.453617) (xy 119.758678 -31.409474)
			(xy 119.798827 -31.370765) (xy 119.844185 -31.338314) (xy 119.893785 -31.312813) (xy 119.946569 -31.294806)
			(xy 120.001412 -31.284676) (xy 120.057146 -31.282639) (xy 120.112583 -31.288739) (xy 120.16654 -31.302845)
			(xy 120.217869 -31.324657) (xy 120.265475 -31.353711) (xy 120.308343 -31.389386) (xy 120.34556 -31.430923)
			(xy 120.376333 -31.477436) (xy 120.400005 -31.527933) (xy 120.416073 -31.58134) (xy 120.424193 -31.636516)
			(xy 120.424702 -31.664402) (xy 120.424193 -31.692288) (xy 120.416073 -31.747464) (xy 120.400005 -31.800871)
			(xy 120.376333 -31.851368) (xy 120.34556 -31.897881) (xy 120.308343 -31.939418) (xy 120.265475 -31.975093)
			(xy 120.217869 -32.004147) (xy 120.16654 -32.025959) (xy 120.112583 -32.040065) (xy 120.057146 -32.046165)
			(xy 120.001412 -32.044128) (xy 119.946569 -32.033998) (xy 119.893785 -32.015991) (xy 119.844185 -31.99049)
			(xy 119.798827 -31.958039) (xy 119.758678 -31.91933) (xy 119.724592 -31.875187) (xy 119.697296 -31.826552)
			(xy 119.677373 -31.774461) (xy 119.665247 -31.720024) (xy 119.661176 -31.664402) (xy 119.144635 -31.664402)
			(xy 119.148605 -31.69138) (xy 119.149114 -31.719266) (xy 119.148605 -31.747152) (xy 119.140485 -31.802328)
			(xy 119.124417 -31.855735) (xy 119.100745 -31.906232) (xy 119.069972 -31.952745) (xy 119.032755 -31.994282)
			(xy 118.989887 -32.029957) (xy 118.942281 -32.059011) (xy 118.890952 -32.080823) (xy 118.836995 -32.094929)
			(xy 118.781558 -32.101029) (xy 118.725824 -32.098992) (xy 118.670981 -32.088862) (xy 118.618197 -32.070855)
			(xy 118.568597 -32.045354) (xy 118.523239 -32.012903) (xy 118.48309 -31.974194) (xy 118.449004 -31.930051)
			(xy 118.421708 -31.881416) (xy 118.401785 -31.829325) (xy 118.389659 -31.774888) (xy 118.385588 -31.719266)
			(xy 117.830661 -31.719266) (xy 117.813981 -31.754848) (xy 117.783208 -31.801361) (xy 117.745991 -31.842898)
			(xy 117.703123 -31.878573) (xy 117.655517 -31.907627) (xy 117.604188 -31.929439) (xy 117.550231 -31.943545)
			(xy 117.494794 -31.949645) (xy 117.43906 -31.947608) (xy 117.384217 -31.937478) (xy 117.331433 -31.919471)
			(xy 117.281833 -31.89397) (xy 117.236475 -31.861519) (xy 117.196326 -31.82281) (xy 117.16224 -31.778667)
			(xy 117.134944 -31.730032) (xy 117.115021 -31.677941) (xy 117.102895 -31.623504) (xy 117.098824 -31.567882)
			(xy 105.206663 -31.567882) (xy 105.202747 -31.573276) (xy 105.18521 -31.591504) (xy 104.989376 -31.787338)
			(xy 104.983788 -31.793942) (xy 104.968294 -31.817056) (xy 104.960745 -31.827175) (xy 104.944341 -31.84637)
			(xy 104.935528 -31.85541) (xy 103.650796 -33.139888) (xy 103.645727 -33.145357) (xy 103.638757 -33.15853)
			(xy 103.63708 -33.165796) (xy 103.636064 -33.175702) (xy 103.636064 -35.073844) (xy 103.636148 -35.078052)
			(xy 103.637561 -35.086349) (xy 103.638858 -35.090354) (xy 103.640878 -35.095715) (xy 103.646903 -35.105455)
			(xy 103.650796 -35.109658) (xy 103.805996 -35.264852) (xy 120.002552 -35.264852) (xy 120.006623 -35.20923)
			(xy 120.018749 -35.154793) (xy 120.038672 -35.102702) (xy 120.065968 -35.054067) (xy 120.100054 -35.009924)
			(xy 120.140203 -34.971215) (xy 120.185561 -34.938764) (xy 120.235161 -34.913263) (xy 120.287945 -34.895256)
			(xy 120.342788 -34.885126) (xy 120.398522 -34.883089) (xy 120.453959 -34.889189) (xy 120.507916 -34.903295)
			(xy 120.559245 -34.925107) (xy 120.606851 -34.954161) (xy 120.649719 -34.989836) (xy 120.686936 -35.031373)
			(xy 120.717709 -35.077886) (xy 120.741381 -35.128383) (xy 120.757449 -35.18179) (xy 120.765569 -35.236966)
			(xy 120.766078 -35.264852) (xy 120.765569 -35.292738) (xy 120.757449 -35.347914) (xy 120.741381 -35.401321)
			(xy 120.717709 -35.451818) (xy 120.686936 -35.498331) (xy 120.649719 -35.539868) (xy 120.606851 -35.575543)
			(xy 120.559245 -35.604597) (xy 120.507916 -35.626409) (xy 120.453959 -35.640515) (xy 120.398522 -35.646615)
			(xy 120.342788 -35.644578) (xy 120.287945 -35.634448) (xy 120.235161 -35.616441) (xy 120.185561 -35.59094)
			(xy 120.140203 -35.558489) (xy 120.100054 -35.51978) (xy 120.065968 -35.475637) (xy 120.038672 -35.427002)
			(xy 120.018749 -35.374911) (xy 120.006623 -35.320474) (xy 120.002552 -35.264852) (xy 103.805996 -35.264852)
			(xy 104.417908 -35.876738) (xy 108.817408 -35.876738) (xy 108.821479 -35.821116) (xy 108.833605 -35.766679)
			(xy 108.853528 -35.714588) (xy 108.880824 -35.665953) (xy 108.91491 -35.62181) (xy 108.955059 -35.583101)
			(xy 109.000417 -35.55065) (xy 109.050017 -35.525149) (xy 109.102801 -35.507142) (xy 109.157644 -35.497012)
			(xy 109.213378 -35.494975) (xy 109.268815 -35.501075) (xy 109.322772 -35.515181) (xy 109.374101 -35.536993)
			(xy 109.421707 -35.566047) (xy 109.464575 -35.601722) (xy 109.501792 -35.643259) (xy 109.532565 -35.689772)
			(xy 109.556237 -35.740269) (xy 109.572305 -35.793676) (xy 109.580425 -35.848852) (xy 109.580934 -35.876738)
			(xy 109.580425 -35.904624) (xy 109.572305 -35.9598) (xy 109.556237 -36.013207) (xy 109.532565 -36.063704)
			(xy 109.501792 -36.110217) (xy 109.464575 -36.151754) (xy 109.421707 -36.187429) (xy 109.374101 -36.216483)
			(xy 109.322772 -36.238295) (xy 109.268815 -36.252401) (xy 109.213378 -36.258501) (xy 109.157644 -36.256464)
			(xy 109.102801 -36.246334) (xy 109.050017 -36.228327) (xy 109.000417 -36.202826) (xy 108.955059 -36.170375)
			(xy 108.91491 -36.131666) (xy 108.880824 -36.087523) (xy 108.853528 -36.038888) (xy 108.833605 -35.986797)
			(xy 108.821479 -35.93236) (xy 108.817408 -35.876738) (xy 104.417908 -35.876738) (xy 105.051157 -36.50996)
			(xy 110.714026 -36.50996) (xy 110.718097 -36.454338) (xy 110.730223 -36.399901) (xy 110.750146 -36.34781)
			(xy 110.777442 -36.299175) (xy 110.811528 -36.255032) (xy 110.851677 -36.216323) (xy 110.897035 -36.183872)
			(xy 110.946635 -36.158371) (xy 110.999419 -36.140364) (xy 111.054262 -36.130234) (xy 111.109996 -36.128197)
			(xy 111.165433 -36.134297) (xy 111.21939 -36.148403) (xy 111.270719 -36.170215) (xy 111.318325 -36.199269)
			(xy 111.361193 -36.234944) (xy 111.39841 -36.276481) (xy 111.429183 -36.322994) (xy 111.452855 -36.373491)
			(xy 111.468923 -36.426898) (xy 111.477043 -36.482074) (xy 111.477552 -36.50996) (xy 111.477043 -36.537846)
			(xy 111.468923 -36.593022) (xy 111.452855 -36.646429) (xy 111.429183 -36.696926) (xy 111.39841 -36.743439)
			(xy 111.361193 -36.784976) (xy 111.318325 -36.820651) (xy 111.270719 -36.849705) (xy 111.21939 -36.871517)
			(xy 111.165433 -36.885623) (xy 111.109996 -36.891723) (xy 111.054262 -36.889686) (xy 110.999419 -36.879556)
			(xy 110.946635 -36.861549) (xy 110.897035 -36.836048) (xy 110.851677 -36.803597) (xy 110.811528 -36.764888)
			(xy 110.777442 -36.720745) (xy 110.750146 -36.67211) (xy 110.730223 -36.620019) (xy 110.718097 -36.565582)
			(xy 110.714026 -36.50996) (xy 105.051157 -36.50996) (xy 106.016398 -37.47516) (xy 107.85932 -37.47516)
			(xy 107.863391 -37.419538) (xy 107.875517 -37.365101) (xy 107.89544 -37.31301) (xy 107.922736 -37.264375)
			(xy 107.956822 -37.220232) (xy 107.996971 -37.181523) (xy 108.042329 -37.149072) (xy 108.091929 -37.123571)
			(xy 108.144713 -37.105564) (xy 108.199556 -37.095434) (xy 108.25529 -37.093397) (xy 108.310727 -37.099497)
			(xy 108.364684 -37.113603) (xy 108.416013 -37.135415) (xy 108.463619 -37.164469) (xy 108.506487 -37.200144)
			(xy 108.543704 -37.241681) (xy 108.574477 -37.288194) (xy 108.598149 -37.338691) (xy 108.614217 -37.392098)
			(xy 108.622337 -37.447274) (xy 108.622846 -37.47516) (xy 108.622337 -37.503046) (xy 108.614217 -37.558222)
			(xy 108.598149 -37.611629) (xy 108.574477 -37.662126) (xy 108.574324 -37.662358) (xy 110.048546 -37.662358)
			(xy 110.052617 -37.606736) (xy 110.064743 -37.552299) (xy 110.084666 -37.500208) (xy 110.111962 -37.451573)
			(xy 110.146048 -37.40743) (xy 110.186197 -37.368721) (xy 110.231555 -37.33627) (xy 110.281155 -37.310769)
			(xy 110.333939 -37.292762) (xy 110.388782 -37.282632) (xy 110.444516 -37.280595) (xy 110.499953 -37.286695)
			(xy 110.55391 -37.300801) (xy 110.605239 -37.322613) (xy 110.652845 -37.351667) (xy 110.695713 -37.387342)
			(xy 110.73293 -37.428879) (xy 110.763703 -37.475392) (xy 110.787375 -37.525889) (xy 110.803443 -37.579296)
			(xy 110.811563 -37.634472) (xy 110.812072 -37.662358) (xy 110.811563 -37.690244) (xy 110.803443 -37.74542)
			(xy 110.787375 -37.798827) (xy 110.763703 -37.849324) (xy 110.73293 -37.895837) (xy 110.695713 -37.937374)
			(xy 110.652845 -37.973049) (xy 110.605239 -38.002103) (xy 110.55391 -38.023915) (xy 110.499953 -38.038021)
			(xy 110.444516 -38.044121) (xy 110.388782 -38.042084) (xy 110.333939 -38.031954) (xy 110.281155 -38.013947)
			(xy 110.231555 -37.988446) (xy 110.186197 -37.955995) (xy 110.146048 -37.917286) (xy 110.111962 -37.873143)
			(xy 110.084666 -37.824508) (xy 110.064743 -37.772417) (xy 110.052617 -37.71798) (xy 110.048546 -37.662358)
			(xy 108.574324 -37.662358) (xy 108.543704 -37.708639) (xy 108.506487 -37.750176) (xy 108.463619 -37.785851)
			(xy 108.416013 -37.814905) (xy 108.364684 -37.836717) (xy 108.310727 -37.850823) (xy 108.25529 -37.856923)
			(xy 108.199556 -37.854886) (xy 108.144713 -37.844756) (xy 108.091929 -37.826749) (xy 108.042329 -37.801248)
			(xy 107.996971 -37.768797) (xy 107.956822 -37.730088) (xy 107.922736 -37.685945) (xy 107.89544 -37.63731)
			(xy 107.875517 -37.585219) (xy 107.863391 -37.530782) (xy 107.85932 -37.47516) (xy 106.016398 -37.47516)
			(xy 109.657896 -41.116504) (xy 109.675926 -41.135276) (xy 109.706502 -41.177394) (xy 109.730124 -41.22377)
			(xy 109.746213 -41.273267) (xy 109.754374 -41.324669) (xy 109.754924 -41.350692) (xy 109.754924 -52.724304)
			(xy 109.756702 -52.737512) (xy 109.758621 -52.743825) (xy 109.765178 -52.755272) (xy 109.769656 -52.760118)
			(xy 110.845346 -53.835808) (xy 112.55883 -55.549038) (xy 112.565884 -55.555495) (xy 112.583437 -55.563049)
			(xy 112.602538 -55.563589) (xy 112.611662 -55.560722) (xy 112.613948 -55.559706) (xy 112.620941 -55.556555)
			(xy 112.632831 -55.546878) (xy 112.637316 -55.540656) (xy 112.641126 -55.534814) (xy 112.645444 -55.520844)
			(xy 112.645444 -36.170108) (xy 112.645975 -36.144086) (xy 112.654147 -36.092685) (xy 112.670246 -36.043192)
			(xy 112.693876 -35.99682) (xy 112.724457 -35.954706) (xy 112.742472 -35.93592) (xy 112.89411 -35.784282)
			(xy 112.901984 -35.774122) (xy 112.904524 -35.769804) (xy 112.906556 -35.763708) (xy 112.914994 -35.738128)
			(xy 112.938058 -35.689452) (xy 112.967732 -35.6445) (xy 113.003429 -35.604164) (xy 113.04444 -35.569244)
			(xy 113.089951 -35.540434) (xy 113.139058 -35.518305) (xy 113.190789 -35.503296) (xy 113.244114 -35.495705)
			(xy 113.271046 -35.49523) (xy 113.298294 -35.495719) (xy 113.352235 -35.503481) (xy 113.404522 -35.518841)
			(xy 113.454091 -35.541485) (xy 113.499933 -35.570953) (xy 113.541114 -35.606645) (xy 113.576797 -35.647835)
			(xy 113.606255 -35.693683) (xy 113.628888 -35.743257) (xy 113.644236 -35.795547) (xy 113.651987 -35.84949)
			(xy 113.652554 -35.876738) (xy 113.65209 -35.903659) (xy 113.644519 -35.956966) (xy 113.629534 -36.00868)
			(xy 113.60743 -36.057776) (xy 113.578648 -36.103279) (xy 113.543758 -36.144287) (xy 113.503452 -36.179985)
			(xy 113.45853 -36.209666) (xy 113.409883 -36.23274) (xy 113.38433 -36.241228) (xy 113.378488 -36.243006)
			(xy 113.36782 -36.249356) (xy 113.35639 -36.260786) (xy 113.323116 -36.293806) (xy 113.317044 -36.300662)
			(xy 113.309769 -36.317455) (xy 113.308892 -36.326572) (xy 113.308892 -36.453572) (xy 114.028726 -36.453572)
			(xy 114.032797 -36.39795) (xy 114.044923 -36.343513) (xy 114.064846 -36.291422) (xy 114.092142 -36.242787)
			(xy 114.126228 -36.198644) (xy 114.166377 -36.159935) (xy 114.211735 -36.127484) (xy 114.261335 -36.101983)
			(xy 114.314119 -36.083976) (xy 114.368962 -36.073846) (xy 114.424696 -36.071809) (xy 114.480133 -36.077909)
			(xy 114.53409 -36.092015) (xy 114.585419 -36.113827) (xy 114.633025 -36.142881) (xy 114.675893 -36.178556)
			(xy 114.71311 -36.220093) (xy 114.743883 -36.266606) (xy 114.753419 -36.286948) (xy 121.300492 -36.286948)
			(xy 121.304563 -36.231326) (xy 121.316689 -36.176889) (xy 121.336612 -36.124798) (xy 121.363908 -36.076163)
			(xy 121.397994 -36.03202) (xy 121.438143 -35.993311) (xy 121.483501 -35.96086) (xy 121.533101 -35.935359)
			(xy 121.585885 -35.917352) (xy 121.640728 -35.907222) (xy 121.696462 -35.905185) (xy 121.751899 -35.911285)
			(xy 121.805856 -35.925391) (xy 121.857185 -35.947203) (xy 121.904791 -35.976257) (xy 121.947659 -36.011932)
			(xy 121.984876 -36.053469) (xy 122.015649 -36.099982) (xy 122.039321 -36.150479) (xy 122.055389 -36.203886)
			(xy 122.063509 -36.259062) (xy 122.064018 -36.286948) (xy 122.063509 -36.314834) (xy 122.055389 -36.37001)
			(xy 122.039321 -36.423417) (xy 122.015649 -36.473914) (xy 121.984876 -36.520427) (xy 121.947659 -36.561964)
			(xy 121.904791 -36.597639) (xy 121.857185 -36.626693) (xy 121.805856 -36.648505) (xy 121.751899 -36.662611)
			(xy 121.696462 -36.668711) (xy 121.640728 -36.666674) (xy 121.585885 -36.656544) (xy 121.533101 -36.638537)
			(xy 121.483501 -36.613036) (xy 121.438143 -36.580585) (xy 121.397994 -36.541876) (xy 121.363908 -36.497733)
			(xy 121.336612 -36.449098) (xy 121.316689 -36.397007) (xy 121.304563 -36.34257) (xy 121.300492 -36.286948)
			(xy 114.753419 -36.286948) (xy 114.767555 -36.317103) (xy 114.783623 -36.37051) (xy 114.791743 -36.425686)
			(xy 114.792252 -36.453572) (xy 114.791743 -36.481458) (xy 114.783623 -36.536634) (xy 114.767555 -36.590041)
			(xy 114.743883 -36.640538) (xy 114.71311 -36.687051) (xy 114.675893 -36.728588) (xy 114.633025 -36.764263)
			(xy 114.585419 -36.793317) (xy 114.53409 -36.815129) (xy 114.480133 -36.829235) (xy 114.424696 -36.835335)
			(xy 114.368962 -36.833298) (xy 114.314119 -36.823168) (xy 114.261335 -36.805161) (xy 114.211735 -36.77966)
			(xy 114.166377 -36.747209) (xy 114.126228 -36.7085) (xy 114.092142 -36.664357) (xy 114.064846 -36.615722)
			(xy 114.044923 -36.563631) (xy 114.032797 -36.509194) (xy 114.028726 -36.453572) (xy 113.308892 -36.453572)
			(xy 113.308892 -37.774118) (xy 121.564906 -37.774118) (xy 121.568977 -37.718496) (xy 121.581103 -37.664059)
			(xy 121.601026 -37.611968) (xy 121.628322 -37.563333) (xy 121.662408 -37.51919) (xy 121.702557 -37.480481)
			(xy 121.747915 -37.44803) (xy 121.797515 -37.422529) (xy 121.850299 -37.404522) (xy 121.905142 -37.394392)
			(xy 121.960876 -37.392355) (xy 122.016313 -37.398455) (xy 122.07027 -37.412561) (xy 122.121599 -37.434373)
			(xy 122.169205 -37.463427) (xy 122.212073 -37.499102) (xy 122.24929 -37.540639) (xy 122.280063 -37.587152)
			(xy 122.303735 -37.637649) (xy 122.319803 -37.691056) (xy 122.327923 -37.746232) (xy 122.328432 -37.774118)
			(xy 122.327923 -37.802004) (xy 122.319803 -37.85718) (xy 122.303735 -37.910587) (xy 122.280063 -37.961084)
			(xy 122.24929 -38.007597) (xy 122.212073 -38.049134) (xy 122.169205 -38.084809) (xy 122.121599 -38.113863)
			(xy 122.07027 -38.135675) (xy 122.016313 -38.149781) (xy 121.960876 -38.155881) (xy 121.905142 -38.153844)
			(xy 121.850299 -38.143714) (xy 121.797515 -38.125707) (xy 121.747915 -38.100206) (xy 121.702557 -38.067755)
			(xy 121.662408 -38.029046) (xy 121.628322 -37.984903) (xy 121.601026 -37.936268) (xy 121.581103 -37.884177)
			(xy 121.568977 -37.82974) (xy 121.564906 -37.774118) (xy 113.308892 -37.774118) (xy 113.308892 -38.729952)
			(xy 113.801097 -38.729952) (xy 113.801097 -38.675448) (xy 113.808855 -38.621499) (xy 113.824211 -38.569204)
			(xy 113.846854 -38.519626) (xy 113.876323 -38.473776) (xy 113.912018 -38.432587) (xy 113.953211 -38.396897)
			(xy 113.999065 -38.367433) (xy 114.048645 -38.344796) (xy 114.100942 -38.329445) (xy 114.154892 -38.321694)
			(xy 114.182144 -38.321234) (xy 114.210447 -38.321752) (xy 114.266435 -38.330097) (xy 114.320575 -38.346626)
			(xy 114.371676 -38.370976) (xy 114.418616 -38.402613) (xy 114.460364 -38.440841) (xy 114.496003 -38.48482)
			(xy 114.51082 -38.50894) (xy 114.518425 -38.520969) (xy 114.539042 -38.540571) (xy 114.564273 -38.553713)
			(xy 114.592152 -38.559374) (xy 114.62051 -38.557111) (xy 114.647139 -38.547101) (xy 114.669966 -38.530123)
			(xy 114.678968 -38.5191) (xy 114.697178 -38.496243) (xy 114.739336 -38.455778) (xy 114.787167 -38.422209)
			(xy 114.839554 -38.396318) (xy 114.895274 -38.378712) (xy 114.953026 -38.3698) (xy 114.982244 -38.36924)
			(xy 115.009497 -38.369633) (xy 115.063446 -38.377395) (xy 115.115742 -38.392756) (xy 115.16532 -38.415403)
			(xy 115.211171 -38.444874) (xy 115.252361 -38.48057) (xy 115.288052 -38.521764) (xy 115.317518 -38.567618)
			(xy 115.340159 -38.617199) (xy 115.355514 -38.669497) (xy 115.36327 -38.723447) (xy 115.36327 -38.777953)
			(xy 115.355514 -38.831903) (xy 115.340159 -38.884201) (xy 115.317518 -38.933782) (xy 115.288052 -38.979636)
			(xy 115.252361 -39.02083) (xy 115.211171 -39.056526) (xy 115.16532 -39.085997) (xy 115.115742 -39.108644)
			(xy 115.063446 -39.124005) (xy 115.009497 -39.131767) (xy 114.982244 -39.132256) (xy 114.95394 -39.131752)
			(xy 114.897951 -39.123406) (xy 114.843811 -39.106874) (xy 114.79271 -39.082522) (xy 114.74577 -39.050883)
			(xy 114.704022 -39.012653) (xy 114.668385 -38.968671) (xy 114.653568 -38.94455) (xy 114.645978 -38.93251)
			(xy 114.625357 -38.91291) (xy 114.600124 -38.899769) (xy 114.572242 -38.89411) (xy 114.543882 -38.896375)
			(xy 114.517251 -38.906387) (xy 114.494423 -38.923366) (xy 114.48542 -38.93439) (xy 114.467215 -38.95725)
			(xy 114.425056 -38.997716) (xy 114.377224 -39.031285) (xy 114.324836 -39.057175) (xy 114.269115 -39.074781)
			(xy 114.211362 -39.083691) (xy 114.182144 -39.08425) (xy 114.154892 -39.083706) (xy 114.100942 -39.075955)
			(xy 114.048645 -39.060604) (xy 113.999065 -39.037967) (xy 113.953211 -39.008503) (xy 113.912018 -38.972813)
			(xy 113.876323 -38.931624) (xy 113.846854 -38.885774) (xy 113.824211 -38.836196) (xy 113.808855 -38.783901)
			(xy 113.801097 -38.729952) (xy 113.308892 -38.729952) (xy 113.308892 -39.97198) (xy 115.996466 -39.97198)
			(xy 115.996959 -39.944729) (xy 116.004718 -39.890783) (xy 116.020074 -39.83849) (xy 116.042716 -39.788915)
			(xy 116.072182 -39.743066) (xy 116.107872 -39.701876) (xy 116.149061 -39.666185) (xy 116.194909 -39.636718)
			(xy 116.244485 -39.614076) (xy 116.296777 -39.598719) (xy 116.350723 -39.59096) (xy 116.377974 -39.590472)
			(xy 116.404663 -39.590955) (xy 116.457518 -39.5984) (xy 116.508822 -39.613135) (xy 116.557573 -39.634872)
			(xy 116.602821 -39.663187) (xy 116.643684 -39.697529) (xy 116.679365 -39.737228) (xy 116.709169 -39.781509)
			(xy 116.732515 -39.829511) (xy 116.748947 -39.880296) (xy 116.758145 -39.932875) (xy 116.759482 -39.959534)
			(xy 116.760244 -39.967154) (xy 116.76286 -39.982194) (xy 116.765658 -40.012595) (xy 116.765832 -40.02786)
			(xy 116.765832 -40.536114) (xy 116.766175 -40.544728) (xy 116.771826 -40.560997) (xy 116.782578 -40.574452)
			(xy 116.789708 -40.579294) (xy 116.873528 -40.631872) (xy 116.899182 -40.633396) (xy 116.91112 -40.627808)
			(xy 116.937007 -40.615942) (xy 116.991436 -40.599204) (xy 117.047748 -40.590742) (xy 117.07622 -40.590216)
			(xy 117.103472 -40.590655) (xy 117.157421 -40.598415) (xy 117.209717 -40.613772) (xy 117.259294 -40.636416)
			(xy 117.305145 -40.665885) (xy 117.346336 -40.701579) (xy 117.382027 -40.742771) (xy 117.411494 -40.788623)
			(xy 117.434135 -40.838202) (xy 117.44949 -40.890499) (xy 117.457246 -40.944448) (xy 117.457246 -40.998952)
			(xy 117.44949 -41.052901) (xy 117.434135 -41.105198) (xy 117.411494 -41.154777) (xy 117.382027 -41.200629)
			(xy 117.346336 -41.241821) (xy 117.305145 -41.277515) (xy 117.259294 -41.306984) (xy 117.209717 -41.329628)
			(xy 117.157421 -41.344985) (xy 117.103472 -41.352745) (xy 117.07622 -41.353232) (xy 117.047747 -41.352726)
			(xy 116.991436 -41.344255) (xy 116.937012 -41.327497) (xy 116.91112 -41.31564) (xy 116.899182 -41.310052)
			(xy 116.873528 -41.311576) (xy 116.789708 -41.364154) (xy 116.782587 -41.369002) (xy 116.771863 -41.382473)
			(xy 116.766172 -41.398725) (xy 116.765832 -41.407334) (xy 116.765832 -49.601953) (xy 122.213059 -49.601953)
			(xy 122.213059 -49.547447) (xy 122.220817 -49.493495) (xy 122.236173 -49.441196) (xy 122.258817 -49.391616)
			(xy 122.288286 -49.345762) (xy 122.323981 -49.30457) (xy 122.365175 -49.268876) (xy 122.41103 -49.239409)
			(xy 122.460611 -49.216768) (xy 122.512911 -49.201413) (xy 122.566863 -49.193658) (xy 122.594116 -49.193196)
			(xy 122.621487 -49.193654) (xy 122.675666 -49.201474) (xy 122.728169 -49.216965) (xy 122.777916 -49.239808)
			(xy 122.823882 -49.269534) (xy 122.844814 -49.287176) (xy 122.845068 -49.28743) (xy 122.852157 -49.293013)
			(xy 122.869072 -49.299261) (xy 122.878088 -49.299622) (xy 122.945144 -49.299622) (xy 122.954158 -49.299234)
			(xy 122.971075 -49.293007) (xy 122.978164 -49.28743) (xy 122.978164 -49.287176) (xy 122.978418 -49.287176)
			(xy 122.999351 -49.269535) (xy 123.045319 -49.239811) (xy 123.095065 -49.216965) (xy 123.147567 -49.201469)
			(xy 123.201745 -49.19364) (xy 123.256487 -49.19364) (xy 123.310665 -49.201469) (xy 123.363167 -49.216965)
			(xy 123.412913 -49.239811) (xy 123.458881 -49.269535) (xy 123.479814 -49.287176) (xy 123.480068 -49.28743)
			(xy 123.487157 -49.293013) (xy 123.504072 -49.299261) (xy 123.513088 -49.299622) (xy 123.580144 -49.299622)
			(xy 123.589158 -49.299234) (xy 123.606075 -49.293007) (xy 123.613164 -49.28743) (xy 123.613164 -49.287176)
			(xy 123.613418 -49.287176) (xy 123.634351 -49.269535) (xy 123.680319 -49.239811) (xy 123.730065 -49.216965)
			(xy 123.782567 -49.201469) (xy 123.836745 -49.19364) (xy 123.891487 -49.19364) (xy 123.945665 -49.201469)
			(xy 123.998167 -49.216965) (xy 124.047913 -49.239811) (xy 124.093881 -49.269535) (xy 124.114814 -49.287176)
			(xy 124.115068 -49.28743) (xy 124.122157 -49.293013) (xy 124.139072 -49.299261) (xy 124.148088 -49.299622)
			(xy 124.215144 -49.299622) (xy 124.224158 -49.299234) (xy 124.241075 -49.293007) (xy 124.248164 -49.28743)
			(xy 124.248164 -49.287176) (xy 124.248418 -49.287176) (xy 124.269367 -49.269558) (xy 124.315336 -49.239844)
			(xy 124.365079 -49.217004) (xy 124.417576 -49.201508) (xy 124.471748 -49.193674) (xy 124.499116 -49.193196)
			(xy 124.526367 -49.193675) (xy 124.580313 -49.201433) (xy 124.632607 -49.21679) (xy 124.682182 -49.239432)
			(xy 124.728031 -49.268899) (xy 124.76922 -49.304591) (xy 124.80491 -49.345781) (xy 124.834375 -49.391632)
			(xy 124.857016 -49.441208) (xy 124.87237 -49.493502) (xy 124.880126 -49.547449) (xy 124.880126 -49.601951)
			(xy 124.87237 -49.655898) (xy 124.857016 -49.708192) (xy 124.834375 -49.757768) (xy 124.80491 -49.803619)
			(xy 124.76922 -49.844809) (xy 124.728031 -49.880501) (xy 124.682182 -49.909968) (xy 124.632607 -49.93261)
			(xy 124.580313 -49.947967) (xy 124.526367 -49.955725) (xy 124.499116 -49.956212) (xy 124.471746 -49.955734)
			(xy 124.417568 -49.947918) (xy 124.365065 -49.932432) (xy 124.315318 -49.909593) (xy 124.26935 -49.879872)
			(xy 124.248418 -49.862232) (xy 124.248164 -49.861978) (xy 124.241065 -49.85641) (xy 124.224158 -49.850153)
			(xy 124.215144 -49.849786) (xy 124.148088 -49.849786) (xy 124.139071 -49.85014) (xy 124.122154 -49.85639)
			(xy 124.115068 -49.861978) (xy 124.114814 -49.862232) (xy 124.093881 -49.879873) (xy 124.047913 -49.909597)
			(xy 123.998167 -49.932443) (xy 123.945665 -49.947939) (xy 123.891487 -49.955768) (xy 123.836745 -49.955768)
			(xy 123.782567 -49.947939) (xy 123.730065 -49.932443) (xy 123.680319 -49.909597) (xy 123.634351 -49.879873)
			(xy 123.613418 -49.862232) (xy 123.613164 -49.861978) (xy 123.606065 -49.85641) (xy 123.589158 -49.850153)
			(xy 123.580144 -49.849786) (xy 123.513088 -49.849786) (xy 123.504071 -49.85014) (xy 123.487154 -49.85639)
			(xy 123.480068 -49.861978) (xy 123.480068 -49.862232) (xy 123.479814 -49.862232) (xy 123.458881 -49.879873)
			(xy 123.412913 -49.909597) (xy 123.363167 -49.932443) (xy 123.310665 -49.947939) (xy 123.256487 -49.955768)
			(xy 123.201745 -49.955768) (xy 123.147567 -49.947939) (xy 123.095065 -49.932443) (xy 123.045319 -49.909597)
			(xy 122.999351 -49.879873) (xy 122.978418 -49.862232) (xy 122.978164 -49.861978) (xy 122.971065 -49.85641)
			(xy 122.954158 -49.850153) (xy 122.945144 -49.849786) (xy 122.878088 -49.849786) (xy 122.869071 -49.85014)
			(xy 122.852154 -49.85639) (xy 122.845068 -49.861978) (xy 122.845068 -49.862232) (xy 122.844814 -49.862232)
			(xy 122.823892 -49.879883) (xy 122.777916 -49.909592) (xy 122.728166 -49.932425) (xy 122.675663 -49.947913)
			(xy 122.621486 -49.955739) (xy 122.594116 -49.956212) (xy 122.566863 -49.955742) (xy 122.512911 -49.947987)
			(xy 122.460611 -49.932632) (xy 122.41103 -49.909991) (xy 122.365175 -49.880524) (xy 122.323981 -49.84483)
			(xy 122.288286 -49.803638) (xy 122.258817 -49.757784) (xy 122.236173 -49.708204) (xy 122.220817 -49.655905)
			(xy 122.213059 -49.601953) (xy 116.765832 -49.601953) (xy 116.765832 -51.243992) (xy 123.23318 -51.243992)
			(xy 123.233622 -51.216621) (xy 123.241443 -51.16244) (xy 123.256936 -51.109936) (xy 123.279784 -51.060189)
			(xy 123.309515 -51.014224) (xy 123.32716 -50.993294) (xy 123.327414 -50.99304) (xy 123.332992 -50.985947)
			(xy 123.339243 -50.969035) (xy 123.339606 -50.96002) (xy 123.339606 -50.892964) (xy 123.339265 -50.883946)
			(xy 123.333006 -50.867029) (xy 123.327414 -50.859944) (xy 123.32716 -50.859944) (xy 123.32716 -50.85969)
			(xy 123.309496 -50.838778) (xy 123.279789 -50.792799) (xy 123.256959 -50.743046) (xy 123.241473 -50.690542)
			(xy 123.233651 -50.636362) (xy 123.23318 -50.608992) (xy 123.23367 -50.581741) (xy 123.241428 -50.527794)
			(xy 123.256783 -50.4755) (xy 123.279424 -50.425924) (xy 123.30889 -50.380074) (xy 123.344581 -50.338884)
			(xy 123.385771 -50.303193) (xy 123.43162 -50.273726) (xy 123.481196 -50.251085) (xy 123.53349 -50.235728)
			(xy 123.587437 -50.227971) (xy 123.614688 -50.227484) (xy 123.643606 -50.227979) (xy 123.70078 -50.236708)
			(xy 123.755981 -50.253969) (xy 123.807943 -50.279365) (xy 123.855476 -50.312314) (xy 123.89749 -50.352061)
			(xy 123.915678 -50.37455) (xy 123.923296 -50.383346) (xy 123.944189 -50.393534) (xy 123.95581 -50.394108)
			(xy 124.035566 -50.394108) (xy 124.047193 -50.393532) (xy 124.068103 -50.383369) (xy 124.075698 -50.37455)
			(xy 124.093877 -50.352057) (xy 124.135901 -50.312325) (xy 124.183439 -50.279388) (xy 124.235402 -50.254002)
			(xy 124.290601 -50.236747) (xy 124.347772 -50.228019) (xy 124.376688 -50.227484) (xy 124.40394 -50.227966)
			(xy 124.45789 -50.235722) (xy 124.510187 -50.251076) (xy 124.559767 -50.273716) (xy 124.605619 -50.303182)
			(xy 124.646812 -50.338874) (xy 124.682506 -50.380065) (xy 124.711974 -50.425916) (xy 124.734617 -50.475494)
			(xy 124.749974 -50.52779) (xy 124.757732 -50.58174) (xy 124.758196 -50.608992) (xy 124.757725 -50.635306)
			(xy 124.750491 -50.687434) (xy 124.736172 -50.738077) (xy 124.715041 -50.786276) (xy 124.687495 -50.83112)
			(xy 124.654057 -50.871759) (xy 124.635006 -50.889916) (xy 124.627596 -50.897431) (xy 124.619076 -50.916716)
			(xy 124.618496 -50.927254) (xy 124.618496 -51.00193) (xy 124.619051 -51.012477) (xy 124.627568 -51.031772)
			(xy 124.635006 -51.039268) (xy 124.654089 -51.057396) (xy 124.687543 -51.098032) (xy 124.715098 -51.142878)
			(xy 124.736232 -51.191084) (xy 124.750544 -51.241736) (xy 124.757761 -51.293874) (xy 124.758196 -51.320192)
			(xy 124.757737 -51.347445) (xy 124.749981 -51.401397) (xy 124.734625 -51.453696) (xy 124.711983 -51.503276)
			(xy 124.682515 -51.54913) (xy 124.64682 -51.590323) (xy 124.605627 -51.626017) (xy 124.559773 -51.655485)
			(xy 124.510192 -51.678127) (xy 124.457893 -51.693482) (xy 124.403941 -51.701237) (xy 124.376688 -51.7017)
			(xy 124.349023 -51.701197) (xy 124.294273 -51.693196) (xy 124.241251 -51.677378) (xy 124.191067 -51.654073)
			(xy 124.144771 -51.623771) (xy 124.103334 -51.587104) (xy 124.067621 -51.544842) (xy 124.052584 -51.521614)
			(xy 124.045965 -51.511923) (xy 124.02609 -51.499487) (xy 124.014484 -51.497738) (xy 123.934474 -51.489864)
			(xy 123.922835 -51.48922) (xy 123.900997 -51.497308) (xy 123.892564 -51.505358) (xy 123.89231 -51.505612)
			(xy 123.874209 -51.524173) (xy 123.833881 -51.556753) (xy 123.789511 -51.583568) (xy 123.741917 -51.604124)
			(xy 123.691976 -51.618042) (xy 123.64061 -51.625065) (xy 123.614688 -51.6255) (xy 123.587436 -51.625033)
			(xy 123.533487 -51.617275) (xy 123.481192 -51.601918) (xy 123.431614 -51.579275) (xy 123.385763 -51.549807)
			(xy 123.344573 -51.514113) (xy 123.308881 -51.472921) (xy 123.279416 -51.427069) (xy 123.256775 -51.37749)
			(xy 123.241421 -51.325193) (xy 123.233665 -51.271244) (xy 123.23318 -51.243992) (xy 116.765832 -51.243992)
			(xy 116.765832 -52.555953) (xy 122.683979 -52.555953) (xy 122.683979 -52.501447) (xy 122.691737 -52.447497)
			(xy 122.707093 -52.3952) (xy 122.729737 -52.345621) (xy 122.759206 -52.299769) (xy 122.794901 -52.258578)
			(xy 122.836095 -52.222887) (xy 122.881949 -52.193421) (xy 122.93153 -52.170782) (xy 122.983828 -52.15543)
			(xy 123.037779 -52.147677) (xy 123.065032 -52.147216) (xy 123.092403 -52.147659) (xy 123.146583 -52.155482)
			(xy 123.199087 -52.170976) (xy 123.248833 -52.193823) (xy 123.294799 -52.223552) (xy 123.31573 -52.241196)
			(xy 123.315984 -52.24145) (xy 123.323067 -52.247042) (xy 123.339987 -52.253284) (xy 123.349004 -52.253642)
			(xy 123.41606 -52.253642) (xy 123.425076 -52.253278) (xy 123.441994 -52.247037) (xy 123.44908 -52.24145)
			(xy 123.44908 -52.241196) (xy 123.449334 -52.241196) (xy 123.47028 -52.223574) (xy 123.516249 -52.19386)
			(xy 123.565993 -52.17102) (xy 123.61849 -52.155525) (xy 123.672664 -52.147693) (xy 123.700032 -52.147216)
			(xy 123.727283 -52.147656) (xy 123.781231 -52.155417) (xy 123.833525 -52.170776) (xy 123.883102 -52.19342)
			(xy 123.928951 -52.222889) (xy 123.97014 -52.258583) (xy 124.00583 -52.299775) (xy 124.035295 -52.345626)
			(xy 124.057936 -52.395205) (xy 124.07329 -52.4475) (xy 124.081046 -52.501448) (xy 124.081046 -52.555952)
			(xy 124.07329 -52.6099) (xy 124.057936 -52.662195) (xy 124.035295 -52.711774) (xy 124.00583 -52.757625)
			(xy 123.97014 -52.798817) (xy 123.928951 -52.834511) (xy 123.883102 -52.86398) (xy 123.833525 -52.886624)
			(xy 123.781231 -52.901983) (xy 123.727283 -52.909744) (xy 123.700032 -52.910232) (xy 123.672662 -52.909764)
			(xy 123.618482 -52.901949) (xy 123.565978 -52.886461) (xy 123.516231 -52.86362) (xy 123.470265 -52.833894)
			(xy 123.449334 -52.816252) (xy 123.44908 -52.815998) (xy 123.442004 -52.810397) (xy 123.425079 -52.804159)
			(xy 123.41606 -52.803806) (xy 123.349004 -52.803806) (xy 123.339987 -52.804164) (xy 123.32307 -52.810411)
			(xy 123.315984 -52.815998) (xy 123.315984 -52.816252) (xy 123.31573 -52.816252) (xy 123.294791 -52.833883)
			(xy 123.248821 -52.863598) (xy 123.199075 -52.886436) (xy 123.146576 -52.901929) (xy 123.092401 -52.909758)
			(xy 123.065032 -52.910232) (xy 123.037779 -52.909723) (xy 122.983828 -52.90197) (xy 122.93153 -52.886618)
			(xy 122.881949 -52.863979) (xy 122.836095 -52.834513) (xy 122.794901 -52.798822) (xy 122.759206 -52.757631)
			(xy 122.729737 -52.711779) (xy 122.707093 -52.6622) (xy 122.691737 -52.609903) (xy 122.683979 -52.555953)
			(xy 116.765832 -52.555953) (xy 116.765832 -53.496552) (xy 122.233664 -53.496552) (xy 122.233664 -53.442048)
			(xy 122.24142 -53.388099) (xy 122.256776 -53.335803) (xy 122.279417 -53.286225) (xy 122.308883 -53.240374)
			(xy 122.344575 -53.199182) (xy 122.385766 -53.163489) (xy 122.431616 -53.134022) (xy 122.481194 -53.111379)
			(xy 122.53349 -53.096022) (xy 122.587438 -53.088264) (xy 122.61469 -53.087778) (xy 122.642061 -53.088231)
			(xy 122.696241 -53.096049) (xy 122.748745 -53.11154) (xy 122.798492 -53.134385) (xy 122.844458 -53.164114)
			(xy 122.865388 -53.181758) (xy 122.865642 -53.182012) (xy 122.87274 -53.187582) (xy 122.889648 -53.193838)
			(xy 122.898662 -53.194204) (xy 122.965718 -53.194204) (xy 122.974736 -53.193855) (xy 122.991652 -53.187602)
			(xy 122.998738 -53.182012) (xy 122.998738 -53.181758) (xy 122.998992 -53.181758) (xy 123.019911 -53.164102)
			(xy 123.065888 -53.134394) (xy 123.115639 -53.111562) (xy 123.168142 -53.096075) (xy 123.22232 -53.08825)
			(xy 123.24969 -53.087778) (xy 123.276942 -53.088269) (xy 123.330892 -53.096024) (xy 123.383189 -53.111379)
			(xy 123.432769 -53.13402) (xy 123.478622 -53.163486) (xy 123.519814 -53.199179) (xy 123.555508 -53.24037)
			(xy 123.584975 -53.286222) (xy 123.607618 -53.335801) (xy 123.622974 -53.388098) (xy 123.630731 -53.442048)
			(xy 123.630731 -53.496552) (xy 123.622974 -53.550502) (xy 123.607618 -53.602799) (xy 123.584975 -53.652378)
			(xy 123.555508 -53.69823) (xy 123.519814 -53.739421) (xy 123.478622 -53.775114) (xy 123.432769 -53.80458)
			(xy 123.383189 -53.827221) (xy 123.330892 -53.842576) (xy 123.276942 -53.850331) (xy 123.24969 -53.850794)
			(xy 123.222319 -53.850335) (xy 123.16814 -53.842516) (xy 123.115637 -53.827025) (xy 123.06589 -53.804182)
			(xy 123.019924 -53.774456) (xy 122.998992 -53.756814) (xy 122.998738 -53.75656) (xy 122.991648 -53.750978)
			(xy 122.974734 -53.74473) (xy 122.965718 -53.744368) (xy 122.898662 -53.744368) (xy 122.889644 -53.744714)
			(xy 122.872728 -53.75097) (xy 122.865642 -53.75656) (xy 122.865642 -53.756814) (xy 122.865388 -53.756814)
			(xy 122.844435 -53.774427) (xy 122.798468 -53.804143) (xy 122.748726 -53.826983) (xy 122.69623 -53.84248)
			(xy 122.642058 -53.850316) (xy 122.61469 -53.850794) (xy 122.587438 -53.850336) (xy 122.53349 -53.842578)
			(xy 122.481194 -53.827221) (xy 122.431616 -53.804578) (xy 122.385766 -53.775111) (xy 122.344575 -53.739418)
			(xy 122.308883 -53.698226) (xy 122.279417 -53.652375) (xy 122.256776 -53.602797) (xy 122.24142 -53.550501)
			(xy 122.233664 -53.496552) (xy 116.765832 -53.496552) (xy 116.765832 -54.989051) (xy 120.001268 -54.989051)
			(xy 120.001268 -54.934549) (xy 120.009024 -54.880601) (xy 120.024379 -54.828306) (xy 120.047019 -54.778729)
			(xy 120.076485 -54.732878) (xy 120.112176 -54.691687) (xy 120.153365 -54.655995) (xy 120.199215 -54.626527)
			(xy 120.248791 -54.603884) (xy 120.301085 -54.588527) (xy 120.355033 -54.580769) (xy 120.382284 -54.580282)
			(xy 120.410375 -54.58079) (xy 120.465952 -54.589014) (xy 120.51972 -54.605303) (xy 120.570518 -54.629304)
			(xy 120.617245 -54.660497) (xy 120.65889 -54.698207) (xy 120.694553 -54.741618) (xy 120.709436 -54.765448)
			(xy 120.71477 -54.774338) (xy 120.731788 -54.78653) (xy 120.825006 -54.80685) (xy 120.84558 -54.802532)
			(xy 120.854216 -54.79669) (xy 120.878273 -54.78068) (xy 120.930207 -54.75534) (xy 120.985367 -54.738117)
			(xy 121.042493 -54.729405) (xy 121.071386 -54.728872) (xy 121.098636 -54.729391) (xy 121.152581 -54.737145)
			(xy 121.204874 -54.752498) (xy 121.25445 -54.775136) (xy 121.300299 -54.804599) (xy 121.341489 -54.840287)
			(xy 121.377181 -54.881473) (xy 121.406648 -54.92732) (xy 121.42929 -54.976894) (xy 121.444647 -55.029185)
			(xy 121.452406 -55.08313) (xy 121.452894 -55.11038) (xy 121.452418 -55.13775) (xy 121.444603 -55.191929)
			(xy 121.429116 -55.244432) (xy 121.406276 -55.294179) (xy 121.376554 -55.340146) (xy 121.358914 -55.361078)
			(xy 121.35866 -55.361332) (xy 121.353091 -55.36843) (xy 121.346835 -55.385338) (xy 121.346468 -55.394352)
			(xy 121.346468 -55.461408) (xy 121.346828 -55.470424) (xy 121.353074 -55.487341) (xy 121.35866 -55.494428)
			(xy 121.358914 -55.494428) (xy 121.358914 -55.494682) (xy 121.376533 -55.515631) (xy 121.406256 -55.561597)
			(xy 121.4291 -55.611341) (xy 121.444596 -55.66384) (xy 121.452426 -55.718016) (xy 121.452428 -55.772754)
			(xy 121.444602 -55.82693) (xy 121.42911 -55.879431) (xy 121.40627 -55.929176) (xy 121.376552 -55.975144)
			(xy 121.358914 -55.996078) (xy 121.35866 -55.996332) (xy 121.353091 -56.00343) (xy 121.346835 -56.020338)
			(xy 121.346468 -56.029352) (xy 121.346468 -56.096408) (xy 121.346828 -56.105424) (xy 121.353074 -56.122341)
			(xy 121.35866 -56.129428) (xy 121.358914 -56.129428) (xy 121.358914 -56.129682) (xy 121.37656 -56.150608)
			(xy 121.406271 -56.196583) (xy 121.429105 -56.246332) (xy 121.444594 -56.298834) (xy 121.452421 -56.35301)
			(xy 121.452894 -56.38038) (xy 121.452408 -56.407631) (xy 121.444652 -56.461579) (xy 121.429297 -56.513874)
			(xy 121.406655 -56.563451) (xy 121.377189 -56.609301) (xy 121.341498 -56.650492) (xy 121.300307 -56.686183)
			(xy 121.254457 -56.715649) (xy 121.20488 -56.738291) (xy 121.152585 -56.753646) (xy 121.098637 -56.761402)
			(xy 121.044135 -56.761402) (xy 120.990187 -56.753646) (xy 120.937892 -56.738291) (xy 120.888315 -56.715649)
			(xy 120.842465 -56.686183) (xy 120.801274 -56.650492) (xy 120.765583 -56.609301) (xy 120.736117 -56.563451)
			(xy 120.713475 -56.513874) (xy 120.69812 -56.461579) (xy 120.690364 -56.407631) (xy 120.689878 -56.38038)
			(xy 120.690313 -56.353008) (xy 120.698136 -56.298827) (xy 120.713631 -56.246323) (xy 120.73648 -56.196577)
			(xy 120.766213 -56.150612) (xy 120.783858 -56.129682) (xy 120.784112 -56.129428) (xy 120.789694 -56.122339)
			(xy 120.795943 -56.105424) (xy 120.796304 -56.096408) (xy 120.796304 -56.029352) (xy 120.795921 -56.020338)
			(xy 120.789691 -56.003421) (xy 120.784112 -55.996332) (xy 120.783858 -55.996332) (xy 120.783858 -55.996078)
			(xy 120.766196 -55.975162) (xy 120.73647 -55.929192) (xy 120.713624 -55.879443) (xy 120.698128 -55.826938)
			(xy 120.690301 -55.772757) (xy 120.690303 -55.718013) (xy 120.698134 -55.663832) (xy 120.713635 -55.611329)
			(xy 120.736485 -55.561582) (xy 120.766215 -55.515614) (xy 120.783858 -55.494682) (xy 120.784112 -55.494428)
			(xy 120.789694 -55.487339) (xy 120.795943 -55.470424) (xy 120.796304 -55.461408) (xy 120.796304 -55.394352)
			(xy 120.795921 -55.385338) (xy 120.789691 -55.368421) (xy 120.784112 -55.361332) (xy 120.783858 -55.360824)
			(xy 120.772912 -55.348091) (xy 120.753072 -55.320999) (xy 120.744234 -55.306722) (xy 120.7389 -55.297832)
			(xy 120.721882 -55.28564) (xy 120.628664 -55.26532) (xy 120.60809 -55.269638) (xy 120.599454 -55.27548)
			(xy 120.575403 -55.2915) (xy 120.523467 -55.316838) (xy 120.468305 -55.334059) (xy 120.411178 -55.342767)
			(xy 120.382284 -55.343298) (xy 120.355033 -55.342831) (xy 120.301085 -55.335073) (xy 120.248791 -55.319716)
			(xy 120.199215 -55.297073) (xy 120.153365 -55.267605) (xy 120.112176 -55.231913) (xy 120.076485 -55.190722)
			(xy 120.047019 -55.144871) (xy 120.024379 -55.095294) (xy 120.009024 -55.042999) (xy 120.001268 -54.989051)
			(xy 116.765832 -54.989051) (xy 116.765832 -55.420851) (xy 118.324868 -55.420851) (xy 118.324868 -55.366349)
			(xy 118.332624 -55.312401) (xy 118.347979 -55.260106) (xy 118.370619 -55.210529) (xy 118.400085 -55.164678)
			(xy 118.435776 -55.123487) (xy 118.476965 -55.087795) (xy 118.522815 -55.058327) (xy 118.572391 -55.035684)
			(xy 118.624685 -55.020327) (xy 118.678633 -55.012569) (xy 118.705884 -55.012082) (xy 118.732197 -55.012566)
			(xy 118.784325 -55.019798) (xy 118.834967 -55.034114) (xy 118.883166 -55.055244) (xy 118.92801 -55.082787)
			(xy 118.968651 -55.116222) (xy 118.986808 -55.135272) (xy 118.994328 -55.142675) (xy 119.013609 -55.1512)
			(xy 119.024146 -55.151782) (xy 119.098822 -55.151782) (xy 119.109369 -55.15123) (xy 119.128665 -55.142711)
			(xy 119.13616 -55.135272) (xy 119.154288 -55.116189) (xy 119.194924 -55.082735) (xy 119.23977 -55.055181)
			(xy 119.287977 -55.034047) (xy 119.338629 -55.019736) (xy 119.390766 -55.012517) (xy 119.417084 -55.012082)
			(xy 119.444337 -55.012564) (xy 119.498288 -55.020319) (xy 119.550587 -55.035673) (xy 119.600167 -55.058314)
			(xy 119.646021 -55.087781) (xy 119.687215 -55.123474) (xy 119.722909 -55.164666) (xy 119.752378 -55.210519)
			(xy 119.775021 -55.260098) (xy 119.790377 -55.312396) (xy 119.798135 -55.366347) (xy 119.798135 -55.420853)
			(xy 119.790377 -55.474804) (xy 119.775021 -55.527102) (xy 119.752378 -55.576681) (xy 119.722909 -55.622534)
			(xy 119.687215 -55.663726) (xy 119.646021 -55.699419) (xy 119.600167 -55.728886) (xy 119.550587 -55.751527)
			(xy 119.498288 -55.766881) (xy 119.444337 -55.774636) (xy 119.417084 -55.775098) (xy 119.39077 -55.774642)
			(xy 119.338641 -55.767405) (xy 119.287998 -55.753084) (xy 119.239799 -55.731949) (xy 119.194955 -55.704401)
			(xy 119.154316 -55.67096) (xy 119.13616 -55.651908) (xy 119.128654 -55.644488) (xy 119.109362 -55.635974)
			(xy 119.098822 -55.635398) (xy 119.024146 -55.635398) (xy 119.013598 -55.635939) (xy 118.994302 -55.644466)
			(xy 118.986808 -55.651908) (xy 118.968643 -55.670954) (xy 118.928015 -55.704412) (xy 118.883177 -55.731972)
			(xy 118.834978 -55.753112) (xy 118.784332 -55.767431) (xy 118.7322 -55.774658) (xy 118.705884 -55.775098)
			(xy 118.678633 -55.774631) (xy 118.624685 -55.766873) (xy 118.572391 -55.751516) (xy 118.522815 -55.728873)
			(xy 118.476965 -55.699405) (xy 118.435776 -55.663713) (xy 118.400085 -55.622522) (xy 118.370619 -55.576671)
			(xy 118.347979 -55.527094) (xy 118.332624 -55.474799) (xy 118.324868 -55.420851) (xy 116.765832 -55.420851)
			(xy 116.765832 -55.79491) (xy 116.766244 -55.804981) (xy 116.773973 -55.823579) (xy 116.780818 -55.830978)
			(xy 118.67896 -57.729374) (xy 118.686383 -57.736185) (xy 118.704965 -57.743922) (xy 118.715028 -57.74436)
			(xy 120.631458 -57.74436) (xy 120.64362 -57.743672) (xy 120.665242 -57.73253) (xy 120.67286 -57.723024)
			(xy 120.720866 -57.65546) (xy 120.72731 -57.64524) (xy 120.730761 -57.621365) (xy 120.72747 -57.60974)
			(xy 120.72747 -57.609232) (xy 120.717737 -57.579174) (xy 120.707275 -57.516869) (xy 120.706642 -57.48528)
			(xy 120.707128 -57.458029) (xy 120.714884 -57.404081) (xy 120.730239 -57.351786) (xy 120.752881 -57.302209)
			(xy 120.782347 -57.256359) (xy 120.818038 -57.215168) (xy 120.859229 -57.179477) (xy 120.905079 -57.150011)
			(xy 120.954656 -57.127369) (xy 121.006951 -57.112014) (xy 121.060899 -57.104258) (xy 121.115401 -57.104258)
			(xy 121.169349 -57.112014) (xy 121.221644 -57.127369) (xy 121.271221 -57.150011) (xy 121.317071 -57.179477)
			(xy 121.358262 -57.215168) (xy 121.393953 -57.256359) (xy 121.423419 -57.302209) (xy 121.446061 -57.351786)
			(xy 121.461416 -57.404081) (xy 121.469172 -57.458029) (xy 121.469658 -57.48528) (xy 121.468979 -57.516926)
			(xy 121.458509 -57.579349) (xy 121.44883 -57.609486) (xy 121.44883 -57.60974) (xy 121.445616 -57.621371)
			(xy 121.449051 -57.645221) (xy 121.455434 -57.65546) (xy 121.50344 -57.723024) (xy 121.511085 -57.732503)
			(xy 121.532687 -57.743656) (xy 121.544842 -57.74436) (xy 121.639076 -57.74436) (xy 121.645225 -57.744159)
			(xy 121.657166 -57.741211) (xy 121.662698 -57.738518) (xy 121.690224 -57.72468) (xy 121.748641 -57.705116)
			(xy 121.809441 -57.695185) (xy 121.840244 -57.694576) (xy 121.867492 -57.695097) (xy 121.921433 -57.702859)
			(xy 121.97372 -57.718217) (xy 122.023289 -57.740859) (xy 122.069132 -57.770326) (xy 122.110316 -57.806016)
			(xy 122.146001 -57.847203) (xy 122.158913 -57.867296) (xy 123.74321 -57.867296) (xy 123.747281 -57.811674)
			(xy 123.759407 -57.757237) (xy 123.77933 -57.705146) (xy 123.806626 -57.656511) (xy 123.840712 -57.612368)
			(xy 123.880861 -57.573659) (xy 123.926219 -57.541208) (xy 123.975819 -57.515707) (xy 124.028603 -57.4977)
			(xy 124.083446 -57.48757) (xy 124.13918 -57.485533) (xy 124.194617 -57.491633) (xy 124.248574 -57.505739)
			(xy 124.299903 -57.527551) (xy 124.347509 -57.556605) (xy 124.390377 -57.59228) (xy 124.427594 -57.633817)
			(xy 124.458367 -57.68033) (xy 124.482039 -57.730827) (xy 124.498107 -57.784234) (xy 124.506227 -57.83941)
			(xy 124.506736 -57.867296) (xy 124.506227 -57.895182) (xy 124.498107 -57.950358) (xy 124.482039 -58.003765)
			(xy 124.458367 -58.054262) (xy 124.427594 -58.100775) (xy 124.390377 -58.142312) (xy 124.347509 -58.177987)
			(xy 124.299903 -58.207041) (xy 124.248574 -58.228853) (xy 124.194617 -58.242959) (xy 124.13918 -58.249059)
			(xy 124.083446 -58.247022) (xy 124.028603 -58.236892) (xy 123.975819 -58.218885) (xy 123.926219 -58.193384)
			(xy 123.880861 -58.160933) (xy 123.840712 -58.122224) (xy 123.806626 -58.078081) (xy 123.77933 -58.029446)
			(xy 123.759407 -57.977355) (xy 123.747281 -57.922918) (xy 123.74321 -57.867296) (xy 122.158913 -57.867296)
			(xy 122.175462 -57.893049) (xy 122.198099 -57.942621) (xy 122.213451 -57.99491) (xy 122.221206 -58.048852)
			(xy 122.221206 -58.103348) (xy 122.213451 -58.15729) (xy 122.198099 -58.209579) (xy 122.175462 -58.259151)
			(xy 122.146001 -58.304997) (xy 122.110316 -58.346184) (xy 122.069132 -58.381874) (xy 122.023289 -58.411341)
			(xy 121.97372 -58.433983) (xy 121.921433 -58.449341) (xy 121.867492 -58.457103) (xy 121.840244 -58.457592)
			(xy 121.80944 -58.456999) (xy 121.748639 -58.447067) (xy 121.690226 -58.427486) (xy 121.662698 -58.41365)
			(xy 121.657175 -58.410932) (xy 121.645229 -58.407978) (xy 121.639076 -58.407808) (xy 118.556024 -58.407808)
			(xy 118.529999 -58.407305) (xy 118.478595 -58.399133) (xy 118.429097 -58.383033) (xy 118.382722 -58.359401)
			(xy 118.340606 -58.328815) (xy 118.321836 -58.31078) (xy 116.199158 -56.188102) (xy 116.181053 -56.169314)
			(xy 116.150367 -56.127119) (xy 116.126665 -56.08064) (xy 116.110531 -56.031023) (xy 116.102363 -55.979493)
			(xy 116.101876 -55.953406) (xy 116.101876 -40.254936) (xy 116.101469 -40.245837) (xy 116.095104 -40.228786)
			(xy 116.08943 -40.221662) (xy 116.071971 -40.200763) (xy 116.042578 -40.154922) (xy 116.019995 -40.105369)
			(xy 116.004682 -40.053111) (xy 115.996948 -39.999208) (xy 115.996466 -39.97198) (xy 113.308892 -39.97198)
			(xy 113.308892 -54.932834) (xy 113.313464 -54.938168) (xy 116.93652 -58.561224) (xy 122.66244 -58.561224)
			(xy 122.666511 -58.505602) (xy 122.678637 -58.451165) (xy 122.69856 -58.399074) (xy 122.725856 -58.350439)
			(xy 122.759942 -58.306296) (xy 122.800091 -58.267587) (xy 122.845449 -58.235136) (xy 122.895049 -58.209635)
			(xy 122.947833 -58.191628) (xy 123.002676 -58.181498) (xy 123.05841 -58.179461) (xy 123.113847 -58.185561)
			(xy 123.167804 -58.199667) (xy 123.219133 -58.221479) (xy 123.266739 -58.250533) (xy 123.309607 -58.286208)
			(xy 123.346824 -58.327745) (xy 123.377597 -58.374258) (xy 123.401269 -58.424755) (xy 123.408779 -58.449718)
			(xy 124.90907 -58.449718) (xy 124.913141 -58.394096) (xy 124.925267 -58.339659) (xy 124.94519 -58.287568)
			(xy 124.972486 -58.238933) (xy 125.006572 -58.19479) (xy 125.046721 -58.156081) (xy 125.092079 -58.12363)
			(xy 125.141679 -58.098129) (xy 125.194463 -58.080122) (xy 125.249306 -58.069992) (xy 125.30504 -58.067955)
			(xy 125.360477 -58.074055) (xy 125.414434 -58.088161) (xy 125.465763 -58.109973) (xy 125.513369 -58.139027)
			(xy 125.556237 -58.174702) (xy 125.593454 -58.216239) (xy 125.624227 -58.262752) (xy 125.647899 -58.313249)
			(xy 125.663967 -58.366656) (xy 125.672087 -58.421832) (xy 125.672596 -58.449718) (xy 125.672087 -58.477604)
			(xy 125.663967 -58.53278) (xy 125.647899 -58.586187) (xy 125.624227 -58.636684) (xy 125.593454 -58.683197)
			(xy 125.556237 -58.724734) (xy 125.513369 -58.760409) (xy 125.465763 -58.789463) (xy 125.414434 -58.811275)
			(xy 125.360477 -58.825381) (xy 125.30504 -58.831481) (xy 125.249306 -58.829444) (xy 125.194463 -58.819314)
			(xy 125.141679 -58.801307) (xy 125.092079 -58.775806) (xy 125.046721 -58.743355) (xy 125.006572 -58.704646)
			(xy 124.972486 -58.660503) (xy 124.94519 -58.611868) (xy 124.925267 -58.559777) (xy 124.913141 -58.50534)
			(xy 124.90907 -58.449718) (xy 123.408779 -58.449718) (xy 123.417337 -58.478162) (xy 123.425457 -58.533338)
			(xy 123.425966 -58.561224) (xy 123.425457 -58.58911) (xy 123.417337 -58.644286) (xy 123.401269 -58.697693)
			(xy 123.377597 -58.74819) (xy 123.346824 -58.794703) (xy 123.309607 -58.83624) (xy 123.266739 -58.871915)
			(xy 123.219133 -58.900969) (xy 123.167804 -58.922781) (xy 123.113847 -58.936887) (xy 123.05841 -58.942987)
			(xy 123.002676 -58.94095) (xy 122.947833 -58.93082) (xy 122.895049 -58.912813) (xy 122.845449 -58.887312)
			(xy 122.800091 -58.854861) (xy 122.759942 -58.816152) (xy 122.725856 -58.772009) (xy 122.69856 -58.723374)
			(xy 122.678637 -58.671283) (xy 122.666511 -58.616846) (xy 122.66244 -58.561224) (xy 116.93652 -58.561224)
			(xy 117.54993 -59.174634) (xy 121.193304 -59.174634) (xy 121.197375 -59.119012) (xy 121.209501 -59.064575)
			(xy 121.229424 -59.012484) (xy 121.25672 -58.963849) (xy 121.290806 -58.919706) (xy 121.330955 -58.880997)
			(xy 121.376313 -58.848546) (xy 121.425913 -58.823045) (xy 121.478697 -58.805038) (xy 121.53354 -58.794908)
			(xy 121.589274 -58.792871) (xy 121.644711 -58.798971) (xy 121.698668 -58.813077) (xy 121.749997 -58.834889)
			(xy 121.797603 -58.863943) (xy 121.840471 -58.899618) (xy 121.877688 -58.941155) (xy 121.908461 -58.987668)
			(xy 121.932133 -59.038165) (xy 121.948201 -59.091572) (xy 121.956321 -59.146748) (xy 121.95683 -59.174634)
			(xy 121.956321 -59.20252) (xy 121.948201 -59.257696) (xy 121.932133 -59.311103) (xy 121.908461 -59.3616)
			(xy 121.877688 -59.408113) (xy 121.840471 -59.44965) (xy 121.797603 -59.485325) (xy 121.749997 -59.514379)
			(xy 121.698668 -59.536191) (xy 121.644711 -59.550297) (xy 121.589274 -59.556397) (xy 121.53354 -59.55436)
			(xy 121.478697 -59.54423) (xy 121.425913 -59.526223) (xy 121.376313 -59.500722) (xy 121.330955 -59.468271)
			(xy 121.290806 -59.429562) (xy 121.25672 -59.385419) (xy 121.229424 -59.336784) (xy 121.209501 -59.284693)
			(xy 121.197375 -59.230256) (xy 121.193304 -59.174634) (xy 117.54993 -59.174634) (xy 119.008652 -60.633356)
			(xy 123.897134 -60.633356) (xy 123.901205 -60.577734) (xy 123.913331 -60.523297) (xy 123.933254 -60.471206)
			(xy 123.96055 -60.422571) (xy 123.994636 -60.378428) (xy 124.034785 -60.339719) (xy 124.080143 -60.307268)
			(xy 124.129743 -60.281767) (xy 124.182527 -60.26376) (xy 124.23737 -60.25363) (xy 124.293104 -60.251593)
			(xy 124.348541 -60.257693) (xy 124.402498 -60.271799) (xy 124.453827 -60.293611) (xy 124.501433 -60.322665)
			(xy 124.544301 -60.35834) (xy 124.581518 -60.399877) (xy 124.612291 -60.44639) (xy 124.635963 -60.496887)
			(xy 124.652031 -60.550294) (xy 124.660151 -60.60547) (xy 124.66066 -60.633356) (xy 124.660151 -60.661242)
			(xy 124.652031 -60.716418) (xy 124.635963 -60.769825) (xy 124.612291 -60.820322) (xy 124.581518 -60.866835)
			(xy 124.544301 -60.908372) (xy 124.501433 -60.944047) (xy 124.453827 -60.973101) (xy 124.402498 -60.994913)
			(xy 124.348541 -61.009019) (xy 124.293104 -61.015119) (xy 124.23737 -61.013082) (xy 124.182527 -61.002952)
			(xy 124.129743 -60.984945) (xy 124.080143 -60.959444) (xy 124.034785 -60.926993) (xy 123.994636 -60.888284)
			(xy 123.96055 -60.844141) (xy 123.933254 -60.795506) (xy 123.913331 -60.743415) (xy 123.901205 -60.688978)
			(xy 123.897134 -60.633356) (xy 119.008652 -60.633356) (xy 120.271032 -61.895736) (xy 120.279001 -61.90286)
			(xy 120.29895 -61.910468) (xy 120.30964 -61.910468) (xy 120.351804 -61.908182) (xy 120.352312 -61.908182)
			(xy 120.38838 -61.905642) (xy 120.398034 -61.904174) (xy 120.415262 -61.895018) (xy 120.421908 -61.887862)
			(xy 120.427242 -61.881512) (xy 120.430544 -61.877448) (xy 120.437402 -61.869574) (xy 120.455613 -61.849528)
			(xy 120.496721 -61.814268) (xy 120.5424 -61.785172) (xy 120.591732 -61.762823) (xy 120.643728 -61.747671)
			(xy 120.697343 -61.74002) (xy 120.724422 -61.739526) (xy 120.751455 -61.739998) (xy 120.804979 -61.747632)
			(xy 120.856889 -61.762746) (xy 120.906146 -61.785036) (xy 120.951764 -61.814055) (xy 120.992829 -61.849223)
			(xy 121.028518 -61.889836) (xy 121.058117 -61.935079) (xy 121.081034 -61.984048) (xy 121.096809 -62.035761)
			(xy 121.105126 -62.089183) (xy 121.10593 -62.116208) (xy 121.10593 -62.121542) (xy 121.105568 -62.145572)
			(xy 121.099528 -62.193251) (xy 121.087538 -62.239791) (xy 121.079006 -62.262258) (xy 121.077228 -62.266576)
			(xy 121.074942 -62.277752) (xy 121.07367 -62.287114) (xy 121.077335 -62.305634) (xy 121.082054 -62.31382)
			(xy 121.082308 -62.314074) (xy 121.082562 -62.314582) (xy 121.13133 -62.387734) (xy 121.134632 -62.390782)
			(xy 121.13514 -62.39129) (xy 121.140728 -62.396116) (xy 122.441462 -62.396116) (xy 122.451114 -62.3951)
			(xy 122.458361 -62.393478) (xy 122.47154 -62.386647) (xy 122.477022 -62.381638) (xy 122.845322 -62.013338)
			(xy 122.845828 -62.009544) (xy 122.845831 -62.001891) (xy 122.845322 -61.998098) (xy 122.844306 -61.991748)
			(xy 122.822208 -61.934344) (xy 122.822208 -61.933836) (xy 122.81154 -61.90615) (xy 122.810524 -61.903864)
			(xy 122.804174 -61.89091) (xy 122.797062 -61.882782) (xy 122.765058 -61.869066) (xy 122.756676 -61.868304)
			(xy 122.72833 -61.865517) (xy 122.672857 -61.85261) (xy 122.619917 -61.831606) (xy 122.570684 -61.802971)
			(xy 122.526251 -61.76734) (xy 122.487604 -61.725503) (xy 122.455601 -61.67839) (xy 122.430951 -61.627046)
			(xy 122.414202 -61.57261) (xy 122.405725 -61.516289) (xy 122.40514 -61.487812) (xy 122.405626 -61.460561)
			(xy 122.413382 -61.406613) (xy 122.428737 -61.354318) (xy 122.451379 -61.304741) (xy 122.480845 -61.258891)
			(xy 122.516536 -61.2177) (xy 122.557727 -61.182009) (xy 122.603577 -61.152543) (xy 122.653154 -61.129901)
			(xy 122.705449 -61.114546) (xy 122.759397 -61.10679) (xy 122.813899 -61.10679) (xy 122.867847 -61.114546)
			(xy 122.920142 -61.129901) (xy 122.969719 -61.152543) (xy 123.015569 -61.182009) (xy 123.05676 -61.2177)
			(xy 123.092451 -61.258891) (xy 123.121917 -61.304741) (xy 123.144559 -61.354318) (xy 123.159914 -61.406613)
			(xy 123.16767 -61.460561) (xy 123.168156 -61.487812) (xy 123.168156 -61.48832) (xy 123.167993 -61.505172)
			(xy 123.16507 -61.53875) (xy 123.162314 -61.555376) (xy 123.160028 -61.56833) (xy 123.163838 -61.57976)
			(xy 123.165884 -61.585422) (xy 123.172169 -61.595686) (xy 123.176284 -61.60008) (xy 123.190254 -61.61405)
			(xy 123.244356 -61.667898) (xy 123.24842 -61.669168) (xy 123.272804 -61.664088) (xy 123.289076 -61.661009)
			(xy 123.32203 -61.657699) (xy 123.33859 -61.657484) (xy 124.64923 -61.657484) (xy 124.671741 -61.657874)
			(xy 124.716346 -61.663988) (xy 124.73813 -61.669676) (xy 124.738638 -61.669676) (xy 124.747274 -61.671454)
			(xy 124.773601 -61.674408) (xy 124.825141 -61.686658) (xy 124.874492 -61.705917) (xy 124.920707 -61.731814)
			(xy 124.962897 -61.763853) (xy 125.000252 -61.801417) (xy 125.016514 -61.82233) (xy 125.03567 -61.848944)
			(xy 125.065551 -61.907309) (xy 125.07595 -61.938408) (xy 125.077728 -61.94425) (xy 125.084078 -61.954918)
			(xy 126.818644 -63.689484) (xy 126.825328 -63.695606) (xy 126.841819 -63.703097) (xy 126.859886 -63.704373)
			(xy 126.868682 -63.702184) (xy 126.874016 -63.699898) (xy 126.880827 -63.696805) (xy 126.892433 -63.687375)
			(xy 126.896876 -63.681356) (xy 126.900686 -63.675768) (xy 126.905004 -63.66129) (xy 126.905004 -42.954194)
			(xy 126.904842 -42.948183) (xy 126.902027 -42.936496) (xy 126.899416 -42.93108) (xy 126.897577 -42.927606)
			(xy 126.892984 -42.921226) (xy 126.890272 -42.91838) (xy 123.271534 -39.299642) (xy 123.25342 -39.280862)
			(xy 123.222734 -39.238666) (xy 123.199034 -39.192184) (xy 123.182905 -39.142566) (xy 123.174743 -39.091033)
			(xy 123.174252 -39.064946) (xy 123.174252 -36.748212) (xy 123.17222 -36.734242) (xy 123.166886 -36.715192)
			(xy 123.163584 -36.709604) (xy 123.152861 -36.690584) (xy 123.135296 -36.650608) (xy 123.128532 -36.629848)
			(xy 123.12777 -36.627054) (xy 123.127008 -36.624514) (xy 123.126754 -36.624006) (xy 123.11761 -36.608512)
			(xy 123.109736 -36.598352) (xy 121.628916 -35.117532) (xy 121.610883 -35.098761) (xy 121.580302 -35.056645)
			(xy 121.556674 -35.010269) (xy 121.540579 -34.960771) (xy 121.532412 -34.909368) (xy 121.531888 -34.883344)
			(xy 121.531888 -32.411162) (xy 121.524522 -32.403288) (xy 121.50344 -32.386016) (xy 121.492772 -32.37738)
			(xy 121.479564 -32.366458) (xy 121.479056 -32.366458) (xy 121.46153 -32.352234) (xy 121.461276 -32.35198)
			(xy 121.452894 -32.345376) (xy 121.429526 -32.350456) (xy 121.399589 -32.356398) (xy 121.338886 -32.362765)
			(xy 121.308368 -32.363156) (xy 121.272981 -32.362621) (xy 121.202723 -32.354089) (xy 121.134004 -32.337153)
			(xy 121.067827 -32.312061) (xy 121.005156 -32.279178) (xy 120.946904 -32.238982) (xy 120.893919 -32.192061)
			(xy 120.846975 -32.139096) (xy 120.806754 -32.080861) (xy 120.773843 -32.018204) (xy 120.748722 -31.952038)
			(xy 120.731757 -31.883327) (xy 120.723195 -31.813073) (xy 120.722644 -31.777686) (xy 120.722644 -30.793944)
			(xy 120.722572 -30.789734) (xy 120.721173 -30.781431) (xy 120.71985 -30.777434) (xy 120.717056 -30.769306)
			(xy 120.715532 -30.767528) (xy 120.692926 -30.754066) (xy 120.642634 -30.72384) (xy 120.637046 -30.720538)
			(xy 120.631704 -30.717596) (xy 120.620014 -30.714138) (xy 120.613932 -30.71368) (xy 120.601486 -30.713172)
			(xy 120.58904 -30.715966) (xy 120.583198 -30.71876) (xy 120.558052 -30.730444) (xy 120.554242 -30.731968)
			(xy 120.54205 -30.739588) (xy 120.510413 -30.750311) (xy 120.444636 -30.761931) (xy 120.41124 -30.762702)
			(xy 120.410732 -30.762702) (xy 120.38317 -30.762236) (xy 120.328606 -30.754395) (xy 120.275714 -30.738867)
			(xy 120.22557 -30.71597) (xy 120.179196 -30.686169) (xy 120.137535 -30.650071) (xy 120.101436 -30.608411)
			(xy 120.071634 -30.562037) (xy 120.048736 -30.511894) (xy 120.033207 -30.459002) (xy 120.025365 -30.404438)
			(xy 120.024906 -30.376876) (xy 120.025416 -30.348467) (xy 120.03377 -30.292267) (xy 120.050293 -30.237905)
			(xy 120.074627 -30.186562) (xy 120.106243 -30.139353) (xy 120.144453 -30.097303) (xy 120.16613 -30.078934)
			(xy 120.166638 -30.078426) (xy 120.172226 -30.0736) (xy 120.17629 -30.070298) (xy 120.179846 -30.066234)
			(xy 120.185688 -30.057344) (xy 120.192292 -30.04312) (xy 120.193959 -30.038668) (xy 120.195747 -30.029331)
			(xy 120.195848 -30.024578) (xy 120.195848 -29.967682) (xy 120.195706 -29.962242) (xy 120.193399 -29.95161)
			(xy 120.191276 -29.9466) (xy 120.187974 -29.939742) (xy 120.187974 -29.939234) (xy 120.181116 -29.925518)
			(xy 120.172734 -29.914088) (xy 120.167908 -29.909262) (xy 120.16613 -29.907738) (xy 120.145104 -29.889499)
			(xy 120.108043 -29.847973) (xy 120.077403 -29.801506) (xy 120.053833 -29.751084) (xy 120.037833 -29.697774)
			(xy 120.029741 -29.642706) (xy 120.029224 -29.614876) (xy 120.029689 -29.587625) (xy 120.037449 -29.533678)
			(xy 120.052807 -29.481385) (xy 120.075452 -29.43181) (xy 120.104921 -29.385962) (xy 120.140615 -29.344775)
			(xy 120.181807 -29.309087) (xy 120.227659 -29.279625) (xy 120.277238 -29.256988) (xy 120.329533 -29.241637)
			(xy 120.383481 -29.233885) (xy 120.410732 -29.233368) (xy 120.410732 -29.233114) (xy 120.437906 -29.233589)
			(xy 120.491705 -29.241291) (xy 120.543867 -29.256547) (xy 120.593337 -29.279051) (xy 120.616472 -29.293312)
			(xy 120.616726 -29.293566) (xy 120.621574 -29.296485) (xy 120.632213 -29.300336) (xy 120.637808 -29.301186)
			(xy 120.648222 -29.302456) (xy 120.730772 -29.276294) (xy 120.733566 -29.275278) (xy 120.738879 -29.273513)
			(xy 120.748625 -29.268006) (xy 120.75287 -29.264356) (xy 120.760998 -29.256736) (xy 120.765316 -29.246068)
			(xy 120.780615 -29.210012) (xy 120.8194 -29.141966) (xy 120.866885 -29.079678) (xy 120.894094 -29.051504)
			(xy 123.332494 -26.613104) (xy 123.337485 -26.607607) (xy 123.344337 -26.594442) (xy 123.345956 -26.587196)
			(xy 123.346972 -26.577544) (xy 123.346972 -24.158194) (xy 123.347468 -24.124094) (xy 123.355385 -24.056354)
			(xy 123.371114 -23.989991) (xy 123.39444 -23.925903) (xy 123.425048 -23.864957) (xy 123.462525 -23.807976)
			(xy 123.506364 -23.755731) (xy 123.555971 -23.708928) (xy 123.610677 -23.668202) (xy 123.669741 -23.634101)
			(xy 123.732364 -23.607088) (xy 123.7977 -23.587528) (xy 123.864864 -23.575685) (xy 123.93295 -23.57172)
			(xy 124.001036 -23.575685) (xy 124.0682 -23.587528) (xy 124.133536 -23.607088) (xy 124.196159 -23.634101)
			(xy 124.255223 -23.668202) (xy 124.309929 -23.708928) (xy 124.359536 -23.755731) (xy 124.403375 -23.807976)
			(xy 124.440852 -23.864957) (xy 124.47146 -23.925903) (xy 124.494786 -23.989991) (xy 124.510515 -24.056354)
			(xy 124.518432 -24.124094) (xy 124.518928 -24.158194) (xy 124.518928 -24.807418) (xy 124.720348 -24.807418)
			(xy 124.724419 -24.751796) (xy 124.736545 -24.697359) (xy 124.756468 -24.645268) (xy 124.783764 -24.596633)
			(xy 124.81785 -24.55249) (xy 124.857999 -24.513781) (xy 124.903357 -24.48133) (xy 124.952957 -24.455829)
			(xy 125.005741 -24.437822) (xy 125.060584 -24.427692) (xy 125.116318 -24.425655) (xy 125.171755 -24.431755)
			(xy 125.225712 -24.445861) (xy 125.277041 -24.467673) (xy 125.324647 -24.496727) (xy 125.367515 -24.532402)
			(xy 125.404732 -24.573939) (xy 125.435505 -24.620452) (xy 125.459177 -24.670949) (xy 125.475245 -24.724356)
			(xy 125.483365 -24.779532) (xy 125.483874 -24.807418) (xy 125.483365 -24.835304) (xy 125.475245 -24.89048)
			(xy 125.459177 -24.943887) (xy 125.435505 -24.994384) (xy 125.404732 -25.040897) (xy 125.367515 -25.082434)
			(xy 125.324647 -25.118109) (xy 125.277041 -25.147163) (xy 125.225712 -25.168975) (xy 125.171755 -25.183081)
			(xy 125.116318 -25.189181) (xy 125.060584 -25.187144) (xy 125.005741 -25.177014) (xy 124.952957 -25.159007)
			(xy 124.903357 -25.133506) (xy 124.857999 -25.101055) (xy 124.81785 -25.062346) (xy 124.783764 -25.018203)
			(xy 124.756468 -24.969568) (xy 124.736545 -24.917477) (xy 124.724419 -24.86304) (xy 124.720348 -24.807418)
			(xy 124.518928 -24.807418) (xy 124.518928 -26.724102) (xy 124.521189 -26.727027) (xy 124.52642 -26.732251)
			(xy 124.529342 -26.734516) (xy 124.823982 -26.734516) (xy 124.826522 -26.734516) (xy 124.831882 -26.734089)
			(xy 124.842258 -26.731274) (xy 124.847096 -26.728928) (xy 124.870718 -26.716228) (xy 124.87656 -26.713434)
			(xy 124.877068 -26.71318) (xy 124.885958 -26.70556) (xy 124.889768 -26.700226) (xy 124.895155 -26.691798)
			(xy 124.899643 -26.672327) (xy 124.896392 -26.652612) (xy 124.885891 -26.635612) (xy 124.878084 -26.62936)
			(xy 124.872242 -26.625296) (xy 124.866146 -26.62301) (xy 124.839452 -26.61224) (xy 124.789387 -26.583838)
			(xy 124.744154 -26.548242) (xy 124.704779 -26.506257) (xy 124.672155 -26.458835) (xy 124.647021 -26.407053)
			(xy 124.629946 -26.352084) (xy 124.62132 -26.295174) (xy 124.620782 -26.266394) (xy 124.621268 -26.239143)
			(xy 124.629025 -26.185195) (xy 124.644381 -26.132901) (xy 124.667022 -26.083323) (xy 124.696489 -26.037473)
			(xy 124.73218 -25.996283) (xy 124.77337 -25.960591) (xy 124.81922 -25.931124) (xy 124.868797 -25.908482)
			(xy 124.921091 -25.893126) (xy 124.975039 -25.885368) (xy 125.00229 -25.884886) (xy 125.030027 -25.88539)
			(xy 125.084915 -25.893433) (xy 125.138061 -25.909336) (xy 125.188345 -25.932765) (xy 125.234708 -25.963226)
			(xy 125.276174 -26.000078) (xy 125.311868 -26.042543) (xy 125.341039 -26.089729) (xy 125.363073 -26.140639)
			(xy 125.377506 -26.194203) (xy 125.381258 -26.22169) (xy 125.383798 -26.24328) (xy 125.384052 -26.24836)
			(xy 125.384052 -26.266394) (xy 125.383538 -26.294284) (xy 125.375411 -26.349469) (xy 125.359343 -26.402884)
			(xy 125.335677 -26.453395) (xy 125.304915 -26.499926) (xy 125.267712 -26.541487) (xy 125.246638 -26.559764)
			(xy 125.24613 -26.560018) (xy 125.24486 -26.561034) (xy 125.244352 -26.561288) (xy 125.235462 -26.568654)
			(xy 125.231144 -26.57221) (xy 125.224794 -26.57983) (xy 125.221238 -26.584402) (xy 125.217228 -26.590114)
			(xy 125.212209 -26.603132) (xy 125.211332 -26.610056) (xy 125.211078 -26.61539) (xy 125.212348 -26.643838)
			(xy 125.212348 -26.644346) (xy 125.215142 -26.690574) (xy 125.217936 -26.702766) (xy 125.224032 -26.713942)
			(xy 125.227017 -26.718656) (xy 125.234706 -26.726737) (xy 125.239272 -26.729944) (xy 125.240288 -26.730706)
			(xy 125.241812 -26.731468) (xy 125.266332 -26.746625) (xy 125.311027 -26.783027) (xy 125.349873 -26.825616)
			(xy 125.382022 -26.873462) (xy 125.406772 -26.925522) (xy 125.423584 -26.98066) (xy 125.43209 -27.037672)
			(xy 125.432566 -27.066494) (xy 125.432093 -27.094345) (xy 125.424166 -27.149481) (xy 125.408473 -27.202927)
			(xy 125.385333 -27.253596) (xy 125.355218 -27.300456) (xy 125.318739 -27.342552) (xy 125.276641 -27.379028)
			(xy 125.22978 -27.409142) (xy 125.17911 -27.432279) (xy 125.125663 -27.44797) (xy 125.070527 -27.455894)
			(xy 125.042676 -27.456384) (xy 125.042422 -27.456384) (xy 125.017102 -27.455979) (xy 124.966886 -27.44943)
			(xy 124.917936 -27.436453) (xy 124.871071 -27.417265) (xy 124.848874 -27.405076) (xy 124.843032 -27.401774)
			(xy 124.836936 -27.40025) (xy 124.823982 -27.398472) (xy 124.699268 -27.398472) (xy 124.689302 -27.398951)
			(xy 124.670867 -27.406527) (xy 124.663454 -27.413204) (xy 122.953935 -29.12237) (xy 124.706888 -29.12237)
			(xy 124.706888 -28.25877) (xy 124.707378 -28.228786) (xy 124.715206 -28.16933) (xy 124.730727 -28.111405)
			(xy 124.753676 -28.056001) (xy 124.78366 -28.004067) (xy 124.820166 -27.956491) (xy 124.862571 -27.914086)
			(xy 124.910147 -27.87758) (xy 124.962081 -27.847596) (xy 125.017485 -27.824647) (xy 125.07541 -27.809126)
			(xy 125.134866 -27.801298) (xy 125.194834 -27.801298) (xy 125.25429 -27.809126) (xy 125.312215 -27.824647)
			(xy 125.367619 -27.847596) (xy 125.419553 -27.87758) (xy 125.467129 -27.914086) (xy 125.509534 -27.956491)
			(xy 125.54604 -28.004067) (xy 125.576024 -28.056001) (xy 125.598973 -28.111405) (xy 125.614494 -28.16933)
			(xy 125.622322 -28.228786) (xy 125.622812 -28.25877) (xy 125.622812 -29.12237) (xy 125.622322 -29.152354)
			(xy 125.614494 -29.21181) (xy 125.598973 -29.269735) (xy 125.576024 -29.325139) (xy 125.54604 -29.377073)
			(xy 125.509534 -29.424649) (xy 125.467129 -29.467054) (xy 125.419553 -29.50356) (xy 125.367619 -29.533544)
			(xy 125.312215 -29.556493) (xy 125.25429 -29.572014) (xy 125.194834 -29.579842) (xy 125.134866 -29.579842)
			(xy 125.07541 -29.572014) (xy 125.017485 -29.556493) (xy 124.962081 -29.533544) (xy 124.910147 -29.50356)
			(xy 124.862571 -29.467054) (xy 124.820166 -29.424649) (xy 124.78366 -29.377073) (xy 124.753676 -29.325139)
			(xy 124.730727 -29.269735) (xy 124.715206 -29.21181) (xy 124.707378 -29.152354) (xy 124.706888 -29.12237)
			(xy 122.953935 -29.12237) (xy 122.200162 -29.875988) (xy 122.195336 -29.881576) (xy 122.195336 -30.922468)
			(xy 122.852688 -30.922468) (xy 122.852688 -30.058868) (xy 122.853178 -30.028884) (xy 122.861006 -29.969428)
			(xy 122.876527 -29.911503) (xy 122.899476 -29.856099) (xy 122.92946 -29.804165) (xy 122.965966 -29.756589)
			(xy 123.008371 -29.714184) (xy 123.055947 -29.677678) (xy 123.107881 -29.647694) (xy 123.163285 -29.624745)
			(xy 123.22121 -29.609224) (xy 123.280666 -29.601396) (xy 123.340634 -29.601396) (xy 123.40009 -29.609224)
			(xy 123.458015 -29.624745) (xy 123.513419 -29.647694) (xy 123.565353 -29.677678) (xy 123.612929 -29.714184)
			(xy 123.655334 -29.756589) (xy 123.69184 -29.804165) (xy 123.721824 -29.856099) (xy 123.744773 -29.911503)
			(xy 123.760294 -29.969428) (xy 123.768122 -30.028884) (xy 123.768612 -30.058868) (xy 123.768612 -30.92069)
			(xy 137.589768 -30.92069) (xy 137.589768 -30.05709) (xy 137.590258 -30.027122) (xy 137.598081 -29.9677)
			(xy 137.613594 -29.909807) (xy 137.63653 -29.854434) (xy 137.666497 -29.802528) (xy 137.702984 -29.754978)
			(xy 137.745364 -29.712598) (xy 137.792914 -29.676111) (xy 137.84482 -29.646144) (xy 137.900193 -29.623208)
			(xy 137.958086 -29.607695) (xy 138.017508 -29.599872) (xy 138.077444 -29.599872) (xy 138.136866 -29.607695)
			(xy 138.194759 -29.623208) (xy 138.250132 -29.646144) (xy 138.302038 -29.676111) (xy 138.349588 -29.712598)
			(xy 138.391968 -29.754978) (xy 138.428455 -29.802528) (xy 138.458422 -29.854434) (xy 138.481358 -29.909807)
			(xy 138.496871 -29.9677) (xy 138.504694 -30.027122) (xy 138.505184 -30.05709) (xy 138.505184 -30.92069)
			(xy 138.504694 -30.950658) (xy 138.496871 -31.01008) (xy 138.481358 -31.067973) (xy 138.458422 -31.123346)
			(xy 138.428455 -31.175252) (xy 138.391968 -31.222802) (xy 138.349588 -31.265182) (xy 138.302038 -31.301669)
			(xy 138.250132 -31.331636) (xy 138.194759 -31.354572) (xy 138.136866 -31.370085) (xy 138.077444 -31.377908)
			(xy 138.017508 -31.377908) (xy 137.958086 -31.370085) (xy 137.900193 -31.354572) (xy 137.84482 -31.331636)
			(xy 137.792914 -31.301669) (xy 137.745364 -31.265182) (xy 137.702984 -31.222802) (xy 137.666497 -31.175252)
			(xy 137.63653 -31.123346) (xy 137.613594 -31.067973) (xy 137.598081 -31.01008) (xy 137.590258 -30.950658)
			(xy 137.589768 -30.92069) (xy 123.768612 -30.92069) (xy 123.768612 -30.922468) (xy 123.768122 -30.952452)
			(xy 123.760294 -31.011908) (xy 123.744773 -31.069833) (xy 123.721824 -31.125237) (xy 123.69184 -31.177171)
			(xy 123.655334 -31.224747) (xy 123.612929 -31.267152) (xy 123.565353 -31.303658) (xy 123.513419 -31.333642)
			(xy 123.458015 -31.356591) (xy 123.40009 -31.372112) (xy 123.340634 -31.37994) (xy 123.280666 -31.37994)
			(xy 123.22121 -31.372112) (xy 123.163285 -31.356591) (xy 123.107881 -31.333642) (xy 123.055947 -31.303658)
			(xy 123.008371 -31.267152) (xy 122.965966 -31.224747) (xy 122.92946 -31.177171) (xy 122.899476 -31.125237)
			(xy 122.876527 -31.069833) (xy 122.861006 -31.011908) (xy 122.853178 -30.952452) (xy 122.852688 -30.922468)
			(xy 122.195336 -30.922468) (xy 122.195336 -32.722312) (xy 124.706888 -32.722312) (xy 124.706888 -31.858712)
			(xy 124.707378 -31.828728) (xy 124.715206 -31.769272) (xy 124.730727 -31.711347) (xy 124.753676 -31.655943)
			(xy 124.78366 -31.604009) (xy 124.820166 -31.556433) (xy 124.862571 -31.514028) (xy 124.910147 -31.477522)
			(xy 124.962081 -31.447538) (xy 125.017485 -31.424589) (xy 125.07541 -31.409068) (xy 125.134866 -31.40124)
			(xy 125.194834 -31.40124) (xy 125.25429 -31.409068) (xy 125.312215 -31.424589) (xy 125.367619 -31.447538)
			(xy 125.419553 -31.477522) (xy 125.467129 -31.514028) (xy 125.509534 -31.556433) (xy 125.54604 -31.604009)
			(xy 125.576024 -31.655943) (xy 125.598973 -31.711347) (xy 125.614494 -31.769272) (xy 125.622322 -31.828728)
			(xy 125.622812 -31.858712) (xy 125.622812 -32.714184) (xy 134.94766 -32.714184) (xy 134.94766 -31.850584)
			(xy 134.94815 -31.820616) (xy 134.955973 -31.761194) (xy 134.971486 -31.703301) (xy 134.994422 -31.647928)
			(xy 135.024389 -31.596022) (xy 135.060876 -31.548472) (xy 135.103256 -31.506092) (xy 135.150806 -31.469605)
			(xy 135.202712 -31.439638) (xy 135.258085 -31.416702) (xy 135.315978 -31.401189) (xy 135.3754 -31.393366)
			(xy 135.435336 -31.393366) (xy 135.494758 -31.401189) (xy 135.552651 -31.416702) (xy 135.608024 -31.439638)
			(xy 135.65993 -31.469605) (xy 135.70748 -31.506092) (xy 135.74986 -31.548472) (xy 135.786347 -31.596022)
			(xy 135.816314 -31.647928) (xy 135.83925 -31.703301) (xy 135.854763 -31.761194) (xy 135.862586 -31.820616)
			(xy 135.863076 -31.850584) (xy 135.863076 -32.714184) (xy 135.862586 -32.744152) (xy 135.854763 -32.803574)
			(xy 135.83925 -32.861467) (xy 135.816314 -32.91684) (xy 135.786347 -32.968746) (xy 135.74986 -33.016296)
			(xy 135.70748 -33.058676) (xy 135.65993 -33.095163) (xy 135.608024 -33.12513) (xy 135.552651 -33.148066)
			(xy 135.494758 -33.163579) (xy 135.435336 -33.171402) (xy 135.3754 -33.171402) (xy 135.315978 -33.163579)
			(xy 135.258085 -33.148066) (xy 135.202712 -33.12513) (xy 135.150806 -33.095163) (xy 135.103256 -33.058676)
			(xy 135.060876 -33.016296) (xy 135.024389 -32.968746) (xy 134.994422 -32.91684) (xy 134.971486 -32.861467)
			(xy 134.955973 -32.803574) (xy 134.94815 -32.744152) (xy 134.94766 -32.714184) (xy 125.622812 -32.714184)
			(xy 125.622812 -32.722312) (xy 125.622322 -32.752296) (xy 125.614494 -32.811752) (xy 125.598973 -32.869677)
			(xy 125.576024 -32.925081) (xy 125.54604 -32.977015) (xy 125.509534 -33.024591) (xy 125.467129 -33.066996)
			(xy 125.419553 -33.103502) (xy 125.367619 -33.133486) (xy 125.312215 -33.156435) (xy 125.25429 -33.171956)
			(xy 125.194834 -33.179784) (xy 125.134866 -33.179784) (xy 125.07541 -33.171956) (xy 125.017485 -33.156435)
			(xy 124.962081 -33.133486) (xy 124.910147 -33.103502) (xy 124.862571 -33.066996) (xy 124.820166 -33.024591)
			(xy 124.78366 -32.977015) (xy 124.753676 -32.925081) (xy 124.730727 -32.869677) (xy 124.715206 -32.811752)
			(xy 124.707378 -32.752296) (xy 124.706888 -32.722312) (xy 122.195336 -32.722312) (xy 122.195336 -34.52241)
			(xy 122.852688 -34.52241) (xy 122.852688 -33.65881) (xy 122.853178 -33.628826) (xy 122.861006 -33.56937)
			(xy 122.876527 -33.511445) (xy 122.899476 -33.456041) (xy 122.92946 -33.404107) (xy 122.965966 -33.356531)
			(xy 123.008371 -33.314126) (xy 123.055947 -33.27762) (xy 123.107881 -33.247636) (xy 123.163285 -33.224687)
			(xy 123.22121 -33.209166) (xy 123.280666 -33.201338) (xy 123.340634 -33.201338) (xy 123.40009 -33.209166)
			(xy 123.458015 -33.224687) (xy 123.513419 -33.247636) (xy 123.565353 -33.27762) (xy 123.612929 -33.314126)
			(xy 123.655334 -33.356531) (xy 123.69184 -33.404107) (xy 123.721824 -33.456041) (xy 123.744773 -33.511445)
			(xy 123.760294 -33.56937) (xy 123.768122 -33.628826) (xy 123.768612 -33.65881) (xy 123.768612 -34.520886)
			(xy 137.589768 -34.520886) (xy 137.589768 -33.657286) (xy 137.590258 -33.627318) (xy 137.598081 -33.567896)
			(xy 137.613594 -33.510003) (xy 137.63653 -33.45463) (xy 137.666497 -33.402724) (xy 137.702984 -33.355174)
			(xy 137.745364 -33.312794) (xy 137.792914 -33.276307) (xy 137.84482 -33.24634) (xy 137.900193 -33.223404)
			(xy 137.958086 -33.207891) (xy 138.017508 -33.200068) (xy 138.077444 -33.200068) (xy 138.136866 -33.207891)
			(xy 138.194759 -33.223404) (xy 138.250132 -33.24634) (xy 138.302038 -33.276307) (xy 138.349588 -33.312794)
			(xy 138.391968 -33.355174) (xy 138.428455 -33.402724) (xy 138.458422 -33.45463) (xy 138.481358 -33.510003)
			(xy 138.496871 -33.567896) (xy 138.504694 -33.627318) (xy 138.505184 -33.657286) (xy 138.505184 -34.520886)
			(xy 138.504694 -34.550854) (xy 138.496871 -34.610276) (xy 138.481358 -34.668169) (xy 138.458422 -34.723542)
			(xy 138.428455 -34.775448) (xy 138.391968 -34.822998) (xy 138.349588 -34.865378) (xy 138.302038 -34.901865)
			(xy 138.250132 -34.931832) (xy 138.194759 -34.954768) (xy 138.136866 -34.970281) (xy 138.077444 -34.978104)
			(xy 138.017508 -34.978104) (xy 137.958086 -34.970281) (xy 137.900193 -34.954768) (xy 137.84482 -34.931832)
			(xy 137.792914 -34.901865) (xy 137.745364 -34.865378) (xy 137.702984 -34.822998) (xy 137.666497 -34.775448)
			(xy 137.63653 -34.723542) (xy 137.613594 -34.668169) (xy 137.598081 -34.610276) (xy 137.590258 -34.550854)
			(xy 137.589768 -34.520886) (xy 123.768612 -34.520886) (xy 123.768612 -34.52241) (xy 123.768122 -34.552394)
			(xy 123.760294 -34.61185) (xy 123.744773 -34.669775) (xy 123.721824 -34.725179) (xy 123.69184 -34.777113)
			(xy 123.655334 -34.824689) (xy 123.612929 -34.867094) (xy 123.565353 -34.9036) (xy 123.513419 -34.933584)
			(xy 123.458015 -34.956533) (xy 123.40009 -34.972054) (xy 123.340634 -34.979882) (xy 123.280666 -34.979882)
			(xy 123.22121 -34.972054) (xy 123.163285 -34.956533) (xy 123.107881 -34.933584) (xy 123.055947 -34.9036)
			(xy 123.008371 -34.867094) (xy 122.965966 -34.824689) (xy 122.92946 -34.777113) (xy 122.899476 -34.725179)
			(xy 122.876527 -34.669775) (xy 122.861006 -34.61185) (xy 122.853178 -34.552394) (xy 122.852688 -34.52241)
			(xy 122.195336 -34.52241) (xy 122.195336 -34.72434) (xy 122.195844 -34.73196) (xy 122.197296 -34.739796)
			(xy 122.204406 -34.754049) (xy 122.209814 -34.7599) (xy 123.130564 -35.680396) (xy 123.579128 -36.12896)
			(xy 123.589288 -36.136834) (xy 123.604782 -36.145978) (xy 123.60529 -36.146232) (xy 123.60783 -36.146994)
			(xy 123.610624 -36.147756) (xy 123.636435 -36.156265) (xy 123.685551 -36.179528) (xy 123.730907 -36.209468)
			(xy 123.771602 -36.245489) (xy 123.806826 -36.286875) (xy 123.83588 -36.332804) (xy 123.858186 -36.382362)
			(xy 123.8733 -36.434565) (xy 123.880922 -36.488374) (xy 123.881388 -36.515548) (xy 123.881388 -36.515802)
			(xy 123.880887 -36.543735) (xy 123.872825 -36.599017) (xy 123.872494 -36.60013) (xy 128.098303 -36.60013)
			(xy 128.102308 -36.512222) (xy 128.114291 -36.425042) (xy 128.134151 -36.339313) (xy 128.161726 -36.255745)
			(xy 128.196785 -36.175031) (xy 128.239038 -36.097839) (xy 128.288136 -36.02481) (xy 128.343672 -35.956548)
			(xy 128.405184 -35.893618) (xy 128.472165 -35.836544) (xy 128.544058 -35.785796) (xy 128.620267 -35.741796)
			(xy 128.700162 -35.704909) (xy 128.783081 -35.67544) (xy 128.868336 -35.653633) (xy 128.95522 -35.639669)
			(xy 129.043014 -35.633663) (xy 129.130991 -35.635667) (xy 129.218421 -35.645662) (xy 129.30458 -35.663566)
			(xy 129.388754 -35.68923) (xy 129.470245 -35.722443) (xy 129.548379 -35.762929) (xy 129.622507 -35.810351)
			(xy 129.692015 -35.864318) (xy 129.705314 -35.876738) (xy 134.817356 -35.876738) (xy 134.821427 -35.821116)
			(xy 134.833553 -35.766679) (xy 134.853476 -35.714588) (xy 134.880772 -35.665953) (xy 134.914858 -35.62181)
			(xy 134.955007 -35.583101) (xy 135.000365 -35.55065) (xy 135.049965 -35.525149) (xy 135.102749 -35.507142)
			(xy 135.157592 -35.497012) (xy 135.213326 -35.494975) (xy 135.268763 -35.501075) (xy 135.32272 -35.515181)
			(xy 135.374049 -35.536993) (xy 135.421655 -35.566047) (xy 135.464523 -35.601722) (xy 135.50174 -35.643259)
			(xy 135.532513 -35.689772) (xy 135.556185 -35.740269) (xy 135.572253 -35.793676) (xy 135.580373 -35.848852)
			(xy 135.580882 -35.876738) (xy 135.580373 -35.904624) (xy 135.572253 -35.9598) (xy 135.556185 -36.013207)
			(xy 135.532513 -36.063704) (xy 135.50174 -36.110217) (xy 135.464523 -36.151754) (xy 135.421655 -36.187429)
			(xy 135.374049 -36.216483) (xy 135.32272 -36.238295) (xy 135.268763 -36.252401) (xy 135.213326 -36.258501)
			(xy 135.157592 -36.256464) (xy 135.102749 -36.246334) (xy 135.049965 -36.228327) (xy 135.000365 -36.202826)
			(xy 134.955007 -36.170375) (xy 134.914858 -36.131666) (xy 134.880772 -36.087523) (xy 134.853476 -36.038888)
			(xy 134.833553 -35.986797) (xy 134.821427 -35.93236) (xy 134.817356 -35.876738) (xy 129.705314 -35.876738)
			(xy 129.756329 -35.924383) (xy 129.814913 -35.990047) (xy 129.867284 -36.060766) (xy 129.913007 -36.135954)
			(xy 129.951704 -36.214989) (xy 129.983053 -36.297215) (xy 130.006795 -36.381951) (xy 130.022733 -36.468495)
			(xy 130.026519 -36.50996) (xy 136.713974 -36.50996) (xy 136.718045 -36.454338) (xy 136.730171 -36.399901)
			(xy 136.750094 -36.34781) (xy 136.77739 -36.299175) (xy 136.811476 -36.255032) (xy 136.851625 -36.216323)
			(xy 136.896983 -36.183872) (xy 136.946583 -36.158371) (xy 136.999367 -36.140364) (xy 137.05421 -36.130234)
			(xy 137.109944 -36.128197) (xy 137.165381 -36.134297) (xy 137.219338 -36.148403) (xy 137.270667 -36.170215)
			(xy 137.318273 -36.199269) (xy 137.361141 -36.234944) (xy 137.398358 -36.276481) (xy 137.429131 -36.322994)
			(xy 137.452803 -36.373491) (xy 137.468871 -36.426898) (xy 137.476991 -36.482074) (xy 137.4775 -36.50996)
			(xy 137.476991 -36.537846) (xy 137.468871 -36.593022) (xy 137.452803 -36.646429) (xy 137.429131 -36.696926)
			(xy 137.398358 -36.743439) (xy 137.361141 -36.784976) (xy 137.318273 -36.820651) (xy 137.270667 -36.849705)
			(xy 137.219338 -36.871517) (xy 137.165381 -36.885623) (xy 137.109944 -36.891723) (xy 137.05421 -36.889686)
			(xy 136.999367 -36.879556) (xy 136.946583 -36.861549) (xy 136.896983 -36.836048) (xy 136.851625 -36.803597)
			(xy 136.811476 -36.764888) (xy 136.77739 -36.720745) (xy 136.750094 -36.67211) (xy 136.730171 -36.620019)
			(xy 136.718045 -36.565582) (xy 136.713974 -36.50996) (xy 130.026519 -36.50996) (xy 130.030735 -36.55613)
			(xy 130.031236 -36.60013) (xy 130.030735 -36.64413) (xy 130.022733 -36.731765) (xy 130.006795 -36.818309)
			(xy 129.983053 -36.903045) (xy 129.951704 -36.985271) (xy 129.913007 -37.064306) (xy 129.867284 -37.139494)
			(xy 129.814913 -37.210213) (xy 129.756329 -37.275877) (xy 129.692015 -37.335942) (xy 129.622507 -37.389909)
			(xy 129.548379 -37.437331) (xy 129.475373 -37.47516) (xy 133.859268 -37.47516) (xy 133.863339 -37.419538)
			(xy 133.875465 -37.365101) (xy 133.895388 -37.31301) (xy 133.922684 -37.264375) (xy 133.95677 -37.220232)
			(xy 133.996919 -37.181523) (xy 134.042277 -37.149072) (xy 134.091877 -37.123571) (xy 134.144661 -37.105564)
			(xy 134.199504 -37.095434) (xy 134.255238 -37.093397) (xy 134.310675 -37.099497) (xy 134.364632 -37.113603)
			(xy 134.415961 -37.135415) (xy 134.463567 -37.164469) (xy 134.506435 -37.200144) (xy 134.543652 -37.241681)
			(xy 134.574425 -37.288194) (xy 134.598097 -37.338691) (xy 134.614165 -37.392098) (xy 134.622285 -37.447274)
			(xy 134.622794 -37.47516) (xy 134.622285 -37.503046) (xy 134.614165 -37.558222) (xy 134.598097 -37.611629)
			(xy 134.574425 -37.662126) (xy 134.574272 -37.662358) (xy 136.048494 -37.662358) (xy 136.052565 -37.606736)
			(xy 136.064691 -37.552299) (xy 136.084614 -37.500208) (xy 136.11191 -37.451573) (xy 136.145996 -37.40743)
			(xy 136.186145 -37.368721) (xy 136.231503 -37.33627) (xy 136.281103 -37.310769) (xy 136.333887 -37.292762)
			(xy 136.38873 -37.282632) (xy 136.444464 -37.280595) (xy 136.499901 -37.286695) (xy 136.553858 -37.300801)
			(xy 136.605187 -37.322613) (xy 136.652793 -37.351667) (xy 136.695661 -37.387342) (xy 136.732878 -37.428879)
			(xy 136.763651 -37.475392) (xy 136.787323 -37.525889) (xy 136.803391 -37.579296) (xy 136.811511 -37.634472)
			(xy 136.81202 -37.662358) (xy 136.811511 -37.690244) (xy 136.803391 -37.74542) (xy 136.787323 -37.798827)
			(xy 136.763651 -37.849324) (xy 136.732878 -37.895837) (xy 136.695661 -37.937374) (xy 136.652793 -37.973049)
			(xy 136.605187 -38.002103) (xy 136.553858 -38.023915) (xy 136.499901 -38.038021) (xy 136.444464 -38.044121)
			(xy 136.38873 -38.042084) (xy 136.333887 -38.031954) (xy 136.281103 -38.013947) (xy 136.231503 -37.988446)
			(xy 136.186145 -37.955995) (xy 136.145996 -37.917286) (xy 136.11191 -37.873143) (xy 136.084614 -37.824508)
			(xy 136.064691 -37.772417) (xy 136.052565 -37.71798) (xy 136.048494 -37.662358) (xy 134.574272 -37.662358)
			(xy 134.543652 -37.708639) (xy 134.506435 -37.750176) (xy 134.463567 -37.785851) (xy 134.415961 -37.814905)
			(xy 134.364632 -37.836717) (xy 134.310675 -37.850823) (xy 134.255238 -37.856923) (xy 134.199504 -37.854886)
			(xy 134.144661 -37.844756) (xy 134.091877 -37.826749) (xy 134.042277 -37.801248) (xy 133.996919 -37.768797)
			(xy 133.95677 -37.730088) (xy 133.922684 -37.685945) (xy 133.895388 -37.63731) (xy 133.875465 -37.585219)
			(xy 133.863339 -37.530782) (xy 133.859268 -37.47516) (xy 129.475373 -37.47516) (xy 129.470245 -37.477817)
			(xy 129.388754 -37.51103) (xy 129.30458 -37.536694) (xy 129.218421 -37.554598) (xy 129.130991 -37.564593)
			(xy 129.043014 -37.566597) (xy 128.95522 -37.560591) (xy 128.868336 -37.546627) (xy 128.783081 -37.52482)
			(xy 128.700162 -37.495351) (xy 128.620267 -37.458464) (xy 128.544058 -37.414464) (xy 128.472165 -37.363716)
			(xy 128.405184 -37.306642) (xy 128.343672 -37.243712) (xy 128.288136 -37.17545) (xy 128.239038 -37.102421)
			(xy 128.196785 -37.025229) (xy 128.161726 -36.944515) (xy 128.134151 -36.860947) (xy 128.114291 -36.775218)
			(xy 128.102308 -36.688038) (xy 128.098303 -36.60013) (xy 123.872494 -36.60013) (xy 123.856883 -36.652561)
			(xy 123.845574 -36.678108) (xy 123.843288 -36.682934) (xy 123.839478 -36.69919) (xy 123.838208 -36.71062)
			(xy 123.838208 -38.729948) (xy 139.80112 -38.729948) (xy 139.80112 -38.675452) (xy 139.808876 -38.621511)
			(xy 139.824229 -38.569223) (xy 139.846867 -38.519652) (xy 139.876329 -38.473807) (xy 139.912016 -38.432621)
			(xy 139.9532 -38.396934) (xy 139.999045 -38.36747) (xy 140.048615 -38.344831) (xy 140.100903 -38.329477)
			(xy 140.154844 -38.321721) (xy 140.182092 -38.321234) (xy 140.210397 -38.321714) (xy 140.266386 -38.330066)
			(xy 140.320526 -38.346602) (xy 140.371628 -38.370958) (xy 140.418567 -38.402601) (xy 140.460314 -38.440834)
			(xy 140.495952 -38.484818) (xy 140.510768 -38.50894) (xy 140.518441 -38.520923) (xy 140.539044 -38.540521)
			(xy 140.56426 -38.553665) (xy 140.592126 -38.559331) (xy 140.620472 -38.557077) (xy 140.647093 -38.547079)
			(xy 140.669915 -38.530116) (xy 140.678916 -38.5191) (xy 140.697098 -38.49622) (xy 140.739262 -38.455757)
			(xy 140.787099 -38.42219) (xy 140.839491 -38.396303) (xy 140.895216 -38.378702) (xy 140.952973 -38.369797)
			(xy 140.982192 -38.36924) (xy 141.009449 -38.369606) (xy 141.063407 -38.377363) (xy 141.115713 -38.392721)
			(xy 141.1653 -38.415366) (xy 141.21116 -38.444837) (xy 141.252359 -38.480535) (xy 141.288058 -38.521733)
			(xy 141.317531 -38.567593) (xy 141.340176 -38.61718) (xy 141.355535 -38.669485) (xy 141.363293 -38.723443)
			(xy 141.363293 -38.777957) (xy 141.355535 -38.831915) (xy 141.340176 -38.88422) (xy 141.317531 -38.933807)
			(xy 141.288058 -38.979667) (xy 141.252359 -39.020865) (xy 141.21116 -39.056563) (xy 141.1653 -39.086034)
			(xy 141.115713 -39.108679) (xy 141.063407 -39.124037) (xy 141.009449 -39.131794) (xy 140.982192 -39.132256)
			(xy 140.953887 -39.131793) (xy 140.897896 -39.123439) (xy 140.843755 -39.106901) (xy 140.792654 -39.082541)
			(xy 140.745714 -39.050896) (xy 140.703968 -39.01266) (xy 140.668332 -38.968674) (xy 140.653516 -38.94455)
			(xy 140.645864 -38.932553) (xy 140.625256 -38.912955) (xy 140.600036 -38.899813) (xy 140.572166 -38.89415)
			(xy 140.543817 -38.896407) (xy 140.517194 -38.906407) (xy 140.49437 -38.923373) (xy 140.485368 -38.93439)
			(xy 140.467192 -38.957275) (xy 140.425028 -38.997739) (xy 140.37719 -39.031306) (xy 140.324796 -39.057191)
			(xy 140.269069 -39.074791) (xy 140.211312 -39.083695) (xy 140.182092 -39.08425) (xy 140.154844 -39.083679)
			(xy 140.100903 -39.075923) (xy 140.048615 -39.060569) (xy 139.999045 -39.03793) (xy 139.9532 -39.008466)
			(xy 139.912016 -38.972779) (xy 139.876329 -38.931593) (xy 139.846867 -38.885748) (xy 139.824229 -38.836177)
			(xy 139.808876 -38.783889) (xy 139.80112 -38.729948) (xy 123.838208 -38.729948) (xy 123.838208 -38.90645)
			(xy 123.839224 -38.916102) (xy 123.840858 -38.923343) (xy 123.847708 -38.936503) (xy 123.852686 -38.94201)
			(xy 126.179431 -41.268755) (xy 131.944027 -41.268755) (xy 131.944027 -41.214245) (xy 131.951785 -41.160289)
			(xy 131.967142 -41.107986) (xy 131.989787 -41.058402) (xy 132.019258 -41.012545) (xy 132.054956 -40.971349)
			(xy 132.096153 -40.935652) (xy 132.142011 -40.906183) (xy 132.191596 -40.883539) (xy 132.243899 -40.868183)
			(xy 132.297855 -40.860426) (xy 132.32511 -40.859964) (xy 132.353849 -40.860491) (xy 132.410675 -40.869114)
			(xy 132.465566 -40.886164) (xy 132.517278 -40.911255) (xy 132.564641 -40.943818) (xy 132.585968 -40.963088)
			(xy 132.592826 -40.969692) (xy 132.61086 -40.976804) (xy 132.69976 -40.976804) (xy 132.717794 -40.969692)
			(xy 132.724652 -40.963088) (xy 132.745982 -40.943821) (xy 132.793343 -40.911252) (xy 132.845053 -40.886158)
			(xy 132.899944 -40.869107) (xy 132.956771 -40.860484) (xy 132.98551 -40.859964) (xy 133.012759 -40.860507)
			(xy 133.066701 -40.868264) (xy 133.118991 -40.883619) (xy 133.168563 -40.906259) (xy 133.214409 -40.935723)
			(xy 133.255595 -40.971412) (xy 133.291283 -41.012599) (xy 133.320746 -41.058445) (xy 133.343385 -41.108018)
			(xy 133.358738 -41.160308) (xy 133.366494 -41.214251) (xy 133.366494 -41.268749) (xy 133.358738 -41.322692)
			(xy 133.343385 -41.374982) (xy 133.320746 -41.424555) (xy 133.291283 -41.470401) (xy 133.255595 -41.511588)
			(xy 133.214409 -41.547277) (xy 133.168563 -41.576741) (xy 133.118991 -41.599381) (xy 133.066701 -41.614736)
			(xy 133.012759 -41.622493) (xy 132.98551 -41.62298) (xy 132.956772 -41.622429) (xy 132.899947 -41.61381)
			(xy 132.845058 -41.596765) (xy 132.793345 -41.57168) (xy 132.745981 -41.539123) (xy 132.724652 -41.519856)
			(xy 132.717794 -41.513252) (xy 132.69976 -41.50614) (xy 132.61086 -41.50614) (xy 132.592826 -41.513252)
			(xy 132.585968 -41.519856) (xy 132.564636 -41.539121) (xy 132.517275 -41.571688) (xy 132.465565 -41.596782)
			(xy 132.410675 -41.613834) (xy 132.353849 -41.622458) (xy 132.32511 -41.62298) (xy 132.297855 -41.622574)
			(xy 132.243899 -41.614817) (xy 132.191596 -41.599461) (xy 132.142011 -41.576817) (xy 132.096153 -41.547348)
			(xy 132.054956 -41.511651) (xy 132.019258 -41.470455) (xy 131.989787 -41.424598) (xy 131.967142 -41.375014)
			(xy 131.951785 -41.322711) (xy 131.944027 -41.268755) (xy 126.179431 -41.268755) (xy 127.471678 -42.561002)
			(xy 127.480502 -42.570032) (xy 127.496901 -42.589231) (xy 127.504444 -42.599356) (xy 127.519938 -42.62247)
			(xy 127.525526 -42.629074) (xy 128.201674 -43.305222) (xy 134.407402 -43.305222) (xy 134.40788 -43.277852)
			(xy 134.415695 -43.223674) (xy 134.431181 -43.171171) (xy 134.45402 -43.121424) (xy 134.483742 -43.075456)
			(xy 134.501382 -43.054524) (xy 134.501636 -43.05427) (xy 134.507203 -43.047171) (xy 134.513461 -43.030263)
			(xy 134.513828 -43.02125) (xy 134.513828 -42.954194) (xy 134.513468 -42.945178) (xy 134.507222 -42.928261)
			(xy 134.501636 -42.921174) (xy 134.501382 -42.921174) (xy 134.501382 -42.92092) (xy 134.483736 -42.899994)
			(xy 134.454026 -42.854019) (xy 134.431192 -42.80427) (xy 134.415702 -42.751768) (xy 134.407875 -42.697592)
			(xy 134.407402 -42.670222) (xy 134.407939 -42.641484) (xy 134.416558 -42.584657) (xy 134.433605 -42.529766)
			(xy 134.458694 -42.478054) (xy 134.491256 -42.430691) (xy 134.510526 -42.409364) (xy 134.51713 -42.402506)
			(xy 134.524242 -42.384472) (xy 134.524242 -42.295572) (xy 134.51713 -42.277538) (xy 134.510526 -42.27068)
			(xy 134.491277 -42.249334) (xy 134.458711 -42.201975) (xy 134.433618 -42.150267) (xy 134.416566 -42.095379)
			(xy 134.407941 -42.038554) (xy 134.407939 -41.981078) (xy 134.416559 -41.924253) (xy 134.433606 -41.869363)
			(xy 134.458695 -41.817653) (xy 134.491257 -41.770291) (xy 134.510526 -41.748964) (xy 134.51713 -41.742106)
			(xy 134.524242 -41.724072) (xy 134.524242 -41.635172) (xy 134.51713 -41.617138) (xy 134.510526 -41.61028)
			(xy 134.491264 -41.588946) (xy 134.458697 -41.541585) (xy 134.433603 -41.489876) (xy 134.41655 -41.434987)
			(xy 134.407925 -41.37816) (xy 134.407402 -41.349422) (xy 134.407888 -41.322171) (xy 134.415644 -41.268223)
			(xy 134.430999 -41.215928) (xy 134.453641 -41.166351) (xy 134.483107 -41.120501) (xy 134.518798 -41.07931)
			(xy 134.559989 -41.043619) (xy 134.605839 -41.014153) (xy 134.655416 -40.991511) (xy 134.707711 -40.976156)
			(xy 134.761659 -40.9684) (xy 134.816161 -40.9684) (xy 134.839282 -40.971724) (xy 142.69415 -40.971724)
			(xy 142.698221 -40.916102) (xy 142.710347 -40.861665) (xy 142.73027 -40.809574) (xy 142.757566 -40.760939)
			(xy 142.791652 -40.716796) (xy 142.831801 -40.678087) (xy 142.877159 -40.645636) (xy 142.926759 -40.620135)
			(xy 142.979543 -40.602128) (xy 143.034386 -40.591998) (xy 143.09012 -40.589961) (xy 143.145557 -40.596061)
			(xy 143.199514 -40.610167) (xy 143.250843 -40.631979) (xy 143.298449 -40.661033) (xy 143.341317 -40.696708)
			(xy 143.378534 -40.738245) (xy 143.409307 -40.784758) (xy 143.432979 -40.835255) (xy 143.449047 -40.888662)
			(xy 143.457167 -40.943838) (xy 143.457676 -40.971724) (xy 143.457167 -40.99961) (xy 143.449047 -41.054786)
			(xy 143.432979 -41.108193) (xy 143.409307 -41.15869) (xy 143.378534 -41.205203) (xy 143.341317 -41.24674)
			(xy 143.298449 -41.282415) (xy 143.250843 -41.311469) (xy 143.199514 -41.333281) (xy 143.145557 -41.347387)
			(xy 143.09012 -41.353487) (xy 143.034386 -41.35145) (xy 142.979543 -41.34132) (xy 142.926759 -41.323313)
			(xy 142.877159 -41.297812) (xy 142.831801 -41.265361) (xy 142.791652 -41.226652) (xy 142.757566 -41.182509)
			(xy 142.73027 -41.133874) (xy 142.710347 -41.081783) (xy 142.698221 -41.027346) (xy 142.69415 -40.971724)
			(xy 134.839282 -40.971724) (xy 134.870109 -40.976156) (xy 134.922404 -40.991511) (xy 134.971981 -41.014153)
			(xy 135.017831 -41.043619) (xy 135.059022 -41.07931) (xy 135.094713 -41.120501) (xy 135.124179 -41.166351)
			(xy 135.146821 -41.215928) (xy 135.162176 -41.268223) (xy 135.169932 -41.322171) (xy 135.170418 -41.349422)
			(xy 135.169903 -41.378161) (xy 135.161277 -41.434989) (xy 135.144225 -41.489879) (xy 135.119132 -41.541591)
			(xy 135.086565 -41.588953) (xy 135.067294 -41.61028) (xy 135.06069 -41.617138) (xy 135.053578 -41.635172)
			(xy 135.053578 -41.724072) (xy 135.06069 -41.742106) (xy 135.067294 -41.748964) (xy 135.086586 -41.770272)
			(xy 135.119149 -41.817638) (xy 135.144238 -41.869353) (xy 135.161286 -41.924247) (xy 135.169906 -41.981076)
			(xy 135.169903 -42.038556) (xy 135.161278 -42.095385) (xy 135.144226 -42.150277) (xy 135.119133 -42.201989)
			(xy 135.086566 -42.249353) (xy 135.067294 -42.27068) (xy 135.06069 -42.277538) (xy 135.053578 -42.295572)
			(xy 135.053578 -42.384472) (xy 135.06069 -42.402506) (xy 135.067294 -42.409364) (xy 135.086564 -42.430692)
			(xy 135.119132 -42.478053) (xy 135.144226 -42.529764) (xy 135.161277 -42.584655) (xy 135.169898 -42.641483)
			(xy 135.170418 -42.670222) (xy 135.169985 -42.697594) (xy 135.162162 -42.751775) (xy 135.146666 -42.804279)
			(xy 135.126108 -42.849038) (xy 136.992104 -42.849038) (xy 136.996175 -42.793416) (xy 137.008301 -42.738979)
			(xy 137.028224 -42.686888) (xy 137.05552 -42.638253) (xy 137.089606 -42.59411) (xy 137.129755 -42.555401)
			(xy 137.175113 -42.52295) (xy 137.224713 -42.497449) (xy 137.277497 -42.479442) (xy 137.33234 -42.469312)
			(xy 137.388074 -42.467275) (xy 137.443511 -42.473375) (xy 137.497468 -42.487481) (xy 137.548797 -42.509293)
			(xy 137.596403 -42.538347) (xy 137.639271 -42.574022) (xy 137.676488 -42.615559) (xy 137.707261 -42.662072)
			(xy 137.730933 -42.712569) (xy 137.747001 -42.765976) (xy 137.755121 -42.821152) (xy 137.755482 -42.84091)
			(xy 143.03324 -42.84091) (xy 143.037311 -42.785288) (xy 143.049437 -42.730851) (xy 143.06936 -42.67876)
			(xy 143.096656 -42.630125) (xy 143.130742 -42.585982) (xy 143.170891 -42.547273) (xy 143.216249 -42.514822)
			(xy 143.265849 -42.489321) (xy 143.318633 -42.471314) (xy 143.373476 -42.461184) (xy 143.42921 -42.459147)
			(xy 143.484647 -42.465247) (xy 143.538604 -42.479353) (xy 143.589933 -42.501165) (xy 143.637539 -42.530219)
			(xy 143.680407 -42.565894) (xy 143.717624 -42.607431) (xy 143.748397 -42.653944) (xy 143.772069 -42.704441)
			(xy 143.788137 -42.757848) (xy 143.796257 -42.813024) (xy 143.796766 -42.84091) (xy 143.796257 -42.868796)
			(xy 143.788137 -42.923972) (xy 143.772069 -42.977379) (xy 143.748397 -43.027876) (xy 143.717624 -43.074389)
			(xy 143.680407 -43.115926) (xy 143.637539 -43.151601) (xy 143.589933 -43.180655) (xy 143.538604 -43.202467)
			(xy 143.484647 -43.216573) (xy 143.42921 -43.222673) (xy 143.373476 -43.220636) (xy 143.318633 -43.210506)
			(xy 143.265849 -43.192499) (xy 143.216249 -43.166998) (xy 143.170891 -43.134547) (xy 143.130742 -43.095838)
			(xy 143.096656 -43.051695) (xy 143.06936 -43.00306) (xy 143.049437 -42.950969) (xy 143.037311 -42.896532)
			(xy 143.03324 -42.84091) (xy 137.755482 -42.84091) (xy 137.75563 -42.849038) (xy 137.755121 -42.876924)
			(xy 137.747001 -42.9321) (xy 137.730933 -42.985507) (xy 137.707261 -43.036004) (xy 137.676488 -43.082517)
			(xy 137.639271 -43.124054) (xy 137.596403 -43.159729) (xy 137.548797 -43.188783) (xy 137.497468 -43.210595)
			(xy 137.443511 -43.224701) (xy 137.388074 -43.230801) (xy 137.33234 -43.228764) (xy 137.277497 -43.218634)
			(xy 137.224713 -43.200627) (xy 137.175113 -43.175126) (xy 137.129755 -43.142675) (xy 137.089606 -43.103966)
			(xy 137.05552 -43.059823) (xy 137.028224 -43.011188) (xy 137.008301 -42.959097) (xy 136.996175 -42.90466)
			(xy 136.992104 -42.849038) (xy 135.126108 -42.849038) (xy 135.123817 -42.854026) (xy 135.094084 -42.89999)
			(xy 135.076438 -42.92092) (xy 135.076184 -42.921174) (xy 135.0706 -42.928263) (xy 135.064352 -42.945178)
			(xy 135.063992 -42.954194) (xy 135.063992 -43.02125) (xy 135.064374 -43.030264) (xy 135.070604 -43.047181)
			(xy 135.076184 -43.05427) (xy 135.076438 -43.05427) (xy 135.076438 -43.054524) (xy 135.094061 -43.075469)
			(xy 135.123774 -43.121439) (xy 135.146613 -43.171183) (xy 135.162108 -43.223681) (xy 135.169941 -43.277854)
			(xy 135.170418 -43.305222) (xy 135.169932 -43.332473) (xy 135.162176 -43.386421) (xy 135.146821 -43.438716)
			(xy 135.124179 -43.488293) (xy 135.094713 -43.534143) (xy 135.059022 -43.575334) (xy 135.017831 -43.611025)
			(xy 134.971981 -43.640491) (xy 134.922404 -43.663133) (xy 134.870109 -43.678488) (xy 134.816161 -43.686244)
			(xy 134.761659 -43.686244) (xy 134.707711 -43.678488) (xy 134.655416 -43.663133) (xy 134.605839 -43.640491)
			(xy 134.559989 -43.611025) (xy 134.518798 -43.575334) (xy 134.483107 -43.534143) (xy 134.453641 -43.488293)
			(xy 134.430999 -43.438716) (xy 134.415644 -43.386421) (xy 134.407888 -43.332473) (xy 134.407402 -43.305222)
			(xy 128.201674 -43.305222) (xy 128.632712 -43.73626) (xy 136.313162 -43.73626) (xy 136.317233 -43.680638)
			(xy 136.329359 -43.626201) (xy 136.349282 -43.57411) (xy 136.376578 -43.525475) (xy 136.410664 -43.481332)
			(xy 136.450813 -43.442623) (xy 136.496171 -43.410172) (xy 136.545771 -43.384671) (xy 136.598555 -43.366664)
			(xy 136.653398 -43.356534) (xy 136.709132 -43.354497) (xy 136.764569 -43.360597) (xy 136.818526 -43.374703)
			(xy 136.869855 -43.396515) (xy 136.917461 -43.425569) (xy 136.960329 -43.461244) (xy 136.997546 -43.502781)
			(xy 137.028319 -43.549294) (xy 137.051991 -43.599791) (xy 137.068059 -43.653198) (xy 137.076179 -43.708374)
			(xy 137.076688 -43.73626) (xy 137.076179 -43.764146) (xy 137.068059 -43.819322) (xy 137.05675 -43.85691)
			(xy 140.819884 -43.85691) (xy 140.823955 -43.801288) (xy 140.836081 -43.746851) (xy 140.856004 -43.69476)
			(xy 140.8833 -43.646125) (xy 140.917386 -43.601982) (xy 140.957535 -43.563273) (xy 141.002893 -43.530822)
			(xy 141.052493 -43.505321) (xy 141.105277 -43.487314) (xy 141.16012 -43.477184) (xy 141.215854 -43.475147)
			(xy 141.271291 -43.481247) (xy 141.325248 -43.495353) (xy 141.376577 -43.517165) (xy 141.424183 -43.546219)
			(xy 141.467051 -43.581894) (xy 141.504268 -43.623431) (xy 141.535041 -43.669944) (xy 141.558713 -43.720441)
			(xy 141.574781 -43.773848) (xy 141.582901 -43.829024) (xy 141.58341 -43.85691) (xy 141.582901 -43.884796)
			(xy 141.574781 -43.939972) (xy 141.558713 -43.993379) (xy 141.535041 -44.043876) (xy 141.504268 -44.090389)
			(xy 141.467051 -44.131926) (xy 141.424183 -44.167601) (xy 141.376577 -44.196655) (xy 141.325248 -44.218467)
			(xy 141.271291 -44.232573) (xy 141.215854 -44.238673) (xy 141.16012 -44.236636) (xy 141.105277 -44.226506)
			(xy 141.052493 -44.208499) (xy 141.002893 -44.182998) (xy 140.957535 -44.150547) (xy 140.917386 -44.111838)
			(xy 140.8833 -44.067695) (xy 140.856004 -44.01906) (xy 140.836081 -43.966969) (xy 140.823955 -43.912532)
			(xy 140.819884 -43.85691) (xy 137.05675 -43.85691) (xy 137.051991 -43.872729) (xy 137.028319 -43.923226)
			(xy 136.997546 -43.969739) (xy 136.960329 -44.011276) (xy 136.917461 -44.046951) (xy 136.869855 -44.076005)
			(xy 136.818526 -44.097817) (xy 136.764569 -44.111923) (xy 136.709132 -44.118023) (xy 136.653398 -44.115986)
			(xy 136.598555 -44.105856) (xy 136.545771 -44.087849) (xy 136.496171 -44.062348) (xy 136.450813 -44.029897)
			(xy 136.410664 -43.991188) (xy 136.376578 -43.947045) (xy 136.349282 -43.89841) (xy 136.329359 -43.846319)
			(xy 136.317233 -43.791882) (xy 136.313162 -43.73626) (xy 128.632712 -43.73626) (xy 129.016506 -44.120054)
			(xy 129.017522 -44.120816) (xy 129.037694 -44.140979) (xy 129.071297 -44.187058) (xy 129.096263 -44.238333)
			(xy 129.104644 -44.265596) (xy 129.105152 -44.26839) (xy 129.105914 -44.271184) (xy 129.110926 -44.291262)
			(xy 129.116403 -44.332282) (xy 129.116836 -44.352972) (xy 129.116836 -45.114464) (xy 136.165588 -45.114464)
			(xy 136.169659 -45.058842) (xy 136.181785 -45.004405) (xy 136.201708 -44.952314) (xy 136.229004 -44.903679)
			(xy 136.26309 -44.859536) (xy 136.303239 -44.820827) (xy 136.348597 -44.788376) (xy 136.398197 -44.762875)
			(xy 136.450981 -44.744868) (xy 136.505824 -44.734738) (xy 136.561558 -44.732701) (xy 136.616995 -44.738801)
			(xy 136.670952 -44.752907) (xy 136.722281 -44.774719) (xy 136.769887 -44.803773) (xy 136.812755 -44.839448)
			(xy 136.842737 -44.87291) (xy 143.03324 -44.87291) (xy 143.037311 -44.817288) (xy 143.049437 -44.762851)
			(xy 143.06936 -44.71076) (xy 143.096656 -44.662125) (xy 143.130742 -44.617982) (xy 143.170891 -44.579273)
			(xy 143.216249 -44.546822) (xy 143.265849 -44.521321) (xy 143.318633 -44.503314) (xy 143.373476 -44.493184)
			(xy 143.42921 -44.491147) (xy 143.484647 -44.497247) (xy 143.538604 -44.511353) (xy 143.589933 -44.533165)
			(xy 143.637539 -44.562219) (xy 143.680407 -44.597894) (xy 143.717624 -44.639431) (xy 143.748397 -44.685944)
			(xy 143.772069 -44.736441) (xy 143.788137 -44.789848) (xy 143.796257 -44.845024) (xy 143.796766 -44.87291)
			(xy 143.796257 -44.900796) (xy 143.788137 -44.955972) (xy 143.772069 -45.009379) (xy 143.748397 -45.059876)
			(xy 143.717624 -45.106389) (xy 143.680407 -45.147926) (xy 143.637539 -45.183601) (xy 143.589933 -45.212655)
			(xy 143.538604 -45.234467) (xy 143.484647 -45.248573) (xy 143.42921 -45.254673) (xy 143.373476 -45.252636)
			(xy 143.318633 -45.242506) (xy 143.265849 -45.224499) (xy 143.216249 -45.198998) (xy 143.170891 -45.166547)
			(xy 143.130742 -45.127838) (xy 143.096656 -45.083695) (xy 143.06936 -45.03506) (xy 143.049437 -44.982969)
			(xy 143.037311 -44.928532) (xy 143.03324 -44.87291) (xy 136.842737 -44.87291) (xy 136.849972 -44.880985)
			(xy 136.880745 -44.927498) (xy 136.904417 -44.977995) (xy 136.920485 -45.031402) (xy 136.928605 -45.086578)
			(xy 136.929114 -45.114464) (xy 136.928605 -45.14235) (xy 136.920485 -45.197526) (xy 136.904417 -45.250933)
			(xy 136.880745 -45.30143) (xy 136.849972 -45.347943) (xy 136.84433 -45.35424) (xy 140.803882 -45.35424)
			(xy 140.807953 -45.298618) (xy 140.820079 -45.244181) (xy 140.840002 -45.19209) (xy 140.867298 -45.143455)
			(xy 140.901384 -45.099312) (xy 140.941533 -45.060603) (xy 140.986891 -45.028152) (xy 141.036491 -45.002651)
			(xy 141.089275 -44.984644) (xy 141.144118 -44.974514) (xy 141.199852 -44.972477) (xy 141.255289 -44.978577)
			(xy 141.309246 -44.992683) (xy 141.360575 -45.014495) (xy 141.408181 -45.043549) (xy 141.451049 -45.079224)
			(xy 141.488266 -45.120761) (xy 141.519039 -45.167274) (xy 141.542711 -45.217771) (xy 141.558779 -45.271178)
			(xy 141.566899 -45.326354) (xy 141.567408 -45.35424) (xy 141.566899 -45.382126) (xy 141.558779 -45.437302)
			(xy 141.542711 -45.490709) (xy 141.519039 -45.541206) (xy 141.488266 -45.587719) (xy 141.451049 -45.629256)
			(xy 141.408181 -45.664931) (xy 141.360575 -45.693985) (xy 141.309246 -45.715797) (xy 141.255289 -45.729903)
			(xy 141.199852 -45.736003) (xy 141.144118 -45.733966) (xy 141.089275 -45.723836) (xy 141.036491 -45.705829)
			(xy 140.986891 -45.680328) (xy 140.941533 -45.647877) (xy 140.901384 -45.609168) (xy 140.867298 -45.565025)
			(xy 140.840002 -45.51639) (xy 140.820079 -45.464299) (xy 140.807953 -45.409862) (xy 140.803882 -45.35424)
			(xy 136.84433 -45.35424) (xy 136.812755 -45.38948) (xy 136.769887 -45.425155) (xy 136.722281 -45.454209)
			(xy 136.670952 -45.476021) (xy 136.616995 -45.490127) (xy 136.561558 -45.496227) (xy 136.505824 -45.49419)
			(xy 136.450981 -45.48406) (xy 136.398197 -45.466053) (xy 136.348597 -45.440552) (xy 136.303239 -45.408101)
			(xy 136.26309 -45.369392) (xy 136.229004 -45.325249) (xy 136.201708 -45.276614) (xy 136.181785 -45.224523)
			(xy 136.169659 -45.170086) (xy 136.165588 -45.114464) (xy 129.116836 -45.114464) (xy 129.116836 -46.082204)
			(xy 134.15264 -46.082204) (xy 134.153059 -46.054949) (xy 134.160817 -46.000994) (xy 134.176175 -45.948692)
			(xy 134.19882 -45.899109) (xy 134.228292 -45.853254) (xy 134.263991 -45.81206) (xy 134.305189 -45.776366)
			(xy 134.351048 -45.746899) (xy 134.400634 -45.724259) (xy 134.452937 -45.708908) (xy 134.506893 -45.701156)
			(xy 134.534148 -45.700696) (xy 134.561052 -45.701122) (xy 134.614323 -45.7087) (xy 134.666003 -45.723686)
			(xy 134.715064 -45.745782) (xy 134.760536 -45.77455) (xy 134.801517 -45.80942) (xy 134.837193 -45.8497)
			(xy 134.85241 -45.871892) (xy 134.859522 -45.882814) (xy 134.882382 -45.894752) (xy 134.99465 -45.89272)
			(xy 135.017002 -45.879766) (xy 135.02386 -45.86859) (xy 135.038754 -45.84497) (xy 135.074438 -45.802019)
			(xy 135.116001 -45.764727) (xy 135.162555 -45.733892) (xy 135.213107 -45.710171) (xy 135.266577 -45.694073)
			(xy 135.321822 -45.685939) (xy 135.349742 -45.685456) (xy 135.376736 -45.685893) (xy 135.430185 -45.693505)
			(xy 135.482029 -45.70857) (xy 135.531233 -45.73079) (xy 135.576816 -45.75972) (xy 135.597646 -45.776896)
			(xy 135.605774 -45.784008) (xy 135.626348 -45.790104) (xy 135.711692 -45.779182) (xy 135.722238 -45.777414)
			(xy 135.74052 -45.766355) (xy 135.746998 -45.757846) (xy 135.762359 -45.736621) (xy 135.797945 -45.698168)
			(xy 135.838461 -45.664949) (xy 135.883142 -45.63759) (xy 135.931149 -45.616605) (xy 135.981577 -45.602391)
			(xy 136.033476 -45.595214) (xy 136.059672 -45.594778) (xy 136.086925 -45.595267) (xy 136.140877 -45.603021)
			(xy 136.193176 -45.618374) (xy 136.242758 -45.641014) (xy 136.288613 -45.67048) (xy 136.329808 -45.706172)
			(xy 136.365503 -45.747364) (xy 136.394973 -45.793217) (xy 136.417616 -45.842797) (xy 136.432973 -45.895095)
			(xy 136.440731 -45.949047) (xy 136.440731 -46.003553) (xy 136.432973 -46.057505) (xy 136.417616 -46.109803)
			(xy 136.394973 -46.159383) (xy 136.365503 -46.205236) (xy 136.329808 -46.246428) (xy 136.288613 -46.28212)
			(xy 136.242758 -46.311586) (xy 136.193176 -46.334226) (xy 136.140877 -46.349579) (xy 136.086925 -46.357333)
			(xy 136.059672 -46.357794) (xy 136.032679 -46.357337) (xy 135.979231 -46.349728) (xy 135.927388 -46.334667)
			(xy 135.878183 -46.312452) (xy 135.832599 -46.283528) (xy 135.811768 -46.266354) (xy 135.80364 -46.259242)
			(xy 135.783066 -46.253146) (xy 135.697722 -46.264068) (xy 135.687182 -46.265861) (xy 135.668899 -46.276903)
			(xy 135.662416 -46.285404) (xy 135.644798 -46.3097) (xy 135.603206 -46.352962) (xy 135.579612 -46.37151)
			(xy 135.571738 -46.377352) (xy 135.561324 -46.394878) (xy 135.548116 -46.485302) (xy 135.552942 -46.504606)
			(xy 135.558784 -46.51248) (xy 135.558784 -46.512734) (xy 135.576288 -46.537477) (xy 135.60409 -46.591331)
			(xy 135.623026 -46.648903) (xy 135.630229 -46.693836) (xy 140.776452 -46.693836) (xy 140.776938 -46.666585)
			(xy 140.784694 -46.612637) (xy 140.800049 -46.560342) (xy 140.822691 -46.510765) (xy 140.852157 -46.464915)
			(xy 140.887848 -46.423724) (xy 140.929039 -46.388033) (xy 140.974889 -46.358567) (xy 141.024466 -46.335925)
			(xy 141.076761 -46.32057) (xy 141.130709 -46.312814) (xy 141.185211 -46.312814) (xy 141.239159 -46.32057)
			(xy 141.291454 -46.335925) (xy 141.341031 -46.358567) (xy 141.386881 -46.388033) (xy 141.428072 -46.423724)
			(xy 141.463763 -46.464915) (xy 141.493229 -46.510765) (xy 141.515871 -46.560342) (xy 141.531226 -46.612637)
			(xy 141.538982 -46.666585) (xy 141.539468 -46.693836) (xy 141.539 -46.720264) (xy 141.53169 -46.772611)
			(xy 141.517215 -46.823446) (xy 141.495853 -46.871793) (xy 141.482318 -46.894496) (xy 141.482064 -46.89475)
			(xy 141.476728 -46.904768) (xy 141.47447 -46.927318) (xy 141.477746 -46.938184) (xy 141.503908 -47.01286)
			(xy 141.508267 -47.023389) (xy 141.524373 -47.039472) (xy 141.534896 -47.043848) (xy 141.53515 -47.043848)
			(xy 141.55966 -47.052915) (xy 141.606112 -47.076858) (xy 141.648864 -47.106915) (xy 141.687116 -47.142522)
			(xy 141.720152 -47.183015) (xy 141.747356 -47.227637) (xy 141.768217 -47.275552) (xy 141.782347 -47.325865)
			(xy 141.789481 -47.377636) (xy 141.789912 -47.403766) (xy 141.789426 -47.431017) (xy 141.787903 -47.441612)
			(xy 143.061942 -47.441612) (xy 143.066013 -47.38599) (xy 143.078139 -47.331553) (xy 143.098062 -47.279462)
			(xy 143.125358 -47.230827) (xy 143.159444 -47.186684) (xy 143.199593 -47.147975) (xy 143.244951 -47.115524)
			(xy 143.294551 -47.090023) (xy 143.347335 -47.072016) (xy 143.402178 -47.061886) (xy 143.457912 -47.059849)
			(xy 143.513349 -47.065949) (xy 143.567306 -47.080055) (xy 143.618635 -47.101867) (xy 143.666241 -47.130921)
			(xy 143.709109 -47.166596) (xy 143.746326 -47.208133) (xy 143.777099 -47.254646) (xy 143.800771 -47.305143)
			(xy 143.816839 -47.35855) (xy 143.824959 -47.413726) (xy 143.825468 -47.441612) (xy 143.824959 -47.469498)
			(xy 143.816839 -47.524674) (xy 143.800771 -47.578081) (xy 143.777099 -47.628578) (xy 143.746326 -47.675091)
			(xy 143.709109 -47.716628) (xy 143.666241 -47.752303) (xy 143.618635 -47.781357) (xy 143.567306 -47.803169)
			(xy 143.513349 -47.817275) (xy 143.457912 -47.823375) (xy 143.402178 -47.821338) (xy 143.347335 -47.811208)
			(xy 143.294551 -47.793201) (xy 143.244951 -47.7677) (xy 143.199593 -47.735249) (xy 143.159444 -47.69654)
			(xy 143.125358 -47.652397) (xy 143.098062 -47.603762) (xy 143.078139 -47.551671) (xy 143.066013 -47.497234)
			(xy 143.061942 -47.441612) (xy 141.787903 -47.441612) (xy 141.78167 -47.484965) (xy 141.766315 -47.53726)
			(xy 141.743673 -47.586837) (xy 141.714207 -47.632687) (xy 141.678516 -47.673878) (xy 141.637325 -47.709569)
			(xy 141.591475 -47.739035) (xy 141.541898 -47.761677) (xy 141.489603 -47.777032) (xy 141.435655 -47.784788)
			(xy 141.381153 -47.784788) (xy 141.327205 -47.777032) (xy 141.27491 -47.761677) (xy 141.225333 -47.739035)
			(xy 141.179483 -47.709569) (xy 141.138292 -47.673878) (xy 141.102601 -47.632687) (xy 141.073135 -47.586837)
			(xy 141.050493 -47.53726) (xy 141.035138 -47.484965) (xy 141.027382 -47.431017) (xy 141.026896 -47.403766)
			(xy 141.02737 -47.377338) (xy 141.034679 -47.324991) (xy 141.049152 -47.274156) (xy 141.070511 -47.225809)
			(xy 141.084046 -47.203106) (xy 141.0843 -47.202852) (xy 141.089635 -47.192833) (xy 141.091896 -47.170283)
			(xy 141.088618 -47.159418) (xy 141.062456 -47.084742) (xy 141.058067 -47.074229) (xy 141.041982 -47.058139)
			(xy 141.031468 -47.053754) (xy 141.031214 -47.053754) (xy 141.006697 -47.044705) (xy 140.960246 -47.020758)
			(xy 140.917495 -46.990699) (xy 140.879245 -46.955088) (xy 140.846209 -46.914593) (xy 140.819007 -46.86997)
			(xy 140.798146 -46.822053) (xy 140.784017 -46.771738) (xy 140.776883 -46.719966) (xy 140.776452 -46.693836)
			(xy 135.630229 -46.693836) (xy 135.632619 -46.708745) (xy 135.633206 -46.739048) (xy 135.632767 -46.766301)
			(xy 135.625004 -46.82025) (xy 135.609642 -46.872546) (xy 135.586996 -46.922123) (xy 135.557524 -46.967974)
			(xy 135.521828 -47.009163) (xy 135.480633 -47.044854) (xy 135.434779 -47.07432) (xy 135.385199 -47.09696)
			(xy 135.332901 -47.112314) (xy 135.278951 -47.12007) (xy 135.251698 -47.120556) (xy 135.225665 -47.120102)
			(xy 135.174082 -47.113016) (xy 135.123941 -47.098988) (xy 135.07617 -47.078278) (xy 135.031655 -47.051271)
			(xy 135.01116 -47.035212) (xy 135.003392 -47.029487) (xy 134.98499 -47.023736) (xy 134.975346 -47.024036)
			(xy 134.89559 -47.030386) (xy 134.87781 -47.039022) (xy 134.87146 -47.046388) (xy 134.853272 -47.066027)
			(xy 134.812366 -47.10055) (xy 134.767038 -47.12902) (xy 134.718178 -47.150878) (xy 134.666744 -47.165697)
			(xy 134.613743 -47.173186) (xy 134.58698 -47.173642) (xy 134.55973 -47.173141) (xy 134.505784 -47.165383)
			(xy 134.453492 -47.150027) (xy 134.403917 -47.127386) (xy 134.358068 -47.09792) (xy 134.316879 -47.062231)
			(xy 134.281188 -47.021043) (xy 134.251721 -46.975195) (xy 134.229078 -46.925621) (xy 134.21372 -46.873329)
			(xy 134.20596 -46.819384) (xy 134.205472 -46.792134) (xy 134.206004 -46.76336) (xy 134.214654 -46.706467)
			(xy 134.231749 -46.651517) (xy 134.256901 -46.599757) (xy 134.289539 -46.55236) (xy 134.30885 -46.531022)
			(xy 134.316216 -46.523148) (xy 134.323328 -46.503336) (xy 134.315962 -46.40707) (xy 134.306056 -46.388274)
			(xy 134.297674 -46.38167) (xy 134.27548 -46.363457) (xy 134.236273 -46.321518) (xy 134.203789 -46.274179)
			(xy 134.178763 -46.222509) (xy 134.161758 -46.167674) (xy 134.153158 -46.11091) (xy 134.15264 -46.082204)
			(xy 129.116836 -46.082204) (xy 129.116836 -48.30699) (xy 140.654022 -48.30699) (xy 140.658093 -48.251368)
			(xy 140.670219 -48.196931) (xy 140.690142 -48.14484) (xy 140.717438 -48.096205) (xy 140.751524 -48.052062)
			(xy 140.791673 -48.013353) (xy 140.837031 -47.980902) (xy 140.886631 -47.955401) (xy 140.939415 -47.937394)
			(xy 140.994258 -47.927264) (xy 141.049992 -47.925227) (xy 141.105429 -47.931327) (xy 141.159386 -47.945433)
			(xy 141.210715 -47.967245) (xy 141.258321 -47.996299) (xy 141.301189 -48.031974) (xy 141.338406 -48.073511)
			(xy 141.369179 -48.120024) (xy 141.392851 -48.170521) (xy 141.408919 -48.223928) (xy 141.417039 -48.279104)
			(xy 141.417548 -48.30699) (xy 141.417039 -48.334876) (xy 141.408919 -48.390052) (xy 141.392851 -48.443459)
			(xy 141.369179 -48.493956) (xy 141.338406 -48.540469) (xy 141.301189 -48.582006) (xy 141.258321 -48.617681)
			(xy 141.210715 -48.646735) (xy 141.159386 -48.668547) (xy 141.105429 -48.682653) (xy 141.049992 -48.688753)
			(xy 140.994258 -48.686716) (xy 140.939415 -48.676586) (xy 140.886631 -48.658579) (xy 140.837031 -48.633078)
			(xy 140.791673 -48.600627) (xy 140.751524 -48.561918) (xy 140.717438 -48.517775) (xy 140.690142 -48.46914)
			(xy 140.670219 -48.417049) (xy 140.658093 -48.362612) (xy 140.654022 -48.30699) (xy 129.116836 -48.30699)
			(xy 129.116836 -48.753014) (xy 137.268456 -48.753014) (xy 137.272527 -48.697392) (xy 137.284653 -48.642955)
			(xy 137.304576 -48.590864) (xy 137.331872 -48.542229) (xy 137.365958 -48.498086) (xy 137.406107 -48.459377)
			(xy 137.451465 -48.426926) (xy 137.501065 -48.401425) (xy 137.553849 -48.383418) (xy 137.608692 -48.373288)
			(xy 137.664426 -48.371251) (xy 137.719863 -48.377351) (xy 137.77382 -48.391457) (xy 137.825149 -48.413269)
			(xy 137.872755 -48.442323) (xy 137.915623 -48.477998) (xy 137.95284 -48.519535) (xy 137.983613 -48.566048)
			(xy 138.007285 -48.616545) (xy 138.023353 -48.669952) (xy 138.031473 -48.725128) (xy 138.031982 -48.753014)
			(xy 138.031473 -48.7809) (xy 138.023353 -48.836076) (xy 138.007285 -48.889483) (xy 138.005889 -48.89246)
			(xy 139.314172 -48.89246) (xy 139.318243 -48.836838) (xy 139.330369 -48.782401) (xy 139.350292 -48.73031)
			(xy 139.377588 -48.681675) (xy 139.411674 -48.637532) (xy 139.451823 -48.598823) (xy 139.497181 -48.566372)
			(xy 139.546781 -48.540871) (xy 139.599565 -48.522864) (xy 139.654408 -48.512734) (xy 139.710142 -48.510697)
			(xy 139.765579 -48.516797) (xy 139.819536 -48.530903) (xy 139.870865 -48.552715) (xy 139.918471 -48.581769)
			(xy 139.961339 -48.617444) (xy 139.998556 -48.658981) (xy 140.029329 -48.705494) (xy 140.053001 -48.755991)
			(xy 140.069069 -48.809398) (xy 140.077189 -48.864574) (xy 140.077698 -48.89246) (xy 140.077189 -48.920346)
			(xy 140.074751 -48.93691) (xy 143.03324 -48.93691) (xy 143.037311 -48.881288) (xy 143.049437 -48.826851)
			(xy 143.06936 -48.77476) (xy 143.096656 -48.726125) (xy 143.130742 -48.681982) (xy 143.170891 -48.643273)
			(xy 143.216249 -48.610822) (xy 143.265849 -48.585321) (xy 143.318633 -48.567314) (xy 143.373476 -48.557184)
			(xy 143.42921 -48.555147) (xy 143.484647 -48.561247) (xy 143.538604 -48.575353) (xy 143.589933 -48.597165)
			(xy 143.637539 -48.626219) (xy 143.680407 -48.661894) (xy 143.717624 -48.703431) (xy 143.748397 -48.749944)
			(xy 143.772069 -48.800441) (xy 143.788137 -48.853848) (xy 143.796257 -48.909024) (xy 143.796766 -48.93691)
			(xy 143.796257 -48.964796) (xy 143.788137 -49.019972) (xy 143.772069 -49.073379) (xy 143.748397 -49.123876)
			(xy 143.717624 -49.170389) (xy 143.680407 -49.211926) (xy 143.637539 -49.247601) (xy 143.589933 -49.276655)
			(xy 143.538604 -49.298467) (xy 143.484647 -49.312573) (xy 143.42921 -49.318673) (xy 143.373476 -49.316636)
			(xy 143.318633 -49.306506) (xy 143.265849 -49.288499) (xy 143.216249 -49.262998) (xy 143.170891 -49.230547)
			(xy 143.130742 -49.191838) (xy 143.096656 -49.147695) (xy 143.06936 -49.09906) (xy 143.049437 -49.046969)
			(xy 143.037311 -48.992532) (xy 143.03324 -48.93691) (xy 140.074751 -48.93691) (xy 140.069069 -48.975522)
			(xy 140.053001 -49.028929) (xy 140.029329 -49.079426) (xy 139.998556 -49.125939) (xy 139.961339 -49.167476)
			(xy 139.918471 -49.203151) (xy 139.870865 -49.232205) (xy 139.819536 -49.254017) (xy 139.765579 -49.268123)
			(xy 139.710142 -49.274223) (xy 139.654408 -49.272186) (xy 139.599565 -49.262056) (xy 139.546781 -49.244049)
			(xy 139.497181 -49.218548) (xy 139.451823 -49.186097) (xy 139.411674 -49.147388) (xy 139.377588 -49.103245)
			(xy 139.350292 -49.05461) (xy 139.330369 -49.002519) (xy 139.318243 -48.948082) (xy 139.314172 -48.89246)
			(xy 138.005889 -48.89246) (xy 137.983613 -48.93998) (xy 137.95284 -48.986493) (xy 137.915623 -49.02803)
			(xy 137.872755 -49.063705) (xy 137.825149 -49.092759) (xy 137.77382 -49.114571) (xy 137.719863 -49.128677)
			(xy 137.664426 -49.134777) (xy 137.608692 -49.13274) (xy 137.553849 -49.12261) (xy 137.501065 -49.104603)
			(xy 137.451465 -49.079102) (xy 137.406107 -49.046651) (xy 137.365958 -49.007942) (xy 137.331872 -48.963799)
			(xy 137.304576 -48.915164) (xy 137.284653 -48.863073) (xy 137.272527 -48.808636) (xy 137.268456 -48.753014)
			(xy 129.116836 -48.753014) (xy 129.116836 -49.95291) (xy 143.03324 -49.95291) (xy 143.037311 -49.897288)
			(xy 143.049437 -49.842851) (xy 143.06936 -49.79076) (xy 143.096656 -49.742125) (xy 143.130742 -49.697982)
			(xy 143.170891 -49.659273) (xy 143.216249 -49.626822) (xy 143.265849 -49.601321) (xy 143.318633 -49.583314)
			(xy 143.373476 -49.573184) (xy 143.42921 -49.571147) (xy 143.484647 -49.577247) (xy 143.538604 -49.591353)
			(xy 143.563539 -49.601949) (xy 148.213082 -49.601949) (xy 148.213082 -49.547451) (xy 148.220837 -49.493507)
			(xy 148.23619 -49.441215) (xy 148.258829 -49.391641) (xy 148.288291 -49.345793) (xy 148.323978 -49.304604)
			(xy 148.365164 -49.268913) (xy 148.411009 -49.239446) (xy 148.460582 -49.216803) (xy 148.512871 -49.201445)
			(xy 148.566815 -49.193684) (xy 148.594064 -49.193196) (xy 148.621433 -49.193684) (xy 148.675612 -49.201497)
			(xy 148.728114 -49.216981) (xy 148.777862 -49.239818) (xy 148.823829 -49.269537) (xy 148.844762 -49.287176)
			(xy 148.845016 -49.28743) (xy 148.852091 -49.293033) (xy 148.869017 -49.299269) (xy 148.878036 -49.299622)
			(xy 148.945092 -49.299622) (xy 148.954108 -49.299256) (xy 148.971025 -49.293014) (xy 148.978112 -49.28743)
			(xy 148.978112 -49.287176) (xy 148.978366 -49.287176) (xy 148.999299 -49.269535) (xy 149.045267 -49.239811)
			(xy 149.095013 -49.216965) (xy 149.147515 -49.201469) (xy 149.201693 -49.19364) (xy 149.256435 -49.19364)
			(xy 149.310613 -49.201469) (xy 149.363115 -49.216965) (xy 149.412861 -49.239811) (xy 149.458829 -49.269535)
			(xy 149.479762 -49.287176) (xy 149.480016 -49.28743) (xy 149.487091 -49.293033) (xy 149.504017 -49.299269)
			(xy 149.513036 -49.299622) (xy 149.580092 -49.299622) (xy 149.589108 -49.299256) (xy 149.606025 -49.293014)
			(xy 149.613112 -49.28743) (xy 149.613112 -49.287176) (xy 149.613366 -49.287176) (xy 149.634299 -49.269535)
			(xy 149.680267 -49.239811) (xy 149.730013 -49.216965) (xy 149.782515 -49.201469) (xy 149.836693 -49.19364)
			(xy 149.891435 -49.19364) (xy 149.945613 -49.201469) (xy 149.998115 -49.216965) (xy 150.047861 -49.239811)
			(xy 150.093829 -49.269535) (xy 150.114762 -49.287176) (xy 150.115016 -49.28743) (xy 150.122091 -49.293033)
			(xy 150.139017 -49.299269) (xy 150.148036 -49.299622) (xy 150.215092 -49.299622) (xy 150.224108 -49.299256)
			(xy 150.241025 -49.293014) (xy 150.248112 -49.28743) (xy 150.248112 -49.287176) (xy 150.248366 -49.287176)
			(xy 150.269297 -49.269536) (xy 150.31527 -49.239825) (xy 150.365018 -49.21699) (xy 150.417519 -49.201499)
			(xy 150.471695 -49.19367) (xy 150.499064 -49.193196) (xy 150.526319 -49.193649) (xy 150.580274 -49.201402)
			(xy 150.632577 -49.216755) (xy 150.682162 -49.239396) (xy 150.72802 -49.268863) (xy 150.769218 -49.304557)
			(xy 150.804916 -49.345751) (xy 150.834387 -49.391606) (xy 150.857033 -49.441189) (xy 150.872391 -49.493491)
			(xy 150.880149 -49.547445) (xy 150.880149 -49.601955) (xy 150.872391 -49.655909) (xy 150.857033 -49.708211)
			(xy 150.834387 -49.757794) (xy 150.804916 -49.803649) (xy 150.769218 -49.844843) (xy 150.72802 -49.880537)
			(xy 150.682162 -49.910004) (xy 150.632577 -49.932645) (xy 150.580274 -49.947998) (xy 150.526319 -49.955751)
			(xy 150.499064 -49.956212) (xy 150.471693 -49.955764) (xy 150.417513 -49.947941) (xy 150.36501 -49.932448)
			(xy 150.315264 -49.909602) (xy 150.269297 -49.879875) (xy 150.248366 -49.862232) (xy 150.248112 -49.861978)
			(xy 150.241028 -49.856388) (xy 150.224109 -49.850144) (xy 150.215092 -49.849786) (xy 150.148036 -49.849786)
			(xy 150.139021 -49.850163) (xy 150.122104 -49.856397) (xy 150.115016 -49.861978) (xy 150.114762 -49.862232)
			(xy 150.093829 -49.879873) (xy 150.047861 -49.909597) (xy 149.998115 -49.932443) (xy 149.945613 -49.947939)
			(xy 149.891435 -49.955768) (xy 149.836693 -49.955768) (xy 149.782515 -49.947939) (xy 149.730013 -49.932443)
			(xy 149.680267 -49.909597) (xy 149.634299 -49.879873) (xy 149.613366 -49.862232) (xy 149.613112 -49.861978)
			(xy 149.606028 -49.856388) (xy 149.589109 -49.850144) (xy 149.580092 -49.849786) (xy 149.513036 -49.849786)
			(xy 149.504021 -49.850163) (xy 149.487104 -49.856397) (xy 149.480016 -49.861978) (xy 149.480016 -49.862232)
			(xy 149.479762 -49.862232) (xy 149.458829 -49.879873) (xy 149.412861 -49.909597) (xy 149.363115 -49.932443)
			(xy 149.310613 -49.947939) (xy 149.256435 -49.955768) (xy 149.201693 -49.955768) (xy 149.147515 -49.947939)
			(xy 149.095013 -49.932443) (xy 149.045267 -49.909597) (xy 148.999299 -49.879873) (xy 148.978366 -49.862232)
			(xy 148.978112 -49.861978) (xy 148.971028 -49.856388) (xy 148.954109 -49.850144) (xy 148.945092 -49.849786)
			(xy 148.878036 -49.849786) (xy 148.869021 -49.850163) (xy 148.852104 -49.856397) (xy 148.845016 -49.861978)
			(xy 148.845016 -49.862232) (xy 148.844762 -49.862232) (xy 148.823821 -49.87986) (xy 148.77785 -49.909573)
			(xy 148.728105 -49.93241) (xy 148.675606 -49.947904) (xy 148.621433 -49.955736) (xy 148.594064 -49.956212)
			(xy 148.566815 -49.955716) (xy 148.512871 -49.947955) (xy 148.460582 -49.932597) (xy 148.411009 -49.909954)
			(xy 148.365164 -49.880487) (xy 148.323978 -49.844796) (xy 148.288291 -49.803607) (xy 148.258829 -49.757759)
			(xy 148.23619 -49.708185) (xy 148.220837 -49.655893) (xy 148.213082 -49.601949) (xy 143.563539 -49.601949)
			(xy 143.589933 -49.613165) (xy 143.637539 -49.642219) (xy 143.680407 -49.677894) (xy 143.717624 -49.719431)
			(xy 143.748397 -49.765944) (xy 143.772069 -49.816441) (xy 143.788137 -49.869848) (xy 143.796257 -49.925024)
			(xy 143.796766 -49.95291) (xy 143.796257 -49.980796) (xy 143.788137 -50.035972) (xy 143.772069 -50.089379)
			(xy 143.748397 -50.139876) (xy 143.717624 -50.186389) (xy 143.680407 -50.227926) (xy 143.637539 -50.263601)
			(xy 143.589933 -50.292655) (xy 143.538604 -50.314467) (xy 143.484647 -50.328573) (xy 143.42921 -50.334673)
			(xy 143.373476 -50.332636) (xy 143.318633 -50.322506) (xy 143.265849 -50.304499) (xy 143.216249 -50.278998)
			(xy 143.170891 -50.246547) (xy 143.130742 -50.207838) (xy 143.096656 -50.163695) (xy 143.06936 -50.11506)
			(xy 143.049437 -50.062969) (xy 143.037311 -50.008532) (xy 143.03324 -49.95291) (xy 129.116836 -49.95291)
			(xy 129.116836 -51.019456) (xy 140.849602 -51.019456) (xy 140.853673 -50.963834) (xy 140.865799 -50.909397)
			(xy 140.885722 -50.857306) (xy 140.913018 -50.808671) (xy 140.947104 -50.764528) (xy 140.987253 -50.725819)
			(xy 141.032611 -50.693368) (xy 141.082211 -50.667867) (xy 141.134995 -50.64986) (xy 141.189838 -50.63973)
			(xy 141.245572 -50.637693) (xy 141.301009 -50.643793) (xy 141.354966 -50.657899) (xy 141.406295 -50.679711)
			(xy 141.453901 -50.708765) (xy 141.496769 -50.74444) (xy 141.533986 -50.785977) (xy 141.564759 -50.83249)
			(xy 141.588431 -50.882987) (xy 141.604499 -50.936394) (xy 141.612619 -50.99157) (xy 141.613128 -51.019456)
			(xy 141.612619 -51.047342) (xy 141.604499 -51.102518) (xy 141.588431 -51.155925) (xy 141.564759 -51.206422)
			(xy 141.539903 -51.243992) (xy 149.233128 -51.243992) (xy 149.233583 -51.216621) (xy 149.241402 -51.162441)
			(xy 149.256894 -51.109938) (xy 149.279738 -51.060191) (xy 149.309465 -51.014225) (xy 149.327108 -50.993294)
			(xy 149.327362 -50.99304) (xy 149.332945 -50.985951) (xy 149.339192 -50.969036) (xy 149.339554 -50.96002)
			(xy 149.339554 -50.892964) (xy 149.339224 -50.883944) (xy 149.332959 -50.867027) (xy 149.327362 -50.859944)
			(xy 149.327108 -50.859944) (xy 149.327108 -50.85969) (xy 149.309452 -50.838772) (xy 149.279742 -50.792795)
			(xy 149.25691 -50.743044) (xy 149.241423 -50.69054) (xy 149.233599 -50.636362) (xy 149.233128 -50.608992)
			(xy 149.233548 -50.581737) (xy 149.241307 -50.527783) (xy 149.256666 -50.475482) (xy 149.279312 -50.4259)
			(xy 149.308784 -50.380045) (xy 149.344482 -50.338851) (xy 149.38568 -50.303158) (xy 149.431538 -50.273691)
			(xy 149.481123 -50.25105) (xy 149.533426 -50.235698) (xy 149.587381 -50.227945) (xy 149.614636 -50.227484)
			(xy 149.643553 -50.228017) (xy 149.700725 -50.236738) (xy 149.755925 -50.253991) (xy 149.807887 -50.27938)
			(xy 149.855421 -50.312323) (xy 149.897437 -50.352064) (xy 149.915626 -50.37455) (xy 149.923223 -50.383368)
			(xy 149.944132 -50.393544) (xy 149.955758 -50.394108) (xy 150.035514 -50.394108) (xy 150.047145 -50.39356)
			(xy 150.068054 -50.383377) (xy 150.075646 -50.37455) (xy 150.093855 -50.352082) (xy 150.135872 -50.312348)
			(xy 150.183404 -50.279409) (xy 150.235362 -50.254018) (xy 150.290555 -50.236758) (xy 150.347721 -50.228023)
			(xy 150.376636 -50.227484) (xy 150.403888 -50.227944) (xy 150.457836 -50.235706) (xy 150.510131 -50.251065)
			(xy 150.559708 -50.27371) (xy 150.605557 -50.303179) (xy 150.646747 -50.338873) (xy 150.682438 -50.380065)
			(xy 150.711904 -50.425917) (xy 150.734545 -50.475496) (xy 150.7499 -50.527791) (xy 150.757658 -50.58174)
			(xy 150.758144 -50.608992) (xy 150.757689 -50.635307) (xy 150.750454 -50.687436) (xy 150.736134 -50.73808)
			(xy 150.714999 -50.786279) (xy 150.68745 -50.831122) (xy 150.654008 -50.871761) (xy 150.634954 -50.889916)
			(xy 150.627551 -50.897437) (xy 150.619026 -50.916717) (xy 150.618444 -50.927254) (xy 150.618444 -51.00193)
			(xy 150.618984 -51.012479) (xy 150.62751 -51.031775) (xy 150.634954 -51.039268) (xy 150.654046 -51.057387)
			(xy 150.687498 -51.098026) (xy 150.715051 -51.142874) (xy 150.736182 -51.191082) (xy 150.750492 -51.241735)
			(xy 150.757709 -51.293874) (xy 150.758144 -51.320192) (xy 150.757615 -51.347441) (xy 150.74986 -51.401386)
			(xy 150.734508 -51.453677) (xy 150.711871 -51.503252) (xy 150.682408 -51.549101) (xy 150.646722 -51.59029)
			(xy 150.605536 -51.625982) (xy 150.559691 -51.655449) (xy 150.510119 -51.678093) (xy 150.457829 -51.693451)
			(xy 150.403885 -51.701212) (xy 150.376636 -51.7017) (xy 150.348972 -51.70116) (xy 150.294224 -51.693165)
			(xy 150.241203 -51.677354) (xy 150.191019 -51.654055) (xy 150.144723 -51.623758) (xy 150.103284 -51.587097)
			(xy 150.06757 -51.544839) (xy 150.052532 -51.521614) (xy 150.04589 -51.511942) (xy 150.026032 -51.499497)
			(xy 150.014432 -51.497738) (xy 149.934422 -51.489864) (xy 149.922784 -51.489249) (xy 149.900947 -51.497317)
			(xy 149.892512 -51.505358) (xy 149.892258 -51.505612) (xy 149.874182 -51.524198) (xy 149.833849 -51.556776)
			(xy 149.789473 -51.583588) (xy 149.741874 -51.604139) (xy 149.691929 -51.618052) (xy 149.640559 -51.625069)
			(xy 149.614636 -51.6255) (xy 149.587384 -51.625011) (xy 149.533433 -51.617259) (xy 149.481135 -51.601907)
			(xy 149.431555 -51.579268) (xy 149.385701 -51.549803) (xy 149.344508 -51.514112) (xy 149.308814 -51.472921)
			(xy 149.279345 -51.42707) (xy 149.256703 -51.377491) (xy 149.241347 -51.325194) (xy 149.233591 -51.271244)
			(xy 149.233128 -51.243992) (xy 141.539903 -51.243992) (xy 141.533986 -51.252935) (xy 141.496769 -51.294472)
			(xy 141.453901 -51.330147) (xy 141.406295 -51.359201) (xy 141.354966 -51.381013) (xy 141.301009 -51.395119)
			(xy 141.245572 -51.401219) (xy 141.189838 -51.399182) (xy 141.134995 -51.389052) (xy 141.082211 -51.371045)
			(xy 141.032611 -51.345544) (xy 140.987253 -51.313093) (xy 140.947104 -51.274384) (xy 140.913018 -51.230241)
			(xy 140.885722 -51.181606) (xy 140.865799 -51.129515) (xy 140.853673 -51.075078) (xy 140.849602 -51.019456)
			(xy 129.116836 -51.019456) (xy 129.116836 -52.035456) (xy 143.041368 -52.035456) (xy 143.045439 -51.979834)
			(xy 143.057565 -51.925397) (xy 143.077488 -51.873306) (xy 143.104784 -51.824671) (xy 143.13887 -51.780528)
			(xy 143.179019 -51.741819) (xy 143.224377 -51.709368) (xy 143.273977 -51.683867) (xy 143.326761 -51.66586)
			(xy 143.381604 -51.65573) (xy 143.437338 -51.653693) (xy 143.492775 -51.659793) (xy 143.546732 -51.673899)
			(xy 143.598061 -51.695711) (xy 143.645667 -51.724765) (xy 143.688535 -51.76044) (xy 143.725752 -51.801977)
			(xy 143.756525 -51.84849) (xy 143.780197 -51.898987) (xy 143.796265 -51.952394) (xy 143.804385 -52.00757)
			(xy 143.804894 -52.035456) (xy 143.804385 -52.063342) (xy 143.796265 -52.118518) (xy 143.780197 -52.171925)
			(xy 143.756525 -52.222422) (xy 143.725752 -52.268935) (xy 143.688535 -52.310472) (xy 143.645667 -52.346147)
			(xy 143.598061 -52.375201) (xy 143.546732 -52.397013) (xy 143.492775 -52.411119) (xy 143.437338 -52.417219)
			(xy 143.381604 -52.415182) (xy 143.326761 -52.405052) (xy 143.273977 -52.387045) (xy 143.224377 -52.361544)
			(xy 143.179019 -52.329093) (xy 143.13887 -52.290384) (xy 143.104784 -52.246241) (xy 143.077488 -52.197606)
			(xy 143.057565 -52.145515) (xy 143.045439 -52.091078) (xy 143.041368 -52.035456) (xy 129.116836 -52.035456)
			(xy 129.116836 -54.731412) (xy 129.620772 -54.731412) (xy 129.621228 -54.704041) (xy 129.629045 -54.649861)
			(xy 129.644536 -54.597357) (xy 129.66738 -54.54761) (xy 129.697109 -54.501645) (xy 129.714752 -54.480714)
			(xy 129.715006 -54.48046) (xy 129.720574 -54.473361) (xy 129.726832 -54.456454) (xy 129.727198 -54.44744)
			(xy 129.727198 -54.380384) (xy 129.726849 -54.371366) (xy 129.720596 -54.354449) (xy 129.715006 -54.347364)
			(xy 129.714752 -54.347364) (xy 129.714752 -54.34711) (xy 129.697122 -54.326168) (xy 129.667395 -54.280203)
			(xy 129.644547 -54.230458) (xy 129.629049 -54.177957) (xy 129.621219 -54.123779) (xy 129.621217 -54.069039)
			(xy 129.629045 -54.014861) (xy 129.644541 -53.962359) (xy 129.667386 -53.912613) (xy 129.697111 -53.866646)
			(xy 129.714752 -53.845714) (xy 129.715006 -53.84546) (xy 129.720574 -53.838361) (xy 129.726832 -53.821454)
			(xy 129.727198 -53.81244) (xy 129.727198 -53.745384) (xy 129.726849 -53.736366) (xy 129.720596 -53.719449)
			(xy 129.715006 -53.712364) (xy 129.714752 -53.712364) (xy 129.714752 -53.71211) (xy 129.697122 -53.691168)
			(xy 129.667395 -53.645203) (xy 129.644547 -53.595458) (xy 129.629049 -53.542957) (xy 129.621219 -53.488779)
			(xy 129.621217 -53.434039) (xy 129.629045 -53.379861) (xy 129.644541 -53.327359) (xy 129.667386 -53.277613)
			(xy 129.697111 -53.231646) (xy 129.714752 -53.210714) (xy 129.715006 -53.21046) (xy 129.720574 -53.203361)
			(xy 129.726832 -53.186454) (xy 129.727198 -53.17744) (xy 129.727198 -53.110384) (xy 129.726849 -53.101366)
			(xy 129.720596 -53.084449) (xy 129.715006 -53.077364) (xy 129.714752 -53.077364) (xy 129.714752 -53.07711)
			(xy 129.697112 -53.056178) (xy 129.667399 -53.010206) (xy 129.644562 -52.960459) (xy 129.629071 -52.907958)
			(xy 129.621245 -52.853781) (xy 129.620772 -52.826412) (xy 129.621258 -52.799161) (xy 129.629014 -52.745213)
			(xy 129.644369 -52.692918) (xy 129.667011 -52.643341) (xy 129.696477 -52.597491) (xy 129.732168 -52.5563)
			(xy 129.773359 -52.520609) (xy 129.819209 -52.491143) (xy 129.868786 -52.468501) (xy 129.921081 -52.453146)
			(xy 129.975029 -52.44539) (xy 130.029531 -52.44539) (xy 130.083479 -52.453146) (xy 130.135774 -52.468501)
			(xy 130.185351 -52.491143) (xy 130.231201 -52.520609) (xy 130.272392 -52.5563) (xy 130.308083 -52.597491)
			(xy 130.337549 -52.643341) (xy 130.360191 -52.692918) (xy 130.375546 -52.745213) (xy 130.383302 -52.799161)
			(xy 130.383788 -52.826412) (xy 130.383332 -52.853783) (xy 130.375512 -52.907962) (xy 130.360021 -52.960466)
			(xy 130.337177 -53.010212) (xy 130.30745 -53.056179) (xy 130.289808 -53.07711) (xy 130.289554 -53.077364)
			(xy 130.283971 -53.084453) (xy 130.277723 -53.101368) (xy 130.277362 -53.110384) (xy 130.277362 -53.17744)
			(xy 130.277708 -53.186458) (xy 130.283964 -53.203374) (xy 130.289554 -53.21046) (xy 130.289808 -53.21046)
			(xy 130.289808 -53.210714) (xy 130.307459 -53.231638) (xy 130.337181 -53.277608) (xy 130.360023 -53.327356)
			(xy 130.375517 -53.379859) (xy 130.383344 -53.434038) (xy 130.383342 -53.48878) (xy 130.375513 -53.542959)
			(xy 130.360017 -53.595461) (xy 130.337172 -53.645208) (xy 130.307448 -53.691177) (xy 130.289808 -53.71211)
			(xy 130.289554 -53.712364) (xy 130.283971 -53.719453) (xy 130.277723 -53.736368) (xy 130.277362 -53.745384)
			(xy 130.277362 -53.81244) (xy 130.277708 -53.821458) (xy 130.283964 -53.838374) (xy 130.289554 -53.84546)
			(xy 130.289808 -53.84546) (xy 130.289808 -53.845714) (xy 130.307459 -53.866638) (xy 130.337181 -53.912608)
			(xy 130.360023 -53.962356) (xy 130.375517 -54.014859) (xy 130.383344 -54.069038) (xy 130.383342 -54.12378)
			(xy 130.375513 -54.177959) (xy 130.360017 -54.230461) (xy 130.337172 -54.280208) (xy 130.307448 -54.326177)
			(xy 130.289808 -54.34711) (xy 130.289554 -54.347364) (xy 130.283971 -54.354453) (xy 130.277723 -54.371368)
			(xy 130.277362 -54.380384) (xy 130.277362 -54.44744) (xy 130.277708 -54.456458) (xy 130.283964 -54.473374)
			(xy 130.289554 -54.48046) (xy 130.289808 -54.48046) (xy 130.289808 -54.480714) (xy 130.307421 -54.501667)
			(xy 130.337137 -54.547634) (xy 130.359978 -54.597376) (xy 130.375475 -54.649872) (xy 130.38331 -54.704044)
			(xy 130.383788 -54.731412) (xy 130.383302 -54.758663) (xy 130.378638 -54.791102) (xy 132.276596 -54.791102)
			(xy 132.277064 -54.763732) (xy 132.284882 -54.709553) (xy 132.30037 -54.65705) (xy 132.323212 -54.607303)
			(xy 132.352935 -54.561336) (xy 132.370576 -54.540404) (xy 132.37083 -54.54015) (xy 132.376405 -54.533056)
			(xy 132.382658 -54.516145) (xy 132.383022 -54.50713) (xy 132.383022 -54.440074) (xy 132.382673 -54.431056)
			(xy 132.376419 -54.41414) (xy 132.37083 -54.407054) (xy 132.370576 -54.407054) (xy 132.370576 -54.4068)
			(xy 132.352935 -54.385867) (xy 132.323207 -54.3399) (xy 132.300358 -54.290154) (xy 132.28486 -54.237652)
			(xy 132.27703 -54.183473) (xy 132.27703 -54.12873) (xy 132.284859 -54.074551) (xy 132.300357 -54.022049)
			(xy 132.323205 -53.972302) (xy 132.352933 -53.926336) (xy 132.370576 -53.905404) (xy 132.37083 -53.90515)
			(xy 132.376405 -53.898056) (xy 132.382658 -53.881145) (xy 132.383022 -53.87213) (xy 132.383022 -53.805074)
			(xy 132.382673 -53.796056) (xy 132.376419 -53.77914) (xy 132.37083 -53.772054) (xy 132.370576 -53.772054)
			(xy 132.370576 -53.7718) (xy 132.352935 -53.750867) (xy 132.323207 -53.7049) (xy 132.300358 -53.655154)
			(xy 132.28486 -53.602652) (xy 132.27703 -53.548473) (xy 132.27703 -53.49373) (xy 132.284859 -53.439551)
			(xy 132.300357 -53.387049) (xy 132.323205 -53.337302) (xy 132.352933 -53.291336) (xy 132.370576 -53.270404)
			(xy 132.37083 -53.27015) (xy 132.376405 -53.263056) (xy 132.382658 -53.246145) (xy 132.383022 -53.23713)
			(xy 132.383022 -53.170074) (xy 132.382673 -53.161056) (xy 132.376419 -53.14414) (xy 132.37083 -53.137054)
			(xy 132.370576 -53.137054) (xy 132.370576 -53.1368) (xy 132.35292 -53.115882) (xy 132.323211 -53.069905)
			(xy 132.300379 -53.020154) (xy 132.284892 -52.96765) (xy 132.277068 -52.913472) (xy 132.276596 -52.886102)
			(xy 132.277082 -52.858851) (xy 132.284838 -52.804903) (xy 132.300193 -52.752608) (xy 132.322835 -52.703031)
			(xy 132.352301 -52.657181) (xy 132.387992 -52.61599) (xy 132.429183 -52.580299) (xy 132.475033 -52.550833)
			(xy 132.52461 -52.528191) (xy 132.576905 -52.512836) (xy 132.630853 -52.50508) (xy 132.685355 -52.50508)
			(xy 132.739303 -52.512836) (xy 132.791598 -52.528191) (xy 132.830698 -52.546048) (xy 137.779796 -52.546048)
			(xy 137.779796 -52.491552) (xy 137.787551 -52.43761) (xy 137.802904 -52.385321) (xy 137.825541 -52.335749)
			(xy 137.855002 -52.289903) (xy 137.890687 -52.248716) (xy 137.931871 -52.213026) (xy 137.977714 -52.18356)
			(xy 138.027284 -52.160918) (xy 138.079571 -52.14556) (xy 138.133512 -52.137799) (xy 138.16076 -52.13731)
			(xy 138.18813 -52.137797) (xy 138.242308 -52.145609) (xy 138.294811 -52.161093) (xy 138.344558 -52.183931)
			(xy 138.390526 -52.213651) (xy 138.411458 -52.23129) (xy 138.411712 -52.231544) (xy 138.418787 -52.237147)
			(xy 138.435713 -52.243383) (xy 138.444732 -52.243736) (xy 138.511788 -52.243736) (xy 138.520803 -52.243365)
			(xy 138.53772 -52.237126) (xy 138.544808 -52.231544) (xy 138.544808 -52.23129) (xy 138.545062 -52.23129)
			(xy 138.565995 -52.213649) (xy 138.611963 -52.183925) (xy 138.661709 -52.161079) (xy 138.714211 -52.145583)
			(xy 138.768389 -52.137754) (xy 138.823131 -52.137754) (xy 138.877309 -52.145583) (xy 138.929811 -52.161079)
			(xy 138.979557 -52.183925) (xy 139.025525 -52.213649) (xy 139.046458 -52.23129) (xy 139.046712 -52.231544)
			(xy 139.053787 -52.237147) (xy 139.070713 -52.243383) (xy 139.079732 -52.243736) (xy 139.146788 -52.243736)
			(xy 139.155803 -52.243365) (xy 139.17272 -52.237126) (xy 139.179808 -52.231544) (xy 139.179808 -52.23129)
			(xy 139.180062 -52.23129) (xy 139.200996 -52.213654) (xy 139.246969 -52.183942) (xy 139.296716 -52.161105)
			(xy 139.349216 -52.145614) (xy 139.403391 -52.137785) (xy 139.43076 -52.13731) (xy 139.458016 -52.137734)
			(xy 139.511974 -52.145487) (xy 139.564279 -52.16084) (xy 139.613867 -52.183482) (xy 139.659727 -52.21295)
			(xy 139.700926 -52.248645) (xy 139.736626 -52.289841) (xy 139.766099 -52.335698) (xy 139.788746 -52.385283)
			(xy 139.804105 -52.437587) (xy 139.811863 -52.491544) (xy 139.811863 -52.546056) (xy 139.805919 -52.587398)
			(xy 140.855444 -52.587398) (xy 140.859515 -52.531776) (xy 140.871641 -52.477339) (xy 140.891564 -52.425248)
			(xy 140.91886 -52.376613) (xy 140.952946 -52.33247) (xy 140.993095 -52.293761) (xy 141.038453 -52.26131)
			(xy 141.088053 -52.235809) (xy 141.140837 -52.217802) (xy 141.19568 -52.207672) (xy 141.251414 -52.205635)
			(xy 141.306851 -52.211735) (xy 141.360808 -52.225841) (xy 141.412137 -52.247653) (xy 141.459743 -52.276707)
			(xy 141.502611 -52.312382) (xy 141.539828 -52.353919) (xy 141.570601 -52.400432) (xy 141.594273 -52.450929)
			(xy 141.610341 -52.504336) (xy 141.617937 -52.555949) (xy 148.684002 -52.555949) (xy 148.684002 -52.501451)
			(xy 148.691758 -52.447509) (xy 148.707111 -52.395219) (xy 148.729749 -52.345646) (xy 148.759212 -52.2998)
			(xy 148.794899 -52.258613) (xy 148.836084 -52.222924) (xy 148.881929 -52.193459) (xy 148.9315 -52.170818)
			(xy 148.983789 -52.155462) (xy 149.037731 -52.147704) (xy 149.06498 -52.147216) (xy 149.09235 -52.14769)
			(xy 149.146529 -52.155505) (xy 149.199032 -52.170992) (xy 149.248779 -52.193832) (xy 149.294746 -52.223555)
			(xy 149.315678 -52.241196) (xy 149.315932 -52.24145) (xy 149.32303 -52.24702) (xy 149.339938 -52.253276)
			(xy 149.348952 -52.253642) (xy 149.416008 -52.253642) (xy 149.425027 -52.253301) (xy 149.441944 -52.247044)
			(xy 149.449028 -52.24145) (xy 149.449028 -52.241196) (xy 149.449282 -52.241196) (xy 149.47021 -52.223551)
			(xy 149.516184 -52.19384) (xy 149.565932 -52.171006) (xy 149.618434 -52.155516) (xy 149.672611 -52.147689)
			(xy 149.69998 -52.147216) (xy 149.727236 -52.14763) (xy 149.781192 -52.155385) (xy 149.833496 -52.17074)
			(xy 149.883081 -52.193383) (xy 149.92894 -52.222852) (xy 149.970138 -52.258548) (xy 150.005836 -52.299744)
			(xy 150.035308 -52.345601) (xy 150.057953 -52.395186) (xy 150.073311 -52.447488) (xy 150.081069 -52.501444)
			(xy 150.081069 -52.555956) (xy 150.073311 -52.609912) (xy 150.057953 -52.662214) (xy 150.035308 -52.711799)
			(xy 150.005836 -52.757656) (xy 149.970138 -52.798852) (xy 149.92894 -52.834548) (xy 149.883081 -52.864017)
			(xy 149.833496 -52.88666) (xy 149.781192 -52.902015) (xy 149.727236 -52.90977) (xy 149.69998 -52.910232)
			(xy 149.672609 -52.909794) (xy 149.618428 -52.901972) (xy 149.565924 -52.886477) (xy 149.516177 -52.863629)
			(xy 149.470212 -52.833897) (xy 149.449282 -52.816252) (xy 149.449028 -52.815998) (xy 149.441938 -52.810417)
			(xy 149.425024 -52.804167) (xy 149.416008 -52.803806) (xy 149.348952 -52.803806) (xy 149.339938 -52.804187)
			(xy 149.32302 -52.810418) (xy 149.315932 -52.815998) (xy 149.315932 -52.816252) (xy 149.315678 -52.816252)
			(xy 149.294721 -52.833861) (xy 149.248756 -52.863579) (xy 149.199015 -52.886421) (xy 149.146519 -52.901919)
			(xy 149.092348 -52.909754) (xy 149.06498 -52.910232) (xy 149.037731 -52.909696) (xy 148.983789 -52.901938)
			(xy 148.9315 -52.886582) (xy 148.881929 -52.863941) (xy 148.836084 -52.834476) (xy 148.794899 -52.798787)
			(xy 148.759212 -52.7576) (xy 148.729749 -52.711754) (xy 148.707111 -52.662181) (xy 148.691758 -52.609891)
			(xy 148.684002 -52.555949) (xy 141.617937 -52.555949) (xy 141.618461 -52.559512) (xy 141.61897 -52.587398)
			(xy 141.618461 -52.615284) (xy 141.610341 -52.67046) (xy 141.594273 -52.723867) (xy 141.570601 -52.774364)
			(xy 141.539828 -52.820877) (xy 141.502611 -52.862414) (xy 141.459743 -52.898089) (xy 141.412137 -52.927143)
			(xy 141.360808 -52.948955) (xy 141.306851 -52.963061) (xy 141.251414 -52.969161) (xy 141.19568 -52.967124)
			(xy 141.140837 -52.956994) (xy 141.088053 -52.938987) (xy 141.038453 -52.913486) (xy 140.993095 -52.881035)
			(xy 140.952946 -52.842326) (xy 140.91886 -52.798183) (xy 140.891564 -52.749548) (xy 140.871641 -52.697457)
			(xy 140.859515 -52.64302) (xy 140.855444 -52.587398) (xy 139.805919 -52.587398) (xy 139.804105 -52.600013)
			(xy 139.788746 -52.652317) (xy 139.766099 -52.701902) (xy 139.736626 -52.747759) (xy 139.700926 -52.788955)
			(xy 139.659727 -52.82465) (xy 139.613867 -52.854118) (xy 139.564279 -52.87676) (xy 139.511974 -52.892113)
			(xy 139.458016 -52.899866) (xy 139.43076 -52.900326) (xy 139.40339 -52.899843) (xy 139.349211 -52.892032)
			(xy 139.296707 -52.876548) (xy 139.24696 -52.853709) (xy 139.200993 -52.823987) (xy 139.180062 -52.806346)
			(xy 139.179808 -52.806092) (xy 139.172724 -52.800502) (xy 139.155805 -52.794258) (xy 139.146788 -52.7939)
			(xy 139.079732 -52.7939) (xy 139.070717 -52.794272) (xy 139.0538 -52.800509) (xy 139.046712 -52.806092)
			(xy 139.046458 -52.806346) (xy 139.025525 -52.823987) (xy 138.979557 -52.853711) (xy 138.929811 -52.876557)
			(xy 138.877309 -52.892053) (xy 138.823131 -52.899882) (xy 138.768389 -52.899882) (xy 138.714211 -52.892053)
			(xy 138.661709 -52.876557) (xy 138.611963 -52.853711) (xy 138.565995 -52.823987) (xy 138.545062 -52.806346)
			(xy 138.544808 -52.806092) (xy 138.537724 -52.800502) (xy 138.520805 -52.794258) (xy 138.511788 -52.7939)
			(xy 138.444732 -52.7939) (xy 138.435717 -52.794272) (xy 138.4188 -52.800509) (xy 138.411712 -52.806092)
			(xy 138.411712 -52.806346) (xy 138.411458 -52.806346) (xy 138.390508 -52.823963) (xy 138.344541 -52.85368)
			(xy 138.294798 -52.876521) (xy 138.242301 -52.892017) (xy 138.188128 -52.89985) (xy 138.16076 -52.900326)
			(xy 138.133512 -52.899801) (xy 138.079571 -52.89204) (xy 138.027284 -52.876682) (xy 137.977714 -52.85404)
			(xy 137.931871 -52.824574) (xy 137.890687 -52.788884) (xy 137.855002 -52.747697) (xy 137.825541 -52.701851)
			(xy 137.802904 -52.652279) (xy 137.787551 -52.59999) (xy 137.779796 -52.546048) (xy 132.830698 -52.546048)
			(xy 132.841175 -52.550833) (xy 132.887025 -52.580299) (xy 132.928216 -52.61599) (xy 132.963907 -52.657181)
			(xy 132.993373 -52.703031) (xy 133.016015 -52.752608) (xy 133.03137 -52.804903) (xy 133.039126 -52.858851)
			(xy 133.039612 -52.886102) (xy 133.039144 -52.913472) (xy 133.031326 -52.967651) (xy 133.015837 -53.020154)
			(xy 132.992996 -53.069901) (xy 132.963273 -53.115868) (xy 132.945632 -53.1368) (xy 132.945378 -53.137054)
			(xy 132.939802 -53.144148) (xy 132.93355 -53.161059) (xy 132.933186 -53.170074) (xy 132.933186 -53.23713)
			(xy 132.933531 -53.246148) (xy 132.939787 -53.263065) (xy 132.945378 -53.27015) (xy 132.945632 -53.27015)
			(xy 132.945632 -53.270404) (xy 132.963276 -53.291334) (xy 132.993004 -53.337302) (xy 133.015852 -53.387048)
			(xy 133.03135 -53.439551) (xy 133.039179 -53.49373) (xy 133.039179 -53.548473) (xy 133.031349 -53.602652)
			(xy 133.015851 -53.655155) (xy 132.993003 -53.704901) (xy 132.963275 -53.750868) (xy 132.946702 -53.77053)
			(xy 133.310884 -53.77053) (xy 133.311392 -53.741612) (xy 133.320119 -53.684439) (xy 133.337376 -53.629239)
			(xy 133.36277 -53.577276) (xy 133.395717 -53.529743) (xy 133.435462 -53.487728) (xy 133.45795 -53.46954)
			(xy 133.466738 -53.461914) (xy 133.47693 -53.441027) (xy 133.477508 -53.429408) (xy 133.477508 -53.349652)
			(xy 133.476979 -53.338019) (xy 133.466783 -53.31711) (xy 133.45795 -53.30952) (xy 133.435466 -53.29133)
			(xy 133.395733 -53.249309) (xy 133.362795 -53.201773) (xy 133.337408 -53.149812) (xy 133.320151 -53.094615)
			(xy 133.31142 -53.037446) (xy 133.310884 -53.00853) (xy 133.311383 -52.981278) (xy 133.319136 -52.927329)
			(xy 133.334488 -52.875032) (xy 133.357126 -52.825453) (xy 133.38659 -52.7796) (xy 133.42228 -52.738407)
			(xy 133.463469 -52.702713) (xy 133.509319 -52.673244) (xy 133.558897 -52.650601) (xy 133.611192 -52.635244)
			(xy 133.66514 -52.627486) (xy 133.692392 -52.627022) (xy 133.718706 -52.627488) (xy 133.770835 -52.634722)
			(xy 133.821478 -52.649041) (xy 133.869677 -52.670174) (xy 133.914521 -52.69772) (xy 133.95516 -52.73116)
			(xy 133.973316 -52.750212) (xy 133.980828 -52.757625) (xy 134.000115 -52.766142) (xy 134.010654 -52.766722)
			(xy 134.08533 -52.766722) (xy 134.095876 -52.766162) (xy 134.115171 -52.757648) (xy 134.122668 -52.750212)
			(xy 134.1408 -52.731133) (xy 134.181434 -52.697677) (xy 134.22628 -52.670121) (xy 134.274485 -52.648987)
			(xy 134.325137 -52.634675) (xy 134.377274 -52.627457) (xy 134.403592 -52.627022) (xy 134.430846 -52.627463)
			(xy 134.484799 -52.63522) (xy 134.537099 -52.650576) (xy 134.586682 -52.67322) (xy 134.632536 -52.70269)
			(xy 134.67373 -52.738386) (xy 134.709423 -52.779582) (xy 134.738891 -52.825438) (xy 134.761532 -52.875021)
			(xy 134.776885 -52.927322) (xy 134.784639 -52.981276) (xy 134.7851 -53.00853) (xy 134.784611 -53.036196)
			(xy 134.776608 -53.090946) (xy 134.760787 -53.143968) (xy 134.73748 -53.194152) (xy 134.707175 -53.240448)
			(xy 134.670507 -53.281885) (xy 134.628242 -53.317597) (xy 134.605014 -53.332634) (xy 134.595316 -53.339245)
			(xy 134.582884 -53.359125) (xy 134.581138 -53.370734) (xy 134.573264 -53.450744) (xy 134.572608 -53.462383)
			(xy 134.580704 -53.484222) (xy 134.588758 -53.492654) (xy 134.589012 -53.492908) (xy 134.607581 -53.511)
			(xy 134.640161 -53.55133) (xy 134.666975 -53.595702) (xy 134.68753 -53.643298) (xy 134.701446 -53.69324)
			(xy 134.708466 -53.744608) (xy 134.7089 -53.77053) (xy 134.70845 -53.797782) (xy 134.700689 -53.851732)
			(xy 134.68533 -53.904028) (xy 134.662685 -53.953606) (xy 134.633215 -53.999456) (xy 134.597519 -54.040646)
			(xy 134.556326 -54.076337) (xy 134.510472 -54.105803) (xy 134.460892 -54.128443) (xy 134.408595 -54.143797)
			(xy 134.354644 -54.151553) (xy 134.327392 -54.152038) (xy 134.300021 -54.151592) (xy 134.24584 -54.143771)
			(xy 134.193336 -54.128279) (xy 134.14359 -54.105432) (xy 134.097624 -54.075702) (xy 134.076694 -54.058058)
			(xy 134.07644 -54.057804) (xy 134.069346 -54.052228) (xy 134.052435 -54.045975) (xy 134.04342 -54.045612)
			(xy 133.976364 -54.045612) (xy 133.967345 -54.045949) (xy 133.950428 -54.05221) (xy 133.943344 -54.057804)
			(xy 133.943344 -54.058058) (xy 133.94309 -54.058058) (xy 133.922167 -54.075709) (xy 133.876192 -54.10542)
			(xy 133.826443 -54.128255) (xy 133.77394 -54.143743) (xy 133.719762 -54.151567) (xy 133.692392 -54.152038)
			(xy 133.665142 -54.15153) (xy 133.611197 -54.143773) (xy 133.558904 -54.128418) (xy 133.509329 -54.105778)
			(xy 133.46348 -54.076314) (xy 133.422291 -54.040625) (xy 133.386599 -53.999438) (xy 133.357132 -53.953591)
			(xy 133.334489 -53.904017) (xy 133.319132 -53.851725) (xy 133.311372 -53.79778) (xy 133.310884 -53.77053)
			(xy 132.946702 -53.77053) (xy 132.945632 -53.7718) (xy 132.945378 -53.772054) (xy 132.939802 -53.779148)
			(xy 132.93355 -53.796059) (xy 132.933186 -53.805074) (xy 132.933186 -53.87213) (xy 132.933531 -53.881148)
			(xy 132.939787 -53.898065) (xy 132.945378 -53.90515) (xy 132.945632 -53.90515) (xy 132.945632 -53.905404)
			(xy 132.963276 -53.926334) (xy 132.993004 -53.972302) (xy 133.015852 -54.022048) (xy 133.03135 -54.074551)
			(xy 133.039179 -54.12873) (xy 133.039179 -54.183473) (xy 133.031349 -54.237652) (xy 133.015851 -54.290155)
			(xy 133.002058 -54.320186) (xy 135.230616 -54.320186) (xy 135.23107 -54.292815) (xy 135.23889 -54.238636)
			(xy 135.254382 -54.186132) (xy 135.277226 -54.136385) (xy 135.306954 -54.090419) (xy 135.324596 -54.069488)
			(xy 135.32485 -54.069234) (xy 135.330434 -54.062146) (xy 135.336681 -54.04523) (xy 135.337042 -54.036214)
			(xy 135.337042 -53.969158) (xy 135.33667 -53.960142) (xy 135.330434 -53.943225) (xy 135.32485 -53.936138)
			(xy 135.324596 -53.936138) (xy 135.324596 -53.935884) (xy 135.306982 -53.914932) (xy 135.277267 -53.868964)
			(xy 135.254426 -53.819222) (xy 135.238929 -53.766726) (xy 135.231094 -53.712554) (xy 135.230616 -53.685186)
			(xy 135.231102 -53.657935) (xy 135.238858 -53.603987) (xy 135.254213 -53.551692) (xy 135.276855 -53.502115)
			(xy 135.306321 -53.456265) (xy 135.342012 -53.415074) (xy 135.383203 -53.379383) (xy 135.429053 -53.349917)
			(xy 135.47863 -53.327275) (xy 135.530925 -53.31192) (xy 135.584873 -53.304164) (xy 135.639375 -53.304164)
			(xy 135.693323 -53.31192) (xy 135.745618 -53.327275) (xy 135.795195 -53.349917) (xy 135.841045 -53.379383)
			(xy 135.882236 -53.415074) (xy 135.917927 -53.456265) (xy 135.947393 -53.502115) (xy 135.970035 -53.551692)
			(xy 135.98539 -53.603987) (xy 135.993146 -53.657935) (xy 135.993632 -53.685186) (xy 135.993174 -53.712557)
			(xy 135.985357 -53.766737) (xy 135.969867 -53.819241) (xy 135.947023 -53.868987) (xy 135.917295 -53.914953)
			(xy 135.899652 -53.935884) (xy 135.899398 -53.936138) (xy 135.893831 -53.943238) (xy 135.887573 -53.960144)
			(xy 135.887206 -53.969158) (xy 135.887206 -54.036214) (xy 135.887555 -54.045232) (xy 135.893808 -54.062149)
			(xy 135.899398 -54.069234) (xy 135.899652 -54.069234) (xy 135.899652 -54.069488) (xy 135.917291 -54.09042)
			(xy 135.947005 -54.136392) (xy 135.969842 -54.186139) (xy 135.985332 -54.23864) (xy 135.993159 -54.292817)
			(xy 135.993632 -54.320186) (xy 135.993146 -54.347437) (xy 135.98539 -54.401385) (xy 135.970035 -54.45368)
			(xy 135.947393 -54.503257) (xy 135.917927 -54.549107) (xy 135.882236 -54.590298) (xy 135.841045 -54.625989)
			(xy 135.795195 -54.655455) (xy 135.745618 -54.678097) (xy 135.693323 -54.693452) (xy 135.639375 -54.701208)
			(xy 135.584873 -54.701208) (xy 135.530925 -54.693452) (xy 135.47863 -54.678097) (xy 135.429053 -54.655455)
			(xy 135.383203 -54.625989) (xy 135.342012 -54.590298) (xy 135.306321 -54.549107) (xy 135.276855 -54.503257)
			(xy 135.254213 -54.45368) (xy 135.238858 -54.401385) (xy 135.231102 -54.347437) (xy 135.230616 -54.320186)
			(xy 133.002058 -54.320186) (xy 132.993003 -54.339901) (xy 132.963275 -54.385868) (xy 132.945632 -54.4068)
			(xy 132.945378 -54.407054) (xy 132.939802 -54.414148) (xy 132.93355 -54.431059) (xy 132.933186 -54.440074)
			(xy 132.933186 -54.50713) (xy 132.933531 -54.516148) (xy 132.939787 -54.533065) (xy 132.945378 -54.54015)
			(xy 132.945632 -54.54015) (xy 132.945632 -54.540404) (xy 132.963291 -54.56132) (xy 132.992999 -54.607297)
			(xy 133.015831 -54.657049) (xy 133.031317 -54.709553) (xy 133.03914 -54.763732) (xy 133.039257 -54.770528)
			(xy 136.171178 -54.770528) (xy 136.171641 -54.743157) (xy 136.179457 -54.688977) (xy 136.194946 -54.636474)
			(xy 136.217788 -54.586727) (xy 136.247515 -54.540761) (xy 136.265158 -54.51983) (xy 136.265412 -54.519576)
			(xy 136.271016 -54.512501) (xy 136.277252 -54.495575) (xy 136.277604 -54.486556) (xy 136.277604 -54.4195)
			(xy 136.277246 -54.410483) (xy 136.270999 -54.393566) (xy 136.265412 -54.38648) (xy 136.265158 -54.38648)
			(xy 136.265158 -54.386226) (xy 136.247511 -54.365301) (xy 136.217801 -54.319325) (xy 136.194968 -54.269576)
			(xy 136.179478 -54.217074) (xy 136.171651 -54.162898) (xy 136.171178 -54.135528) (xy 136.171664 -54.108277)
			(xy 136.17942 -54.054329) (xy 136.194775 -54.002034) (xy 136.217417 -53.952457) (xy 136.246883 -53.906607)
			(xy 136.282574 -53.865416) (xy 136.323765 -53.829725) (xy 136.369615 -53.800259) (xy 136.419192 -53.777617)
			(xy 136.471487 -53.762262) (xy 136.525435 -53.754506) (xy 136.579937 -53.754506) (xy 136.633885 -53.762262)
			(xy 136.68618 -53.777617) (xy 136.735757 -53.800259) (xy 136.781607 -53.829725) (xy 136.822798 -53.865416)
			(xy 136.858489 -53.906607) (xy 136.887955 -53.952457) (xy 136.89303 -53.96357) (xy 140.872208 -53.96357)
			(xy 140.876279 -53.907948) (xy 140.888405 -53.853511) (xy 140.908328 -53.80142) (xy 140.935624 -53.752785)
			(xy 140.96971 -53.708642) (xy 141.009859 -53.669933) (xy 141.055217 -53.637482) (xy 141.104817 -53.611981)
			(xy 141.157601 -53.593974) (xy 141.212444 -53.583844) (xy 141.268178 -53.581807) (xy 141.323615 -53.587907)
			(xy 141.377572 -53.602013) (xy 141.428901 -53.623825) (xy 141.476507 -53.652879) (xy 141.519375 -53.688554)
			(xy 141.556592 -53.730091) (xy 141.587365 -53.776604) (xy 141.611037 -53.827101) (xy 141.627105 -53.880508)
			(xy 141.635225 -53.935684) (xy 141.635734 -53.96357) (xy 141.635225 -53.991456) (xy 141.627105 -54.046632)
			(xy 141.611037 -54.100039) (xy 141.587365 -54.150536) (xy 141.556592 -54.197049) (xy 141.519375 -54.238586)
			(xy 141.476507 -54.274261) (xy 141.428901 -54.303315) (xy 141.377572 -54.325127) (xy 141.323615 -54.339233)
			(xy 141.268178 -54.345333) (xy 141.212444 -54.343296) (xy 141.157601 -54.333166) (xy 141.104817 -54.315159)
			(xy 141.055217 -54.289658) (xy 141.009859 -54.257207) (xy 140.96971 -54.218498) (xy 140.935624 -54.174355)
			(xy 140.908328 -54.12572) (xy 140.888405 -54.073629) (xy 140.876279 -54.019192) (xy 140.872208 -53.96357)
			(xy 136.89303 -53.96357) (xy 136.910597 -54.002034) (xy 136.925952 -54.054329) (xy 136.933708 -54.108277)
			(xy 136.934194 -54.135528) (xy 136.933746 -54.162899) (xy 136.925924 -54.217079) (xy 136.910431 -54.269582)
			(xy 136.887585 -54.319329) (xy 136.857857 -54.365295) (xy 136.840214 -54.386226) (xy 136.83996 -54.38648)
			(xy 136.834371 -54.393565) (xy 136.828127 -54.410483) (xy 136.827768 -54.4195) (xy 136.827768 -54.486556)
			(xy 136.828153 -54.49557) (xy 136.834382 -54.512487) (xy 136.83996 -54.519576) (xy 136.840214 -54.519576)
			(xy 136.840214 -54.51983) (xy 136.857836 -54.540776) (xy 136.88755 -54.586745) (xy 136.910389 -54.636489)
			(xy 136.925884 -54.688987) (xy 136.933717 -54.74316) (xy 136.934194 -54.770528) (xy 136.933708 -54.797779)
			(xy 136.925952 -54.851727) (xy 136.910597 -54.904022) (xy 136.887955 -54.953599) (xy 136.858489 -54.999449)
			(xy 136.822798 -55.04064) (xy 136.781607 -55.076331) (xy 136.735757 -55.105797) (xy 136.68618 -55.128439)
			(xy 136.633885 -55.143794) (xy 136.579937 -55.15155) (xy 136.525435 -55.15155) (xy 136.471487 -55.143794)
			(xy 136.419192 -55.128439) (xy 136.369615 -55.105797) (xy 136.323765 -55.076331) (xy 136.282574 -55.04064)
			(xy 136.246883 -54.999449) (xy 136.217417 -54.953599) (xy 136.194775 -54.904022) (xy 136.17942 -54.851727)
			(xy 136.171664 -54.797779) (xy 136.171178 -54.770528) (xy 133.039257 -54.770528) (xy 133.039612 -54.791102)
			(xy 133.039126 -54.818353) (xy 133.03137 -54.872301) (xy 133.016015 -54.924596) (xy 132.993373 -54.974173)
			(xy 132.963907 -55.020023) (xy 132.928216 -55.061214) (xy 132.887025 -55.096905) (xy 132.841175 -55.126371)
			(xy 132.791598 -55.149013) (xy 132.739303 -55.164368) (xy 132.685355 -55.172124) (xy 132.630853 -55.172124)
			(xy 132.576905 -55.164368) (xy 132.52461 -55.149013) (xy 132.475033 -55.126371) (xy 132.429183 -55.096905)
			(xy 132.387992 -55.061214) (xy 132.352301 -55.020023) (xy 132.322835 -54.974173) (xy 132.300193 -54.924596)
			(xy 132.284838 -54.872301) (xy 132.277082 -54.818353) (xy 132.276596 -54.791102) (xy 130.378638 -54.791102)
			(xy 130.375546 -54.812611) (xy 130.360191 -54.864906) (xy 130.337549 -54.914483) (xy 130.308083 -54.960333)
			(xy 130.272392 -55.001524) (xy 130.231201 -55.037215) (xy 130.185351 -55.066681) (xy 130.135774 -55.089323)
			(xy 130.083479 -55.104678) (xy 130.029531 -55.112434) (xy 129.975029 -55.112434) (xy 129.921081 -55.104678)
			(xy 129.868786 -55.089323) (xy 129.819209 -55.066681) (xy 129.773359 -55.037215) (xy 129.732168 -55.001524)
			(xy 129.696477 -54.960333) (xy 129.667011 -54.914483) (xy 129.644369 -54.864906) (xy 129.629014 -54.812611)
			(xy 129.621258 -54.758663) (xy 129.620772 -54.731412) (xy 129.116836 -54.731412) (xy 129.116836 -57.002934)
			(xy 137.663682 -57.002934) (xy 137.664204 -56.974843) (xy 137.672426 -56.919268) (xy 137.688712 -56.865499)
			(xy 137.712711 -56.814702) (xy 137.743901 -56.767975) (xy 137.78161 -56.726329) (xy 137.825019 -56.690665)
			(xy 137.848848 -56.675782) (xy 137.857738 -56.670448) (xy 137.86993 -56.65343) (xy 137.89025 -56.560212)
			(xy 137.885932 -56.539638) (xy 137.88009 -56.531002) (xy 137.864087 -56.50694) (xy 137.838746 -56.455008)
			(xy 137.821521 -56.399849) (xy 137.812806 -56.342725) (xy 137.812272 -56.313832) (xy 137.812785 -56.286581)
			(xy 137.820537 -56.232633) (xy 137.835888 -56.180337) (xy 137.858525 -56.130758) (xy 137.887988 -56.084906)
			(xy 137.923677 -56.043714) (xy 137.964864 -56.008019) (xy 138.010713 -55.97855) (xy 138.060288 -55.955906)
			(xy 138.112582 -55.940548) (xy 138.166529 -55.932789) (xy 138.19378 -55.932324) (xy 138.22115 -55.932796)
			(xy 138.275329 -55.940611) (xy 138.327832 -55.956099) (xy 138.377579 -55.978939) (xy 138.423546 -56.008663)
			(xy 138.444478 -56.026304) (xy 138.444732 -56.026558) (xy 138.451829 -56.032129) (xy 138.468738 -56.038384)
			(xy 138.477752 -56.03875) (xy 138.544808 -56.03875) (xy 138.553827 -56.038407) (xy 138.570744 -56.032151)
			(xy 138.577828 -56.026558) (xy 138.577828 -56.026304) (xy 138.578082 -56.026304) (xy 138.599015 -56.008663)
			(xy 138.644983 -55.978939) (xy 138.694729 -55.956093) (xy 138.747231 -55.940597) (xy 138.801409 -55.932768)
			(xy 138.856151 -55.932768) (xy 138.910329 -55.940597) (xy 138.962831 -55.956093) (xy 139.012577 -55.978939)
			(xy 139.058545 -56.008663) (xy 139.079478 -56.026304) (xy 139.079732 -56.026558) (xy 139.086829 -56.032129)
			(xy 139.103738 -56.038384) (xy 139.112752 -56.03875) (xy 139.179808 -56.03875) (xy 139.188827 -56.038407)
			(xy 139.205744 -56.032151) (xy 139.212828 -56.026558) (xy 139.212828 -56.026304) (xy 139.213082 -56.026304)
			(xy 139.234011 -56.008661) (xy 139.279984 -55.978949) (xy 139.329733 -55.956114) (xy 139.382234 -55.940624)
			(xy 139.436411 -55.932797) (xy 139.46378 -55.932324) (xy 139.491036 -55.932722) (xy 139.544994 -55.940477)
			(xy 139.597298 -55.955832) (xy 139.646885 -55.978476) (xy 139.692745 -56.007946) (xy 139.733943 -56.043642)
			(xy 139.769642 -56.084839) (xy 139.799115 -56.130697) (xy 139.821761 -56.180283) (xy 139.837119 -56.232587)
			(xy 139.844877 -56.286544) (xy 139.844877 -56.341056) (xy 139.837119 -56.395013) (xy 139.821761 -56.447317)
			(xy 139.799115 -56.496903) (xy 139.769642 -56.542761) (xy 139.733943 -56.583958) (xy 139.692745 -56.619654)
			(xy 139.646885 -56.649124) (xy 139.597298 -56.671768) (xy 139.544994 -56.687123) (xy 139.491036 -56.694878)
			(xy 139.46378 -56.69534) (xy 139.436409 -56.6949) (xy 139.382228 -56.687078) (xy 139.329724 -56.671584)
			(xy 139.279977 -56.648736) (xy 139.234012 -56.619005) (xy 139.213082 -56.60136) (xy 139.212828 -56.601106)
			(xy 139.205737 -56.595526) (xy 139.188824 -56.589275) (xy 139.179808 -56.588914) (xy 139.112752 -56.588914)
			(xy 139.103737 -56.589293) (xy 139.08682 -56.595525) (xy 139.079732 -56.601106) (xy 139.079732 -56.60136)
			(xy 139.079478 -56.60136) (xy 139.058545 -56.619001) (xy 139.012577 -56.648725) (xy 138.962831 -56.671571)
			(xy 138.910329 -56.687067) (xy 138.856151 -56.694896) (xy 138.801409 -56.694896) (xy 138.747231 -56.687067)
			(xy 138.694729 -56.671571) (xy 138.644983 -56.648725) (xy 138.599015 -56.619001) (xy 138.578082 -56.60136)
			(xy 138.577828 -56.601106) (xy 138.570737 -56.595526) (xy 138.553824 -56.589275) (xy 138.544808 -56.588914)
			(xy 138.477752 -56.588914) (xy 138.468737 -56.589293) (xy 138.45182 -56.595525) (xy 138.444732 -56.601106)
			(xy 138.444224 -56.60136) (xy 138.431492 -56.612307) (xy 138.404399 -56.632146) (xy 138.390122 -56.640984)
			(xy 138.381232 -56.646318) (xy 138.36904 -56.663336) (xy 138.34872 -56.756554) (xy 138.353038 -56.777128)
			(xy 138.35888 -56.785764) (xy 138.374865 -56.809838) (xy 138.400211 -56.861765) (xy 138.417441 -56.91692)
			(xy 138.426161 -56.974042) (xy 138.426698 -57.002934) (xy 138.426212 -57.030185) (xy 138.418456 -57.084133)
			(xy 138.403101 -57.136428) (xy 138.380459 -57.186005) (xy 138.350993 -57.231855) (xy 138.315302 -57.273046)
			(xy 138.274111 -57.308737) (xy 138.228261 -57.338203) (xy 138.178684 -57.360845) (xy 138.126389 -57.3762)
			(xy 138.072441 -57.383956) (xy 138.017939 -57.383956) (xy 137.963991 -57.3762) (xy 137.911696 -57.360845)
			(xy 137.862119 -57.338203) (xy 137.816269 -57.308737) (xy 137.775078 -57.273046) (xy 137.739387 -57.231855)
			(xy 137.709921 -57.186005) (xy 137.687279 -57.136428) (xy 137.671924 -57.084133) (xy 137.664168 -57.030185)
			(xy 137.663682 -57.002934) (xy 129.116836 -57.002934) (xy 129.116836 -58.679334) (xy 138.095482 -58.679334)
			(xy 138.095911 -58.653019) (xy 138.103155 -58.600889) (xy 138.117482 -58.550246) (xy 138.138621 -58.502047)
			(xy 138.166174 -58.457204) (xy 138.199618 -58.416566) (xy 138.218672 -58.39841) (xy 138.226067 -58.390883)
			(xy 138.234596 -58.371607) (xy 138.235182 -58.361072) (xy 138.235182 -58.286396) (xy 138.234674 -58.275844)
			(xy 138.226124 -58.256548) (xy 138.218672 -58.249058) (xy 138.199598 -58.230921) (xy 138.166143 -58.190287)
			(xy 138.138588 -58.145443) (xy 138.117453 -58.097238) (xy 138.103139 -58.046588) (xy 138.095918 -57.994451)
			(xy 138.095482 -57.968134) (xy 138.095968 -57.940883) (xy 138.103724 -57.886935) (xy 138.119079 -57.83464)
			(xy 138.141721 -57.785063) (xy 138.171187 -57.739213) (xy 138.206878 -57.698022) (xy 138.248069 -57.662331)
			(xy 138.293919 -57.632865) (xy 138.343496 -57.610223) (xy 138.395791 -57.594868) (xy 138.449739 -57.587112)
			(xy 138.504241 -57.587112) (xy 138.558189 -57.594868) (xy 138.610484 -57.610223) (xy 138.660061 -57.632865)
			(xy 138.705911 -57.662331) (xy 138.747102 -57.698022) (xy 138.782793 -57.739213) (xy 138.812259 -57.785063)
			(xy 138.834901 -57.83464) (xy 138.850256 -57.886935) (xy 138.858012 -57.940883) (xy 138.858498 -57.968134)
			(xy 138.858054 -57.994449) (xy 138.850814 -58.046578) (xy 138.836491 -58.097221) (xy 138.815354 -58.14542)
			(xy 138.787804 -58.190263) (xy 138.754361 -58.230902) (xy 138.735308 -58.249058) (xy 138.727924 -58.256594)
			(xy 138.719389 -58.275863) (xy 138.718798 -58.286396) (xy 138.718798 -58.361072) (xy 138.719329 -58.371621)
			(xy 138.727863 -58.390917) (xy 138.735308 -58.39841) (xy 138.754363 -58.416566) (xy 138.78782 -58.457196)
			(xy 138.815379 -58.502036) (xy 138.836517 -58.550237) (xy 138.850835 -58.600884) (xy 138.858059 -58.653018)
			(xy 138.858498 -58.679334) (xy 138.858012 -58.706585) (xy 138.850256 -58.760533) (xy 138.834901 -58.812828)
			(xy 138.812259 -58.862405) (xy 138.782793 -58.908255) (xy 138.747102 -58.949446) (xy 138.705911 -58.985137)
			(xy 138.660061 -59.014603) (xy 138.610484 -59.037245) (xy 138.558189 -59.0526) (xy 138.504241 -59.060356)
			(xy 138.449739 -59.060356) (xy 138.395791 -59.0526) (xy 138.343496 -59.037245) (xy 138.293919 -59.014603)
			(xy 138.248069 -58.985137) (xy 138.206878 -58.949446) (xy 138.171187 -58.908255) (xy 138.141721 -58.862405)
			(xy 138.119079 -58.812828) (xy 138.103724 -58.760533) (xy 138.095968 -58.706585) (xy 138.095482 -58.679334)
			(xy 129.116836 -58.679334) (xy 129.116836 -60.019254) (xy 138.235861 -60.019254) (xy 138.235861 -59.964746)
			(xy 138.243619 -59.910792) (xy 138.258977 -59.858491) (xy 138.281623 -59.808909) (xy 138.311094 -59.763054)
			(xy 138.346792 -59.721861) (xy 138.38799 -59.686168) (xy 138.433848 -59.656702) (xy 138.483432 -59.634062)
			(xy 138.535735 -59.61871) (xy 138.58969 -59.610958) (xy 138.616944 -59.610498) (xy 138.644313 -59.610997)
			(xy 138.698491 -59.618807) (xy 138.750993 -59.634289) (xy 138.800741 -59.657123) (xy 138.846709 -59.68684)
			(xy 138.867642 -59.704478) (xy 138.867896 -59.704732) (xy 138.874977 -59.710327) (xy 138.891898 -59.716567)
			(xy 138.900916 -59.716924) (xy 138.967972 -59.716924) (xy 138.976987 -59.716548) (xy 138.993904 -59.710313)
			(xy 139.000992 -59.704732) (xy 139.000992 -59.704478) (xy 139.001246 -59.704478) (xy 139.022179 -59.686837)
			(xy 139.068147 -59.657113) (xy 139.117893 -59.634267) (xy 139.170395 -59.618771) (xy 139.224573 -59.610942)
			(xy 139.279315 -59.610942) (xy 139.333493 -59.618771) (xy 139.385995 -59.634267) (xy 139.435741 -59.657113)
			(xy 139.481709 -59.686837) (xy 139.502642 -59.704478) (xy 139.502896 -59.704732) (xy 139.509977 -59.710327)
			(xy 139.526898 -59.716567) (xy 139.535916 -59.716924) (xy 139.602972 -59.716924) (xy 139.611987 -59.716548)
			(xy 139.628904 -59.710313) (xy 139.635992 -59.704732) (xy 139.635992 -59.704478) (xy 139.636246 -59.704478)
			(xy 139.657185 -59.686847) (xy 139.703156 -59.657135) (xy 139.752902 -59.634298) (xy 139.805401 -59.618805)
			(xy 139.859575 -59.610974) (xy 139.886944 -59.610498) (xy 139.914194 -59.610975) (xy 139.968137 -59.618737)
			(xy 140.020428 -59.634096) (xy 140.07 -59.65674) (xy 140.115846 -59.686208) (xy 140.157031 -59.7219)
			(xy 140.192719 -59.763089) (xy 140.222181 -59.808938) (xy 140.24482 -59.858514) (xy 140.260173 -59.910806)
			(xy 140.267928 -59.96475) (xy 140.267928 -60.01925) (xy 140.260173 -60.073194) (xy 140.24482 -60.125486)
			(xy 140.222181 -60.175062) (xy 140.192719 -60.220911) (xy 140.157031 -60.2621) (xy 140.115846 -60.297792)
			(xy 140.07 -60.32726) (xy 140.020428 -60.349904) (xy 139.968137 -60.365263) (xy 139.914194 -60.373025)
			(xy 139.886944 -60.373514) (xy 139.859575 -60.373019) (xy 139.805397 -60.365207) (xy 139.752894 -60.349725)
			(xy 139.703147 -60.32689) (xy 139.657179 -60.297172) (xy 139.636246 -60.279534) (xy 139.635992 -60.27928)
			(xy 139.628914 -60.273682) (xy 139.61199 -60.267443) (xy 139.602972 -60.267088) (xy 139.535916 -60.267088)
			(xy 139.5269 -60.267455) (xy 139.509983 -60.273696) (xy 139.502896 -60.27928) (xy 139.502642 -60.279534)
			(xy 139.481709 -60.297175) (xy 139.435741 -60.326899) (xy 139.385995 -60.349745) (xy 139.333493 -60.365241)
			(xy 139.279315 -60.37307) (xy 139.224573 -60.37307) (xy 139.170395 -60.365241) (xy 139.117893 -60.349745)
			(xy 139.068147 -60.326899) (xy 139.022179 -60.297175) (xy 139.001246 -60.279534) (xy 139.000992 -60.27928)
			(xy 138.993914 -60.273682) (xy 138.97699 -60.267443) (xy 138.967972 -60.267088) (xy 138.900916 -60.267088)
			(xy 138.8919 -60.267455) (xy 138.874983 -60.273696) (xy 138.867896 -60.27928) (xy 138.867896 -60.279534)
			(xy 138.867642 -60.279534) (xy 138.846709 -60.297172) (xy 138.800736 -60.326883) (xy 138.750989 -60.349719)
			(xy 138.698488 -60.36521) (xy 138.644313 -60.373039) (xy 138.616944 -60.373514) (xy 138.58969 -60.373042)
			(xy 138.535735 -60.36529) (xy 138.483432 -60.349938) (xy 138.433847 -60.327298) (xy 138.38799 -60.297832)
			(xy 138.346792 -60.262139) (xy 138.311094 -60.220946) (xy 138.281623 -60.175091) (xy 138.258977 -60.125509)
			(xy 138.243619 -60.073208) (xy 138.235861 -60.019254) (xy 129.116836 -60.019254) (xy 129.116836 -67.128954)
			(xy 130.466775 -67.128954) (xy 130.466775 -67.074446) (xy 130.474533 -67.020494) (xy 130.489891 -66.968196)
			(xy 130.512535 -66.918615) (xy 130.542006 -66.872762) (xy 130.577703 -66.83157) (xy 130.618899 -66.795879)
			(xy 130.664755 -66.766413) (xy 130.714339 -66.743775) (xy 130.766639 -66.728423) (xy 130.820592 -66.720672)
			(xy 130.847846 -66.720212) (xy 130.875215 -66.720707) (xy 130.929393 -66.728517) (xy 130.981896 -66.743999)
			(xy 131.031643 -66.766835) (xy 131.077611 -66.796553) (xy 131.098544 -66.814192) (xy 131.098798 -66.814446)
			(xy 131.105877 -66.820043) (xy 131.1228 -66.826282) (xy 131.131818 -66.826638) (xy 131.198874 -66.826638)
			(xy 131.207889 -66.82626) (xy 131.224805 -66.820026) (xy 131.231894 -66.814446) (xy 131.231894 -66.814192)
			(xy 131.232148 -66.814192) (xy 131.253088 -66.796563) (xy 131.299059 -66.76685) (xy 131.348804 -66.744012)
			(xy 131.401303 -66.728519) (xy 131.455477 -66.720688) (xy 131.482846 -66.720212) (xy 131.510097 -66.720661)
			(xy 131.564042 -66.728423) (xy 131.616334 -66.743783) (xy 131.665908 -66.766428) (xy 131.711755 -66.795897)
			(xy 131.752942 -66.831591) (xy 131.78863 -66.872782) (xy 131.818094 -66.918632) (xy 131.840733 -66.968209)
			(xy 131.856087 -67.020503) (xy 131.863842 -67.074449) (xy 131.863842 -67.128951) (xy 131.856087 -67.182897)
			(xy 131.840733 -67.235191) (xy 131.818094 -67.284768) (xy 131.78863 -67.330618) (xy 131.752942 -67.371809)
			(xy 131.711755 -67.407503) (xy 131.665908 -67.436972) (xy 131.616334 -67.459617) (xy 131.564042 -67.474977)
			(xy 131.510097 -67.482739) (xy 131.482846 -67.483228) (xy 131.455476 -67.482753) (xy 131.401297 -67.47494)
			(xy 131.348793 -67.459454) (xy 131.299046 -67.436614) (xy 131.253079 -67.406889) (xy 131.232148 -67.389248)
			(xy 131.231894 -67.388994) (xy 131.224814 -67.383398) (xy 131.207892 -67.377157) (xy 131.198874 -67.376802)
			(xy 131.131818 -67.376802) (xy 131.122802 -67.377167) (xy 131.105885 -67.383409) (xy 131.098798 -67.388994)
			(xy 131.098798 -67.389248) (xy 131.098544 -67.389248) (xy 131.077599 -67.406872) (xy 131.031631 -67.436588)
			(xy 130.981887 -67.459427) (xy 130.929388 -67.474922) (xy 130.875214 -67.482753) (xy 130.847846 -67.483228)
			(xy 130.820592 -67.482728) (xy 130.766639 -67.474977) (xy 130.714339 -67.459625) (xy 130.664755 -67.436987)
			(xy 130.618899 -67.407521) (xy 130.577703 -67.37183) (xy 130.542006 -67.330638) (xy 130.512535 -67.284785)
			(xy 130.489891 -67.235204) (xy 130.474533 -67.182906) (xy 130.466775 -67.128954) (xy 129.116836 -67.128954)
			(xy 129.116836 -67.488054) (xy 134.879332 -67.488054) (xy 134.883403 -67.432432) (xy 134.895529 -67.377995)
			(xy 134.915452 -67.325904) (xy 134.942748 -67.277269) (xy 134.976834 -67.233126) (xy 135.016983 -67.194417)
			(xy 135.062341 -67.161966) (xy 135.111941 -67.136465) (xy 135.164725 -67.118458) (xy 135.219568 -67.108328)
			(xy 135.275302 -67.106291) (xy 135.330739 -67.112391) (xy 135.384696 -67.126497) (xy 135.436025 -67.148309)
			(xy 135.483631 -67.177363) (xy 135.526499 -67.213038) (xy 135.563716 -67.254575) (xy 135.594489 -67.301088)
			(xy 135.618161 -67.351585) (xy 135.634229 -67.404992) (xy 135.642349 -67.460168) (xy 135.642858 -67.488054)
			(xy 135.642349 -67.51594) (xy 135.639164 -67.537584) (xy 136.17143 -67.537584) (xy 136.175501 -67.481962)
			(xy 136.187627 -67.427525) (xy 136.20755 -67.375434) (xy 136.234846 -67.326799) (xy 136.268932 -67.282656)
			(xy 136.309081 -67.243947) (xy 136.354439 -67.211496) (xy 136.404039 -67.185995) (xy 136.456823 -67.167988)
			(xy 136.511666 -67.157858) (xy 136.5674 -67.155821) (xy 136.622837 -67.161921) (xy 136.676794 -67.176027)
			(xy 136.728123 -67.197839) (xy 136.775729 -67.226893) (xy 136.818597 -67.262568) (xy 136.855814 -67.304105)
			(xy 136.886587 -67.350618) (xy 136.910259 -67.401115) (xy 136.926327 -67.454522) (xy 136.934447 -67.509698)
			(xy 136.934956 -67.537584) (xy 136.934447 -67.56547) (xy 136.930402 -67.592956) (xy 137.445494 -67.592956)
			(xy 137.449565 -67.537334) (xy 137.461691 -67.482897) (xy 137.481614 -67.430806) (xy 137.50891 -67.382171)
			(xy 137.542996 -67.338028) (xy 137.583145 -67.299319) (xy 137.628503 -67.266868) (xy 137.678103 -67.241367)
			(xy 137.730887 -67.22336) (xy 137.78573 -67.21323) (xy 137.841464 -67.211193) (xy 137.896901 -67.217293)
			(xy 137.950858 -67.231399) (xy 138.002187 -67.253211) (xy 138.049793 -67.282265) (xy 138.092661 -67.31794)
			(xy 138.129878 -67.359477) (xy 138.160651 -67.40599) (xy 138.184323 -67.456487) (xy 138.200391 -67.509894)
			(xy 138.208511 -67.56507) (xy 138.20902 -67.592956) (xy 138.208511 -67.620842) (xy 138.200391 -67.676018)
			(xy 138.184323 -67.729425) (xy 138.160651 -67.779922) (xy 138.129878 -67.826435) (xy 138.092661 -67.867972)
			(xy 138.049793 -67.903647) (xy 138.002187 -67.932701) (xy 137.950858 -67.954513) (xy 137.896901 -67.968619)
			(xy 137.841464 -67.974719) (xy 137.78573 -67.972682) (xy 137.730887 -67.962552) (xy 137.678103 -67.944545)
			(xy 137.628503 -67.919044) (xy 137.583145 -67.886593) (xy 137.542996 -67.847884) (xy 137.50891 -67.803741)
			(xy 137.481614 -67.755106) (xy 137.461691 -67.703015) (xy 137.449565 -67.648578) (xy 137.445494 -67.592956)
			(xy 136.930402 -67.592956) (xy 136.926327 -67.620646) (xy 136.910259 -67.674053) (xy 136.886587 -67.72455)
			(xy 136.855814 -67.771063) (xy 136.818597 -67.8126) (xy 136.775729 -67.848275) (xy 136.728123 -67.877329)
			(xy 136.676794 -67.899141) (xy 136.622837 -67.913247) (xy 136.5674 -67.919347) (xy 136.511666 -67.91731)
			(xy 136.456823 -67.90718) (xy 136.404039 -67.889173) (xy 136.354439 -67.863672) (xy 136.309081 -67.831221)
			(xy 136.268932 -67.792512) (xy 136.234846 -67.748369) (xy 136.20755 -67.699734) (xy 136.187627 -67.647643)
			(xy 136.175501 -67.593206) (xy 136.17143 -67.537584) (xy 135.639164 -67.537584) (xy 135.634229 -67.571116)
			(xy 135.618161 -67.624523) (xy 135.594489 -67.67502) (xy 135.563716 -67.721533) (xy 135.526499 -67.76307)
			(xy 135.483631 -67.798745) (xy 135.436025 -67.827799) (xy 135.384696 -67.849611) (xy 135.330739 -67.863717)
			(xy 135.275302 -67.869817) (xy 135.219568 -67.86778) (xy 135.164725 -67.85765) (xy 135.111941 -67.839643)
			(xy 135.062341 -67.814142) (xy 135.016983 -67.781691) (xy 134.976834 -67.742982) (xy 134.942748 -67.698839)
			(xy 134.915452 -67.650204) (xy 134.895529 -67.598113) (xy 134.883403 -67.543676) (xy 134.879332 -67.488054)
			(xy 129.116836 -67.488054) (xy 129.116836 -68.586604) (xy 132.725414 -68.586604) (xy 132.725879 -68.559234)
			(xy 132.733697 -68.505054) (xy 132.749186 -68.452551) (xy 132.772028 -68.402804) (xy 132.801753 -68.356838)
			(xy 132.819394 -68.335906) (xy 132.819648 -68.335652) (xy 132.825225 -68.328559) (xy 132.831476 -68.311647)
			(xy 132.83184 -68.302632) (xy 132.83184 -68.235576) (xy 132.831507 -68.226556) (xy 132.825244 -68.209639)
			(xy 132.819648 -68.202556) (xy 132.819394 -68.202556) (xy 132.819394 -68.202302) (xy 132.801741 -68.181381)
			(xy 132.772032 -68.135405) (xy 132.749199 -68.085655) (xy 132.733711 -68.033152) (xy 132.725886 -67.978974)
			(xy 132.725414 -67.951604) (xy 132.725859 -67.92435) (xy 132.733616 -67.870398) (xy 132.748973 -67.818098)
			(xy 132.771616 -67.768516) (xy 132.801086 -67.722662) (xy 132.836782 -67.681469) (xy 132.877977 -67.645775)
			(xy 132.923832 -67.616308) (xy 132.973415 -67.593666) (xy 133.025715 -67.578312) (xy 133.079668 -67.570558)
			(xy 133.106922 -67.570096) (xy 133.133236 -67.57055) (xy 133.185365 -67.577788) (xy 133.236008 -67.59211)
			(xy 133.284207 -67.613245) (xy 133.32905 -67.640793) (xy 133.36969 -67.674234) (xy 133.387846 -67.693286)
			(xy 133.39535 -67.700708) (xy 133.414643 -67.709221) (xy 133.425184 -67.709796) (xy 133.49986 -67.709796)
			(xy 133.510409 -67.70926) (xy 133.529704 -67.70073) (xy 133.537198 -67.693286) (xy 133.555359 -67.674236)
			(xy 133.595988 -67.640779) (xy 133.640827 -67.613219) (xy 133.689027 -67.59208) (xy 133.739673 -67.577762)
			(xy 133.791806 -67.570535) (xy 133.818122 -67.570096) (xy 133.845493 -67.57055) (xy 133.899672 -67.578371)
			(xy 133.952175 -67.593863) (xy 134.001922 -67.616707) (xy 134.047889 -67.646434) (xy 134.06882 -67.664076)
			(xy 134.069074 -67.66433) (xy 134.076161 -67.669915) (xy 134.093078 -67.676162) (xy 134.102094 -67.676522)
			(xy 134.16915 -67.676522) (xy 134.178164 -67.676136) (xy 134.195081 -67.669908) (xy 134.20217 -67.66433)
			(xy 134.20217 -67.664076) (xy 134.202424 -67.664076) (xy 134.223371 -67.646455) (xy 134.26934 -67.616742)
			(xy 134.319084 -67.593902) (xy 134.371581 -67.578407) (xy 134.425754 -67.570573) (xy 134.453122 -67.570096)
			(xy 134.480374 -67.570557) (xy 134.534323 -67.578317) (xy 134.586618 -67.593675) (xy 134.636196 -67.616319)
			(xy 134.682046 -67.645788) (xy 134.723236 -67.681482) (xy 134.758928 -67.722675) (xy 134.788393 -67.768527)
			(xy 134.811034 -67.818106) (xy 134.826389 -67.870403) (xy 134.834145 -67.924352) (xy 134.83463 -67.951604)
			(xy 134.834183 -67.978975) (xy 134.826363 -68.033156) (xy 134.810871 -68.08566) (xy 134.788024 -68.135406)
			(xy 134.758294 -68.181372) (xy 134.74065 -68.202302) (xy 134.740396 -68.202556) (xy 134.734821 -68.209651)
			(xy 134.728568 -68.226561) (xy 134.728204 -68.235576) (xy 134.728204 -68.302632) (xy 134.728545 -68.311651)
			(xy 134.734804 -68.328567) (xy 134.740396 -68.335652) (xy 134.74065 -68.335652) (xy 134.74065 -68.335906)
			(xy 134.758298 -68.356831) (xy 134.78801 -68.402805) (xy 134.810845 -68.452554) (xy 134.826334 -68.505057)
			(xy 134.834158 -68.559234) (xy 134.83463 -68.586604) (xy 134.834126 -68.613854) (xy 134.82637 -68.6678)
			(xy 134.811015 -68.720093) (xy 134.794375 -68.75653) (xy 138.270488 -68.75653) (xy 138.270975 -68.729161)
			(xy 138.278788 -68.674982) (xy 138.294272 -68.62248) (xy 138.317109 -68.572733) (xy 138.346829 -68.526765)
			(xy 138.364468 -68.505832) (xy 138.364722 -68.505578) (xy 138.370326 -68.498504) (xy 138.376562 -68.481577)
			(xy 138.376914 -68.472558) (xy 138.376914 -68.405502) (xy 138.376553 -68.396486) (xy 138.370308 -68.379569)
			(xy 138.364722 -68.372482) (xy 138.364468 -68.372482) (xy 138.364468 -68.372228) (xy 138.346824 -68.3513)
			(xy 138.317114 -68.305326) (xy 138.294279 -68.255577) (xy 138.278789 -68.203076) (xy 138.270962 -68.148899)
			(xy 138.270488 -68.12153) (xy 138.270983 -68.094278) (xy 138.278736 -68.040328) (xy 138.294088 -67.988031)
			(xy 138.316727 -67.938452) (xy 138.346191 -67.892599) (xy 138.381882 -67.851406) (xy 138.423071 -67.815712)
			(xy 138.468922 -67.786243) (xy 138.5185 -67.7636) (xy 138.570795 -67.748243) (xy 138.624744 -67.740486)
			(xy 138.651996 -67.740022) (xy 138.679366 -67.740485) (xy 138.733546 -67.748303) (xy 138.786049 -67.763792)
			(xy 138.835796 -67.786635) (xy 138.881763 -67.81636) (xy 138.902694 -67.834002) (xy 138.902948 -67.834256)
			(xy 138.91004 -67.839834) (xy 138.926953 -67.846084) (xy 138.935968 -67.846448) (xy 139.003024 -67.846448)
			(xy 139.012043 -67.846114) (xy 139.028961 -67.839852) (xy 139.036044 -67.834256) (xy 139.036044 -67.834002)
			(xy 139.036298 -67.834002) (xy 139.05722 -67.816351) (xy 139.103196 -67.786641) (xy 139.152946 -67.763807)
			(xy 139.205449 -67.748319) (xy 139.259626 -67.740494) (xy 139.286996 -67.740022) (xy 139.31331 -67.740485)
			(xy 139.365439 -67.74772) (xy 139.416082 -67.762039) (xy 139.464281 -67.783173) (xy 139.509125 -67.81072)
			(xy 139.549764 -67.84416) (xy 139.56792 -67.863212) (xy 139.575431 -67.870626) (xy 139.594719 -67.879143)
			(xy 139.605258 -67.879722) (xy 139.679934 -67.879722) (xy 139.69048 -67.879164) (xy 139.709776 -67.870649)
			(xy 139.717272 -67.863212) (xy 139.735451 -67.844179) (xy 139.776075 -67.81072) (xy 139.82091 -67.783157)
			(xy 139.869107 -67.762015) (xy 139.91975 -67.747693) (xy 139.971881 -67.740463) (xy 139.998196 -67.740022)
			(xy 140.02545 -67.740459) (xy 140.079404 -67.748216) (xy 140.131704 -67.763573) (xy 140.181286 -67.786218)
			(xy 140.22714 -67.815688) (xy 140.268334 -67.851385) (xy 140.304028 -67.89258) (xy 140.333495 -67.938437)
			(xy 140.356136 -67.988021) (xy 140.371489 -68.040322) (xy 140.379243 -68.094276) (xy 140.379704 -68.12153)
			(xy 140.379255 -68.148901) (xy 140.371433 -68.203081) (xy 140.35594 -68.255584) (xy 140.333094 -68.30533)
			(xy 140.303367 -68.351297) (xy 140.285724 -68.372228) (xy 140.28547 -68.372482) (xy 140.279881 -68.379567)
			(xy 140.273637 -68.396485) (xy 140.273278 -68.405502) (xy 140.273278 -68.472558) (xy 140.27366 -68.481572)
			(xy 140.279891 -68.498489) (xy 140.28547 -68.505578) (xy 140.285724 -68.505578) (xy 140.285724 -68.505832)
			(xy 140.303348 -68.526776) (xy 140.333062 -68.572746) (xy 140.3559 -68.62249) (xy 140.371395 -68.674988)
			(xy 140.379227 -68.729162) (xy 140.379704 -68.75653) (xy 140.37925 -68.783782) (xy 140.371489 -68.837731)
			(xy 140.35613 -68.890027) (xy 140.333485 -68.939604) (xy 140.304016 -68.985455) (xy 140.268321 -69.026645)
			(xy 140.227128 -69.062336) (xy 140.181275 -69.091802) (xy 140.131695 -69.114442) (xy 140.079398 -69.129797)
			(xy 140.025448 -69.137553) (xy 139.998196 -69.138038) (xy 139.971881 -69.137593) (xy 139.919751 -69.130356)
			(xy 139.869107 -69.116034) (xy 139.820907 -69.094898) (xy 139.776065 -69.067347) (xy 139.735427 -69.033902)
			(xy 139.717272 -69.014848) (xy 139.709756 -69.007439) (xy 139.690472 -68.998917) (xy 139.679934 -68.998338)
			(xy 139.605258 -68.998338) (xy 139.594709 -68.998874) (xy 139.575413 -69.007403) (xy 139.56792 -69.014848)
			(xy 139.549757 -69.033896) (xy 139.509128 -69.067352) (xy 139.464289 -69.094911) (xy 139.41609 -69.11605)
			(xy 139.365444 -69.13037) (xy 139.313312 -69.137597) (xy 139.286996 -69.138038) (xy 139.259625 -69.137589)
			(xy 139.205445 -69.12977) (xy 139.152941 -69.114277) (xy 139.103194 -69.091431) (xy 139.057229 -69.061702)
			(xy 139.036298 -69.044058) (xy 139.036044 -69.043804) (xy 139.028949 -69.03823) (xy 139.012039 -69.031976)
			(xy 139.003024 -69.031612) (xy 138.935968 -69.031612) (xy 138.926949 -69.031951) (xy 138.910032 -69.038211)
			(xy 138.902948 -69.043804) (xy 138.902948 -69.044058) (xy 138.902694 -69.044058) (xy 138.88177 -69.061707)
			(xy 138.835795 -69.091419) (xy 138.786046 -69.114253) (xy 138.733543 -69.129742) (xy 138.679366 -69.137566)
			(xy 138.651996 -69.138038) (xy 138.624746 -69.137526) (xy 138.570801 -69.12977) (xy 138.518508 -69.114416)
			(xy 138.468933 -69.091776) (xy 138.423084 -69.062312) (xy 138.381895 -69.026624) (xy 138.346203 -68.985437)
			(xy 138.316736 -68.93959) (xy 138.294093 -68.890016) (xy 138.278736 -68.837725) (xy 138.270976 -68.78378)
			(xy 138.270488 -68.75653) (xy 134.794375 -68.75653) (xy 134.788375 -68.769669) (xy 134.75891 -68.815518)
			(xy 134.723221 -68.856708) (xy 134.682033 -68.8924) (xy 134.636185 -68.921866) (xy 134.58661 -68.944509)
			(xy 134.534318 -68.959866) (xy 134.480372 -68.967625) (xy 134.453122 -68.968112) (xy 134.425752 -68.96763)
			(xy 134.371574 -68.959816) (xy 134.319071 -68.94433) (xy 134.269324 -68.921492) (xy 134.223356 -68.891771)
			(xy 134.202424 -68.874132) (xy 134.20217 -68.873878) (xy 134.195069 -68.868312) (xy 134.178163 -68.862054)
			(xy 134.16915 -68.861686) (xy 134.102094 -68.861686) (xy 134.093077 -68.862043) (xy 134.07616 -68.868291)
			(xy 134.069074 -68.873878) (xy 134.069074 -68.874132) (xy 134.06882 -68.874132) (xy 134.047895 -68.89178)
			(xy 134.00192 -68.92149) (xy 133.952171 -68.944323) (xy 133.899668 -68.959812) (xy 133.845492 -68.967639)
			(xy 133.818122 -68.968112) (xy 133.791809 -68.967626) (xy 133.739681 -68.960394) (xy 133.689039 -68.946079)
			(xy 133.64084 -68.92495) (xy 133.595996 -68.897407) (xy 133.555355 -68.863972) (xy 133.537198 -68.844922)
			(xy 133.529676 -68.837521) (xy 133.510396 -68.828995) (xy 133.49986 -68.828412) (xy 133.425184 -68.828412)
			(xy 133.414631 -68.828915) (xy 133.395336 -68.837468) (xy 133.387846 -68.844922) (xy 133.369714 -68.864001)
			(xy 133.329079 -68.897455) (xy 133.284233 -68.925011) (xy 133.236028 -68.946145) (xy 133.185377 -68.960457)
			(xy 133.133239 -68.967676) (xy 133.106922 -68.968112) (xy 133.07967 -68.967624) (xy 133.02572 -68.95987)
			(xy 132.973423 -68.944517) (xy 132.923843 -68.921878) (xy 132.87799 -68.892412) (xy 132.836797 -68.856721)
			(xy 132.801103 -68.815531) (xy 132.771635 -68.76968) (xy 132.748992 -68.720102) (xy 132.733635 -68.667805)
			(xy 132.725878 -68.613856) (xy 132.725414 -68.586604) (xy 129.116836 -68.586604) (xy 129.116836 -71.555864)
			(xy 135.294622 -71.555864) (xy 135.298693 -71.500242) (xy 135.310819 -71.445805) (xy 135.330742 -71.393714)
			(xy 135.358038 -71.345079) (xy 135.392124 -71.300936) (xy 135.432273 -71.262227) (xy 135.477631 -71.229776)
			(xy 135.527231 -71.204275) (xy 135.580015 -71.186268) (xy 135.634858 -71.176138) (xy 135.690592 -71.174101)
			(xy 135.746029 -71.180201) (xy 135.799986 -71.194307) (xy 135.851315 -71.216119) (xy 135.898921 -71.245173)
			(xy 135.941789 -71.280848) (xy 135.979006 -71.322385) (xy 136.009779 -71.368898) (xy 136.033451 -71.419395)
			(xy 136.049519 -71.472802) (xy 136.057639 -71.527978) (xy 136.058148 -71.555864) (xy 136.057639 -71.58375)
			(xy 136.0518 -71.623428) (xy 136.803636 -71.623428) (xy 136.807707 -71.567806) (xy 136.819833 -71.513369)
			(xy 136.839756 -71.461278) (xy 136.867052 -71.412643) (xy 136.901138 -71.3685) (xy 136.941287 -71.329791)
			(xy 136.986645 -71.29734) (xy 137.036245 -71.271839) (xy 137.089029 -71.253832) (xy 137.143872 -71.243702)
			(xy 137.199606 -71.241665) (xy 137.255043 -71.247765) (xy 137.309 -71.261871) (xy 137.360329 -71.283683)
			(xy 137.407935 -71.312737) (xy 137.450803 -71.348412) (xy 137.48802 -71.389949) (xy 137.518793 -71.436462)
			(xy 137.542465 -71.486959) (xy 137.558533 -71.540366) (xy 137.566653 -71.595542) (xy 137.567162 -71.623428)
			(xy 137.566653 -71.651314) (xy 137.558533 -71.70649) (xy 137.542465 -71.759897) (xy 137.518793 -71.810394)
			(xy 137.48802 -71.856907) (xy 137.450803 -71.898444) (xy 137.407935 -71.934119) (xy 137.360329 -71.963173)
			(xy 137.309 -71.984985) (xy 137.255043 -71.999091) (xy 137.199606 -72.005191) (xy 137.143872 -72.003154)
			(xy 137.089029 -71.993024) (xy 137.036245 -71.975017) (xy 136.986645 -71.949516) (xy 136.941287 -71.917065)
			(xy 136.901138 -71.878356) (xy 136.867052 -71.834213) (xy 136.839756 -71.785578) (xy 136.819833 -71.733487)
			(xy 136.807707 -71.67905) (xy 136.803636 -71.623428) (xy 136.0518 -71.623428) (xy 136.049519 -71.638926)
			(xy 136.033451 -71.692333) (xy 136.009779 -71.74283) (xy 135.979006 -71.789343) (xy 135.941789 -71.83088)
			(xy 135.898921 -71.866555) (xy 135.851315 -71.895609) (xy 135.799986 -71.917421) (xy 135.746029 -71.931527)
			(xy 135.690592 -71.937627) (xy 135.634858 -71.93559) (xy 135.580015 -71.92546) (xy 135.527231 -71.907453)
			(xy 135.477631 -71.881952) (xy 135.432273 -71.849501) (xy 135.392124 -71.810792) (xy 135.358038 -71.766649)
			(xy 135.330742 -71.718014) (xy 135.310819 -71.665923) (xy 135.298693 -71.611486) (xy 135.294622 -71.555864)
			(xy 129.116836 -71.555864) (xy 129.116836 -74.916538) (xy 129.117344 -74.92365) (xy 130.8862 -76.692506)
			(xy 130.891698 -76.697496) (xy 130.904863 -76.704346) (xy 130.912108 -76.705968) (xy 130.92176 -76.706984)
			(xy 131.61137 -76.706984) (xy 131.637458 -76.707468) (xy 131.688991 -76.715631) (xy 131.738611 -76.731762)
			(xy 131.785093 -76.755461) (xy 131.827293 -76.786145) (xy 131.846066 -76.804266) (xy 132.289804 -77.248004)
			(xy 132.307834 -77.266776) (xy 132.338409 -77.308894) (xy 132.36203 -77.355271) (xy 132.378119 -77.404767)
			(xy 132.38628 -77.456169) (xy 132.386832 -77.482192) (xy 132.386832 -78.17231) (xy 132.38861 -78.185264)
			(xy 132.390491 -78.191651) (xy 132.39705 -78.20323) (xy 132.401564 -78.208124) (xy 134.936738 -80.743044)
			(xy 135.065516 -80.871822) (xy 135.070596 -80.872584) (xy 140.459714 -80.872584) (xy 140.467842 -80.871822)
			(xy 140.46835 -80.871822) (xy 140.475868 -80.870219) (xy 140.489555 -80.863242) (xy 140.495274 -80.858106)
			(xy 141.70025 -79.65313) (xy 141.705225 -79.647697) (xy 141.712058 -79.634655) (xy 141.713712 -79.627476)
			(xy 141.713712 -79.626968) (xy 141.714728 -79.61757) (xy 141.714728 -68.013326) (xy 141.713966 -68.005198)
			(xy 141.713966 -68.004944) (xy 141.713712 -68.003674) (xy 141.711934 -67.993768) (xy 141.708886 -67.984116)
			(xy 141.707362 -67.980306) (xy 141.701012 -67.973448) (xy 141.693392 -67.966844) (xy 141.686788 -67.963034)
			(xy 141.673326 -67.956176) (xy 141.66215 -67.948556) (xy 141.640814 -67.928744) (xy 141.635345 -67.924503)
			(xy 141.622724 -67.918842) (xy 141.615922 -67.917568) (xy 141.603476 -67.917314) (xy 141.60246 -67.917314)
			(xy 141.600174 -67.917568) (xy 141.590166 -67.91847) (xy 141.57009 -67.919357) (xy 141.560042 -67.919346)
			(xy 141.534708 -67.918752) (xy 141.484529 -67.911682) (xy 141.43573 -67.898019) (xy 141.389174 -67.878006)
			(xy 141.345684 -67.851995) (xy 141.3256 -67.836542) (xy 141.325346 -67.836288) (xy 141.322298 -67.833748)
			(xy 141.316186 -67.830022) (xy 141.302521 -67.82578) (xy 141.295374 -67.825366) (xy 141.272006 -67.825366)
			(xy 141.266566 -67.825227) (xy 141.255931 -67.822925) (xy 141.250924 -67.820794) (xy 141.237208 -67.814444)
			(xy 141.232503 -67.812382) (xy 141.222522 -67.809956) (xy 141.217396 -67.809618) (xy 141.20876 -67.810126)
			(xy 141.20147 -67.811401) (xy 141.188033 -67.817587) (xy 141.182344 -67.822318) (xy 141.18209 -67.822572)
			(xy 141.16102 -67.840682) (xy 141.114628 -67.871248) (xy 141.064295 -67.89477) (xy 141.011086 -67.910749)
			(xy 140.956122 -67.918849) (xy 140.928344 -67.919346) (xy 140.927836 -67.919346) (xy 140.900579 -67.918886)
			(xy 140.846618 -67.911132) (xy 140.794311 -67.895777) (xy 140.744721 -67.873135) (xy 140.698859 -67.843665)
			(xy 140.657658 -67.807967) (xy 140.621957 -67.76677) (xy 140.592483 -67.72091) (xy 140.569835 -67.671323)
			(xy 140.554476 -67.619017) (xy 140.546717 -67.565057) (xy 140.546717 -67.510543) (xy 140.554476 -67.456583)
			(xy 140.569835 -67.404277) (xy 140.592483 -67.35469) (xy 140.621957 -67.30883) (xy 140.657658 -67.267633)
			(xy 140.698859 -67.231935) (xy 140.744721 -67.202465) (xy 140.794311 -67.179823) (xy 140.846618 -67.164468)
			(xy 140.900579 -67.156714) (xy 140.927836 -67.15633) (xy 140.928344 -67.15633) (xy 140.953971 -67.156757)
			(xy 141.00476 -67.16365) (xy 141.054165 -67.177292) (xy 141.101295 -67.197436) (xy 141.145297 -67.223719)
			(xy 141.16558 -67.239388) (xy 141.172184 -67.244468) (xy 141.18336 -67.248278) (xy 141.196822 -67.25031)
			(xy 141.216888 -67.25031) (xy 141.222896 -67.250482) (xy 141.234574 -67.253314) (xy 141.240002 -67.255898)
			(xy 141.240256 -67.256152) (xy 141.241272 -67.25666) (xy 141.242542 -67.257168) (xy 141.252448 -67.261994)
			(xy 141.263931 -67.266113) (xy 141.28822 -67.264275) (xy 141.29893 -67.258438) (xy 141.313154 -67.249294)
			(xy 141.316456 -67.2465) (xy 141.31798 -67.24523) (xy 141.318488 -67.244722) (xy 141.321536 -67.242182)
			(xy 141.326616 -67.237102) (xy 141.330251 -67.233278) (xy 141.336016 -67.224445) (xy 141.338046 -67.219576)
			(xy 141.339429 -67.215777) (xy 141.341082 -67.207863) (xy 141.341348 -67.203828) (xy 141.343888 -67.156076)
			(xy 141.343888 -67.155568) (xy 141.345412 -67.130422) (xy 141.34592 -67.11823) (xy 141.34211 -67.10807)
			(xy 141.340067 -67.103106) (xy 141.334164 -67.094143) (xy 141.330426 -67.09029) (xy 140.773404 -66.533268)
			(xy 140.770554 -66.530561) (xy 140.764177 -66.525964) (xy 140.760704 -66.524124) (xy 140.755276 -66.521545)
			(xy 140.743597 -66.518732) (xy 140.73759 -66.518536) (xy 137.710672 -66.518536) (xy 137.683218 -66.518111)
			(xy 137.62907 -66.509045) (xy 137.602976 -66.500502) (xy 137.602722 -66.500248) (xy 137.60196 -66.499994)
			(xy 137.600182 -66.499232) (xy 137.59942 -66.498978) (xy 137.597134 -66.497962) (xy 137.5791 -66.490596)
			(xy 137.483596 -66.424048) (xy 137.476738 -66.418206) (xy 136.987788 -65.929002) (xy 136.983978 -65.926716)
			(xy 136.982454 -65.9257) (xy 136.966749 -65.915677) (xy 136.93747 -65.892633) (xy 136.924034 -65.879726)
			(xy 136.923018 -65.87871) (xy 136.517888 -65.47358) (xy 136.50722 -65.46723) (xy 136.501378 -65.465452)
			(xy 136.47407 -65.456422) (xy 136.422327 -65.431309) (xy 136.374938 -65.398717) (xy 136.332976 -65.359382)
			(xy 136.297392 -65.314196) (xy 136.268992 -65.264182) (xy 136.248418 -65.210472) (xy 136.236137 -65.154284)
			(xy 136.232427 -65.096888) (xy 136.234424 -65.068196) (xy 136.234678 -65.066164) (xy 136.234678 -65.065402)
			(xy 136.235948 -65.052956) (xy 136.233154 -65.041526) (xy 136.231509 -65.036452) (xy 136.226393 -65.027094)
			(xy 136.222994 -65.022984) (xy 136.178798 -64.9732) (xy 136.17067 -64.964056) (xy 136.165974 -64.959715)
			(xy 136.154921 -64.953292) (xy 136.148826 -64.951356) (xy 136.148318 -64.951102) (xy 136.140444 -64.948816)
			(xy 135.615426 -64.948816) (xy 135.61182 -64.948877) (xy 135.604679 -64.949892) (xy 135.601202 -64.950848)
			(xy 135.59663 -64.952372) (xy 135.587486 -64.956182) (xy 134.560564 -65.983104) (xy 134.547102 -65.995804)
			(xy 134.546086 -65.99682) (xy 134.527487 -66.013707) (xy 134.486151 -66.042253) (xy 134.440989 -66.064251)
			(xy 134.393029 -66.079198) (xy 134.343366 -66.086753) (xy 134.318248 -66.087244) (xy 131.017518 -66.087244)
			(xy 131.013708 -66.089276) (xy 130.985218 -66.104275) (xy 130.924456 -66.125558) (xy 130.860987 -66.136361)
			(xy 130.828796 -66.137028) (xy 130.801544 -66.136542) (xy 130.747593 -66.128785) (xy 130.695296 -66.113428)
			(xy 130.645717 -66.090786) (xy 130.599865 -66.061318) (xy 130.558673 -66.025624) (xy 130.52298 -65.984432)
			(xy 130.493512 -65.938579) (xy 130.47087 -65.889) (xy 130.455515 -65.836703) (xy 130.447758 -65.782752)
			(xy 130.447758 -65.728248) (xy 130.455515 -65.674297) (xy 130.47087 -65.622) (xy 130.493512 -65.572421)
			(xy 130.52298 -65.526568) (xy 130.558673 -65.485376) (xy 130.599865 -65.449682) (xy 130.645717 -65.420214)
			(xy 130.695296 -65.397572) (xy 130.747593 -65.382215) (xy 130.801544 -65.374458) (xy 130.828796 -65.374012)
			(xy 130.860987 -65.374679) (xy 130.924456 -65.385477) (xy 130.985216 -65.406768) (xy 131.013708 -65.421764)
			(xy 131.017518 -65.423796) (xy 134.159752 -65.423796) (xy 134.168896 -65.423034) (xy 134.176387 -65.421405)
			(xy 134.189963 -65.414296) (xy 134.195566 -65.409064) (xy 135.165338 -64.439038) (xy 135.222234 -64.382142)
			(xy 135.241951 -64.363291) (xy 135.286373 -64.331636) (xy 135.310626 -64.31915) (xy 135.318246 -64.31534)
			(xy 135.896858 -63.736474) (xy 135.89762 -63.735458) (xy 135.917781 -63.715282) (xy 135.963857 -63.681672)
			(xy 136.015132 -63.656701) (xy 136.0424 -63.648336) (xy 136.045194 -63.647828) (xy 136.047988 -63.647066)
			(xy 136.068066 -63.642053) (xy 136.109086 -63.636575) (xy 136.129776 -63.636144) (xy 138.267694 -63.636144)
			(xy 138.269472 -63.636144) (xy 138.278496 -63.635479) (xy 138.29523 -63.628626) (xy 138.30853 -63.616376)
			(xy 138.312906 -63.608458) (xy 138.313668 -63.60668) (xy 138.314684 -63.604394) (xy 138.347704 -63.523368)
			(xy 138.349477 -63.518614) (xy 138.351272 -63.50863) (xy 138.35126 -63.503556) (xy 138.351082 -63.498652)
			(xy 138.349033 -63.489056) (xy 138.347196 -63.484506) (xy 138.347196 -63.484252) (xy 138.34364 -63.475616)
			(xy 138.33729 -63.461392) (xy 138.330686 -63.454534) (xy 138.330432 -63.45428) (xy 138.309956 -63.432722)
			(xy 138.275263 -63.384439) (xy 138.248476 -63.33136) (xy 138.230245 -63.27477) (xy 138.221008 -63.216037)
			(xy 138.22045 -63.18631) (xy 138.220935 -63.159057) (xy 138.22869 -63.105106) (xy 138.244044 -63.052808)
			(xy 138.266684 -63.003227) (xy 138.296149 -62.957372) (xy 138.33184 -62.916177) (xy 138.37303 -62.880481)
			(xy 138.418881 -62.851009) (xy 138.468459 -62.828362) (xy 138.520755 -62.813001) (xy 138.574705 -62.805239)
			(xy 138.601958 -62.804802) (xy 138.602466 -62.804802) (xy 138.628093 -62.80523) (xy 138.67888 -62.812125)
			(xy 138.728285 -62.825769) (xy 138.775413 -62.845914) (xy 138.819415 -62.872198) (xy 138.839702 -62.88786)
			(xy 138.846306 -62.89294) (xy 138.857482 -62.89675) (xy 138.870944 -62.898782) (xy 138.892788 -62.898782)
			(xy 138.896394 -62.898844) (xy 138.903534 -62.899862) (xy 138.907012 -62.900814) (xy 138.910568 -62.901576)
			(xy 138.964416 -62.901576) (xy 138.973022 -62.901248) (xy 138.989262 -62.895547) (xy 138.996166 -62.8904)
			(xy 138.99642 -62.890146) (xy 138.997182 -62.889638) (xy 139.001754 -62.886082) (xy 139.004294 -62.88405)
			(xy 139.005056 -62.883288) (xy 139.027154 -62.86754) (xy 139.02817 -62.867032) (xy 139.036044 -62.861698)
			(xy 139.0396 -62.859666) (xy 139.056238 -62.849892) (xy 139.091102 -62.833351) (xy 139.109196 -62.826646)
			(xy 139.109958 -62.826392) (xy 139.113768 -62.825122) (xy 139.138792 -62.817066) (xy 139.190412 -62.807121)
			(xy 139.216638 -62.80531) (xy 139.236196 -62.804802) (xy 139.236958 -62.804802) (xy 139.25296 -62.805056)
			(xy 139.257278 -62.80531) (xy 139.286687 -62.807451) (xy 139.344376 -62.819647) (xy 139.399508 -62.84056)
			(xy 139.450772 -62.869692) (xy 139.474194 -62.887606) (xy 139.474448 -62.88786) (xy 139.477496 -62.8904)
			(xy 139.483607 -62.89413) (xy 139.497272 -62.898377) (xy 139.50442 -62.898782) (xy 139.527788 -62.898782)
			(xy 139.533229 -62.89892) (xy 139.543864 -62.901219) (xy 139.54887 -62.903354) (xy 139.562586 -62.909704)
			(xy 139.567291 -62.911768) (xy 139.577271 -62.914198) (xy 139.582398 -62.91453) (xy 139.591034 -62.914022)
			(xy 139.598323 -62.912746) (xy 139.611757 -62.906556) (xy 139.61745 -62.90183) (xy 139.617704 -62.901576)
			(xy 139.638774 -62.883469) (xy 139.685168 -62.852911) (xy 139.735502 -62.829399) (xy 139.788711 -62.81343)
			(xy 139.843673 -62.805343) (xy 139.87145 -62.804802) (xy 139.871958 -62.804802) (xy 139.899213 -62.805262)
			(xy 139.953167 -62.813015) (xy 140.00547 -62.828367) (xy 140.055055 -62.851007) (xy 140.100912 -62.880474)
			(xy 140.142109 -62.916168) (xy 140.177806 -62.957362) (xy 140.207277 -63.003217) (xy 140.229922 -63.0528)
			(xy 140.245279 -63.105101) (xy 140.253035 -63.159055) (xy 140.253466 -63.18631) (xy 140.252896 -63.216037)
			(xy 140.243669 -63.274769) (xy 140.225438 -63.331358) (xy 140.198648 -63.384433) (xy 140.163945 -63.432707)
			(xy 140.143484 -63.45428) (xy 140.14323 -63.454534) (xy 140.137134 -63.460884) (xy 140.130276 -63.475616)
			(xy 140.12926 -63.478156) (xy 140.125196 -63.488316) (xy 140.123109 -63.495998) (xy 140.123251 -63.511906)
			(xy 140.12545 -63.519558) (xy 140.141452 -63.559944) (xy 140.143484 -63.565024) (xy 140.143484 -63.565532)
			(xy 140.160248 -63.606172) (xy 140.16101 -63.60795) (xy 140.165339 -63.615741) (xy 140.178255 -63.628003)
			(xy 140.19457 -63.635144) (xy 140.203428 -63.636144) (xy 141.401292 -63.636144) (xy 141.409368 -63.634857)
			(xy 141.424142 -63.627867) (xy 141.430248 -63.622428) (xy 141.497558 -63.555118) (xy 141.502546 -63.549619)
			(xy 141.509393 -63.536453) (xy 141.51102 -63.52921) (xy 141.512036 -63.519558) (xy 141.512036 -58.181494)
			(xy 141.511874 -58.175483) (xy 141.509061 -58.163795) (xy 141.506448 -58.15838) (xy 141.504607 -58.154907)
			(xy 141.50001 -58.148532) (xy 141.497304 -58.14568) (xy 141.175232 -57.823608) (xy 141.159761 -57.807606)
			(xy 141.132928 -57.772093) (xy 141.111252 -57.733218) (xy 141.102842 -57.71261) (xy 141.101826 -57.709816)
			(xy 141.095984 -57.700418) (xy 141.09573 -57.69991) (xy 141.080327 -57.678514) (xy 141.05578 -57.63186)
			(xy 141.038923 -57.58191) (xy 141.03018 -57.529922) (xy 141.029436 -57.503568) (xy 141.029436 -56.577992)
			(xy 141.02536 -56.572858) (xy 141.015061 -56.564753) (xy 141.009116 -56.56199) (xy 140.91666 -56.528208)
			(xy 140.909286 -56.525733) (xy 140.89376 -56.524943) (xy 140.88618 -56.526684) (xy 140.878814 -56.528716)
			(xy 140.865606 -56.537098) (xy 140.860526 -56.543194) (xy 140.84227 -56.564011) (xy 140.800785 -56.600679)
			(xy 140.754444 -56.630978) (xy 140.704216 -56.654274) (xy 140.651152 -56.67008) (xy 140.596364 -56.678065)
			(xy 140.56868 -56.678576) (xy 140.541432 -56.678088) (xy 140.487491 -56.67033) (xy 140.435203 -56.654975)
			(xy 140.385633 -56.632334) (xy 140.339789 -56.60287) (xy 140.298604 -56.567182) (xy 140.262918 -56.525995)
			(xy 140.233456 -56.48015) (xy 140.210818 -56.430578) (xy 140.195465 -56.378289) (xy 140.18771 -56.324348)
			(xy 140.18771 -56.269852) (xy 140.195465 -56.215911) (xy 140.210818 -56.163622) (xy 140.233456 -56.11405)
			(xy 140.262918 -56.068205) (xy 140.298604 -56.027018) (xy 140.339789 -55.99133) (xy 140.385633 -55.961866)
			(xy 140.435203 -55.939225) (xy 140.487491 -55.92387) (xy 140.541432 -55.916112) (xy 140.56868 -55.91556)
			(xy 140.595537 -55.916016) (xy 140.64872 -55.92354) (xy 140.700324 -55.938444) (xy 140.74933 -55.960432)
			(xy 140.794771 -55.989072) (xy 140.83575 -56.023797) (xy 140.853922 -56.043576) (xy 140.854176 -56.04383)
			(xy 140.86078 -56.051196) (xy 140.876528 -56.06161) (xy 140.885769 -56.066308) (xy 140.906346 -56.068679)
			(xy 140.916406 -56.066182) (xy 140.973048 -56.045608) (xy 141.006322 -56.033416) (xy 141.013125 -56.030668)
			(xy 141.024873 -56.021889) (xy 141.029436 -56.016144) (xy 141.029436 -55.113428) (xy 141.02992 -55.08734)
			(xy 141.038083 -55.035806) (xy 141.054211 -54.986185) (xy 141.077908 -54.9397) (xy 141.10859 -54.897498)
			(xy 141.126718 -54.878732) (xy 143.050768 -52.954682) (xy 143.057118 -52.944014) (xy 143.058896 -52.938172)
			(xy 143.067331 -52.912592) (xy 143.090389 -52.863915) (xy 143.120061 -52.818964) (xy 143.155758 -52.77863)
			(xy 143.196771 -52.743716) (xy 143.242285 -52.714913) (xy 143.291396 -52.692796) (xy 143.343128 -52.677802)
			(xy 143.396455 -52.67023) (xy 143.450317 -52.67023) (xy 143.503644 -52.677802) (xy 143.555376 -52.692796)
			(xy 143.604487 -52.714913) (xy 143.650001 -52.743716) (xy 143.691014 -52.77863) (xy 143.726711 -52.818964)
			(xy 143.756383 -52.863915) (xy 143.779441 -52.912592) (xy 143.787876 -52.938172) (xy 143.789654 -52.944014)
			(xy 143.796004 -52.954682) (xy 144.337878 -53.496556) (xy 148.233541 -53.496556) (xy 148.233541 -53.442044)
			(xy 148.241299 -53.388088) (xy 148.256658 -53.335785) (xy 148.279304 -53.286201) (xy 148.308777 -53.240344)
			(xy 148.344476 -53.199149) (xy 148.385674 -53.163454) (xy 148.431534 -53.133986) (xy 148.481121 -53.111344)
			(xy 148.533425 -53.095991) (xy 148.587382 -53.088238) (xy 148.614638 -53.087778) (xy 148.642008 -53.088261)
			(xy 148.696187 -53.096072) (xy 148.748691 -53.111556) (xy 148.798438 -53.134394) (xy 148.844405 -53.164117)
			(xy 148.865336 -53.181758) (xy 148.86559 -53.182012) (xy 148.872674 -53.187602) (xy 148.889593 -53.193846)
			(xy 148.89861 -53.194204) (xy 148.965666 -53.194204) (xy 148.974681 -53.19383) (xy 148.991598 -53.187594)
			(xy 148.998686 -53.182012) (xy 148.998686 -53.181758) (xy 148.99894 -53.181758) (xy 149.019878 -53.164127)
			(xy 149.06585 -53.134415) (xy 149.115596 -53.111578) (xy 149.168095 -53.096085) (xy 149.222269 -53.088254)
			(xy 149.249638 -53.087778) (xy 149.276886 -53.088295) (xy 149.330828 -53.096055) (xy 149.383116 -53.111413)
			(xy 149.432687 -53.134056) (xy 149.478531 -53.163522) (xy 149.519715 -53.199212) (xy 149.555401 -53.2404)
			(xy 149.584863 -53.286247) (xy 149.6075 -53.335819) (xy 149.622853 -53.388109) (xy 149.630608 -53.442052)
			(xy 149.630608 -53.496548) (xy 149.622853 -53.550491) (xy 149.6075 -53.602781) (xy 149.584863 -53.652353)
			(xy 149.555401 -53.6982) (xy 149.519715 -53.739388) (xy 149.478531 -53.775078) (xy 149.432687 -53.804544)
			(xy 149.383116 -53.827187) (xy 149.330828 -53.842545) (xy 149.276886 -53.850305) (xy 149.249638 -53.850794)
			(xy 149.222269 -53.850307) (xy 149.16809 -53.842495) (xy 149.115587 -53.82701) (xy 149.06584 -53.804173)
			(xy 149.019872 -53.774453) (xy 148.99894 -53.756814) (xy 148.998686 -53.75656) (xy 148.991611 -53.750957)
			(xy 148.974685 -53.744721) (xy 148.965666 -53.744368) (xy 148.89861 -53.744368) (xy 148.889594 -53.744737)
			(xy 148.872678 -53.750977) (xy 148.86559 -53.75656) (xy 148.86559 -53.756814) (xy 148.865336 -53.756814)
			(xy 148.844403 -53.774452) (xy 148.79843 -53.804163) (xy 148.748683 -53.826999) (xy 148.696183 -53.842491)
			(xy 148.642007 -53.85032) (xy 148.614638 -53.850794) (xy 148.587382 -53.850362) (xy 148.533425 -53.842609)
			(xy 148.481121 -53.827256) (xy 148.431534 -53.804614) (xy 148.385674 -53.775146) (xy 148.344476 -53.739451)
			(xy 148.308777 -53.698256) (xy 148.279304 -53.652399) (xy 148.256658 -53.602815) (xy 148.241299 -53.550512)
			(xy 148.233541 -53.496556) (xy 144.337878 -53.496556) (xy 144.456658 -53.615336) (xy 144.474773 -53.634115)
			(xy 144.505463 -53.676311) (xy 144.529167 -53.722792) (xy 144.5453 -53.772411) (xy 144.553465 -53.823944)
			(xy 144.55394 -53.850032) (xy 144.55394 -54.912768) (xy 144.554399 -54.922403) (xy 144.561572 -54.940295)
			(xy 144.56791 -54.947566) (xy 144.570196 -54.949852) (xy 144.613495 -54.989055) (xy 146.001145 -54.989055)
			(xy 146.001145 -54.934545) (xy 146.008903 -54.88059) (xy 146.024261 -54.828288) (xy 146.046906 -54.778704)
			(xy 146.076378 -54.732848) (xy 146.112076 -54.691654) (xy 146.153274 -54.655959) (xy 146.199132 -54.626491)
			(xy 146.248718 -54.60385) (xy 146.301021 -54.588496) (xy 146.354977 -54.580743) (xy 146.382232 -54.580282)
			(xy 146.410324 -54.580751) (xy 146.465903 -54.588983) (xy 146.519672 -54.605279) (xy 146.57047 -54.629286)
			(xy 146.617196 -54.660484) (xy 146.658841 -54.6982) (xy 146.694502 -54.741616) (xy 146.709384 -54.765448)
			(xy 146.714718 -54.774338) (xy 146.731736 -54.78653) (xy 146.824954 -54.80685) (xy 146.845528 -54.802532)
			(xy 146.854164 -54.79669) (xy 146.878235 -54.780702) (xy 146.930164 -54.755357) (xy 146.98532 -54.738128)
			(xy 147.042442 -54.729409) (xy 147.071334 -54.728872) (xy 147.098585 -54.729346) (xy 147.152532 -54.737107)
			(xy 147.204826 -54.752465) (xy 147.254402 -54.775109) (xy 147.300251 -54.804577) (xy 147.341441 -54.840269)
			(xy 147.377132 -54.88146) (xy 147.406598 -54.92731) (xy 147.42924 -54.976887) (xy 147.444596 -55.029181)
			(xy 147.452355 -55.083129) (xy 147.452842 -55.11038) (xy 147.452378 -55.13775) (xy 147.444562 -55.19193)
			(xy 147.429073 -55.244434) (xy 147.406231 -55.294181) (xy 147.376504 -55.340147) (xy 147.358862 -55.361078)
			(xy 147.358608 -55.361332) (xy 147.353045 -55.368435) (xy 147.346784 -55.385339) (xy 147.346416 -55.394352)
			(xy 147.346416 -55.461408) (xy 147.346766 -55.470426) (xy 147.353018 -55.487343) (xy 147.358608 -55.494428)
			(xy 147.358862 -55.494428) (xy 147.358862 -55.494682) (xy 147.376484 -55.51563) (xy 147.40621 -55.561595)
			(xy 147.429057 -55.611339) (xy 147.444555 -55.663839) (xy 147.452386 -55.718015) (xy 147.452388 -55.772755)
			(xy 147.444562 -55.826932) (xy 147.429068 -55.879433) (xy 147.406225 -55.929178) (xy 147.376502 -55.975146)
			(xy 147.358862 -55.996078) (xy 147.358608 -55.996332) (xy 147.353045 -56.003435) (xy 147.346784 -56.020339)
			(xy 147.346416 -56.029352) (xy 147.346416 -56.096408) (xy 147.346766 -56.105426) (xy 147.353018 -56.122343)
			(xy 147.358608 -56.129428) (xy 147.358862 -56.129428) (xy 147.358862 -56.129682) (xy 147.3765 -56.150615)
			(xy 147.406213 -56.196587) (xy 147.42905 -56.246334) (xy 147.444541 -56.298835) (xy 147.452369 -56.353011)
			(xy 147.452842 -56.38038) (xy 147.452356 -56.407631) (xy 147.4446 -56.461579) (xy 147.429245 -56.513874)
			(xy 147.406603 -56.563451) (xy 147.377137 -56.609301) (xy 147.341446 -56.650492) (xy 147.300255 -56.686183)
			(xy 147.254405 -56.715649) (xy 147.204828 -56.738291) (xy 147.152533 -56.753646) (xy 147.098585 -56.761402)
			(xy 147.044083 -56.761402) (xy 146.990135 -56.753646) (xy 146.93784 -56.738291) (xy 146.888263 -56.715649)
			(xy 146.842413 -56.686183) (xy 146.801222 -56.650492) (xy 146.765531 -56.609301) (xy 146.736065 -56.563451)
			(xy 146.713423 -56.513874) (xy 146.698068 -56.461579) (xy 146.690312 -56.407631) (xy 146.689826 -56.38038)
			(xy 146.690274 -56.353009) (xy 146.698095 -56.298829) (xy 146.713588 -56.246325) (xy 146.736434 -56.196579)
			(xy 146.766163 -56.150613) (xy 146.783806 -56.129682) (xy 146.78406 -56.129428) (xy 146.789648 -56.122343)
			(xy 146.795892 -56.105425) (xy 146.796252 -56.096408) (xy 146.796252 -56.029352) (xy 146.795881 -56.020336)
			(xy 146.789644 -56.003419) (xy 146.78406 -55.996332) (xy 146.783806 -55.996332) (xy 146.783806 -55.996078)
			(xy 146.766147 -55.975161) (xy 146.736424 -55.92919) (xy 146.713581 -55.879441) (xy 146.698087 -55.826937)
			(xy 146.690261 -55.772756) (xy 146.690263 -55.718014) (xy 146.698094 -55.663834) (xy 146.713592 -55.611331)
			(xy 146.736439 -55.561584) (xy 146.766165 -55.515615) (xy 146.783806 -55.494682) (xy 146.78406 -55.494428)
			(xy 146.789648 -55.487343) (xy 146.795892 -55.470425) (xy 146.796252 -55.461408) (xy 146.796252 -55.394352)
			(xy 146.795881 -55.385336) (xy 146.789644 -55.368419) (xy 146.78406 -55.361332) (xy 146.783806 -55.360824)
			(xy 146.772863 -55.348089) (xy 146.753021 -55.320998) (xy 146.744182 -55.306722) (xy 146.738848 -55.297832)
			(xy 146.72183 -55.28564) (xy 146.628612 -55.26532) (xy 146.608038 -55.269638) (xy 146.599402 -55.27548)
			(xy 146.575338 -55.291479) (xy 146.523407 -55.316823) (xy 146.468249 -55.334049) (xy 146.411125 -55.342764)
			(xy 146.382232 -55.343298) (xy 146.354977 -55.342857) (xy 146.301021 -55.335104) (xy 146.248718 -55.31975)
			(xy 146.199132 -55.297109) (xy 146.153274 -55.267641) (xy 146.112076 -55.231946) (xy 146.076378 -55.190752)
			(xy 146.046906 -55.144896) (xy 146.024261 -55.095312) (xy 146.008903 -55.04301) (xy 146.001145 -54.989055)
			(xy 144.613495 -54.989055) (xy 144.626584 -55.000906) (xy 144.63395 -55.006494) (xy 144.640065 -55.009976)
			(xy 144.653589 -55.013843) (xy 144.66062 -55.014114) (xy 144.665446 -55.014114) (xy 144.667732 -55.01386)
			(xy 144.704816 -55.012082) (xy 144.705324 -55.012082) (xy 144.712436 -55.012082) (xy 144.742356 -55.01318)
			(xy 144.80132 -55.023547) (xy 144.85794 -55.043) (xy 144.910825 -55.071062) (xy 144.958675 -55.107042)
			(xy 144.979898 -55.12816) (xy 144.98701 -55.135526) (xy 145.01622 -55.148226) (xy 145.020374 -55.149782)
			(xy 145.029061 -55.151571) (xy 145.033492 -55.151782) (xy 145.088864 -55.151782) (xy 145.10131 -55.149242)
			(xy 145.107152 -55.148226) (xy 145.135854 -55.135526) (xy 145.142712 -55.128414) (xy 145.160741 -55.110347)
			(xy 145.200791 -55.078704) (xy 145.244703 -55.052688) (xy 145.291695 -55.032761) (xy 145.340924 -55.019282)
			(xy 145.391511 -55.012491) (xy 145.417032 -55.012082) (xy 145.444282 -55.01257) (xy 145.498228 -55.02033)
			(xy 145.55052 -55.035689) (xy 145.600095 -55.058332) (xy 145.645943 -55.0878) (xy 145.68713 -55.123493)
			(xy 145.722819 -55.164683) (xy 145.752283 -55.210533) (xy 145.774922 -55.26011) (xy 145.790276 -55.312403)
			(xy 145.798032 -55.366349) (xy 145.798032 -55.420851) (xy 145.790276 -55.474797) (xy 145.774922 -55.52709)
			(xy 145.752283 -55.576667) (xy 145.722819 -55.622517) (xy 145.68713 -55.663707) (xy 145.645943 -55.6994)
			(xy 145.600095 -55.728868) (xy 145.55052 -55.751511) (xy 145.498228 -55.76687) (xy 145.444282 -55.77463)
			(xy 145.417032 -55.775098) (xy 145.391545 -55.774669) (xy 145.341026 -55.767874) (xy 145.291862 -55.754413)
			(xy 145.244927 -55.734527) (xy 145.201057 -55.708569) (xy 145.161034 -55.677002) (xy 145.142966 -55.65902)
			(xy 145.135854 -55.651654) (xy 145.106644 -55.638954) (xy 145.10249 -55.637401) (xy 145.093802 -55.635619)
			(xy 145.089372 -55.635398) (xy 145.04035 -55.635398) (xy 145.03019 -55.636414) (xy 145.019268 -55.6387)
			(xy 145.01368 -55.639716) (xy 144.98701 -55.651654) (xy 144.980152 -55.65902) (xy 144.960459 -55.678639)
			(xy 144.916408 -55.71254) (xy 144.867902 -55.739689) (xy 144.81597 -55.75951) (xy 144.761711 -55.771584)
			(xy 144.734026 -55.774082) (xy 144.724628 -55.774844) (xy 144.715992 -55.778908) (xy 144.704054 -55.786782)
			(xy 144.677892 -55.813198) (xy 144.672088 -55.820411) (xy 144.665582 -55.837729) (xy 144.665192 -55.84698)
			(xy 144.665192 -57.48528) (xy 146.70608 -57.48528) (xy 146.710151 -57.429658) (xy 146.722277 -57.375221)
			(xy 146.7422 -57.32313) (xy 146.769496 -57.274495) (xy 146.803582 -57.230352) (xy 146.843731 -57.191643)
			(xy 146.889089 -57.159192) (xy 146.938689 -57.133691) (xy 146.991473 -57.115684) (xy 147.046316 -57.105554)
			(xy 147.10205 -57.103517) (xy 147.157487 -57.109617) (xy 147.211444 -57.123723) (xy 147.262773 -57.145535)
			(xy 147.310379 -57.174589) (xy 147.353247 -57.210264) (xy 147.390464 -57.251801) (xy 147.421237 -57.298314)
			(xy 147.444909 -57.348811) (xy 147.460977 -57.402218) (xy 147.469097 -57.457394) (xy 147.469606 -57.48528)
			(xy 147.469097 -57.513166) (xy 147.460977 -57.568342) (xy 147.444909 -57.621749) (xy 147.421237 -57.672246)
			(xy 147.390464 -57.718759) (xy 147.353247 -57.760296) (xy 147.310379 -57.795971) (xy 147.262773 -57.825025)
			(xy 147.211444 -57.846837) (xy 147.157487 -57.860943) (xy 147.10205 -57.867043) (xy 147.046316 -57.865006)
			(xy 146.991473 -57.854876) (xy 146.938689 -57.836869) (xy 146.889089 -57.811368) (xy 146.843731 -57.778917)
			(xy 146.803582 -57.740208) (xy 146.769496 -57.696065) (xy 146.7422 -57.64743) (xy 146.722277 -57.595339)
			(xy 146.710151 -57.540902) (xy 146.70608 -57.48528) (xy 144.665192 -57.48528) (xy 144.665192 -58.561224)
			(xy 148.662388 -58.561224) (xy 148.666459 -58.505602) (xy 148.678585 -58.451165) (xy 148.698508 -58.399074)
			(xy 148.725804 -58.350439) (xy 148.75989 -58.306296) (xy 148.800039 -58.267587) (xy 148.845397 -58.235136)
			(xy 148.894997 -58.209635) (xy 148.947781 -58.191628) (xy 149.002624 -58.181498) (xy 149.058358 -58.179461)
			(xy 149.113795 -58.185561) (xy 149.167752 -58.199667) (xy 149.219081 -58.221479) (xy 149.266687 -58.250533)
			(xy 149.309555 -58.286208) (xy 149.346772 -58.327745) (xy 149.377545 -58.374258) (xy 149.401217 -58.424755)
			(xy 149.417285 -58.478162) (xy 149.425405 -58.533338) (xy 149.425914 -58.561224) (xy 149.425405 -58.58911)
			(xy 149.417285 -58.644286) (xy 149.401217 -58.697693) (xy 149.377545 -58.74819) (xy 149.346772 -58.794703)
			(xy 149.309555 -58.83624) (xy 149.266687 -58.871915) (xy 149.219081 -58.900969) (xy 149.167752 -58.922781)
			(xy 149.113795 -58.936887) (xy 149.058358 -58.942987) (xy 149.002624 -58.94095) (xy 148.947781 -58.93082)
			(xy 148.894997 -58.912813) (xy 148.845397 -58.887312) (xy 148.800039 -58.854861) (xy 148.75989 -58.816152)
			(xy 148.725804 -58.772009) (xy 148.698508 -58.723374) (xy 148.678585 -58.671283) (xy 148.666459 -58.616846)
			(xy 148.662388 -58.561224) (xy 144.665192 -58.561224) (xy 144.665192 -59.174634) (xy 147.193252 -59.174634)
			(xy 147.197323 -59.119012) (xy 147.209449 -59.064575) (xy 147.229372 -59.012484) (xy 147.256668 -58.963849)
			(xy 147.290754 -58.919706) (xy 147.330903 -58.880997) (xy 147.376261 -58.848546) (xy 147.425861 -58.823045)
			(xy 147.478645 -58.805038) (xy 147.533488 -58.794908) (xy 147.589222 -58.792871) (xy 147.644659 -58.798971)
			(xy 147.698616 -58.813077) (xy 147.749945 -58.834889) (xy 147.797551 -58.863943) (xy 147.840419 -58.899618)
			(xy 147.877636 -58.941155) (xy 147.908409 -58.987668) (xy 147.932081 -59.038165) (xy 147.948149 -59.091572)
			(xy 147.956269 -59.146748) (xy 147.956778 -59.174634) (xy 147.956269 -59.20252) (xy 147.948149 -59.257696)
			(xy 147.932081 -59.311103) (xy 147.908409 -59.3616) (xy 147.877636 -59.408113) (xy 147.840419 -59.44965)
			(xy 147.797551 -59.485325) (xy 147.749945 -59.514379) (xy 147.698616 -59.536191) (xy 147.644659 -59.550297)
			(xy 147.589222 -59.556397) (xy 147.533488 -59.55436) (xy 147.478645 -59.54423) (xy 147.425861 -59.526223)
			(xy 147.376261 -59.500722) (xy 147.330903 -59.468271) (xy 147.290754 -59.429562) (xy 147.256668 -59.385419)
			(xy 147.229372 -59.336784) (xy 147.209449 -59.284693) (xy 147.197323 -59.230256) (xy 147.193252 -59.174634)
			(xy 144.665192 -59.174634) (xy 144.665192 -59.643772) (xy 144.664755 -59.653836) (xy 144.657022 -59.672421)
			(xy 144.650206 -59.67984) (xy 144.568672 -59.761374) (xy 144.565963 -59.764223) (xy 144.561364 -59.770598)
			(xy 144.559528 -59.774074) (xy 144.556947 -59.779501) (xy 144.554129 -59.791181) (xy 144.55394 -59.797188)
			(xy 144.55394 -60.633356) (xy 149.897082 -60.633356) (xy 149.901153 -60.577734) (xy 149.913279 -60.523297)
			(xy 149.933202 -60.471206) (xy 149.960498 -60.422571) (xy 149.994584 -60.378428) (xy 150.034733 -60.339719)
			(xy 150.080091 -60.307268) (xy 150.129691 -60.281767) (xy 150.182475 -60.26376) (xy 150.237318 -60.25363)
			(xy 150.293052 -60.251593) (xy 150.348489 -60.257693) (xy 150.402446 -60.271799) (xy 150.453775 -60.293611)
			(xy 150.501381 -60.322665) (xy 150.544249 -60.35834) (xy 150.581466 -60.399877) (xy 150.612239 -60.44639)
			(xy 150.635911 -60.496887) (xy 150.651979 -60.550294) (xy 150.660099 -60.60547) (xy 150.660608 -60.633356)
			(xy 150.660099 -60.661242) (xy 150.651979 -60.716418) (xy 150.635911 -60.769825) (xy 150.612239 -60.820322)
			(xy 150.581466 -60.866835) (xy 150.544249 -60.908372) (xy 150.501381 -60.944047) (xy 150.453775 -60.973101)
			(xy 150.402446 -60.994913) (xy 150.348489 -61.009019) (xy 150.293052 -61.015119) (xy 150.237318 -61.013082)
			(xy 150.182475 -61.002952) (xy 150.129691 -60.984945) (xy 150.080091 -60.959444) (xy 150.034733 -60.926993)
			(xy 149.994584 -60.888284) (xy 149.960498 -60.844141) (xy 149.933202 -60.795506) (xy 149.913279 -60.743415)
			(xy 149.901153 -60.688978) (xy 149.897082 -60.633356) (xy 144.55394 -60.633356) (xy 144.55394 -61.487812)
			(xy 148.404578 -61.487812) (xy 148.408649 -61.43219) (xy 148.420775 -61.377753) (xy 148.440698 -61.325662)
			(xy 148.467994 -61.277027) (xy 148.50208 -61.232884) (xy 148.542229 -61.194175) (xy 148.587587 -61.161724)
			(xy 148.637187 -61.136223) (xy 148.689971 -61.118216) (xy 148.744814 -61.108086) (xy 148.800548 -61.106049)
			(xy 148.855985 -61.112149) (xy 148.909942 -61.126255) (xy 148.961271 -61.148067) (xy 149.008877 -61.177121)
			(xy 149.051745 -61.212796) (xy 149.088962 -61.254333) (xy 149.119735 -61.300846) (xy 149.143407 -61.351343)
			(xy 149.159475 -61.40475) (xy 149.167595 -61.459926) (xy 149.168104 -61.487812) (xy 149.167595 -61.515698)
			(xy 149.159475 -61.570874) (xy 149.143407 -61.624281) (xy 149.119735 -61.674778) (xy 149.088962 -61.721291)
			(xy 149.051745 -61.762828) (xy 149.008877 -61.798503) (xy 148.961271 -61.827557) (xy 148.909942 -61.849369)
			(xy 148.855985 -61.863475) (xy 148.800548 -61.869575) (xy 148.744814 -61.867538) (xy 148.689971 -61.857408)
			(xy 148.637187 -61.839401) (xy 148.587587 -61.8139) (xy 148.542229 -61.781449) (xy 148.50208 -61.74274)
			(xy 148.467994 -61.698597) (xy 148.440698 -61.649962) (xy 148.420775 -61.597871) (xy 148.408649 -61.543434)
			(xy 148.404578 -61.487812) (xy 144.55394 -61.487812) (xy 144.55394 -61.783214) (xy 144.553453 -61.809301)
			(xy 144.545284 -61.860831) (xy 144.529149 -61.910447) (xy 144.505447 -61.956926) (xy 144.474762 -61.999121)
			(xy 144.456658 -62.01791) (xy 144.353534 -62.121034) (xy 146.342352 -62.121034) (xy 146.346423 -62.065412)
			(xy 146.358549 -62.010975) (xy 146.378472 -61.958884) (xy 146.405768 -61.910249) (xy 146.439854 -61.866106)
			(xy 146.480003 -61.827397) (xy 146.525361 -61.794946) (xy 146.574961 -61.769445) (xy 146.627745 -61.751438)
			(xy 146.682588 -61.741308) (xy 146.738322 -61.739271) (xy 146.793759 -61.745371) (xy 146.847716 -61.759477)
			(xy 146.899045 -61.781289) (xy 146.946651 -61.810343) (xy 146.989519 -61.846018) (xy 147.026736 -61.887555)
			(xy 147.057509 -61.934068) (xy 147.081181 -61.984565) (xy 147.097249 -62.037972) (xy 147.105369 -62.093148)
			(xy 147.105878 -62.121034) (xy 147.105369 -62.14892) (xy 147.097249 -62.204096) (xy 147.081181 -62.257503)
			(xy 147.057509 -62.308) (xy 147.026736 -62.354513) (xy 146.989519 -62.39605) (xy 146.946651 -62.431725)
			(xy 146.899045 -62.460779) (xy 146.847716 -62.482591) (xy 146.793759 -62.496697) (xy 146.738322 -62.502797)
			(xy 146.682588 -62.50076) (xy 146.627745 -62.49063) (xy 146.574961 -62.472623) (xy 146.525361 -62.447122)
			(xy 146.480003 -62.414671) (xy 146.439854 -62.375962) (xy 146.405768 -62.331819) (xy 146.378472 -62.283184)
			(xy 146.358549 -62.231093) (xy 146.346423 -62.176656) (xy 146.342352 -62.121034) (xy 144.353534 -62.121034)
			(xy 143.89989 -62.574678) (xy 143.899467 -62.578354) (xy 143.899595 -62.585751) (xy 143.900144 -62.58941)
			(xy 143.920718 -62.664594) (xy 143.925036 -62.680088) (xy 143.927361 -62.687499) (xy 143.935768 -62.700551)
			(xy 143.941546 -62.705742) (xy 143.946068 -62.709272) (xy 143.956329 -62.714399) (xy 143.961866 -62.715902)
			(xy 143.96212 -62.715902) (xy 143.989281 -62.723219) (xy 144.04125 -62.744742) (xy 144.089499 -62.773658)
			(xy 144.132982 -62.809341) (xy 144.170757 -62.851019) (xy 144.202007 -62.897789) (xy 144.226056 -62.948639)
			(xy 144.242382 -63.002467) (xy 144.250631 -63.058109) (xy 144.251172 -63.086234) (xy 144.250706 -63.113484)
			(xy 144.242945 -63.16743) (xy 144.227586 -63.219721) (xy 144.204941 -63.269295) (xy 144.202282 -63.273432)
			(xy 145.676872 -63.273432) (xy 145.680943 -63.21781) (xy 145.693069 -63.163373) (xy 145.712992 -63.111282)
			(xy 145.740288 -63.062647) (xy 145.774374 -63.018504) (xy 145.814523 -62.979795) (xy 145.859881 -62.947344)
			(xy 145.909481 -62.921843) (xy 145.962265 -62.903836) (xy 146.017108 -62.893706) (xy 146.072842 -62.891669)
			(xy 146.128279 -62.897769) (xy 146.182236 -62.911875) (xy 146.233565 -62.933687) (xy 146.281171 -62.962741)
			(xy 146.324039 -62.998416) (xy 146.361256 -63.039953) (xy 146.392029 -63.086466) (xy 146.415701 -63.136963)
			(xy 146.431769 -63.19037) (xy 146.439889 -63.245546) (xy 146.440398 -63.273432) (xy 146.439889 -63.301318)
			(xy 146.431769 -63.356494) (xy 146.415701 -63.409901) (xy 146.392029 -63.460398) (xy 146.361256 -63.506911)
			(xy 146.324039 -63.548448) (xy 146.281171 -63.584123) (xy 146.233565 -63.613177) (xy 146.182236 -63.634989)
			(xy 146.128279 -63.649095) (xy 146.072842 -63.655195) (xy 146.017108 -63.653158) (xy 145.962265 -63.643028)
			(xy 145.909481 -63.625021) (xy 145.859881 -63.59952) (xy 145.814523 -63.567069) (xy 145.774374 -63.52836)
			(xy 145.740288 -63.484217) (xy 145.712992 -63.435582) (xy 145.693069 -63.383491) (xy 145.680943 -63.329054)
			(xy 145.676872 -63.273432) (xy 144.202282 -63.273432) (xy 144.175471 -63.315141) (xy 144.139777 -63.356327)
			(xy 144.098585 -63.392013) (xy 144.052733 -63.421475) (xy 144.003156 -63.44411) (xy 143.950861 -63.45946)
			(xy 143.896914 -63.467211) (xy 143.869664 -63.467742) (xy 143.868902 -63.467742) (xy 143.842848 -63.467301)
			(xy 143.79123 -63.46016) (xy 143.766032 -63.453518) (xy 143.761968 -63.452248) (xy 143.753332 -63.451232)
			(xy 143.743855 -63.450658) (xy 143.725574 -63.455731) (xy 143.717772 -63.461138) (xy 143.660876 -63.503556)
			(xy 143.652494 -63.509906) (xy 143.643096 -63.519558) (xy 143.643096 -65.124076) (xy 148.207474 -65.124076)
			(xy 148.211545 -65.068454) (xy 148.223671 -65.014017) (xy 148.243594 -64.961926) (xy 148.27089 -64.913291)
			(xy 148.304976 -64.869148) (xy 148.345125 -64.830439) (xy 148.390483 -64.797988) (xy 148.440083 -64.772487)
			(xy 148.492867 -64.75448) (xy 148.54771 -64.74435) (xy 148.603444 -64.742313) (xy 148.658881 -64.748413)
			(xy 148.712838 -64.762519) (xy 148.764167 -64.784331) (xy 148.811773 -64.813385) (xy 148.854641 -64.84906)
			(xy 148.891858 -64.890597) (xy 148.922631 -64.93711) (xy 148.946303 -64.987607) (xy 148.962371 -65.041014)
			(xy 148.970491 -65.09619) (xy 148.971 -65.124076) (xy 148.970491 -65.151962) (xy 148.962371 -65.207138)
			(xy 148.946303 -65.260545) (xy 148.922631 -65.311042) (xy 148.891858 -65.357555) (xy 148.854641 -65.399092)
			(xy 148.811773 -65.434767) (xy 148.764167 -65.463821) (xy 148.712838 -65.485633) (xy 148.658881 -65.499739)
			(xy 148.603444 -65.505839) (xy 148.54771 -65.503802) (xy 148.492867 -65.493672) (xy 148.440083 -65.475665)
			(xy 148.390483 -65.450164) (xy 148.345125 -65.417713) (xy 148.304976 -65.379004) (xy 148.27089 -65.334861)
			(xy 148.243594 -65.286226) (xy 148.223671 -65.234135) (xy 148.211545 -65.179698) (xy 148.207474 -65.124076)
			(xy 143.643096 -65.124076) (xy 143.643096 -78.647544) (xy 143.643592 -78.657546) (xy 143.651259 -78.676023)
			(xy 143.66541 -78.690164) (xy 143.683894 -78.697816) (xy 143.693896 -78.698344) (xy 144.764252 -78.698344)
			(xy 144.77238 -78.697582) (xy 144.772888 -78.697582) (xy 144.780409 -78.695986) (xy 144.794104 -78.689016)
			(xy 144.799812 -78.683866) (xy 151.6253 -71.858124) (xy 151.631142 -71.851012) (xy 151.636476 -71.841106)
			(xy 151.636476 -63.46698) (xy 151.635968 -63.459868) (xy 151.634546 -63.451911) (xy 151.627424 -63.437411)
			(xy 151.621998 -63.43142) (xy 150.943564 -62.75324) (xy 150.609808 -62.419484) (xy 150.59914 -62.416182)
			(xy 150.592028 -62.413896) (xy 150.573782 -62.407656) (xy 150.538536 -62.392004) (xy 150.52167 -62.382654)
			(xy 150.492714 -62.364366) (xy 150.488142 -62.361318) (xy 150.479694 -62.356843) (xy 150.460818 -62.353905)
			(xy 150.442174 -62.358074) (xy 150.43404 -62.363096) (xy 150.43404 -62.36335) (xy 150.426006 -62.369307)
			(xy 150.414889 -62.385909) (xy 150.41245 -62.395608) (xy 150.411434 -62.404244) (xy 150.411111 -62.408387)
			(xy 150.411629 -62.41668) (xy 150.41245 -62.420754) (xy 150.413974 -62.427358) (xy 150.420324 -62.439042)
			(xy 150.424896 -62.443868) (xy 150.444287 -62.465227) (xy 150.477069 -62.512692) (xy 150.502336 -62.56455)
			(xy 150.519513 -62.619619) (xy 150.528209 -62.676645) (xy 150.528782 -62.705488) (xy 150.528782 -62.71514)
			(xy 150.528528 -62.722506) (xy 150.526933 -62.748968) (xy 150.517339 -62.801104) (xy 150.500617 -62.85141)
			(xy 150.47709 -62.898914) (xy 150.44721 -62.942703) (xy 150.411553 -62.981931) (xy 150.370807 -63.015843)
			(xy 150.325758 -63.043785) (xy 150.277272 -63.065218) (xy 150.226285 -63.07973) (xy 150.17378 -63.087041)
			(xy 150.147274 -63.087504) (xy 150.120024 -63.087016) (xy 150.06608 -63.079257) (xy 150.013789 -63.0639)
			(xy 149.964215 -63.041257) (xy 149.918369 -63.011791) (xy 149.877182 -62.9761) (xy 149.841494 -62.93491)
			(xy 149.81203 -62.889062) (xy 149.789391 -62.839487) (xy 149.774037 -62.787195) (xy 149.766282 -62.73325)
			(xy 149.766282 -62.67875) (xy 149.774037 -62.624805) (xy 149.789391 -62.572513) (xy 149.81203 -62.522938)
			(xy 149.841494 -62.47709) (xy 149.877182 -62.4359) (xy 149.918369 -62.400209) (xy 149.964215 -62.370743)
			(xy 150.013789 -62.3481) (xy 150.06608 -62.332743) (xy 150.120024 -62.324984) (xy 150.147274 -62.324488)
			(xy 150.148036 -62.324488) (xy 150.170407 -62.324811) (xy 150.214844 -62.330033) (xy 150.236682 -62.334902)
			(xy 150.237952 -62.33541) (xy 150.244302 -62.336426) (xy 150.251414 -62.336934) (xy 150.261781 -62.336751)
			(xy 150.281044 -62.329138) (xy 150.288752 -62.322202) (xy 150.291546 -62.319408) (xy 150.306024 -62.303152)
			(xy 150.306532 -62.30239) (xy 150.34641 -62.255908) (xy 150.352063 -62.248843) (xy 150.358452 -62.231926)
			(xy 150.358856 -62.222888) (xy 150.358856 -62.208918) (xy 150.3553 -62.190122) (xy 150.353776 -62.186058)
			(xy 150.342379 -62.153709) (xy 150.330104 -62.086236) (xy 150.329392 -62.051946) (xy 150.329392 -62.051438)
			(xy 150.329646 -62.039246) (xy 150.330154 -62.032642) (xy 150.330154 -62.031626) (xy 150.331992 -62.00493)
			(xy 150.342207 -61.952404) (xy 150.359662 -61.901821) (xy 150.384016 -61.854173) (xy 150.414789 -61.810397)
			(xy 150.43277 -61.79058) (xy 150.453509 -61.769286) (xy 150.500391 -61.732747) (xy 150.552368 -61.703915)
			(xy 150.608186 -61.683486) (xy 150.666496 -61.671955) (xy 150.696168 -61.670184) (xy 150.707852 -61.66993)
			(xy 150.712678 -61.66993) (xy 150.743513 -61.670481) (xy 150.804391 -61.68032) (xy 150.862894 -61.699826)
			(xy 150.890478 -61.713618) (xy 150.896009 -61.716313) (xy 150.90795 -61.719268) (xy 150.9141 -61.71946)
			(xy 151.061674 -61.71946) (xy 151.071326 -61.718444) (xy 151.078571 -61.716819) (xy 151.091743 -61.70998)
			(xy 151.097234 -61.704982) (xy 151.628856 -61.17336) (xy 151.629364 -61.165994) (xy 151.629364 -58.867802)
			(xy 151.627332 -58.856118) (xy 151.624148 -58.847137) (xy 151.612269 -58.832258) (xy 151.604218 -58.827162)
			(xy 151.58466 -58.815732) (xy 151.539448 -58.789316) (xy 151.533098 -58.786268) (xy 151.529545 -58.784906)
			(xy 151.522149 -58.783119) (xy 151.518366 -58.782712) (xy 151.517858 -58.782712) (xy 151.514048 -58.782458)
			(xy 151.485346 -58.782458) (xy 151.475186 -58.784744) (xy 151.468836 -58.7883) (xy 151.441492 -58.801841)
			(xy 151.383564 -58.820999) (xy 151.323322 -58.830671) (xy 151.292814 -58.831226) (xy 151.291036 -58.831226)
			(xy 151.26378 -58.830766) (xy 151.209823 -58.823012) (xy 151.157518 -58.807659) (xy 151.107931 -58.785017)
			(xy 151.062071 -58.755549) (xy 151.020872 -58.719853) (xy 150.985173 -58.678658) (xy 150.9557 -58.632801)
			(xy 150.933054 -58.583216) (xy 150.917695 -58.530913) (xy 150.909937 -58.476956) (xy 150.909937 -58.422444)
			(xy 150.917695 -58.368487) (xy 150.933054 -58.316184) (xy 150.9557 -58.266599) (xy 150.985173 -58.220742)
			(xy 151.020872 -58.179547) (xy 151.062071 -58.143851) (xy 151.107931 -58.114383) (xy 151.157518 -58.091741)
			(xy 151.209823 -58.076388) (xy 151.26378 -58.068634) (xy 151.291036 -58.06821) (xy 151.291798 -58.06821)
			(xy 151.31612 -58.068587) (xy 151.36437 -58.074761) (xy 151.411444 -58.087021) (xy 151.456575 -58.105169)
			(xy 151.47798 -58.116724) (xy 151.478234 -58.116978) (xy 151.481028 -58.118502) (xy 151.486366 -58.120903)
			(xy 151.497782 -58.123477) (xy 151.503634 -58.123582) (xy 151.516842 -58.123328) (xy 151.605488 -58.071512)
			(xy 151.610845 -58.067985) (xy 151.619715 -58.058725) (xy 151.623014 -58.053224) (xy 151.625999 -58.047441)
			(xy 151.629218 -58.034837) (xy 151.629364 -58.028332) (xy 151.629364 -54.863238) (xy 151.629105 -54.857977)
			(xy 151.62668 -54.847729) (xy 151.624538 -54.842918) (xy 151.61895 -54.840632) (xy 151.598122 -54.831996)
			(xy 151.588734 -54.828454) (xy 151.568687 -54.82829) (xy 151.550123 -54.835862) (xy 151.54275 -54.842664)
			(xy 148.518349 -57.867296) (xy 149.743158 -57.867296) (xy 149.747229 -57.811674) (xy 149.759355 -57.757237)
			(xy 149.779278 -57.705146) (xy 149.806574 -57.656511) (xy 149.84066 -57.612368) (xy 149.880809 -57.573659)
			(xy 149.926167 -57.541208) (xy 149.975767 -57.515707) (xy 150.028551 -57.4977) (xy 150.083394 -57.48757)
			(xy 150.139128 -57.485533) (xy 150.194565 -57.491633) (xy 150.248522 -57.505739) (xy 150.299851 -57.527551)
			(xy 150.347457 -57.556605) (xy 150.390325 -57.59228) (xy 150.427542 -57.633817) (xy 150.458315 -57.68033)
			(xy 150.481987 -57.730827) (xy 150.498055 -57.784234) (xy 150.506175 -57.83941) (xy 150.506684 -57.867296)
			(xy 150.506175 -57.895182) (xy 150.498055 -57.950358) (xy 150.481987 -58.003765) (xy 150.458315 -58.054262)
			(xy 150.427542 -58.100775) (xy 150.390325 -58.142312) (xy 150.347457 -58.177987) (xy 150.299851 -58.207041)
			(xy 150.248522 -58.228853) (xy 150.194565 -58.242959) (xy 150.139128 -58.249059) (xy 150.083394 -58.247022)
			(xy 150.028551 -58.236892) (xy 149.975767 -58.218885) (xy 149.926167 -58.193384) (xy 149.880809 -58.160933)
			(xy 149.84066 -58.122224) (xy 149.806574 -58.078081) (xy 149.779278 -58.029446) (xy 149.759355 -57.977355)
			(xy 149.747229 -57.922918) (xy 149.743158 -57.867296) (xy 148.518349 -57.867296) (xy 148.21281 -58.172858)
			(xy 148.20646 -58.183526) (xy 148.204682 -58.189368) (xy 148.196233 -58.214933) (xy 148.173151 -58.263578)
			(xy 148.143464 -58.308498) (xy 148.10776 -58.3488) (xy 148.066747 -58.383686) (xy 148.02124 -58.412463)
			(xy 147.97214 -58.434561) (xy 147.920423 -58.44954) (xy 147.867114 -58.457104) (xy 147.840192 -58.457592)
			(xy 147.81294 -58.457128) (xy 147.758991 -58.44937) (xy 147.706695 -58.434013) (xy 147.657117 -58.41137)
			(xy 147.611266 -58.381902) (xy 147.570075 -58.346208) (xy 147.534384 -58.305015) (xy 147.504918 -58.259162)
			(xy 147.482278 -58.209583) (xy 147.466925 -58.157286) (xy 147.45917 -58.103336) (xy 147.458684 -58.076084)
			(xy 147.45843 -58.076084) (xy 147.458887 -58.049148) (xy 147.466453 -57.99581) (xy 147.481445 -57.944066)
			(xy 147.503567 -57.894946) (xy 147.532377 -57.849425) (xy 147.567304 -57.808409) (xy 147.607652 -57.772714)
			(xy 147.652621 -57.743048) (xy 147.701314 -57.720003) (xy 147.726908 -57.711594) (xy 147.727162 -57.711594)
			(xy 147.732998 -57.709585) (xy 147.743538 -57.703168) (xy 147.74799 -57.698894) (xy 151.291036 -54.155848)
			(xy 151.291544 -54.148482) (xy 151.291544 -46.159674) (xy 151.291472 -46.155667) (xy 151.290188 -46.147755)
			(xy 151.289004 -46.143926) (xy 151.287988 -46.140878) (xy 151.284432 -46.132242) (xy 151.27732 -46.124876)
			(xy 151.276304 -46.123606) (xy 151.27478 -46.121828) (xy 145.461228 -40.308276) (xy 145.455894 -40.303704)
			(xy 142.566644 -40.303704) (xy 142.562834 -40.305736) (xy 142.534343 -40.320735) (xy 142.473581 -40.342019)
			(xy 142.410113 -40.352824) (xy 142.377922 -40.353488) (xy 142.350669 -40.353026) (xy 142.296716 -40.345272)
			(xy 142.244417 -40.329917) (xy 142.194835 -40.307276) (xy 142.148981 -40.277808) (xy 142.107787 -40.242114)
			(xy 142.072093 -40.200921) (xy 142.042625 -40.155066) (xy 142.019983 -40.105485) (xy 142.004629 -40.053186)
			(xy 141.996874 -39.999233) (xy 141.996414 -39.97198) (xy 141.996895 -39.944823) (xy 142.004602 -39.891057)
			(xy 142.019856 -39.838928) (xy 142.04235 -39.78949) (xy 142.071629 -39.743742) (xy 142.107101 -39.70261)
			(xy 142.148048 -39.666924) (xy 142.193642 -39.637407) (xy 142.242963 -39.614655) (xy 142.295011 -39.599129)
			(xy 142.348736 -39.591142) (xy 142.37589 -39.590472) (xy 142.378684 -39.590472) (xy 142.410746 -39.5912)
			(xy 142.473949 -39.602044) (xy 142.534457 -39.623282) (xy 142.562834 -39.638224) (xy 142.566644 -39.640256)
			(xy 145.148554 -39.640256) (xy 145.158603 -39.639839) (xy 145.177166 -39.632138) (xy 145.191349 -39.6179)
			(xy 145.195544 -39.60876) (xy 145.206974 -39.581074) (xy 145.205704 -39.574724) (xy 145.042636 -39.41191)
			(xy 141.840966 -36.210494) (xy 141.83868 -36.208716) (xy 140.838682 -36.208716) (xy 140.829792 -36.216844)
			(xy 140.79728 -36.261802) (xy 140.78077 -36.284916) (xy 140.777032 -36.291025) (xy 140.772766 -36.304689)
			(xy 140.772388 -36.31184) (xy 140.772388 -36.331906) (xy 140.774674 -36.339526) (xy 140.782837 -36.367329)
			(xy 140.791631 -36.424601) (xy 140.7922 -36.453572) (xy 140.791739 -36.480826) (xy 140.783985 -36.534779)
			(xy 140.768631 -36.58708) (xy 140.74599 -36.636663) (xy 140.716523 -36.682519) (xy 140.680829 -36.723715)
			(xy 140.639635 -36.759411) (xy 140.593781 -36.78888) (xy 140.544199 -36.811524) (xy 140.491899 -36.826881)
			(xy 140.437946 -36.834637) (xy 140.410692 -36.83508) (xy 140.383569 -36.834602) (xy 140.329869 -36.826916)
			(xy 140.2778 -36.811701) (xy 140.228412 -36.789263) (xy 140.1827 -36.760055) (xy 140.141587 -36.724666)
			(xy 140.105901 -36.68381) (xy 140.076363 -36.63831) (xy 140.053569 -36.589085) (xy 140.037978 -36.537127)
			(xy 140.029904 -36.483485) (xy 140.029184 -36.456366) (xy 140.029184 -36.45281) (xy 140.029745 -36.423839)
			(xy 140.038553 -36.366569) (xy 140.04671 -36.338764) (xy 140.047472 -36.336224) (xy 140.048996 -36.331398)
			(xy 140.05052 -36.318444) (xy 140.050791 -36.31029) (xy 140.046786 -36.294484) (xy 140.042646 -36.287456)
			(xy 140.023596 -36.260786) (xy 139.992608 -36.21786) (xy 139.98321 -36.208716) (xy 139.460478 -36.208716)
			(xy 139.454636 -36.211764) (xy 139.451334 -36.213288) (xy 139.423532 -36.227423) (xy 139.36447 -36.247452)
			(xy 139.302938 -36.257614) (xy 139.271756 -36.258246) (xy 139.270994 -36.258246) (xy 139.24374 -36.25776)
			(xy 139.189788 -36.250002) (xy 139.137489 -36.234645) (xy 139.087907 -36.212001) (xy 139.042053 -36.182531)
			(xy 139.000859 -36.146836) (xy 138.965165 -36.105642) (xy 138.935696 -36.059787) (xy 138.913053 -36.010206)
			(xy 138.897697 -35.957906) (xy 138.88994 -35.903954) (xy 138.88994 -35.849446) (xy 138.897697 -35.795494)
			(xy 138.913053 -35.743194) (xy 138.935696 -35.693613) (xy 138.965165 -35.647758) (xy 139.000859 -35.606564)
			(xy 139.042053 -35.570869) (xy 139.087907 -35.541399) (xy 139.137489 -35.518755) (xy 139.189788 -35.503398)
			(xy 139.24374 -35.49564) (xy 139.270994 -35.49523) (xy 139.271756 -35.49523) (xy 139.302938 -35.495868)
			(xy 139.364469 -35.506032) (xy 139.423534 -35.52605) (xy 139.451334 -35.540188) (xy 139.454636 -35.541712)
			(xy 139.460478 -35.54476) (xy 141.675104 -35.54476) (xy 141.684192 -35.544332) (xy 141.70119 -35.537876)
			(xy 141.714859 -35.525887) (xy 141.719554 -35.51809) (xy 141.730476 -35.491928) (xy 141.730476 -35.48888)
			(xy 141.72692 -35.480244) (xy 141.724945 -35.475606) (xy 141.71944 -35.467164) (xy 141.715998 -35.46348)
			(xy 139.77366 -33.521396) (xy 139.758245 -33.505422) (xy 139.731508 -33.469987) (xy 139.709901 -33.431209)
			(xy 139.701524 -33.410652) (xy 139.692888 -33.388554) (xy 139.690348 -33.379664) (xy 139.688824 -33.370774)
			(xy 139.68857 -33.36925) (xy 139.684421 -33.35086) (xy 139.67996 -33.313424) (xy 139.67968 -33.294574)
			(xy 139.67968 -33.197292) (xy 139.67841 -33.19145) (xy 139.674263 -33.172673) (xy 139.669805 -33.134477)
			(xy 139.66952 -33.11525) (xy 139.66952 -28.997148) (xy 139.669841 -28.974644) (xy 139.675827 -28.930038)
			(xy 139.681458 -28.908248) (xy 139.687554 -28.886404) (xy 139.686177 -28.88302) (xy 139.682604 -28.876649)
			(xy 139.680442 -28.873704) (xy 139.679934 -28.872942) (xy 139.650216 -28.834842) (xy 139.645898 -28.829254)
			(xy 139.631166 -28.810712) (xy 139.628061 -28.806922) (xy 139.620638 -28.800528) (xy 139.616434 -28.798012)
			(xy 139.608306 -28.794202) (xy 139.599162 -28.7909) (xy 137.481818 -28.7909) (xy 137.45653 -28.790399)
			(xy 137.406579 -28.782479) (xy 137.35848 -28.766847) (xy 137.313417 -28.743888) (xy 137.272497 -28.714165)
			(xy 137.254234 -28.696666) (xy 136.708896 -28.151328) (xy 136.707118 -28.14955) (xy 136.598406 -28.040838)
			(xy 136.33577 -27.777948) (xy 136.329779 -27.772557) (xy 136.315271 -27.76556) (xy 136.307322 -27.764232)
			(xy 136.300464 -27.763724) (xy 135.810752 -27.763724) (xy 135.801084 -27.764194) (xy 135.783154 -27.771446)
			(xy 135.769187 -27.784824) (xy 135.764778 -27.793442) (xy 135.75284 -27.821128) (xy 135.72744 -27.88031)
			(xy 135.725532 -27.885171) (xy 135.723486 -27.895409) (xy 135.723376 -27.90063) (xy 135.737092 -27.934666)
			(xy 135.743188 -27.941524) (xy 135.761984 -27.962672) (xy 135.794762 -28.008792) (xy 135.821605 -28.058601)
			(xy 135.842102 -28.111339) (xy 135.855941 -28.166201) (xy 135.862912 -28.222351) (xy 135.86333 -28.250642)
			(xy 135.863076 -28.734512) (xy 135.863076 -29.114242) (xy 135.862586 -29.14421) (xy 135.854763 -29.203632)
			(xy 135.83925 -29.261525) (xy 135.816314 -29.316898) (xy 135.786347 -29.368804) (xy 135.74986 -29.416354)
			(xy 135.70748 -29.458734) (xy 135.65993 -29.495221) (xy 135.608024 -29.525188) (xy 135.552651 -29.548124)
			(xy 135.494758 -29.563637) (xy 135.435336 -29.57146) (xy 135.3754 -29.57146) (xy 135.315978 -29.563637)
			(xy 135.258085 -29.548124) (xy 135.202712 -29.525188) (xy 135.150806 -29.495221) (xy 135.103256 -29.458734)
			(xy 135.060876 -29.416354) (xy 135.024389 -29.368804) (xy 134.994422 -29.316898) (xy 134.971486 -29.261525)
			(xy 134.955973 -29.203632) (xy 134.94815 -29.14421) (xy 134.94766 -29.114242) (xy 134.94766 -28.734512)
			(xy 134.947406 -28.250642) (xy 134.947831 -28.222353) (xy 134.954811 -28.166206) (xy 134.968656 -28.111348)
			(xy 134.989156 -28.058614) (xy 135.015998 -28.008808) (xy 135.048773 -27.96269) (xy 135.067548 -27.941524)
			(xy 135.073644 -27.934666) (xy 135.08736 -27.90063) (xy 135.08729 -27.895404) (xy 135.085248 -27.885157)
			(xy 135.083296 -27.88031) (xy 135.057896 -27.821128) (xy 135.045958 -27.793442) (xy 135.04156 -27.784821)
			(xy 135.027584 -27.771457) (xy 135.009651 -27.764224) (xy 134.999984 -27.763724) (xy 134.934198 -27.763724)
			(xy 134.908176 -27.763193) (xy 134.856777 -27.755018) (xy 134.807286 -27.738917) (xy 134.760916 -27.715285)
			(xy 134.718806 -27.684701) (xy 134.70001 -27.666696) (xy 133.648704 -26.615136) (xy 133.644789 -26.611386)
			(xy 133.635694 -26.605489) (xy 133.63067 -26.603452) (xy 133.620159 -26.600102) (xy 133.598175 -26.60168)
			(xy 133.588252 -26.6065) (xy 133.584188 -26.608786) (xy 133.570788 -26.618609) (xy 133.550675 -26.645027)
			(xy 133.540126 -26.67651) (xy 133.539484 -26.693114) (xy 133.539484 -27.342846) (xy 133.538994 -27.37283)
			(xy 133.531166 -27.432286) (xy 133.515645 -27.490211) (xy 133.492696 -27.545615) (xy 133.462712 -27.597549)
			(xy 133.426206 -27.645125) (xy 133.383801 -27.68753) (xy 133.336225 -27.724036) (xy 133.284291 -27.75402)
			(xy 133.228887 -27.776969) (xy 133.170962 -27.79249) (xy 133.111506 -27.800318) (xy 133.051538 -27.800318)
			(xy 132.992082 -27.79249) (xy 132.934157 -27.776969) (xy 132.878753 -27.75402) (xy 132.826819 -27.724036)
			(xy 132.779243 -27.68753) (xy 132.736838 -27.645125) (xy 132.700332 -27.597549) (xy 132.670348 -27.545615)
			(xy 132.647399 -27.490211) (xy 132.631878 -27.432286) (xy 132.62405 -27.37283) (xy 132.62356 -27.342846)
			(xy 132.62356 -26.479246) (xy 132.624091 -26.448026) (xy 132.632575 -26.386166) (xy 132.649378 -26.326031)
			(xy 132.674189 -26.268733) (xy 132.706549 -26.215333) (xy 132.745859 -26.166821) (xy 132.79139 -26.124095)
			(xy 132.8423 -26.087945) (xy 132.897646 -26.059041) (xy 132.926836 -26.047954) (xy 132.93725 -26.044144)
			(xy 132.95249 -26.029412) (xy 132.955792 -26.025602) (xy 132.958872 -26.021652) (xy 132.963614 -26.01283)
			(xy 132.96519 -26.008076) (xy 132.967984 -25.99563) (xy 132.967984 -25.995122) (xy 132.973572 -25.970992)
			(xy 132.974845 -25.961252) (xy 132.9708 -25.942047) (xy 132.965698 -25.933654) (xy 132.963666 -25.93086)
			(xy 132.959602 -25.926288) (xy 132.770118 -25.736804) (xy 132.767267 -25.734099) (xy 132.760888 -25.729506)
			(xy 132.757418 -25.72766) (xy 132.751991 -25.725079) (xy 132.740311 -25.722261) (xy 132.734304 -25.722072)
			(xy 130.480054 -25.722072) (xy 130.474212 -25.72512) (xy 130.468624 -25.727914) (xy 130.441123 -25.741684)
			(xy 130.382787 -25.761153) (xy 130.322082 -25.77101) (xy 130.291332 -25.771602) (xy 130.264078 -25.771141)
			(xy 130.210124 -25.763388) (xy 130.157822 -25.748034) (xy 130.108239 -25.725393) (xy 130.062382 -25.695926)
			(xy 130.021186 -25.660232) (xy 129.985489 -25.619039) (xy 129.956019 -25.573184) (xy 129.933375 -25.523602)
			(xy 129.918018 -25.471302) (xy 129.910261 -25.417348) (xy 129.909824 -25.390094) (xy 129.910312 -25.362163)
			(xy 129.918457 -25.306898) (xy 129.934574 -25.253411) (xy 129.958316 -25.202846) (xy 129.989178 -25.156283)
			(xy 130.026499 -25.114717) (xy 130.069481 -25.079036) (xy 130.117206 -25.050004) (xy 130.168654 -25.02824)
			(xy 130.195574 -25.020778) (xy 130.202432 -25.019) (xy 130.209036 -25.01519) (xy 130.219196 -25.007316)
			(xy 130.227324 -24.999188) (xy 130.235236 -24.990342) (xy 130.242649 -24.967826) (xy 130.241548 -24.956008)
			(xy 129.889758 -24.604218) (xy 129.864609 -24.578277) (xy 129.82019 -24.521293) (xy 129.783106 -24.459284)
			(xy 129.753919 -24.39319) (xy 129.733071 -24.324012) (xy 129.726436 -24.288496) (xy 129.722372 -24.263858)
			(xy 129.718319 -24.260147) (xy 129.708968 -24.254376) (xy 129.70383 -24.252428) (xy 129.636774 -24.231092)
			(xy 129.636266 -24.231092) (xy 129.624074 -24.227282) (xy 129.615438 -24.225504) (xy 129.608834 -24.224996)
			(xy 129.603246 -24.224996) (xy 129.594102 -24.228806) (xy 129.58954 -24.230815) (xy 129.581228 -24.236317)
			(xy 129.577592 -24.239728) (xy 129.39268 -24.42464) (xy 129.373909 -24.442672) (xy 129.331793 -24.47325)
			(xy 129.285416 -24.496875) (xy 129.235918 -24.512964) (xy 129.184515 -24.521124) (xy 129.158492 -24.521668)
			(xy 127.969772 -24.521668) (xy 127.965962 -24.5237) (xy 127.937471 -24.538695) (xy 127.876708 -24.559969)
			(xy 127.81324 -24.570763) (xy 127.78105 -24.571452) (xy 127.753794 -24.570993) (xy 127.699835 -24.563242)
			(xy 127.647528 -24.54789) (xy 127.597939 -24.525251) (xy 127.552077 -24.495785) (xy 127.510874 -24.460092)
			(xy 127.475171 -24.418899) (xy 127.445694 -24.373043) (xy 127.423043 -24.32346) (xy 127.407678 -24.271157)
			(xy 127.399914 -24.2172) (xy 127.399542 -24.189944) (xy 127.400018 -24.162782) (xy 127.407717 -24.109005)
			(xy 127.422965 -24.056865) (xy 127.445455 -24.007414) (xy 127.474731 -23.961653) (xy 127.510201 -23.920507)
			(xy 127.551149 -23.884808) (xy 127.596746 -23.855277) (xy 127.646071 -23.832512) (xy 127.698126 -23.816974)
			(xy 127.751858 -23.808975) (xy 127.779018 -23.808436) (xy 127.781812 -23.808436) (xy 127.813873 -23.809166)
			(xy 127.877074 -23.820017) (xy 127.937578 -23.841261) (xy 127.965962 -23.856188) (xy 127.969772 -23.85822)
			(xy 128.999488 -23.85822) (xy 129.00279 -23.85822) (xy 129.011808 -23.857267) (xy 129.028335 -23.84984)
			(xy 129.035048 -23.843742) (xy 129.114804 -23.763732) (xy 129.15392 -23.724616) (xy 129.154472 -23.720241)
			(xy 129.154214 -23.711427) (xy 129.153412 -23.70709) (xy 129.148332 -23.69058) (xy 129.148332 -23.690072)
			(xy 129.125218 -23.616412) (xy 129.123347 -23.611066) (xy 129.117569 -23.601326) (xy 129.113788 -23.597108)
			(xy 129.11074 -23.5966) (xy 129.08915 -23.59279) (xy 129.056333 -23.58636) (xy 128.992316 -23.567016)
			(xy 128.93092 -23.540503) (xy 128.872947 -23.507166) (xy 128.81915 -23.467439) (xy 128.770231 -23.421839)
			(xy 128.726828 -23.370962) (xy 128.689506 -23.31547) (xy 128.658752 -23.256085) (xy 128.646428 -23.224998)
			(xy 128.637538 -23.201884) (xy 128.633728 -23.198582) (xy 128.538478 -23.178516) (xy 128.533398 -23.1775)
			(xy 128.525524 -23.175722) (xy 128.521206 -23.176992) (xy 128.258824 -23.439374) (xy 128.235245 -23.462282)
			(xy 128.18383 -23.503251) (xy 128.128151 -23.538207) (xy 128.06891 -23.56671) (xy 128.00685 -23.588403)
			(xy 127.942752 -23.603013) (xy 127.877421 -23.610355) (xy 127.84455 -23.610824) (xy 127.832358 -23.611078)
			(xy 127.797433 -23.609825) (xy 127.728236 -23.600035) (xy 127.660693 -23.582088) (xy 127.595762 -23.556239)
			(xy 127.534365 -23.522855) (xy 127.477372 -23.482408) (xy 127.425591 -23.435474) (xy 127.379757 -23.382716)
			(xy 127.340519 -23.324884) (xy 127.308434 -23.262797) (xy 127.283958 -23.197337) (xy 127.267437 -23.129431)
			(xy 127.259105 -23.060043) (xy 127.258572 -23.0251) (xy 127.258572 -23.023576) (xy 127.259284 -22.984997)
			(xy 127.269615 -22.908529) (xy 127.289912 -22.834084) (xy 127.304292 -22.798278) (xy 127.319515 -22.763533)
			(xy 127.357634 -22.697948) (xy 127.40389 -22.637825) (xy 127.430276 -22.610572) (xy 127.717042 -22.32406)
			(xy 127.923036 -22.118066) (xy 127.9466 -22.095167) (xy 127.997982 -22.054212) (xy 128.053625 -22.019262)
			(xy 128.112828 -21.990757) (xy 128.174849 -21.969055) (xy 128.238908 -21.954428) (xy 128.304202 -21.94706)
			(xy 128.337056 -21.946616) (xy 132.169154 -21.946616) (xy 132.170678 -21.94433) (xy 132.171694 -21.942806)
			(xy 132.202174 -21.892514) (xy 132.202174 -21.892006) (xy 132.217668 -21.866098) (xy 132.222494 -21.85416)
			(xy 132.224018 -21.842476) (xy 132.224272 -21.830792) (xy 132.218684 -21.818854) (xy 132.218176 -21.817838)
			(xy 132.204277 -21.790282) (xy 132.184594 -21.731792) (xy 132.174594 -21.670894) (xy 132.17398 -21.640038)
			(xy 132.17398 -21.63572) (xy 132.174748 -21.607318) (xy 132.183661 -21.551206) (xy 132.2008 -21.497037)
			(xy 132.225787 -21.446011) (xy 132.258068 -21.399257) (xy 132.277104 -21.378164) (xy 132.283962 -21.371052)
			(xy 132.287518 -21.362162) (xy 132.290058 -21.353018) (xy 132.29082 -21.344128) (xy 132.29082 -21.27377)
			(xy 132.290756 -21.269636) (xy 132.289488 -21.261468) (xy 132.28828 -21.257514) (xy 132.287518 -21.255736)
			(xy 132.284216 -21.2471) (xy 132.277104 -21.23948) (xy 132.257832 -21.218153) (xy 132.225266 -21.170789)
			(xy 132.200172 -21.119076) (xy 132.18312 -21.064185) (xy 132.174495 -21.007356) (xy 132.174493 -20.949876)
			(xy 132.183113 -20.893047) (xy 132.20016 -20.838153) (xy 132.225249 -20.786439) (xy 132.257812 -20.739072)
			(xy 132.277104 -20.717764) (xy 132.284216 -20.710144) (xy 132.287518 -20.701508) (xy 132.28828 -20.69973)
			(xy 132.289513 -20.695782) (xy 132.290791 -20.68761) (xy 132.29082 -20.683474) (xy 132.29082 -20.61337)
			(xy 132.290756 -20.609236) (xy 132.289488 -20.601068) (xy 132.28828 -20.597114) (xy 132.287518 -20.595336)
			(xy 132.284216 -20.5867) (xy 132.277104 -20.57908) (xy 132.257832 -20.557753) (xy 132.225266 -20.510389)
			(xy 132.200172 -20.458676) (xy 132.18312 -20.403785) (xy 132.174495 -20.346956) (xy 132.174493 -20.289476)
			(xy 132.183113 -20.232647) (xy 132.20016 -20.177753) (xy 132.225249 -20.126039) (xy 132.257812 -20.078672)
			(xy 132.277104 -20.057364) (xy 132.284216 -20.049744) (xy 132.287518 -20.041108) (xy 132.28828 -20.03933)
			(xy 132.289513 -20.035382) (xy 132.290791 -20.02721) (xy 132.29082 -20.023074) (xy 132.29082 -19.95297)
			(xy 132.290756 -19.948836) (xy 132.289488 -19.940668) (xy 132.28828 -19.936714) (xy 132.287518 -19.934936)
			(xy 132.284216 -19.9263) (xy 132.277104 -19.91868) (xy 132.257832 -19.897353) (xy 132.225266 -19.849989)
			(xy 132.200172 -19.798276) (xy 132.18312 -19.743385) (xy 132.174495 -19.686556) (xy 132.174493 -19.629076)
			(xy 132.183113 -19.572247) (xy 132.20016 -19.517353) (xy 132.225249 -19.465639) (xy 132.257812 -19.418272)
			(xy 132.277104 -19.396964) (xy 132.284216 -19.389344) (xy 132.287518 -19.380708) (xy 132.28828 -19.37893)
			(xy 132.289513 -19.374982) (xy 132.290791 -19.36681) (xy 132.29082 -19.362674) (xy 132.29082 -19.29257)
			(xy 132.290756 -19.288436) (xy 132.289488 -19.280268) (xy 132.28828 -19.276314) (xy 132.287518 -19.274536)
			(xy 132.284216 -19.2659) (xy 132.277104 -19.25828) (xy 132.257833 -19.236953) (xy 132.225267 -19.189591)
			(xy 132.200173 -19.137879) (xy 132.183121 -19.082989) (xy 132.174496 -19.026161) (xy 132.17398 -18.997422)
			(xy 132.174466 -18.970171) (xy 132.182222 -18.916223) (xy 132.197577 -18.863928) (xy 132.220219 -18.814351)
			(xy 132.249685 -18.768501) (xy 132.285376 -18.72731) (xy 132.326567 -18.691619) (xy 132.372417 -18.662153)
			(xy 132.421994 -18.639511) (xy 132.474289 -18.624156) (xy 132.528237 -18.6164) (xy 132.582739 -18.6164)
			(xy 132.636687 -18.624156) (xy 132.688982 -18.639511) (xy 132.738559 -18.662153) (xy 132.784409 -18.691619)
			(xy 132.8256 -18.72731) (xy 132.861291 -18.768501) (xy 132.890757 -18.814351) (xy 132.913399 -18.863928)
			(xy 132.928754 -18.916223) (xy 132.93651 -18.970171) (xy 132.936996 -18.997422) (xy 132.936473 -19.02616)
			(xy 132.927848 -19.082987) (xy 132.910795 -19.137876) (xy 132.885701 -19.189585) (xy 132.853134 -19.236945)
			(xy 132.833872 -19.25828) (xy 132.82676 -19.2659) (xy 132.823458 -19.274536) (xy 132.822696 -19.276314)
			(xy 132.821467 -19.280263) (xy 132.820197 -19.288434) (xy 132.820156 -19.29257) (xy 132.820156 -19.362674)
			(xy 132.820223 -19.366807) (xy 132.821498 -19.374974) (xy 132.822696 -19.37893) (xy 132.823458 -19.380708)
			(xy 132.82676 -19.389344) (xy 132.833872 -19.396964) (xy 132.853141 -19.418291) (xy 132.885704 -19.465653)
			(xy 132.910792 -19.517363) (xy 132.92784 -19.572253) (xy 132.93646 -19.629078) (xy 132.936457 -19.686554)
			(xy 132.927832 -19.743379) (xy 132.910781 -19.798267) (xy 132.885687 -19.849975) (xy 132.853121 -19.897334)
			(xy 132.833872 -19.91868) (xy 132.82676 -19.9263) (xy 132.823458 -19.934936) (xy 132.822696 -19.936714)
			(xy 132.821467 -19.940663) (xy 132.820197 -19.948834) (xy 132.820156 -19.95297) (xy 132.820156 -20.023074)
			(xy 132.820223 -20.027207) (xy 132.821498 -20.035374) (xy 132.822696 -20.03933) (xy 132.823458 -20.041108)
			(xy 132.82676 -20.049744) (xy 132.833872 -20.057364) (xy 132.853141 -20.078691) (xy 132.885704 -20.126053)
			(xy 132.910792 -20.177763) (xy 132.92784 -20.232653) (xy 132.93646 -20.289478) (xy 132.936457 -20.346954)
			(xy 132.927832 -20.403779) (xy 132.910781 -20.458667) (xy 132.885687 -20.510375) (xy 132.853121 -20.557734)
			(xy 132.833872 -20.57908) (xy 132.82676 -20.5867) (xy 132.823458 -20.595336) (xy 132.822696 -20.597114)
			(xy 132.821467 -20.601063) (xy 132.820197 -20.609234) (xy 132.820156 -20.61337) (xy 132.820156 -20.683474)
			(xy 132.820223 -20.687607) (xy 132.821498 -20.695774) (xy 132.822696 -20.69973) (xy 132.823458 -20.701508)
			(xy 132.82676 -20.710144) (xy 132.833872 -20.717764) (xy 132.853141 -20.739091) (xy 132.885704 -20.786453)
			(xy 132.910792 -20.838163) (xy 132.92784 -20.893053) (xy 132.93646 -20.949878) (xy 132.936457 -21.007354)
			(xy 132.927832 -21.064179) (xy 132.910781 -21.119067) (xy 132.885687 -21.170775) (xy 132.853121 -21.218134)
			(xy 132.833872 -21.23948) (xy 132.82676 -21.2471) (xy 132.823458 -21.255736) (xy 132.822696 -21.257514)
			(xy 132.821467 -21.261463) (xy 132.820197 -21.269634) (xy 132.820156 -21.27377) (xy 132.820156 -21.343874)
			(xy 132.820223 -21.348007) (xy 132.821498 -21.356174) (xy 132.822696 -21.36013) (xy 132.823458 -21.361908)
			(xy 132.82676 -21.370544) (xy 132.833872 -21.378164) (xy 132.853142 -21.399491) (xy 132.885705 -21.446854)
			(xy 132.910793 -21.498566) (xy 132.927841 -21.553457) (xy 132.93646 -21.610284) (xy 132.936996 -21.639022)
			(xy 132.936996 -21.641308) (xy 132.936244 -21.671946) (xy 132.926173 -21.732397) (xy 132.906581 -21.790464)
			(xy 132.8928 -21.817838) (xy 132.891276 -21.820632) (xy 132.889152 -21.825769) (xy 132.886965 -21.836664)
			(xy 132.886958 -21.842222) (xy 132.887212 -21.855684) (xy 132.908802 -21.892006) (xy 132.908802 -21.892514)
			(xy 132.939282 -21.942552) (xy 132.942076 -21.946616) (xy 137.352786 -21.946616) (xy 137.360493 -21.946379)
			(xy 137.37522 -21.941841) (xy 137.381742 -21.937726) (xy 137.385806 -21.934424) (xy 137.72896 -21.59127)
			(xy 137.729468 -21.583904) (xy 137.729468 -21.567902) (xy 137.72642 -21.556218) (xy 137.722102 -21.547836)
			(xy 137.708568 -21.520574) (xy 137.689372 -21.46282) (xy 137.679584 -21.402751) (xy 137.678922 -21.372322)
			(xy 137.678922 -21.36394) (xy 137.679917 -21.337044) (xy 137.688537 -21.283919) (xy 137.704538 -21.232533)
			(xy 137.727604 -21.183906) (xy 137.757275 -21.139004) (xy 137.792964 -21.098719) (xy 137.833961 -21.06385)
			(xy 137.879452 -21.03509) (xy 137.928533 -21.013009) (xy 137.980232 -20.998047) (xy 138.03352 -20.9905)
			(xy 138.06043 -20.990052) (xy 138.060684 -20.990052) (xy 138.076686 -20.990306) (xy 138.087354 -20.990814)
			(xy 138.096498 -20.987258) (xy 138.100861 -20.985503) (xy 138.108908 -20.980642) (xy 138.1125 -20.977606)
			(xy 138.126216 -20.964652) (xy 138.126724 -20.964144) (xy 138.168634 -20.923758) (xy 138.172444 -20.919186)
			(xy 138.172444 -19.452844) (xy 138.172992 -19.417114) (xy 138.181712 -19.346187) (xy 138.198992 -19.276846)
			(xy 138.224575 -19.210122) (xy 138.258081 -19.147003) (xy 138.299014 -19.088426) (xy 138.346765 -19.035261)
			(xy 138.373358 -19.011392) (xy 138.389868 -18.997168) (xy 138.390376 -18.991326) (xy 138.390884 -18.971514)
			(xy 138.392154 -18.922238) (xy 138.392154 -18.92046) (xy 138.392662 -18.906744) (xy 138.359642 -18.873978)
			(xy 138.344148 -18.858738) (xy 138.317438 -18.831163) (xy 138.270727 -18.770238) (xy 138.232375 -18.703733)
			(xy 138.217148 -18.668492) (xy 138.203119 -18.633085) (xy 138.1833 -18.55955) (xy 138.173183 -18.484066)
			(xy 138.172444 -18.445988) (xy 138.172444 -18.44421) (xy 138.172957 -18.408796) (xy 138.181493 -18.338484)
			(xy 138.198443 -18.269714) (xy 138.223559 -18.203489) (xy 138.256474 -18.140774) (xy 138.296709 -18.082484)
			(xy 138.343677 -18.029469) (xy 138.396693 -17.982502) (xy 138.454984 -17.942268) (xy 138.5177 -17.909354)
			(xy 138.583926 -17.88424) (xy 138.652696 -17.867291) (xy 138.723008 -17.858756) (xy 138.758422 -17.858232)
			(xy 138.76782 -17.858232) (xy 138.804614 -17.859434) (xy 138.877488 -17.869884) (xy 138.948483 -17.889364)
			(xy 138.982704 -17.902936) (xy 139.017931 -17.918191) (xy 139.084429 -17.956546) (xy 139.145354 -18.00325)
			(xy 139.17295 -18.029936) (xy 139.503658 -18.360898) (xy 139.741402 -18.598642) (xy 139.764302 -18.622205)
			(xy 139.805259 -18.673587) (xy 139.84021 -18.729229) (xy 139.868716 -18.788433) (xy 139.890419 -18.850454)
			(xy 139.905046 -18.914514) (xy 139.912413 -18.979808) (xy 139.912852 -19.012662) (xy 139.912852 -21.474684)
			(xy 139.915782 -21.478428) (xy 139.922816 -21.484823) (xy 139.926822 -21.487384) (xy 139.932664 -21.49094)
			(xy 140.02004 -21.527516) (xy 140.026593 -21.53002) (xy 140.040514 -21.531705) (xy 140.047472 -21.530818)
			(xy 140.637006 -20.941284) (xy 140.637478 -20.937552) (xy 140.637476 -20.93003) (xy 140.637006 -20.926298)
			(xy 140.637006 -20.925536) (xy 140.631672 -20.892516) (xy 140.623798 -20.842986) (xy 140.620964 -20.831916)
			(xy 140.607085 -20.813793) (xy 140.597128 -20.808188) (xy 140.59027 -20.804632) (xy 140.564497 -20.790258)
			(xy 140.517325 -20.754804) (xy 140.476167 -20.712517) (xy 140.442001 -20.664403) (xy 140.415639 -20.611609)
			(xy 140.39771 -20.555388) (xy 140.38864 -20.497079) (xy 140.388086 -20.467574) (xy 140.388574 -20.440324)
			(xy 140.396333 -20.386379) (xy 140.41169 -20.334087) (xy 140.434333 -20.284512) (xy 140.4638 -20.238665)
			(xy 140.499491 -20.197477) (xy 140.540681 -20.161788) (xy 140.58653 -20.132323) (xy 140.636105 -20.109683)
			(xy 140.688398 -20.094329) (xy 140.742344 -20.086572) (xy 140.769594 -20.086066) (xy 140.796742 -20.086544)
			(xy 140.850491 -20.094241) (xy 140.902605 -20.10948) (xy 140.952033 -20.131953) (xy 140.997775 -20.161207)
			(xy 141.038908 -20.196651) (xy 141.074601 -20.237567) (xy 141.104132 -20.283131) (xy 141.126905 -20.332421)
			(xy 141.142461 -20.384442) (xy 141.150484 -20.438143) (xy 141.151102 -20.465288) (xy 141.151102 -20.467828)
			(xy 141.150505 -20.498333) (xy 141.140814 -20.558568) (xy 141.131798 -20.587716) (xy 141.130274 -20.592288)
			(xy 141.129004 -20.601432) (xy 141.129004 -20.601686) (xy 141.12748 -20.611084) (xy 141.129766 -20.620736)
			(xy 141.131047 -20.625488) (xy 141.135137 -20.634439) (xy 141.137894 -20.638516) (xy 141.170914 -20.684744)
			(xy 141.175781 -20.690925) (xy 141.188455 -20.700229) (xy 141.195806 -20.703032) (xy 141.199701 -20.704211)
			(xy 141.207739 -20.705487) (xy 141.211808 -20.705572) (xy 142.75689 -20.705572) (xy 142.790911 -20.706079)
			(xy 142.858493 -20.713987) (xy 142.904483 -20.724876) (xy 147.280388 -20.724876) (xy 147.284358 -20.594742)
			(xy 147.296254 -20.465092) (xy 147.316033 -20.336409) (xy 147.343619 -20.20917) (xy 147.378912 -20.083851)
			(xy 147.421778 -19.960915) (xy 147.47206 -19.840822) (xy 147.529569 -19.724018) (xy 147.594093 -19.610936)
			(xy 147.66539 -19.501999) (xy 147.743195 -19.397611) (xy 147.82722 -19.29816) (xy 147.917152 -19.204017)
			(xy 148.012656 -19.115532) (xy 148.113376 -19.033033) (xy 148.218938 -18.956828) (xy 148.32895 -18.887201)
			(xy 148.443002 -18.82441) (xy 148.56067 -18.768688) (xy 148.681516 -18.720244) (xy 148.805091 -18.679257)
			(xy 148.930934 -18.64588) (xy 149.058579 -18.620237) (xy 149.187549 -18.602423) (xy 149.317365 -18.592505)
			(xy 149.447544 -18.59052) (xy 149.577603 -18.596474) (xy 149.707056 -18.610347) (xy 149.835423 -18.632085)
			(xy 149.962226 -18.661609) (xy 150.086993 -18.698808) (xy 150.20926 -18.743544) (xy 150.328573 -18.795652)
			(xy 150.444486 -18.854935) (xy 150.556571 -18.921176) (xy 150.664408 -18.994126) (xy 150.767597 -19.073514)
			(xy 150.865755 -19.159046) (xy 150.958516 -19.250403) (xy 151.045535 -19.347245) (xy 151.126488 -19.449212)
			(xy 151.201074 -19.555924) (xy 151.269015 -19.666985) (xy 151.33006 -19.781981) (xy 151.383981 -19.900485)
			(xy 151.430576 -20.022056) (xy 151.469674 -20.146241) (xy 151.501128 -20.272579) (xy 151.524822 -20.4006)
			(xy 151.540666 -20.529826) (xy 151.548604 -20.659779) (xy 151.5491 -20.724876) (xy 151.548604 -20.789973)
			(xy 151.540666 -20.919926) (xy 151.524822 -21.049152) (xy 151.501128 -21.177173) (xy 151.469674 -21.303511)
			(xy 151.430576 -21.427696) (xy 151.383981 -21.549267) (xy 151.33006 -21.667771) (xy 151.269015 -21.782767)
			(xy 151.201074 -21.893828) (xy 151.126488 -22.00054) (xy 151.045535 -22.102507) (xy 150.958516 -22.199349)
			(xy 150.865755 -22.290706) (xy 150.767597 -22.376238) (xy 150.664408 -22.455626) (xy 150.556571 -22.528576)
			(xy 150.444486 -22.594817) (xy 150.328573 -22.6541) (xy 150.20926 -22.706208) (xy 150.086993 -22.750944)
			(xy 149.962226 -22.788143) (xy 149.835423 -22.817667) (xy 149.707056 -22.839405) (xy 149.577603 -22.853278)
			(xy 149.447544 -22.859232) (xy 149.317365 -22.857247) (xy 149.187549 -22.847329) (xy 149.058579 -22.829515)
			(xy 148.930934 -22.803872) (xy 148.805091 -22.770495) (xy 148.681516 -22.729508) (xy 148.56067 -22.681064)
			(xy 148.443002 -22.625342) (xy 148.32895 -22.562551) (xy 148.218938 -22.492924) (xy 148.113376 -22.416719)
			(xy 148.012656 -22.33422) (xy 147.917152 -22.245735) (xy 147.82722 -22.151592) (xy 147.743195 -22.052141)
			(xy 147.66539 -21.947753) (xy 147.594093 -21.838816) (xy 147.529569 -21.725734) (xy 147.47206 -21.60893)
			(xy 147.421778 -21.488837) (xy 147.378912 -21.365901) (xy 147.343619 -21.240582) (xy 147.316033 -21.113343)
			(xy 147.296254 -20.98466) (xy 147.284358 -20.85501) (xy 147.280388 -20.724876) (xy 142.904483 -20.724876)
			(xy 142.924705 -20.729664) (xy 142.988658 -20.752899) (xy 143.049492 -20.783379) (xy 143.106389 -20.820695)
			(xy 143.158586 -20.864345) (xy 143.18234 -20.888706) (xy 143.183356 -20.889722) (xy 143.735044 -21.441156)
			(xy 143.757991 -21.46471) (xy 143.799014 -21.516108) (xy 143.83402 -21.571779) (xy 143.862568 -21.631021)
			(xy 143.884299 -21.693089) (xy 143.898939 -21.757201) (xy 143.906304 -21.822549) (xy 143.906635 -21.847048)
			(xy 144.172938 -21.847048) (xy 144.177009 -21.791426) (xy 144.189135 -21.736989) (xy 144.209058 -21.684898)
			(xy 144.236354 -21.636263) (xy 144.27044 -21.59212) (xy 144.310589 -21.553411) (xy 144.355947 -21.52096)
			(xy 144.405547 -21.495459) (xy 144.458331 -21.477452) (xy 144.513174 -21.467322) (xy 144.568908 -21.465285)
			(xy 144.624345 -21.471385) (xy 144.678302 -21.485491) (xy 144.729631 -21.507303) (xy 144.777237 -21.536357)
			(xy 144.820105 -21.572032) (xy 144.857322 -21.613569) (xy 144.888095 -21.660082) (xy 144.911767 -21.710579)
			(xy 144.927835 -21.763986) (xy 144.935955 -21.819162) (xy 144.936464 -21.847048) (xy 144.935955 -21.874934)
			(xy 144.927835 -21.93011) (xy 144.911767 -21.983517) (xy 144.888095 -22.034014) (xy 144.857322 -22.080527)
			(xy 144.820105 -22.122064) (xy 144.777237 -22.157739) (xy 144.729631 -22.186793) (xy 144.678302 -22.208605)
			(xy 144.624345 -22.222711) (xy 144.568908 -22.228811) (xy 144.513174 -22.226774) (xy 144.458331 -22.216644)
			(xy 144.405547 -22.198637) (xy 144.355947 -22.173136) (xy 144.310589 -22.140685) (xy 144.27044 -22.101976)
			(xy 144.236354 -22.057833) (xy 144.209058 -22.009198) (xy 144.189135 -21.957107) (xy 144.177009 -21.90267)
			(xy 144.172938 -21.847048) (xy 143.906635 -21.847048) (xy 143.906748 -21.85543) (xy 143.906748 -21.869908)
			(xy 143.906494 -21.87575) (xy 143.904805 -21.910353) (xy 143.894291 -21.978832) (xy 143.875772 -22.045592)
			(xy 143.849504 -22.1097) (xy 143.815856 -22.170262) (xy 143.775297 -22.22643) (xy 143.728394 -22.27742)
			(xy 143.675803 -22.32252) (xy 143.618257 -22.361099) (xy 143.556562 -22.39262) (xy 143.491578 -22.41664)
			(xy 143.424214 -22.432826) (xy 143.355411 -22.44095) (xy 143.32077 -22.441408) (xy 143.287897 -22.440978)
			(xy 143.222561 -22.433644) (xy 143.158458 -22.419036) (xy 143.096395 -22.39734) (xy 143.037153 -22.368827)
			(xy 142.981478 -22.333858) (xy 142.930071 -22.292872) (xy 142.906496 -22.269958) (xy 142.847822 -22.211284)
			(xy 142.84198 -22.210776) (xy 142.829534 -22.210776) (xy 142.820515 -22.21113) (xy 142.80359 -22.217366)
			(xy 142.796514 -22.222968) (xy 142.79499 -22.224238) (xy 142.768555 -22.24584) (xy 142.711548 -22.283406)
			(xy 142.650561 -22.314089) (xy 142.586421 -22.337475) (xy 142.519997 -22.353247) (xy 142.452189 -22.361189)
			(xy 142.418054 -22.361652) (xy 142.261082 -22.361652) (xy 142.252446 -22.369272) (xy 142.232634 -22.393656)
			(xy 142.199614 -22.43455) (xy 142.197074 -22.438614) (xy 142.193264 -22.447758) (xy 142.1892 -22.463506)
			(xy 142.19174 -22.474936) (xy 142.195587 -22.494203) (xy 142.199788 -22.533269) (xy 142.200122 -22.552914)
			(xy 142.200122 -22.553422) (xy 142.200122 -22.559264) (xy 142.199359 -22.586806) (xy 142.190885 -22.641246)
			(xy 142.174671 -22.693901) (xy 142.151053 -22.743678) (xy 142.120523 -22.789541) (xy 142.083715 -22.830538)
			(xy 142.041395 -22.865816) (xy 141.994442 -22.894641) (xy 141.943831 -22.916416) (xy 141.890616 -22.930686)
			(xy 141.863318 -22.934422) (xy 141.849094 -22.935946) (xy 141.81582 -22.937216) (xy 141.813788 -22.937216)
			(xy 141.788757 -22.936486) (xy 141.739202 -22.929268) (xy 141.691018 -22.915628) (xy 141.645033 -22.895801)
			(xy 141.602037 -22.870126) (xy 141.58214 -22.85492) (xy 141.565376 -22.84095) (xy 141.563852 -22.83968)
			(xy 141.562074 -22.838156) (xy 141.553946 -22.832822) (xy 141.543528 -22.827172) (xy 141.519943 -22.825168)
			(xy 141.508734 -22.829012) (xy 141.484858 -22.839426) (xy 141.48435 -22.839426) (xy 141.42339 -22.866604)
			(xy 141.421358 -22.86762) (xy 141.407642 -22.874478) (xy 141.402816 -22.882352) (xy 141.402816 -23.965154)
			(xy 142.177514 -23.965154) (xy 142.181585 -23.909532) (xy 142.193711 -23.855095) (xy 142.213634 -23.803004)
			(xy 142.24093 -23.754369) (xy 142.275016 -23.710226) (xy 142.315165 -23.671517) (xy 142.360523 -23.639066)
			(xy 142.410123 -23.613565) (xy 142.462907 -23.595558) (xy 142.51775 -23.585428) (xy 142.573484 -23.583391)
			(xy 142.628921 -23.589491) (xy 142.682878 -23.603597) (xy 142.734207 -23.625409) (xy 142.781813 -23.654463)
			(xy 142.824681 -23.690138) (xy 142.861898 -23.731675) (xy 142.892671 -23.778188) (xy 142.916343 -23.828685)
			(xy 142.932411 -23.882092) (xy 142.940531 -23.937268) (xy 142.940706 -23.946866) (xy 143.18056 -23.946866)
			(xy 143.184631 -23.891244) (xy 143.196757 -23.836807) (xy 143.21668 -23.784716) (xy 143.243976 -23.736081)
			(xy 143.278062 -23.691938) (xy 143.318211 -23.653229) (xy 143.363569 -23.620778) (xy 143.413169 -23.595277)
			(xy 143.465953 -23.57727) (xy 143.520796 -23.56714) (xy 143.57653 -23.565103) (xy 143.631967 -23.571203)
			(xy 143.685924 -23.585309) (xy 143.737253 -23.607121) (xy 143.784859 -23.636175) (xy 143.827727 -23.67185)
			(xy 143.864944 -23.713387) (xy 143.895717 -23.7599) (xy 143.919389 -23.810397) (xy 143.935457 -23.863804)
			(xy 143.943577 -23.91898) (xy 143.944086 -23.946866) (xy 143.943646 -23.970996) (xy 144.172938 -23.970996)
			(xy 144.177009 -23.915374) (xy 144.189135 -23.860937) (xy 144.209058 -23.808846) (xy 144.236354 -23.760211)
			(xy 144.27044 -23.716068) (xy 144.310589 -23.677359) (xy 144.355947 -23.644908) (xy 144.405547 -23.619407)
			(xy 144.458331 -23.6014) (xy 144.513174 -23.59127) (xy 144.568908 -23.589233) (xy 144.624345 -23.595333)
			(xy 144.678302 -23.609439) (xy 144.729631 -23.631251) (xy 144.777237 -23.660305) (xy 144.820105 -23.69598)
			(xy 144.857322 -23.737517) (xy 144.888095 -23.78403) (xy 144.911767 -23.834527) (xy 144.927835 -23.887934)
			(xy 144.935955 -23.94311) (xy 144.936464 -23.970996) (xy 144.935955 -23.998882) (xy 144.927835 -24.054058)
			(xy 144.911767 -24.107465) (xy 144.888095 -24.157962) (xy 144.857322 -24.204475) (xy 144.820105 -24.246012)
			(xy 144.777237 -24.281687) (xy 144.729631 -24.310741) (xy 144.678302 -24.332553) (xy 144.624345 -24.346659)
			(xy 144.568908 -24.352759) (xy 144.513174 -24.350722) (xy 144.458331 -24.340592) (xy 144.405547 -24.322585)
			(xy 144.355947 -24.297084) (xy 144.310589 -24.264633) (xy 144.27044 -24.225924) (xy 144.236354 -24.181781)
			(xy 144.209058 -24.133146) (xy 144.189135 -24.081055) (xy 144.177009 -24.026618) (xy 144.172938 -23.970996)
			(xy 143.943646 -23.970996) (xy 143.943577 -23.974752) (xy 143.935457 -24.029928) (xy 143.919389 -24.083335)
			(xy 143.895717 -24.133832) (xy 143.864944 -24.180345) (xy 143.827727 -24.221882) (xy 143.784859 -24.257557)
			(xy 143.737253 -24.286611) (xy 143.685924 -24.308423) (xy 143.631967 -24.322529) (xy 143.57653 -24.328629)
			(xy 143.520796 -24.326592) (xy 143.465953 -24.316462) (xy 143.413169 -24.298455) (xy 143.363569 -24.272954)
			(xy 143.318211 -24.240503) (xy 143.278062 -24.201794) (xy 143.243976 -24.157651) (xy 143.21668 -24.109016)
			(xy 143.196757 -24.056925) (xy 143.184631 -24.002488) (xy 143.18056 -23.946866) (xy 142.940706 -23.946866)
			(xy 142.94104 -23.965154) (xy 142.940531 -23.99304) (xy 142.932411 -24.048216) (xy 142.916343 -24.101623)
			(xy 142.892671 -24.15212) (xy 142.861898 -24.198633) (xy 142.824681 -24.24017) (xy 142.781813 -24.275845)
			(xy 142.734207 -24.304899) (xy 142.682878 -24.326711) (xy 142.628921 -24.340817) (xy 142.573484 -24.346917)
			(xy 142.51775 -24.34488) (xy 142.462907 -24.33475) (xy 142.410123 -24.316743) (xy 142.360523 -24.291242)
			(xy 142.315165 -24.258791) (xy 142.275016 -24.220082) (xy 142.24093 -24.175939) (xy 142.213634 -24.127304)
			(xy 142.193711 -24.075213) (xy 142.181585 -24.020776) (xy 142.177514 -23.965154) (xy 141.402816 -23.965154)
			(xy 141.402816 -24.807418) (xy 148.47138 -24.807418) (xy 148.475451 -24.751796) (xy 148.487577 -24.697359)
			(xy 148.5075 -24.645268) (xy 148.534796 -24.596633) (xy 148.568882 -24.55249) (xy 148.609031 -24.513781)
			(xy 148.654389 -24.48133) (xy 148.703989 -24.455829) (xy 148.756773 -24.437822) (xy 148.811616 -24.427692)
			(xy 148.86735 -24.425655) (xy 148.922787 -24.431755) (xy 148.976744 -24.445861) (xy 149.028073 -24.467673)
			(xy 149.075679 -24.496727) (xy 149.118547 -24.532402) (xy 149.155764 -24.573939) (xy 149.186537 -24.620452)
			(xy 149.210209 -24.670949) (xy 149.226277 -24.724356) (xy 149.234397 -24.779532) (xy 149.234906 -24.807418)
			(xy 149.234397 -24.835304) (xy 149.226277 -24.89048) (xy 149.210209 -24.943887) (xy 149.186537 -24.994384)
			(xy 149.155764 -25.040897) (xy 149.118547 -25.082434) (xy 149.075679 -25.118109) (xy 149.028073 -25.147163)
			(xy 148.976744 -25.168975) (xy 148.922787 -25.183081) (xy 148.86735 -25.189181) (xy 148.811616 -25.187144)
			(xy 148.756773 -25.177014) (xy 148.703989 -25.159007) (xy 148.654389 -25.133506) (xy 148.609031 -25.101055)
			(xy 148.568882 -25.062346) (xy 148.534796 -25.018203) (xy 148.5075 -24.969568) (xy 148.487577 -24.917477)
			(xy 148.475451 -24.86304) (xy 148.47138 -24.807418) (xy 141.402816 -24.807418) (xy 141.402816 -25.912572)
			(xy 141.402894 -25.916781) (xy 141.404294 -25.925083) (xy 141.40561 -25.929082) (xy 141.40815 -25.936448)
			(xy 141.412722 -25.942544) (xy 141.43863 -25.950418) (xy 141.462196 -25.958147) (xy 141.507281 -25.978817)
			(xy 141.549349 -26.005086) (xy 141.5843 -26.03373) (xy 147.368004 -26.03373) (xy 147.372075 -25.978108)
			(xy 147.384201 -25.923671) (xy 147.404124 -25.87158) (xy 147.43142 -25.822945) (xy 147.465506 -25.778802)
			(xy 147.505655 -25.740093) (xy 147.551013 -25.707642) (xy 147.600613 -25.682141) (xy 147.653397 -25.664134)
			(xy 147.70824 -25.654004) (xy 147.763974 -25.651967) (xy 147.819411 -25.658067) (xy 147.873368 -25.672173)
			(xy 147.924697 -25.693985) (xy 147.972303 -25.723039) (xy 148.015171 -25.758714) (xy 148.052388 -25.800251)
			(xy 148.083161 -25.846764) (xy 148.106833 -25.897261) (xy 148.122901 -25.950668) (xy 148.131021 -26.005844)
			(xy 148.13153 -26.03373) (xy 148.131021 -26.061616) (xy 148.122901 -26.116792) (xy 148.106833 -26.170199)
			(xy 148.083161 -26.220696) (xy 148.052388 -26.267209) (xy 148.015171 -26.308746) (xy 147.972303 -26.344421)
			(xy 147.924697 -26.373475) (xy 147.873368 -26.395287) (xy 147.819411 -26.409393) (xy 147.763974 -26.415493)
			(xy 147.70824 -26.413456) (xy 147.653397 -26.403326) (xy 147.600613 -26.385319) (xy 147.551013 -26.359818)
			(xy 147.505655 -26.327367) (xy 147.465506 -26.288658) (xy 147.43142 -26.244515) (xy 147.404124 -26.19588)
			(xy 147.384201 -26.143789) (xy 147.372075 -26.089352) (xy 147.368004 -26.03373) (xy 141.5843 -26.03373)
			(xy 141.587709 -26.036524) (xy 141.605 -26.054304) (xy 141.62622 -26.077636) (xy 141.661557 -26.129869)
			(xy 141.687951 -26.187144) (xy 141.696948 -26.217372) (xy 141.699234 -26.2255) (xy 143.12138 -27.647646)
			(xy 143.139414 -27.666416) (xy 143.169999 -27.708532) (xy 143.19363 -27.754908) (xy 143.209729 -27.804405)
			(xy 143.217899 -27.85581) (xy 143.218408 -27.881834) (xy 143.218408 -28.139136) (xy 144.498058 -28.139136)
			(xy 144.502129 -28.083514) (xy 144.514255 -28.029077) (xy 144.534178 -27.976986) (xy 144.561474 -27.928351)
			(xy 144.59556 -27.884208) (xy 144.635709 -27.845499) (xy 144.681067 -27.813048) (xy 144.730667 -27.787547)
			(xy 144.783451 -27.76954) (xy 144.838294 -27.75941) (xy 144.894028 -27.757373) (xy 144.949465 -27.763473)
			(xy 145.003422 -27.777579) (xy 145.054751 -27.799391) (xy 145.102357 -27.828445) (xy 145.145225 -27.86412)
			(xy 145.182442 -27.905657) (xy 145.213215 -27.95217) (xy 145.236887 -28.002667) (xy 145.252955 -28.056074)
			(xy 145.261075 -28.11125) (xy 145.261584 -28.139136) (xy 145.768058 -28.139136) (xy 145.772129 -28.083514)
			(xy 145.784255 -28.029077) (xy 145.804178 -27.976986) (xy 145.831474 -27.928351) (xy 145.86556 -27.884208)
			(xy 145.905709 -27.845499) (xy 145.951067 -27.813048) (xy 146.000667 -27.787547) (xy 146.053451 -27.76954)
			(xy 146.108294 -27.75941) (xy 146.164028 -27.757373) (xy 146.219465 -27.763473) (xy 146.273422 -27.777579)
			(xy 146.324751 -27.799391) (xy 146.372357 -27.828445) (xy 146.415225 -27.86412) (xy 146.452442 -27.905657)
			(xy 146.483215 -27.95217) (xy 146.506887 -28.002667) (xy 146.522955 -28.056074) (xy 146.531075 -28.11125)
			(xy 146.531584 -28.139136) (xy 146.531075 -28.167022) (xy 146.522955 -28.222198) (xy 146.506887 -28.275605)
			(xy 146.483215 -28.326102) (xy 146.452442 -28.372615) (xy 146.415225 -28.414152) (xy 146.372357 -28.449827)
			(xy 146.324751 -28.478881) (xy 146.273422 -28.500693) (xy 146.219465 -28.514799) (xy 146.164028 -28.520899)
			(xy 146.108294 -28.518862) (xy 146.053451 -28.508732) (xy 146.000667 -28.490725) (xy 145.951067 -28.465224)
			(xy 145.905709 -28.432773) (xy 145.86556 -28.394064) (xy 145.831474 -28.349921) (xy 145.804178 -28.301286)
			(xy 145.784255 -28.249195) (xy 145.772129 -28.194758) (xy 145.768058 -28.139136) (xy 145.261584 -28.139136)
			(xy 145.261075 -28.167022) (xy 145.252955 -28.222198) (xy 145.236887 -28.275605) (xy 145.213215 -28.326102)
			(xy 145.182442 -28.372615) (xy 145.145225 -28.414152) (xy 145.102357 -28.449827) (xy 145.054751 -28.478881)
			(xy 145.003422 -28.500693) (xy 144.949465 -28.514799) (xy 144.894028 -28.520899) (xy 144.838294 -28.518862)
			(xy 144.783451 -28.508732) (xy 144.730667 -28.490725) (xy 144.681067 -28.465224) (xy 144.635709 -28.432773)
			(xy 144.59556 -28.394064) (xy 144.561474 -28.349921) (xy 144.534178 -28.301286) (xy 144.514255 -28.249195)
			(xy 144.502129 -28.194758) (xy 144.498058 -28.139136) (xy 143.218408 -28.139136) (xy 143.218408 -29.134308)
			(xy 143.218662 -29.14015) (xy 143.219192 -29.143951) (xy 143.221227 -29.15135) (xy 143.222726 -29.154882)
			(xy 143.22505 -29.159822) (xy 143.231463 -29.168652) (xy 143.235426 -29.172408) (xy 143.291814 -29.2227)
			(xy 143.295817 -29.226097) (xy 143.304904 -29.23135) (xy 143.309848 -29.233114) (xy 143.320008 -29.236416)
			(xy 143.330676 -29.2354) (xy 143.340617 -29.234434) (xy 143.360566 -29.233419) (xy 143.370554 -29.233368)
			(xy 143.39781 -29.233828) (xy 143.451767 -29.241579) (xy 143.504072 -29.256931) (xy 143.553659 -29.279571)
			(xy 143.59952 -29.309037) (xy 143.64072 -29.34473) (xy 143.676421 -29.385924) (xy 143.705896 -29.431779)
			(xy 143.728544 -29.481363) (xy 143.743906 -29.533665) (xy 143.751667 -29.58762) (xy 143.752062 -29.614876)
			(xy 143.751985 -29.627614) (xy 143.750333 -29.653035) (xy 143.74876 -29.665676) (xy 143.744435 -29.693893)
			(xy 143.728499 -29.748707) (xy 143.704576 -29.800537) (xy 143.6732 -29.848224) (xy 143.635071 -29.890707)
			(xy 143.613378 -29.909262) (xy 143.60906 -29.912564) (xy 143.602202 -29.9212) (xy 143.590518 -29.94533)
			(xy 143.58817 -29.950552) (xy 143.585596 -29.961705) (xy 143.585438 -29.967428) (xy 143.585438 -30.024324)
			(xy 143.585582 -30.03005) (xy 143.588139 -30.041212) (xy 143.590518 -30.046422) (xy 143.602202 -30.070552)
			(xy 143.60906 -30.079188) (xy 143.613378 -30.08249) (xy 143.634673 -30.100719) (xy 143.672207 -30.142351)
			(xy 143.703248 -30.189025) (xy 143.72713 -30.239737) (xy 143.743339 -30.293396) (xy 143.751525 -30.348849)
			(xy 143.752062 -30.376876) (xy 143.7516 -30.404129) (xy 143.743846 -30.45808) (xy 143.728491 -30.510378)
			(xy 143.70585 -30.559958) (xy 143.676382 -30.605811) (xy 143.640687 -30.647003) (xy 143.599493 -30.682695)
			(xy 143.553639 -30.71216) (xy 143.504057 -30.734799) (xy 143.451758 -30.750151) (xy 143.397807 -30.757902)
			(xy 143.370554 -30.758384) (xy 143.360566 -30.758331) (xy 143.340617 -30.757314) (xy 143.330676 -30.756352)
			(xy 143.320008 -30.755336) (xy 143.309848 -30.758638) (xy 143.304894 -30.760382) (xy 143.295802 -30.765635)
			(xy 143.291814 -30.769052) (xy 143.235426 -30.819344) (xy 143.231449 -30.823086) (xy 143.22504 -30.831924)
			(xy 143.222726 -30.83687) (xy 143.221213 -30.840398) (xy 143.219167 -30.847797) (xy 143.218662 -30.851602)
			(xy 143.218408 -30.857444) (xy 143.218408 -31.11246) (xy 143.218408 -31.112714) (xy 143.218855 -31.12226)
			(xy 143.225897 -31.14001) (xy 143.232124 -31.147258) (xy 143.239998 -31.154116) (xy 143.307562 -31.201614)
			(xy 143.312632 -31.204933) (xy 143.323928 -31.20931) (xy 143.329914 -31.21025) (xy 143.34236 -31.212028)
			(xy 143.34617 -31.210758) (xy 143.378474 -31.199439) (xy 143.445808 -31.187163) (xy 143.480028 -31.186374)
			(xy 143.48079 -31.186374) (xy 143.508045 -31.186836) (xy 143.561999 -31.194592) (xy 143.614301 -31.209948)
			(xy 143.663885 -31.232591) (xy 143.709741 -31.26206) (xy 143.750937 -31.297756) (xy 143.786634 -31.338951)
			(xy 143.816104 -31.384807) (xy 143.838748 -31.43439) (xy 143.854105 -31.486691) (xy 143.861863 -31.540645)
			(xy 143.861863 -31.595155) (xy 143.854105 -31.649109) (xy 143.838748 -31.70141) (xy 143.830593 -31.719266)
			(xy 144.385536 -31.719266) (xy 144.389607 -31.663644) (xy 144.401733 -31.609207) (xy 144.421656 -31.557116)
			(xy 144.448952 -31.508481) (xy 144.483038 -31.464338) (xy 144.523187 -31.425629) (xy 144.568545 -31.393178)
			(xy 144.618145 -31.367677) (xy 144.670929 -31.34967) (xy 144.725772 -31.33954) (xy 144.781506 -31.337503)
			(xy 144.836943 -31.343603) (xy 144.8909 -31.357709) (xy 144.942229 -31.379521) (xy 144.989835 -31.408575)
			(xy 145.032703 -31.44425) (xy 145.06992 -31.485787) (xy 145.100693 -31.5323) (xy 145.124365 -31.582797)
			(xy 145.140433 -31.636204) (xy 145.144583 -31.664402) (xy 145.661124 -31.664402) (xy 145.665195 -31.60878)
			(xy 145.677321 -31.554343) (xy 145.697244 -31.502252) (xy 145.72454 -31.453617) (xy 145.758626 -31.409474)
			(xy 145.798775 -31.370765) (xy 145.844133 -31.338314) (xy 145.893733 -31.312813) (xy 145.946517 -31.294806)
			(xy 146.00136 -31.284676) (xy 146.057094 -31.282639) (xy 146.112531 -31.288739) (xy 146.166488 -31.302845)
			(xy 146.217817 -31.324657) (xy 146.265423 -31.353711) (xy 146.308291 -31.389386) (xy 146.345508 -31.430923)
			(xy 146.376281 -31.477436) (xy 146.399953 -31.527933) (xy 146.416021 -31.58134) (xy 146.424141 -31.636516)
			(xy 146.42465 -31.664402) (xy 146.424141 -31.692288) (xy 146.416021 -31.747464) (xy 146.399953 -31.800871)
			(xy 146.376281 -31.851368) (xy 146.345508 -31.897881) (xy 146.308291 -31.939418) (xy 146.265423 -31.975093)
			(xy 146.217817 -32.004147) (xy 146.166488 -32.025959) (xy 146.112531 -32.040065) (xy 146.057094 -32.046165)
			(xy 146.00136 -32.044128) (xy 145.946517 -32.033998) (xy 145.893733 -32.015991) (xy 145.844133 -31.99049)
			(xy 145.798775 -31.958039) (xy 145.758626 -31.91933) (xy 145.72454 -31.875187) (xy 145.697244 -31.826552)
			(xy 145.677321 -31.774461) (xy 145.665195 -31.720024) (xy 145.661124 -31.664402) (xy 145.144583 -31.664402)
			(xy 145.148553 -31.69138) (xy 145.149062 -31.719266) (xy 145.148553 -31.747152) (xy 145.140433 -31.802328)
			(xy 145.124365 -31.855735) (xy 145.100693 -31.906232) (xy 145.06992 -31.952745) (xy 145.032703 -31.994282)
			(xy 144.989835 -32.029957) (xy 144.942229 -32.059011) (xy 144.8909 -32.080823) (xy 144.836943 -32.094929)
			(xy 144.781506 -32.101029) (xy 144.725772 -32.098992) (xy 144.670929 -32.088862) (xy 144.618145 -32.070855)
			(xy 144.568545 -32.045354) (xy 144.523187 -32.012903) (xy 144.483038 -31.974194) (xy 144.448952 -31.930051)
			(xy 144.421656 -31.881416) (xy 144.401733 -31.829325) (xy 144.389607 -31.774888) (xy 144.385536 -31.719266)
			(xy 143.830593 -31.719266) (xy 143.816104 -31.750993) (xy 143.786634 -31.796849) (xy 143.750937 -31.838044)
			(xy 143.709741 -31.87374) (xy 143.663885 -31.903209) (xy 143.614301 -31.925852) (xy 143.561999 -31.941208)
			(xy 143.508045 -31.948964) (xy 143.48079 -31.94939) (xy 143.480028 -31.94939) (xy 143.445802 -31.94865)
			(xy 143.378459 -31.936381) (xy 143.34617 -31.925006) (xy 143.34236 -31.923736) (xy 143.329914 -31.925514)
			(xy 143.323935 -31.92648) (xy 143.312641 -31.930849) (xy 143.307562 -31.93415) (xy 143.239998 -31.981648)
			(xy 143.232124 -31.988506) (xy 143.225877 -31.995743) (xy 143.218828 -32.013499) (xy 143.218408 -32.02305)
			(xy 143.218408 -33.239964) (xy 143.218456 -33.243835) (xy 143.219604 -33.25149) (xy 143.220694 -33.255204)
			(xy 143.222687 -33.260947) (xy 143.228986 -33.271339) (xy 143.23314 -33.275778) (xy 145.222459 -35.264852)
			(xy 146.0025 -35.264852) (xy 146.006571 -35.20923) (xy 146.018697 -35.154793) (xy 146.03862 -35.102702)
			(xy 146.065916 -35.054067) (xy 146.100002 -35.009924) (xy 146.140151 -34.971215) (xy 146.185509 -34.938764)
			(xy 146.235109 -34.913263) (xy 146.287893 -34.895256) (xy 146.342736 -34.885126) (xy 146.39847 -34.883089)
			(xy 146.453907 -34.889189) (xy 146.507864 -34.903295) (xy 146.559193 -34.925107) (xy 146.606799 -34.954161)
			(xy 146.649667 -34.989836) (xy 146.686884 -35.031373) (xy 146.717657 -35.077886) (xy 146.741329 -35.128383)
			(xy 146.757397 -35.18179) (xy 146.765517 -35.236966) (xy 146.766026 -35.264852) (xy 146.765517 -35.292738)
			(xy 146.757397 -35.347914) (xy 146.741329 -35.401321) (xy 146.717657 -35.451818) (xy 146.686884 -35.498331)
			(xy 146.649667 -35.539868) (xy 146.606799 -35.575543) (xy 146.559193 -35.604597) (xy 146.507864 -35.626409)
			(xy 146.453907 -35.640515) (xy 146.39847 -35.646615) (xy 146.342736 -35.644578) (xy 146.287893 -35.634448)
			(xy 146.235109 -35.616441) (xy 146.185509 -35.59094) (xy 146.140151 -35.558489) (xy 146.100002 -35.51978)
			(xy 146.065916 -35.475637) (xy 146.03862 -35.427002) (xy 146.018697 -35.374911) (xy 146.006571 -35.320474)
			(xy 146.0025 -35.264852) (xy 145.222459 -35.264852) (xy 145.296636 -35.33902) (xy 146.244564 -36.286948)
			(xy 147.30044 -36.286948) (xy 147.304511 -36.231326) (xy 147.316637 -36.176889) (xy 147.33656 -36.124798)
			(xy 147.363856 -36.076163) (xy 147.397942 -36.03202) (xy 147.438091 -35.993311) (xy 147.483449 -35.96086)
			(xy 147.533049 -35.935359) (xy 147.585833 -35.917352) (xy 147.640676 -35.907222) (xy 147.69641 -35.905185)
			(xy 147.751847 -35.911285) (xy 147.805804 -35.925391) (xy 147.857133 -35.947203) (xy 147.904739 -35.976257)
			(xy 147.947607 -36.011932) (xy 147.984824 -36.053469) (xy 148.015597 -36.099982) (xy 148.039269 -36.150479)
			(xy 148.055337 -36.203886) (xy 148.063457 -36.259062) (xy 148.063966 -36.286948) (xy 148.063457 -36.314834)
			(xy 148.055337 -36.37001) (xy 148.039269 -36.423417) (xy 148.015597 -36.473914) (xy 147.984824 -36.520427)
			(xy 147.947607 -36.561964) (xy 147.904739 -36.597639) (xy 147.857133 -36.626693) (xy 147.805804 -36.648505)
			(xy 147.751847 -36.662611) (xy 147.69641 -36.668711) (xy 147.640676 -36.666674) (xy 147.585833 -36.656544)
			(xy 147.533049 -36.638537) (xy 147.483449 -36.613036) (xy 147.438091 -36.580585) (xy 147.397942 -36.541876)
			(xy 147.363856 -36.497733) (xy 147.33656 -36.449098) (xy 147.316637 -36.397007) (xy 147.304511 -36.34257)
			(xy 147.30044 -36.286948) (xy 146.244564 -36.286948) (xy 147.499578 -37.541962) (xy 147.507546 -37.549087)
			(xy 147.527496 -37.556688) (xy 147.538186 -37.556694) (xy 147.613624 -37.55263) (xy 147.618905 -37.55223)
			(xy 147.629149 -37.549545) (xy 147.633944 -37.547296) (xy 147.643342 -37.54247) (xy 147.6502 -37.533834)
			(xy 147.668431 -37.512187) (xy 147.710192 -37.473991) (xy 147.757132 -37.442377) (xy 147.808224 -37.418037)
			(xy 147.862349 -37.401503) (xy 147.918321 -37.393139) (xy 147.946618 -37.39261) (xy 147.946872 -37.39261)
			(xy 147.974609 -37.393113) (xy 148.029498 -37.401154) (xy 148.082645 -37.417056) (xy 148.13293 -37.440484)
			(xy 148.179293 -37.470945) (xy 148.220759 -37.507797) (xy 148.256453 -37.550264) (xy 148.285623 -37.59745)
			(xy 148.307656 -37.648362) (xy 148.322086 -37.701927) (xy 148.32584 -37.729414) (xy 148.327364 -37.743892)
			(xy 148.328634 -37.774118) (xy 148.328117 -37.802447) (xy 148.319743 -37.858482) (xy 148.303179 -37.912664)
			(xy 148.278792 -37.963805) (xy 148.247115 -38.01078) (xy 148.208845 -38.052558) (xy 148.187156 -38.07079)
			(xy 148.182838 -38.074092) (xy 148.17598 -38.082728) (xy 148.173694 -38.087046) (xy 148.171425 -38.091834)
			(xy 148.168734 -38.102081) (xy 148.16836 -38.107366) (xy 148.164296 -38.182804) (xy 148.164182 -38.19351)
			(xy 148.171825 -38.213489) (xy 148.179028 -38.221412) (xy 149.08784 -39.130224) (xy 149.094521 -39.136353)
			(xy 149.111013 -39.143854) (xy 149.129085 -39.145132) (xy 149.137878 -39.142924) (xy 149.143212 -39.140638)
			(xy 149.150025 -39.137547) (xy 149.161637 -39.128122) (xy 149.166072 -39.122096) (xy 149.169882 -39.116508)
			(xy 149.1742 -39.10203) (xy 149.1742 -36.734496) (xy 149.17401 -36.728551) (xy 149.171187 -36.716998)
			(xy 149.168612 -36.711636) (xy 149.166326 -36.707318) (xy 149.158408 -36.693366) (xy 149.144674 -36.664371)
			(xy 149.138894 -36.649406) (xy 149.137624 -36.64585) (xy 149.13483 -36.637722) (xy 149.134576 -36.637214)
			(xy 149.133814 -36.634674) (xy 149.13356 -36.633912) (xy 149.132798 -36.631626) (xy 149.13229 -36.630102)
			(xy 149.131528 -36.62807) (xy 149.130512 -36.625022) (xy 149.129242 -36.621974) (xy 149.127279 -36.618144)
			(xy 149.122299 -36.611126) (xy 149.119336 -36.608004) (xy 147.628864 -35.117532) (xy 147.610829 -35.098763)
			(xy 147.580243 -35.056647) (xy 147.556612 -35.010271) (xy 147.540514 -34.960773) (xy 147.532346 -34.909369)
			(xy 147.531836 -34.883344) (xy 147.531836 -32.411162) (xy 147.52447 -32.403288) (xy 147.503388 -32.386016)
			(xy 147.49272 -32.37738) (xy 147.479512 -32.366458) (xy 147.479004 -32.366458) (xy 147.461478 -32.352234)
			(xy 147.461224 -32.35198) (xy 147.452842 -32.345376) (xy 147.429474 -32.350456) (xy 147.399537 -32.356395)
			(xy 147.338834 -32.362757) (xy 147.308316 -32.363156) (xy 147.272927 -32.362623) (xy 147.202664 -32.354096)
			(xy 147.133941 -32.337165) (xy 147.067759 -32.312076) (xy 147.005083 -32.279194) (xy 146.946826 -32.238999)
			(xy 146.893836 -32.192078) (xy 146.846887 -32.139112) (xy 146.806662 -32.080876) (xy 146.773749 -32.018216)
			(xy 146.748625 -31.952047) (xy 146.731658 -31.883333) (xy 146.723095 -31.813075) (xy 146.722592 -31.777686)
			(xy 146.722592 -30.793944) (xy 146.722515 -30.789734) (xy 146.721118 -30.781432) (xy 146.719798 -30.777434)
			(xy 146.717004 -30.769306) (xy 146.71548 -30.767528) (xy 146.692874 -30.754066) (xy 146.642582 -30.72384)
			(xy 146.636994 -30.720538) (xy 146.631654 -30.71759) (xy 146.619964 -30.714121) (xy 146.61388 -30.71368)
			(xy 146.601434 -30.713172) (xy 146.588988 -30.715966) (xy 146.583146 -30.71876) (xy 146.558 -30.730444)
			(xy 146.55419 -30.731968) (xy 146.541998 -30.739588) (xy 146.510361 -30.750315) (xy 146.444585 -30.761943)
			(xy 146.411188 -30.762702) (xy 146.41068 -30.762702) (xy 146.38312 -30.762232) (xy 146.328562 -30.754385)
			(xy 146.275676 -30.738853) (xy 146.225539 -30.715953) (xy 146.179171 -30.686151) (xy 146.137516 -30.650053)
			(xy 146.101423 -30.608394) (xy 146.071626 -30.562023) (xy 146.048731 -30.511883) (xy 146.033206 -30.458995)
			(xy 146.025365 -30.404436) (xy 146.024854 -30.376876) (xy 146.025364 -30.348468) (xy 146.033719 -30.292269)
			(xy 146.050244 -30.237908) (xy 146.07458 -30.186567) (xy 146.106198 -30.139361) (xy 146.144411 -30.097315)
			(xy 146.166078 -30.078934) (xy 146.166586 -30.078426) (xy 146.172174 -30.0736) (xy 146.176238 -30.070298)
			(xy 146.179794 -30.066234) (xy 146.185636 -30.057344) (xy 146.19224 -30.04312) (xy 146.193905 -30.038667)
			(xy 146.195692 -30.029331) (xy 146.195796 -30.024578) (xy 146.195796 -29.967682) (xy 146.195654 -29.962242)
			(xy 146.19335 -29.951609) (xy 146.191224 -29.9466) (xy 146.187922 -29.939742) (xy 146.187922 -29.939234)
			(xy 146.181064 -29.925518) (xy 146.172682 -29.914088) (xy 146.167856 -29.909262) (xy 146.166078 -29.907738)
			(xy 146.14505 -29.8895) (xy 146.107984 -29.847976) (xy 146.07734 -29.80151) (xy 146.053767 -29.751087)
			(xy 146.037765 -29.697776) (xy 146.029672 -29.642706) (xy 146.029172 -29.614876) (xy 146.029659 -29.587625)
			(xy 146.037419 -29.533679) (xy 146.052776 -29.481386) (xy 146.075418 -29.431811) (xy 146.104884 -29.385962)
			(xy 146.140576 -29.344773) (xy 146.181765 -29.309082) (xy 146.227614 -29.279616) (xy 146.27719 -29.256974)
			(xy 146.329483 -29.241618) (xy 146.383429 -29.233859) (xy 146.41068 -29.233368) (xy 146.436049 -29.233783)
			(xy 146.48634 -29.240505) (xy 146.535296 -29.253834) (xy 146.582054 -29.273534) (xy 146.625788 -29.299258)
			(xy 146.665727 -29.330552) (xy 146.68373 -29.34843) (xy 146.685762 -29.350462) (xy 146.696684 -29.358082)
			(xy 146.727926 -29.372052) (xy 146.73961 -29.37129) (xy 146.739864 -29.37129) (xy 146.765264 -29.37002)
			(xy 146.773392 -29.369004) (xy 146.783533 -29.366307) (xy 146.800578 -29.354105) (xy 146.806412 -29.345382)
			(xy 146.806412 -29.345128) (xy 146.808444 -29.34208) (xy 146.80946 -29.340302) (xy 146.827828 -29.311482)
			(xy 146.870227 -29.257879) (xy 146.894042 -29.233368) (xy 149.332442 -26.794968) (xy 149.337426 -26.789467)
			(xy 149.344263 -26.776299) (xy 149.345904 -26.76906) (xy 149.34692 -26.759408) (xy 149.34692 -24.158194)
			(xy 149.347416 -24.124094) (xy 149.355333 -24.056354) (xy 149.371062 -23.989991) (xy 149.394388 -23.925903)
			(xy 149.424996 -23.864957) (xy 149.462473 -23.807976) (xy 149.506312 -23.755731) (xy 149.555919 -23.708928)
			(xy 149.610625 -23.668202) (xy 149.669689 -23.634101) (xy 149.732312 -23.607088) (xy 149.797648 -23.587528)
			(xy 149.864812 -23.575685) (xy 149.932898 -23.57172) (xy 150.000984 -23.575685) (xy 150.068148 -23.587528)
			(xy 150.133484 -23.607088) (xy 150.196107 -23.634101) (xy 150.255171 -23.668202) (xy 150.309877 -23.708928)
			(xy 150.359484 -23.755731) (xy 150.403323 -23.807976) (xy 150.4408 -23.864957) (xy 150.471408 -23.925903)
			(xy 150.494734 -23.989991) (xy 150.510463 -24.056354) (xy 150.51838 -24.124094) (xy 150.518876 -24.158194)
			(xy 150.518876 -24.807418) (xy 150.720296 -24.807418) (xy 150.724367 -24.751796) (xy 150.736493 -24.697359)
			(xy 150.756416 -24.645268) (xy 150.783712 -24.596633) (xy 150.817798 -24.55249) (xy 150.857947 -24.513781)
			(xy 150.903305 -24.48133) (xy 150.952905 -24.455829) (xy 151.005689 -24.437822) (xy 151.060532 -24.427692)
			(xy 151.116266 -24.425655) (xy 151.171703 -24.431755) (xy 151.22566 -24.445861) (xy 151.276989 -24.467673)
			(xy 151.324595 -24.496727) (xy 151.367463 -24.532402) (xy 151.40468 -24.573939) (xy 151.435453 -24.620452)
			(xy 151.459125 -24.670949) (xy 151.475193 -24.724356) (xy 151.483313 -24.779532) (xy 151.483822 -24.807418)
			(xy 151.483313 -24.835304) (xy 151.475193 -24.89048) (xy 151.459125 -24.943887) (xy 151.435453 -24.994384)
			(xy 151.40468 -25.040897) (xy 151.367463 -25.082434) (xy 151.324595 -25.118109) (xy 151.276989 -25.147163)
			(xy 151.22566 -25.168975) (xy 151.171703 -25.183081) (xy 151.116266 -25.189181) (xy 151.060532 -25.187144)
			(xy 151.005689 -25.177014) (xy 150.952905 -25.159007) (xy 150.903305 -25.133506) (xy 150.857947 -25.101055)
			(xy 150.817798 -25.062346) (xy 150.783712 -25.018203) (xy 150.756416 -24.969568) (xy 150.736493 -24.917477)
			(xy 150.724367 -24.86304) (xy 150.720296 -24.807418) (xy 150.518876 -24.807418) (xy 150.518876 -26.724356)
			(xy 150.521089 -26.727203) (xy 150.526188 -26.732303) (xy 150.529036 -26.734516) (xy 150.82393 -26.734516)
			(xy 150.82647 -26.734516) (xy 150.831829 -26.734084) (xy 150.8422 -26.73126) (xy 150.847044 -26.728928)
			(xy 150.870666 -26.716228) (xy 150.876508 -26.713434) (xy 150.877016 -26.71318) (xy 150.885906 -26.70556)
			(xy 150.889716 -26.700226) (xy 150.895099 -26.691797) (xy 150.899583 -26.672326) (xy 150.896334 -26.652611)
			(xy 150.885841 -26.635608) (xy 150.878032 -26.62936) (xy 150.87219 -26.625296) (xy 150.866094 -26.62301)
			(xy 150.839397 -26.612242) (xy 150.789327 -26.583845) (xy 150.744089 -26.54825) (xy 150.704709 -26.506265)
			(xy 150.67208 -26.458844) (xy 150.646942 -26.40706) (xy 150.629865 -26.352088) (xy 150.621237 -26.295176)
			(xy 150.62073 -26.266394) (xy 150.621216 -26.239143) (xy 150.628972 -26.185195) (xy 150.644327 -26.1329)
			(xy 150.666969 -26.083323) (xy 150.696435 -26.037473) (xy 150.732126 -25.996282) (xy 150.773317 -25.960591)
			(xy 150.819167 -25.931125) (xy 150.868744 -25.908483) (xy 150.921039 -25.893128) (xy 150.974987 -25.885372)
			(xy 151.029489 -25.885372) (xy 151.083437 -25.893128) (xy 151.135732 -25.908483) (xy 151.185309 -25.931125)
			(xy 151.231159 -25.960591) (xy 151.27235 -25.996282) (xy 151.308041 -26.037473) (xy 151.337507 -26.083323)
			(xy 151.360149 -26.1329) (xy 151.375504 -26.185195) (xy 151.38326 -26.239143) (xy 151.383746 -26.266394)
			(xy 151.383212 -26.29531) (xy 151.374485 -26.352481) (xy 151.35723 -26.407679) (xy 151.331842 -26.459641)
			(xy 151.298903 -26.507177) (xy 151.259167 -26.549197) (xy 151.23668 -26.567384) (xy 151.232108 -26.57094)
			(xy 151.22271 -26.58237) (xy 151.220417 -26.585227) (xy 151.216592 -26.591475) (xy 151.21509 -26.594816)
			(xy 151.21509 -26.595324) (xy 151.212979 -26.600591) (xy 151.210919 -26.611749) (xy 151.211026 -26.617422)
			(xy 151.212296 -26.643838) (xy 151.212296 -26.644346) (xy 151.21509 -26.690574) (xy 151.217884 -26.702766)
			(xy 151.22398 -26.713942) (xy 151.226967 -26.718654) (xy 151.234661 -26.726729) (xy 151.23922 -26.729944)
			(xy 151.240236 -26.730706) (xy 151.24176 -26.731468) (xy 151.266277 -26.746627) (xy 151.310968 -26.783032)
			(xy 151.349809 -26.825622) (xy 151.381953 -26.873468) (xy 151.4067 -26.925527) (xy 151.423509 -26.980663)
			(xy 151.432015 -27.037673) (xy 151.432514 -27.066494) (xy 151.432018 -27.094345) (xy 151.424092 -27.14948)
			(xy 151.4084 -27.202926) (xy 151.385262 -27.253594) (xy 151.355149 -27.300454) (xy 151.318674 -27.342552)
			(xy 151.276579 -27.379031) (xy 151.229721 -27.409148) (xy 151.179054 -27.432289) (xy 151.125609 -27.447985)
			(xy 151.070475 -27.455916) (xy 151.042624 -27.456384) (xy 151.04237 -27.456384) (xy 151.017049 -27.455982)
			(xy 150.966831 -27.449439) (xy 150.917878 -27.436467) (xy 150.87101 -27.417284) (xy 150.848822 -27.405076)
			(xy 150.84298 -27.401774) (xy 150.836884 -27.40025) (xy 150.82393 -27.398472) (xy 150.699216 -27.398472)
			(xy 150.689255 -27.398961) (xy 150.670832 -27.40655) (xy 150.663402 -27.413204) (xy 149.110192 -28.965906)
			(xy 148.953772 -29.12237) (xy 150.706836 -29.12237) (xy 150.706836 -28.25877) (xy 150.707326 -28.228786)
			(xy 150.715154 -28.16933) (xy 150.730675 -28.111405) (xy 150.753624 -28.056001) (xy 150.783608 -28.004067)
			(xy 150.820114 -27.956491) (xy 150.862519 -27.914086) (xy 150.910095 -27.87758) (xy 150.962029 -27.847596)
			(xy 151.017433 -27.824647) (xy 151.075358 -27.809126) (xy 151.134814 -27.801298) (xy 151.194782 -27.801298)
			(xy 151.254238 -27.809126) (xy 151.312163 -27.824647) (xy 151.367567 -27.847596) (xy 151.419501 -27.87758)
			(xy 151.467077 -27.914086) (xy 151.509482 -27.956491) (xy 151.545988 -28.004067) (xy 151.575972 -28.056001)
			(xy 151.598921 -28.111405) (xy 151.614442 -28.16933) (xy 151.62227 -28.228786) (xy 151.62276 -28.25877)
			(xy 151.62276 -29.12237) (xy 151.62227 -29.152354) (xy 151.614442 -29.21181) (xy 151.598921 -29.269735)
			(xy 151.575972 -29.325139) (xy 151.545988 -29.377073) (xy 151.509482 -29.424649) (xy 151.467077 -29.467054)
			(xy 151.419501 -29.50356) (xy 151.367567 -29.533544) (xy 151.312163 -29.556493) (xy 151.254238 -29.572014)
			(xy 151.194782 -29.579842) (xy 151.134814 -29.579842) (xy 151.075358 -29.572014) (xy 151.017433 -29.556493)
			(xy 150.962029 -29.533544) (xy 150.910095 -29.50356) (xy 150.862519 -29.467054) (xy 150.820114 -29.424649)
			(xy 150.783608 -29.377073) (xy 150.753624 -29.325139) (xy 150.730675 -29.269735) (xy 150.715154 -29.21181)
			(xy 150.707326 -29.152354) (xy 150.706836 -29.12237) (xy 148.953772 -29.12237) (xy 148.20011 -29.876242)
			(xy 148.195284 -29.88183) (xy 148.195284 -30.922468) (xy 148.852636 -30.922468) (xy 148.852636 -30.058868)
			(xy 148.853126 -30.028884) (xy 148.860954 -29.969428) (xy 148.876475 -29.911503) (xy 148.899424 -29.856099)
			(xy 148.929408 -29.804165) (xy 148.965914 -29.756589) (xy 149.008319 -29.714184) (xy 149.055895 -29.677678)
			(xy 149.107829 -29.647694) (xy 149.163233 -29.624745) (xy 149.221158 -29.609224) (xy 149.280614 -29.601396)
			(xy 149.340582 -29.601396) (xy 149.400038 -29.609224) (xy 149.457963 -29.624745) (xy 149.513367 -29.647694)
			(xy 149.565301 -29.677678) (xy 149.612877 -29.714184) (xy 149.655282 -29.756589) (xy 149.691788 -29.804165)
			(xy 149.721772 -29.856099) (xy 149.744721 -29.911503) (xy 149.760242 -29.969428) (xy 149.76807 -30.028884)
			(xy 149.76856 -30.058868) (xy 149.76856 -30.92069) (xy 163.589716 -30.92069) (xy 163.589716 -30.05709)
			(xy 163.590206 -30.027122) (xy 163.598029 -29.9677) (xy 163.613542 -29.909807) (xy 163.636478 -29.854434)
			(xy 163.666445 -29.802528) (xy 163.702932 -29.754978) (xy 163.745312 -29.712598) (xy 163.792862 -29.676111)
			(xy 163.844768 -29.646144) (xy 163.900141 -29.623208) (xy 163.958034 -29.607695) (xy 164.017456 -29.599872)
			(xy 164.077392 -29.599872) (xy 164.136814 -29.607695) (xy 164.194707 -29.623208) (xy 164.25008 -29.646144)
			(xy 164.301986 -29.676111) (xy 164.349536 -29.712598) (xy 164.391916 -29.754978) (xy 164.428403 -29.802528)
			(xy 164.45837 -29.854434) (xy 164.481306 -29.909807) (xy 164.496819 -29.9677) (xy 164.504642 -30.027122)
			(xy 164.505132 -30.05709) (xy 164.505132 -30.92069) (xy 164.504642 -30.950658) (xy 164.496819 -31.01008)
			(xy 164.481306 -31.067973) (xy 164.45837 -31.123346) (xy 164.428403 -31.175252) (xy 164.391916 -31.222802)
			(xy 164.349536 -31.265182) (xy 164.301986 -31.301669) (xy 164.25008 -31.331636) (xy 164.194707 -31.354572)
			(xy 164.136814 -31.370085) (xy 164.077392 -31.377908) (xy 164.017456 -31.377908) (xy 163.958034 -31.370085)
			(xy 163.900141 -31.354572) (xy 163.844768 -31.331636) (xy 163.792862 -31.301669) (xy 163.745312 -31.265182)
			(xy 163.702932 -31.222802) (xy 163.666445 -31.175252) (xy 163.636478 -31.123346) (xy 163.613542 -31.067973)
			(xy 163.598029 -31.01008) (xy 163.590206 -30.950658) (xy 163.589716 -30.92069) (xy 149.76856 -30.92069)
			(xy 149.76856 -30.922468) (xy 149.76807 -30.952452) (xy 149.760242 -31.011908) (xy 149.744721 -31.069833)
			(xy 149.721772 -31.125237) (xy 149.691788 -31.177171) (xy 149.655282 -31.224747) (xy 149.612877 -31.267152)
			(xy 149.565301 -31.303658) (xy 149.513367 -31.333642) (xy 149.457963 -31.356591) (xy 149.400038 -31.372112)
			(xy 149.340582 -31.37994) (xy 149.280614 -31.37994) (xy 149.221158 -31.372112) (xy 149.163233 -31.356591)
			(xy 149.107829 -31.333642) (xy 149.055895 -31.303658) (xy 149.008319 -31.267152) (xy 148.965914 -31.224747)
			(xy 148.929408 -31.177171) (xy 148.899424 -31.125237) (xy 148.876475 -31.069833) (xy 148.860954 -31.011908)
			(xy 148.853126 -30.952452) (xy 148.852636 -30.922468) (xy 148.195284 -30.922468) (xy 148.195284 -32.722312)
			(xy 150.706836 -32.722312) (xy 150.706836 -31.858712) (xy 150.707326 -31.828728) (xy 150.715154 -31.769272)
			(xy 150.730675 -31.711347) (xy 150.753624 -31.655943) (xy 150.783608 -31.604009) (xy 150.820114 -31.556433)
			(xy 150.862519 -31.514028) (xy 150.910095 -31.477522) (xy 150.962029 -31.447538) (xy 151.017433 -31.424589)
			(xy 151.075358 -31.409068) (xy 151.134814 -31.40124) (xy 151.194782 -31.40124) (xy 151.254238 -31.409068)
			(xy 151.312163 -31.424589) (xy 151.367567 -31.447538) (xy 151.419501 -31.477522) (xy 151.467077 -31.514028)
			(xy 151.509482 -31.556433) (xy 151.545988 -31.604009) (xy 151.575972 -31.655943) (xy 151.598921 -31.711347)
			(xy 151.614442 -31.769272) (xy 151.62227 -31.828728) (xy 151.62276 -31.858712) (xy 151.62276 -32.714184)
			(xy 160.947608 -32.714184) (xy 160.947608 -31.850584) (xy 160.948098 -31.820616) (xy 160.955921 -31.761194)
			(xy 160.971434 -31.703301) (xy 160.99437 -31.647928) (xy 161.024337 -31.596022) (xy 161.060824 -31.548472)
			(xy 161.103204 -31.506092) (xy 161.150754 -31.469605) (xy 161.20266 -31.439638) (xy 161.258033 -31.416702)
			(xy 161.315926 -31.401189) (xy 161.375348 -31.393366) (xy 161.435284 -31.393366) (xy 161.494706 -31.401189)
			(xy 161.552599 -31.416702) (xy 161.607972 -31.439638) (xy 161.659878 -31.469605) (xy 161.707428 -31.506092)
			(xy 161.749808 -31.548472) (xy 161.786295 -31.596022) (xy 161.816262 -31.647928) (xy 161.839198 -31.703301)
			(xy 161.854711 -31.761194) (xy 161.862534 -31.820616) (xy 161.863024 -31.850584) (xy 161.863024 -32.714184)
			(xy 161.862534 -32.744152) (xy 161.854711 -32.803574) (xy 161.839198 -32.861467) (xy 161.816262 -32.91684)
			(xy 161.786295 -32.968746) (xy 161.749808 -33.016296) (xy 161.707428 -33.058676) (xy 161.659878 -33.095163)
			(xy 161.607972 -33.12513) (xy 161.552599 -33.148066) (xy 161.494706 -33.163579) (xy 161.435284 -33.171402)
			(xy 161.375348 -33.171402) (xy 161.315926 -33.163579) (xy 161.258033 -33.148066) (xy 161.20266 -33.12513)
			(xy 161.150754 -33.095163) (xy 161.103204 -33.058676) (xy 161.060824 -33.016296) (xy 161.024337 -32.968746)
			(xy 160.99437 -32.91684) (xy 160.971434 -32.861467) (xy 160.955921 -32.803574) (xy 160.948098 -32.744152)
			(xy 160.947608 -32.714184) (xy 151.62276 -32.714184) (xy 151.62276 -32.722312) (xy 151.62227 -32.752296)
			(xy 151.614442 -32.811752) (xy 151.598921 -32.869677) (xy 151.575972 -32.925081) (xy 151.545988 -32.977015)
			(xy 151.509482 -33.024591) (xy 151.467077 -33.066996) (xy 151.419501 -33.103502) (xy 151.367567 -33.133486)
			(xy 151.312163 -33.156435) (xy 151.254238 -33.171956) (xy 151.194782 -33.179784) (xy 151.134814 -33.179784)
			(xy 151.075358 -33.171956) (xy 151.017433 -33.156435) (xy 150.962029 -33.133486) (xy 150.910095 -33.103502)
			(xy 150.862519 -33.066996) (xy 150.820114 -33.024591) (xy 150.783608 -32.977015) (xy 150.753624 -32.925081)
			(xy 150.730675 -32.869677) (xy 150.715154 -32.811752) (xy 150.707326 -32.752296) (xy 150.706836 -32.722312)
			(xy 148.195284 -32.722312) (xy 148.195284 -34.52241) (xy 148.852636 -34.52241) (xy 148.852636 -33.65881)
			(xy 148.853126 -33.628826) (xy 148.860954 -33.56937) (xy 148.876475 -33.511445) (xy 148.899424 -33.456041)
			(xy 148.929408 -33.404107) (xy 148.965914 -33.356531) (xy 149.008319 -33.314126) (xy 149.055895 -33.27762)
			(xy 149.107829 -33.247636) (xy 149.163233 -33.224687) (xy 149.221158 -33.209166) (xy 149.280614 -33.201338)
			(xy 149.340582 -33.201338) (xy 149.400038 -33.209166) (xy 149.457963 -33.224687) (xy 149.513367 -33.247636)
			(xy 149.565301 -33.27762) (xy 149.612877 -33.314126) (xy 149.655282 -33.356531) (xy 149.691788 -33.404107)
			(xy 149.721772 -33.456041) (xy 149.744721 -33.511445) (xy 149.760242 -33.56937) (xy 149.76807 -33.628826)
			(xy 149.76856 -33.65881) (xy 149.76856 -34.520886) (xy 163.589716 -34.520886) (xy 163.589716 -33.657286)
			(xy 163.590206 -33.627318) (xy 163.598029 -33.567896) (xy 163.613542 -33.510003) (xy 163.636478 -33.45463)
			(xy 163.666445 -33.402724) (xy 163.702932 -33.355174) (xy 163.745312 -33.312794) (xy 163.792862 -33.276307)
			(xy 163.844768 -33.24634) (xy 163.900141 -33.223404) (xy 163.958034 -33.207891) (xy 164.017456 -33.200068)
			(xy 164.077392 -33.200068) (xy 164.136814 -33.207891) (xy 164.194707 -33.223404) (xy 164.25008 -33.24634)
			(xy 164.301986 -33.276307) (xy 164.349536 -33.312794) (xy 164.391916 -33.355174) (xy 164.428403 -33.402724)
			(xy 164.45837 -33.45463) (xy 164.481306 -33.510003) (xy 164.496819 -33.567896) (xy 164.504642 -33.627318)
			(xy 164.505132 -33.657286) (xy 164.505132 -34.520886) (xy 164.504642 -34.550854) (xy 164.496819 -34.610276)
			(xy 164.481306 -34.668169) (xy 164.45837 -34.723542) (xy 164.428403 -34.775448) (xy 164.391916 -34.822998)
			(xy 164.349536 -34.865378) (xy 164.301986 -34.901865) (xy 164.25008 -34.931832) (xy 164.194707 -34.954768)
			(xy 164.136814 -34.970281) (xy 164.077392 -34.978104) (xy 164.017456 -34.978104) (xy 163.958034 -34.970281)
			(xy 163.900141 -34.954768) (xy 163.844768 -34.931832) (xy 163.792862 -34.901865) (xy 163.745312 -34.865378)
			(xy 163.702932 -34.822998) (xy 163.666445 -34.775448) (xy 163.636478 -34.723542) (xy 163.613542 -34.668169)
			(xy 163.598029 -34.610276) (xy 163.590206 -34.550854) (xy 163.589716 -34.520886) (xy 149.76856 -34.520886)
			(xy 149.76856 -34.52241) (xy 149.76807 -34.552394) (xy 149.760242 -34.61185) (xy 149.744721 -34.669775)
			(xy 149.721772 -34.725179) (xy 149.691788 -34.777113) (xy 149.655282 -34.824689) (xy 149.612877 -34.867094)
			(xy 149.565301 -34.9036) (xy 149.513367 -34.933584) (xy 149.457963 -34.956533) (xy 149.400038 -34.972054)
			(xy 149.340582 -34.979882) (xy 149.280614 -34.979882) (xy 149.221158 -34.972054) (xy 149.163233 -34.956533)
			(xy 149.107829 -34.933584) (xy 149.055895 -34.9036) (xy 149.008319 -34.867094) (xy 148.965914 -34.824689)
			(xy 148.929408 -34.777113) (xy 148.899424 -34.725179) (xy 148.876475 -34.669775) (xy 148.860954 -34.61185)
			(xy 148.853126 -34.552394) (xy 148.852636 -34.52241) (xy 148.195284 -34.52241) (xy 148.195284 -34.72434)
			(xy 148.195792 -34.73196) (xy 148.197245 -34.739795) (xy 148.20436 -34.754043) (xy 148.209762 -34.7599)
			(xy 149.13991 -35.689794) (xy 149.597618 -36.147502) (xy 149.604222 -36.149534) (xy 149.630034 -36.157633)
			(xy 149.679245 -36.180105) (xy 149.724786 -36.209304) (xy 149.765745 -36.244645) (xy 149.8013 -36.285419)
			(xy 149.830736 -36.330807) (xy 149.853464 -36.3799) (xy 149.869028 -36.431711) (xy 149.877114 -36.485201)
			(xy 149.87778 -36.512246) (xy 149.87778 -36.519104) (xy 149.877457 -36.536937) (xy 149.8739 -36.572429)
			(xy 149.870668 -36.58997) (xy 149.869144 -36.597336) (xy 149.868493 -36.60013) (xy 154.098251 -36.60013)
			(xy 154.102256 -36.512222) (xy 154.114239 -36.425042) (xy 154.134099 -36.339313) (xy 154.161674 -36.255745)
			(xy 154.196733 -36.175031) (xy 154.238986 -36.097839) (xy 154.288084 -36.02481) (xy 154.34362 -35.956548)
			(xy 154.405132 -35.893618) (xy 154.472113 -35.836544) (xy 154.544006 -35.785796) (xy 154.620215 -35.741796)
			(xy 154.70011 -35.704909) (xy 154.783029 -35.67544) (xy 154.868284 -35.653633) (xy 154.955168 -35.639669)
			(xy 155.042962 -35.633663) (xy 155.130939 -35.635667) (xy 155.218369 -35.645662) (xy 155.304528 -35.663566)
			(xy 155.388702 -35.68923) (xy 155.470193 -35.722443) (xy 155.548327 -35.762929) (xy 155.622455 -35.810351)
			(xy 155.691963 -35.864318) (xy 155.705262 -35.876738) (xy 160.817304 -35.876738) (xy 160.821375 -35.821116)
			(xy 160.833501 -35.766679) (xy 160.853424 -35.714588) (xy 160.88072 -35.665953) (xy 160.914806 -35.62181)
			(xy 160.954955 -35.583101) (xy 161.000313 -35.55065) (xy 161.049913 -35.525149) (xy 161.102697 -35.507142)
			(xy 161.15754 -35.497012) (xy 161.213274 -35.494975) (xy 161.268711 -35.501075) (xy 161.322668 -35.515181)
			(xy 161.373997 -35.536993) (xy 161.421603 -35.566047) (xy 161.464471 -35.601722) (xy 161.501688 -35.643259)
			(xy 161.532461 -35.689772) (xy 161.556133 -35.740269) (xy 161.572201 -35.793676) (xy 161.580321 -35.848852)
			(xy 161.58083 -35.876738) (xy 161.580321 -35.904624) (xy 161.572201 -35.9598) (xy 161.556133 -36.013207)
			(xy 161.532461 -36.063704) (xy 161.501688 -36.110217) (xy 161.464471 -36.151754) (xy 161.421603 -36.187429)
			(xy 161.373997 -36.216483) (xy 161.322668 -36.238295) (xy 161.268711 -36.252401) (xy 161.213274 -36.258501)
			(xy 161.15754 -36.256464) (xy 161.102697 -36.246334) (xy 161.049913 -36.228327) (xy 161.000313 -36.202826)
			(xy 160.954955 -36.170375) (xy 160.914806 -36.131666) (xy 160.88072 -36.087523) (xy 160.853424 -36.038888)
			(xy 160.833501 -35.986797) (xy 160.821375 -35.93236) (xy 160.817304 -35.876738) (xy 155.705262 -35.876738)
			(xy 155.756277 -35.924383) (xy 155.814861 -35.990047) (xy 155.867232 -36.060766) (xy 155.912955 -36.135954)
			(xy 155.951652 -36.214989) (xy 155.983001 -36.297215) (xy 156.006743 -36.381951) (xy 156.022681 -36.468495)
			(xy 156.026467 -36.50996) (xy 162.713922 -36.50996) (xy 162.717993 -36.454338) (xy 162.730119 -36.399901)
			(xy 162.750042 -36.34781) (xy 162.777338 -36.299175) (xy 162.811424 -36.255032) (xy 162.851573 -36.216323)
			(xy 162.896931 -36.183872) (xy 162.946531 -36.158371) (xy 162.999315 -36.140364) (xy 163.054158 -36.130234)
			(xy 163.109892 -36.128197) (xy 163.165329 -36.134297) (xy 163.219286 -36.148403) (xy 163.270615 -36.170215)
			(xy 163.318221 -36.199269) (xy 163.361089 -36.234944) (xy 163.398306 -36.276481) (xy 163.429079 -36.322994)
			(xy 163.452751 -36.373491) (xy 163.468819 -36.426898) (xy 163.476939 -36.482074) (xy 163.477448 -36.50996)
			(xy 163.476939 -36.537846) (xy 163.468819 -36.593022) (xy 163.452751 -36.646429) (xy 163.429079 -36.696926)
			(xy 163.398306 -36.743439) (xy 163.361089 -36.784976) (xy 163.318221 -36.820651) (xy 163.270615 -36.849705)
			(xy 163.219286 -36.871517) (xy 163.165329 -36.885623) (xy 163.109892 -36.891723) (xy 163.054158 -36.889686)
			(xy 162.999315 -36.879556) (xy 162.946531 -36.861549) (xy 162.896931 -36.836048) (xy 162.851573 -36.803597)
			(xy 162.811424 -36.764888) (xy 162.777338 -36.720745) (xy 162.750042 -36.67211) (xy 162.730119 -36.620019)
			(xy 162.717993 -36.565582) (xy 162.713922 -36.50996) (xy 156.026467 -36.50996) (xy 156.030683 -36.55613)
			(xy 156.031184 -36.60013) (xy 156.030683 -36.64413) (xy 156.022681 -36.731765) (xy 156.006743 -36.818309)
			(xy 155.983001 -36.903045) (xy 155.951652 -36.985271) (xy 155.912955 -37.064306) (xy 155.867232 -37.139494)
			(xy 155.814861 -37.210213) (xy 155.756277 -37.275877) (xy 155.691963 -37.335942) (xy 155.622455 -37.389909)
			(xy 155.548327 -37.437331) (xy 155.475321 -37.47516) (xy 159.859216 -37.47516) (xy 159.863287 -37.419538)
			(xy 159.875413 -37.365101) (xy 159.895336 -37.31301) (xy 159.922632 -37.264375) (xy 159.956718 -37.220232)
			(xy 159.996867 -37.181523) (xy 160.042225 -37.149072) (xy 160.091825 -37.123571) (xy 160.144609 -37.105564)
			(xy 160.199452 -37.095434) (xy 160.255186 -37.093397) (xy 160.310623 -37.099497) (xy 160.36458 -37.113603)
			(xy 160.415909 -37.135415) (xy 160.463515 -37.164469) (xy 160.506383 -37.200144) (xy 160.5436 -37.241681)
			(xy 160.574373 -37.288194) (xy 160.598045 -37.338691) (xy 160.614113 -37.392098) (xy 160.622233 -37.447274)
			(xy 160.622742 -37.47516) (xy 160.622233 -37.503046) (xy 160.614113 -37.558222) (xy 160.598045 -37.611629)
			(xy 160.574373 -37.662126) (xy 160.57422 -37.662358) (xy 162.048442 -37.662358) (xy 162.052513 -37.606736)
			(xy 162.064639 -37.552299) (xy 162.084562 -37.500208) (xy 162.111858 -37.451573) (xy 162.145944 -37.40743)
			(xy 162.186093 -37.368721) (xy 162.231451 -37.33627) (xy 162.281051 -37.310769) (xy 162.333835 -37.292762)
			(xy 162.388678 -37.282632) (xy 162.444412 -37.280595) (xy 162.499849 -37.286695) (xy 162.553806 -37.300801)
			(xy 162.605135 -37.322613) (xy 162.652741 -37.351667) (xy 162.695609 -37.387342) (xy 162.732826 -37.428879)
			(xy 162.763599 -37.475392) (xy 162.787271 -37.525889) (xy 162.803339 -37.579296) (xy 162.811459 -37.634472)
			(xy 162.811968 -37.662358) (xy 162.811459 -37.690244) (xy 162.803339 -37.74542) (xy 162.787271 -37.798827)
			(xy 162.763599 -37.849324) (xy 162.732826 -37.895837) (xy 162.695609 -37.937374) (xy 162.652741 -37.973049)
			(xy 162.605135 -38.002103) (xy 162.553806 -38.023915) (xy 162.499849 -38.038021) (xy 162.444412 -38.044121)
			(xy 162.388678 -38.042084) (xy 162.333835 -38.031954) (xy 162.281051 -38.013947) (xy 162.231451 -37.988446)
			(xy 162.186093 -37.955995) (xy 162.145944 -37.917286) (xy 162.111858 -37.873143) (xy 162.084562 -37.824508)
			(xy 162.064639 -37.772417) (xy 162.052513 -37.71798) (xy 162.048442 -37.662358) (xy 160.57422 -37.662358)
			(xy 160.5436 -37.708639) (xy 160.506383 -37.750176) (xy 160.463515 -37.785851) (xy 160.415909 -37.814905)
			(xy 160.36458 -37.836717) (xy 160.310623 -37.850823) (xy 160.255186 -37.856923) (xy 160.199452 -37.854886)
			(xy 160.144609 -37.844756) (xy 160.091825 -37.826749) (xy 160.042225 -37.801248) (xy 159.996867 -37.768797)
			(xy 159.956718 -37.730088) (xy 159.922632 -37.685945) (xy 159.895336 -37.63731) (xy 159.875413 -37.585219)
			(xy 159.863287 -37.530782) (xy 159.859216 -37.47516) (xy 155.475321 -37.47516) (xy 155.470193 -37.477817)
			(xy 155.388702 -37.51103) (xy 155.304528 -37.536694) (xy 155.218369 -37.554598) (xy 155.130939 -37.564593)
			(xy 155.042962 -37.566597) (xy 154.955168 -37.560591) (xy 154.868284 -37.546627) (xy 154.783029 -37.52482)
			(xy 154.70011 -37.495351) (xy 154.620215 -37.458464) (xy 154.544006 -37.414464) (xy 154.472113 -37.363716)
			(xy 154.405132 -37.306642) (xy 154.34362 -37.243712) (xy 154.288084 -37.17545) (xy 154.238986 -37.102421)
			(xy 154.196733 -37.025229) (xy 154.161674 -36.944515) (xy 154.134099 -36.860947) (xy 154.114239 -36.775218)
			(xy 154.102256 -36.688038) (xy 154.098251 -36.60013) (xy 149.868493 -36.60013) (xy 149.864974 -36.615244)
			(xy 149.85365 -36.650229) (xy 149.846538 -36.667186) (xy 149.846538 -36.667694) (xy 149.842728 -36.675822)
			(xy 149.838156 -36.685982) (xy 149.838156 -38.729952) (xy 165.800997 -38.729952) (xy 165.800997 -38.675448)
			(xy 165.808755 -38.6215) (xy 165.824111 -38.569205) (xy 165.846754 -38.519627) (xy 165.876222 -38.473777)
			(xy 165.911916 -38.432588) (xy 165.953109 -38.396898) (xy 165.998962 -38.367435) (xy 166.048542 -38.344797)
			(xy 166.100839 -38.329446) (xy 166.154788 -38.321695) (xy 166.18204 -38.321234) (xy 166.210343 -38.321755)
			(xy 166.266331 -38.330099) (xy 166.32047 -38.346628) (xy 166.371571 -38.370978) (xy 166.418512 -38.402614)
			(xy 166.46026 -38.440841) (xy 166.495899 -38.48482) (xy 166.510716 -38.50894) (xy 166.518326 -38.520966)
			(xy 166.538943 -38.540567) (xy 166.564172 -38.55371) (xy 166.59205 -38.55937) (xy 166.620407 -38.557108)
			(xy 166.647036 -38.547099) (xy 166.669862 -38.530123) (xy 166.678864 -38.5191) (xy 166.697076 -38.496245)
			(xy 166.739234 -38.45578) (xy 166.787064 -38.42221) (xy 166.839451 -38.396319) (xy 166.895171 -38.378712)
			(xy 166.952922 -38.3698) (xy 166.98214 -38.36924) (xy 167.009393 -38.369633) (xy 167.063343 -38.377395)
			(xy 167.11564 -38.392755) (xy 167.165218 -38.415402) (xy 167.211069 -38.444873) (xy 167.25226 -38.480569)
			(xy 167.287951 -38.521763) (xy 167.317418 -38.567617) (xy 167.340059 -38.617198) (xy 167.355414 -38.669496)
			(xy 167.36317 -38.723447) (xy 167.36317 -38.777953) (xy 167.355414 -38.831904) (xy 167.340059 -38.884202)
			(xy 167.317418 -38.933783) (xy 167.287951 -38.979637) (xy 167.25226 -39.020831) (xy 167.211069 -39.056527)
			(xy 167.165218 -39.085998) (xy 167.11564 -39.108645) (xy 167.063343 -39.124005) (xy 167.009393 -39.131767)
			(xy 166.98214 -39.132256) (xy 166.953836 -39.131756) (xy 166.897847 -39.123408) (xy 166.843707 -39.106877)
			(xy 166.792606 -39.082523) (xy 166.745666 -39.050884) (xy 166.703918 -39.012653) (xy 166.668281 -38.968671)
			(xy 166.653464 -38.94455) (xy 166.64588 -38.932507) (xy 166.625257 -38.912906) (xy 166.600023 -38.899765)
			(xy 166.57214 -38.894107) (xy 166.543779 -38.896373) (xy 166.517147 -38.906385) (xy 166.494319 -38.923365)
			(xy 166.485316 -38.93439) (xy 166.467113 -38.957252) (xy 166.424954 -38.997717) (xy 166.377122 -39.031287)
			(xy 166.324733 -39.057176) (xy 166.269012 -39.074781) (xy 166.211258 -39.083691) (xy 166.18204 -39.08425)
			(xy 166.154788 -39.083705) (xy 166.100839 -39.075954) (xy 166.048542 -39.060603) (xy 165.998962 -39.037965)
			(xy 165.953109 -39.008502) (xy 165.911916 -38.972812) (xy 165.876222 -38.931623) (xy 165.846754 -38.885773)
			(xy 165.824111 -38.836195) (xy 165.808755 -38.7839) (xy 165.800997 -38.729952) (xy 149.838156 -38.729952)
			(xy 149.838156 -38.940994) (xy 149.842728 -38.946328) (xy 152.165151 -41.268751) (xy 157.28365 -41.268751)
			(xy 157.28365 -41.214249) (xy 157.291406 -41.160301) (xy 157.30676 -41.108005) (xy 157.3294 -41.058427)
			(xy 157.358864 -41.012576) (xy 157.394554 -40.971383) (xy 157.435742 -40.935689) (xy 157.48159 -40.90622)
			(xy 157.531166 -40.883575) (xy 157.58346 -40.868215) (xy 157.637407 -40.860453) (xy 157.664658 -40.859964)
			(xy 157.693398 -40.860462) (xy 157.750226 -40.869092) (xy 157.805116 -40.886149) (xy 157.856828 -40.911246)
			(xy 157.90419 -40.943815) (xy 157.925516 -40.963088) (xy 157.932374 -40.969692) (xy 157.950408 -40.976804)
			(xy 158.039308 -40.976804) (xy 158.057342 -40.969692) (xy 158.0642 -40.963088) (xy 158.085527 -40.943818)
			(xy 158.13289 -40.911253) (xy 158.184601 -40.886162) (xy 158.239492 -40.869112) (xy 158.296319 -40.86049)
			(xy 158.353797 -40.86049) (xy 158.410624 -40.869112) (xy 158.465515 -40.886162) (xy 158.517226 -40.911253)
			(xy 158.564589 -40.943818) (xy 158.585916 -40.963088) (xy 158.592774 -40.969692) (xy 158.610808 -40.976804)
			(xy 158.699708 -40.976804) (xy 158.717742 -40.969692) (xy 158.7246 -40.963088) (xy 158.745911 -40.943798)
			(xy 158.793276 -40.911233) (xy 158.844992 -40.886143) (xy 158.899887 -40.869097) (xy 158.956718 -40.860481)
			(xy 158.985458 -40.859964) (xy 159.012711 -40.86048) (xy 159.066662 -40.868232) (xy 159.118961 -40.883583)
			(xy 159.168543 -40.906222) (xy 159.214398 -40.935686) (xy 159.255593 -40.971377) (xy 159.291288 -41.012568)
			(xy 159.320758 -41.05842) (xy 159.343402 -41.107999) (xy 159.358759 -41.160297) (xy 159.366517 -41.214247)
			(xy 159.366517 -41.268753) (xy 159.358759 -41.322703) (xy 159.343402 -41.375001) (xy 159.320758 -41.42458)
			(xy 159.291288 -41.470432) (xy 159.255593 -41.511623) (xy 159.214398 -41.547314) (xy 159.168543 -41.576778)
			(xy 159.118961 -41.599417) (xy 159.066662 -41.614768) (xy 159.012711 -41.62252) (xy 158.985458 -41.62298)
			(xy 158.956719 -41.62246) (xy 158.899893 -41.613834) (xy 158.845003 -41.596781) (xy 158.793291 -41.571689)
			(xy 158.745928 -41.539126) (xy 158.7246 -41.519856) (xy 158.717742 -41.513252) (xy 158.699708 -41.50614)
			(xy 158.610808 -41.50614) (xy 158.592774 -41.513252) (xy 158.585916 -41.519856) (xy 158.564589 -41.539126)
			(xy 158.517226 -41.571691) (xy 158.465515 -41.596782) (xy 158.410624 -41.613832) (xy 158.353797 -41.622454)
			(xy 158.296319 -41.622454) (xy 158.239492 -41.613832) (xy 158.184601 -41.596782) (xy 158.13289 -41.571691)
			(xy 158.085527 -41.539126) (xy 158.0642 -41.519856) (xy 158.057342 -41.513252) (xy 158.039308 -41.50614)
			(xy 157.950408 -41.50614) (xy 157.932374 -41.513252) (xy 157.925516 -41.519856) (xy 157.904205 -41.539146)
			(xy 157.856839 -41.57171) (xy 157.805123 -41.596799) (xy 157.750229 -41.613845) (xy 157.693398 -41.622462)
			(xy 157.664658 -41.62298) (xy 157.637407 -41.622547) (xy 157.58346 -41.614785) (xy 157.531166 -41.599425)
			(xy 157.48159 -41.57678) (xy 157.435742 -41.547311) (xy 157.394554 -41.511617) (xy 157.358864 -41.470424)
			(xy 157.3294 -41.424573) (xy 157.30676 -41.374995) (xy 157.291406 -41.322699) (xy 157.28365 -41.268751)
			(xy 152.165151 -41.268751) (xy 154.201622 -43.305222) (xy 160.40735 -43.305222) (xy 160.407817 -43.277852)
			(xy 160.415633 -43.223672) (xy 160.431121 -43.171169) (xy 160.453963 -43.121422) (xy 160.483688 -43.075455)
			(xy 160.50133 -43.054524) (xy 160.501584 -43.05427) (xy 160.507146 -43.047166) (xy 160.513408 -43.030263)
			(xy 160.513776 -43.02125) (xy 160.513776 -42.954194) (xy 160.513427 -42.945176) (xy 160.507175 -42.928259)
			(xy 160.501584 -42.921174) (xy 160.50133 -42.921174) (xy 160.50133 -42.92092) (xy 160.483691 -42.899987)
			(xy 160.453979 -42.854015) (xy 160.431142 -42.804268) (xy 160.415651 -42.751767) (xy 160.407823 -42.697591)
			(xy 160.40735 -42.670222) (xy 160.4079 -42.641484) (xy 160.416519 -42.584659) (xy 160.433563 -42.529769)
			(xy 160.458648 -42.478057) (xy 160.491207 -42.430692) (xy 160.510474 -42.409364) (xy 160.517078 -42.402506)
			(xy 160.52419 -42.384472) (xy 160.52419 -42.295572) (xy 160.517078 -42.277538) (xy 160.510474 -42.27068)
			(xy 160.491227 -42.249333) (xy 160.458665 -42.201973) (xy 160.433576 -42.150264) (xy 160.416527 -42.095377)
			(xy 160.407903 -42.038553) (xy 160.407901 -41.981079) (xy 160.41652 -41.924255) (xy 160.433564 -41.869366)
			(xy 160.458649 -41.817655) (xy 160.491207 -41.770292) (xy 160.510474 -41.748964) (xy 160.517078 -41.742106)
			(xy 160.52419 -41.724072) (xy 160.52419 -41.635172) (xy 160.517078 -41.617138) (xy 160.510474 -41.61028)
			(xy 160.49122 -41.588939) (xy 160.45865 -41.541581) (xy 160.433554 -41.489873) (xy 160.416499 -41.434985)
			(xy 160.407873 -41.37816) (xy 160.40735 -41.349422) (xy 160.407836 -41.322171) (xy 160.415592 -41.268223)
			(xy 160.430947 -41.215928) (xy 160.453589 -41.166351) (xy 160.483055 -41.120501) (xy 160.518746 -41.07931)
			(xy 160.559937 -41.043619) (xy 160.605787 -41.014153) (xy 160.655364 -40.991511) (xy 160.707659 -40.976156)
			(xy 160.761607 -40.9684) (xy 160.816109 -40.9684) (xy 160.83923 -40.971724) (xy 168.694098 -40.971724)
			(xy 168.698169 -40.916102) (xy 168.710295 -40.861665) (xy 168.730218 -40.809574) (xy 168.757514 -40.760939)
			(xy 168.7916 -40.716796) (xy 168.831749 -40.678087) (xy 168.877107 -40.645636) (xy 168.926707 -40.620135)
			(xy 168.979491 -40.602128) (xy 169.034334 -40.591998) (xy 169.090068 -40.589961) (xy 169.145505 -40.596061)
			(xy 169.199462 -40.610167) (xy 169.250791 -40.631979) (xy 169.298397 -40.661033) (xy 169.341265 -40.696708)
			(xy 169.378482 -40.738245) (xy 169.409255 -40.784758) (xy 169.432927 -40.835255) (xy 169.448995 -40.888662)
			(xy 169.457115 -40.943838) (xy 169.457624 -40.971724) (xy 169.457115 -40.99961) (xy 169.448995 -41.054786)
			(xy 169.432927 -41.108193) (xy 169.409255 -41.15869) (xy 169.378482 -41.205203) (xy 169.341265 -41.24674)
			(xy 169.298397 -41.282415) (xy 169.250791 -41.311469) (xy 169.199462 -41.333281) (xy 169.145505 -41.347387)
			(xy 169.090068 -41.353487) (xy 169.034334 -41.35145) (xy 168.979491 -41.34132) (xy 168.926707 -41.323313)
			(xy 168.877107 -41.297812) (xy 168.831749 -41.265361) (xy 168.7916 -41.226652) (xy 168.757514 -41.182509)
			(xy 168.730218 -41.133874) (xy 168.710295 -41.081783) (xy 168.698169 -41.027346) (xy 168.694098 -40.971724)
			(xy 160.83923 -40.971724) (xy 160.870057 -40.976156) (xy 160.922352 -40.991511) (xy 160.971929 -41.014153)
			(xy 161.017779 -41.043619) (xy 161.05897 -41.07931) (xy 161.094661 -41.120501) (xy 161.124127 -41.166351)
			(xy 161.146769 -41.215928) (xy 161.162124 -41.268223) (xy 161.16988 -41.322171) (xy 161.170366 -41.349422)
			(xy 161.169838 -41.378161) (xy 161.161214 -41.434987) (xy 161.144164 -41.489877) (xy 161.119074 -41.541589)
			(xy 161.086511 -41.588952) (xy 161.067242 -41.61028) (xy 161.060638 -41.617138) (xy 161.053526 -41.635172)
			(xy 161.053526 -41.724072) (xy 161.060638 -41.742106) (xy 161.067242 -41.748964) (xy 161.086536 -41.770271)
			(xy 161.119103 -41.817636) (xy 161.144196 -41.869351) (xy 161.161246 -41.924245) (xy 161.169868 -41.981076)
			(xy 161.169865 -42.038557) (xy 161.161239 -42.095387) (xy 161.144184 -42.150279) (xy 161.119087 -42.201992)
			(xy 161.086516 -42.249354) (xy 161.067242 -42.27068) (xy 161.060638 -42.277538) (xy 161.053526 -42.295572)
			(xy 161.053526 -42.384472) (xy 161.060638 -42.402506) (xy 161.067242 -42.409364) (xy 161.08652 -42.430685)
			(xy 161.119086 -42.478048) (xy 161.144177 -42.529761) (xy 161.161226 -42.584654) (xy 161.169847 -42.641483)
			(xy 161.170366 -42.670222) (xy 161.169921 -42.697593) (xy 161.162099 -42.751773) (xy 161.146606 -42.804277)
			(xy 161.126049 -42.849038) (xy 162.992052 -42.849038) (xy 162.996123 -42.793416) (xy 163.008249 -42.738979)
			(xy 163.028172 -42.686888) (xy 163.055468 -42.638253) (xy 163.089554 -42.59411) (xy 163.129703 -42.555401)
			(xy 163.175061 -42.52295) (xy 163.224661 -42.497449) (xy 163.277445 -42.479442) (xy 163.332288 -42.469312)
			(xy 163.388022 -42.467275) (xy 163.443459 -42.473375) (xy 163.497416 -42.487481) (xy 163.548745 -42.509293)
			(xy 163.596351 -42.538347) (xy 163.639219 -42.574022) (xy 163.676436 -42.615559) (xy 163.707209 -42.662072)
			(xy 163.730881 -42.712569) (xy 163.746949 -42.765976) (xy 163.755069 -42.821152) (xy 163.75543 -42.84091)
			(xy 169.033188 -42.84091) (xy 169.037259 -42.785288) (xy 169.049385 -42.730851) (xy 169.069308 -42.67876)
			(xy 169.096604 -42.630125) (xy 169.13069 -42.585982) (xy 169.170839 -42.547273) (xy 169.216197 -42.514822)
			(xy 169.265797 -42.489321) (xy 169.318581 -42.471314) (xy 169.373424 -42.461184) (xy 169.429158 -42.459147)
			(xy 169.484595 -42.465247) (xy 169.538552 -42.479353) (xy 169.589881 -42.501165) (xy 169.637487 -42.530219)
			(xy 169.680355 -42.565894) (xy 169.717572 -42.607431) (xy 169.748345 -42.653944) (xy 169.772017 -42.704441)
			(xy 169.788085 -42.757848) (xy 169.796205 -42.813024) (xy 169.796714 -42.84091) (xy 169.796205 -42.868796)
			(xy 169.788085 -42.923972) (xy 169.772017 -42.977379) (xy 169.748345 -43.027876) (xy 169.717572 -43.074389)
			(xy 169.680355 -43.115926) (xy 169.637487 -43.151601) (xy 169.589881 -43.180655) (xy 169.538552 -43.202467)
			(xy 169.484595 -43.216573) (xy 169.429158 -43.222673) (xy 169.373424 -43.220636) (xy 169.318581 -43.210506)
			(xy 169.265797 -43.192499) (xy 169.216197 -43.166998) (xy 169.170839 -43.134547) (xy 169.13069 -43.095838)
			(xy 169.096604 -43.051695) (xy 169.069308 -43.00306) (xy 169.049385 -42.950969) (xy 169.037259 -42.896532)
			(xy 169.033188 -42.84091) (xy 163.75543 -42.84091) (xy 163.755578 -42.849038) (xy 163.755069 -42.876924)
			(xy 163.746949 -42.9321) (xy 163.730881 -42.985507) (xy 163.707209 -43.036004) (xy 163.676436 -43.082517)
			(xy 163.639219 -43.124054) (xy 163.596351 -43.159729) (xy 163.548745 -43.188783) (xy 163.497416 -43.210595)
			(xy 163.443459 -43.224701) (xy 163.388022 -43.230801) (xy 163.332288 -43.228764) (xy 163.277445 -43.218634)
			(xy 163.224661 -43.200627) (xy 163.175061 -43.175126) (xy 163.129703 -43.142675) (xy 163.089554 -43.103966)
			(xy 163.055468 -43.059823) (xy 163.028172 -43.011188) (xy 163.008249 -42.959097) (xy 162.996123 -42.90466)
			(xy 162.992052 -42.849038) (xy 161.126049 -42.849038) (xy 161.123759 -42.854024) (xy 161.09403 -42.899989)
			(xy 161.076386 -42.92092) (xy 161.076132 -42.921174) (xy 161.070542 -42.928258) (xy 161.064299 -42.945177)
			(xy 161.06394 -42.954194) (xy 161.06394 -43.02125) (xy 161.064312 -43.030266) (xy 161.070548 -43.047183)
			(xy 161.076132 -43.05427) (xy 161.076386 -43.05427) (xy 161.076386 -43.054524) (xy 161.094001 -43.075476)
			(xy 161.123717 -43.121443) (xy 161.146558 -43.171185) (xy 161.162054 -43.223682) (xy 161.169889 -43.277854)
			(xy 161.170366 -43.305222) (xy 161.16988 -43.332473) (xy 161.162124 -43.386421) (xy 161.146769 -43.438716)
			(xy 161.124127 -43.488293) (xy 161.094661 -43.534143) (xy 161.05897 -43.575334) (xy 161.017779 -43.611025)
			(xy 160.971929 -43.640491) (xy 160.922352 -43.663133) (xy 160.870057 -43.678488) (xy 160.816109 -43.686244)
			(xy 160.761607 -43.686244) (xy 160.707659 -43.678488) (xy 160.655364 -43.663133) (xy 160.605787 -43.640491)
			(xy 160.559937 -43.611025) (xy 160.518746 -43.575334) (xy 160.483055 -43.534143) (xy 160.453589 -43.488293)
			(xy 160.430947 -43.438716) (xy 160.415592 -43.386421) (xy 160.407836 -43.332473) (xy 160.40735 -43.305222)
			(xy 154.201622 -43.305222) (xy 154.63266 -43.73626) (xy 162.31311 -43.73626) (xy 162.317181 -43.680638)
			(xy 162.329307 -43.626201) (xy 162.34923 -43.57411) (xy 162.376526 -43.525475) (xy 162.410612 -43.481332)
			(xy 162.450761 -43.442623) (xy 162.496119 -43.410172) (xy 162.545719 -43.384671) (xy 162.598503 -43.366664)
			(xy 162.653346 -43.356534) (xy 162.70908 -43.354497) (xy 162.764517 -43.360597) (xy 162.818474 -43.374703)
			(xy 162.869803 -43.396515) (xy 162.917409 -43.425569) (xy 162.960277 -43.461244) (xy 162.997494 -43.502781)
			(xy 163.028267 -43.549294) (xy 163.051939 -43.599791) (xy 163.068007 -43.653198) (xy 163.076127 -43.708374)
			(xy 163.076636 -43.73626) (xy 163.076127 -43.764146) (xy 163.068007 -43.819322) (xy 163.056698 -43.85691)
			(xy 166.819832 -43.85691) (xy 166.823903 -43.801288) (xy 166.836029 -43.746851) (xy 166.855952 -43.69476)
			(xy 166.883248 -43.646125) (xy 166.917334 -43.601982) (xy 166.957483 -43.563273) (xy 167.002841 -43.530822)
			(xy 167.052441 -43.505321) (xy 167.105225 -43.487314) (xy 167.160068 -43.477184) (xy 167.215802 -43.475147)
			(xy 167.271239 -43.481247) (xy 167.325196 -43.495353) (xy 167.376525 -43.517165) (xy 167.424131 -43.546219)
			(xy 167.466999 -43.581894) (xy 167.504216 -43.623431) (xy 167.534989 -43.669944) (xy 167.558661 -43.720441)
			(xy 167.574729 -43.773848) (xy 167.582849 -43.829024) (xy 167.583358 -43.85691) (xy 167.582849 -43.884796)
			(xy 167.574729 -43.939972) (xy 167.558661 -43.993379) (xy 167.534989 -44.043876) (xy 167.504216 -44.090389)
			(xy 167.466999 -44.131926) (xy 167.424131 -44.167601) (xy 167.376525 -44.196655) (xy 167.325196 -44.218467)
			(xy 167.271239 -44.232573) (xy 167.215802 -44.238673) (xy 167.160068 -44.236636) (xy 167.105225 -44.226506)
			(xy 167.052441 -44.208499) (xy 167.002841 -44.182998) (xy 166.957483 -44.150547) (xy 166.917334 -44.111838)
			(xy 166.883248 -44.067695) (xy 166.855952 -44.01906) (xy 166.836029 -43.966969) (xy 166.823903 -43.912532)
			(xy 166.819832 -43.85691) (xy 163.056698 -43.85691) (xy 163.051939 -43.872729) (xy 163.028267 -43.923226)
			(xy 162.997494 -43.969739) (xy 162.960277 -44.011276) (xy 162.917409 -44.046951) (xy 162.869803 -44.076005)
			(xy 162.818474 -44.097817) (xy 162.764517 -44.111923) (xy 162.70908 -44.118023) (xy 162.653346 -44.115986)
			(xy 162.598503 -44.105856) (xy 162.545719 -44.087849) (xy 162.496119 -44.062348) (xy 162.450761 -44.029897)
			(xy 162.410612 -43.991188) (xy 162.376526 -43.947045) (xy 162.34923 -43.89841) (xy 162.329307 -43.846319)
			(xy 162.317181 -43.791882) (xy 162.31311 -43.73626) (xy 154.63266 -43.73626) (xy 154.706574 -43.810174)
			(xy 154.70759 -43.81119) (xy 154.72664 -43.830748) (xy 154.741856 -43.848499) (xy 154.76753 -43.88757)
			(xy 154.787284 -43.929945) (xy 154.8007 -43.974731) (xy 154.807497 -44.020986) (xy 154.80792 -44.044362)
			(xy 154.80792 -44.322238) (xy 154.808936 -44.33189) (xy 154.810568 -44.339131) (xy 154.817417 -44.352293)
			(xy 154.822398 -44.357798) (xy 154.862276 -44.397676) (xy 154.880309 -44.416447) (xy 154.91089 -44.458563)
			(xy 154.934517 -44.504939) (xy 154.950612 -44.554437) (xy 154.958777 -44.60584) (xy 154.959304 -44.631864)
			(xy 154.959304 -45.114464) (xy 162.165536 -45.114464) (xy 162.169607 -45.058842) (xy 162.181733 -45.004405)
			(xy 162.201656 -44.952314) (xy 162.228952 -44.903679) (xy 162.263038 -44.859536) (xy 162.303187 -44.820827)
			(xy 162.348545 -44.788376) (xy 162.398145 -44.762875) (xy 162.450929 -44.744868) (xy 162.505772 -44.734738)
			(xy 162.561506 -44.732701) (xy 162.616943 -44.738801) (xy 162.6709 -44.752907) (xy 162.722229 -44.774719)
			(xy 162.769835 -44.803773) (xy 162.812703 -44.839448) (xy 162.842685 -44.87291) (xy 169.033188 -44.87291)
			(xy 169.037259 -44.817288) (xy 169.049385 -44.762851) (xy 169.069308 -44.71076) (xy 169.096604 -44.662125)
			(xy 169.13069 -44.617982) (xy 169.170839 -44.579273) (xy 169.216197 -44.546822) (xy 169.265797 -44.521321)
			(xy 169.318581 -44.503314) (xy 169.373424 -44.493184) (xy 169.429158 -44.491147) (xy 169.484595 -44.497247)
			(xy 169.538552 -44.511353) (xy 169.589881 -44.533165) (xy 169.637487 -44.562219) (xy 169.680355 -44.597894)
			(xy 169.717572 -44.639431) (xy 169.748345 -44.685944) (xy 169.772017 -44.736441) (xy 169.788085 -44.789848)
			(xy 169.796205 -44.845024) (xy 169.796714 -44.87291) (xy 169.796205 -44.900796) (xy 169.788085 -44.955972)
			(xy 169.772017 -45.009379) (xy 169.748345 -45.059876) (xy 169.717572 -45.106389) (xy 169.680355 -45.147926)
			(xy 169.637487 -45.183601) (xy 169.589881 -45.212655) (xy 169.538552 -45.234467) (xy 169.484595 -45.248573)
			(xy 169.429158 -45.254673) (xy 169.373424 -45.252636) (xy 169.318581 -45.242506) (xy 169.265797 -45.224499)
			(xy 169.216197 -45.198998) (xy 169.170839 -45.166547) (xy 169.13069 -45.127838) (xy 169.096604 -45.083695)
			(xy 169.069308 -45.03506) (xy 169.049385 -44.982969) (xy 169.037259 -44.928532) (xy 169.033188 -44.87291)
			(xy 162.842685 -44.87291) (xy 162.84992 -44.880985) (xy 162.880693 -44.927498) (xy 162.904365 -44.977995)
			(xy 162.920433 -45.031402) (xy 162.928553 -45.086578) (xy 162.929062 -45.114464) (xy 162.928553 -45.14235)
			(xy 162.920433 -45.197526) (xy 162.904365 -45.250933) (xy 162.880693 -45.30143) (xy 162.84992 -45.347943)
			(xy 162.844278 -45.35424) (xy 166.80383 -45.35424) (xy 166.807901 -45.298618) (xy 166.820027 -45.244181)
			(xy 166.83995 -45.19209) (xy 166.867246 -45.143455) (xy 166.901332 -45.099312) (xy 166.941481 -45.060603)
			(xy 166.986839 -45.028152) (xy 167.036439 -45.002651) (xy 167.089223 -44.984644) (xy 167.144066 -44.974514)
			(xy 167.1998 -44.972477) (xy 167.255237 -44.978577) (xy 167.309194 -44.992683) (xy 167.360523 -45.014495)
			(xy 167.408129 -45.043549) (xy 167.450997 -45.079224) (xy 167.488214 -45.120761) (xy 167.518987 -45.167274)
			(xy 167.542659 -45.217771) (xy 167.558727 -45.271178) (xy 167.566847 -45.326354) (xy 167.567356 -45.35424)
			(xy 167.566847 -45.382126) (xy 167.558727 -45.437302) (xy 167.542659 -45.490709) (xy 167.518987 -45.541206)
			(xy 167.488214 -45.587719) (xy 167.450997 -45.629256) (xy 167.408129 -45.664931) (xy 167.360523 -45.693985)
			(xy 167.309194 -45.715797) (xy 167.255237 -45.729903) (xy 167.1998 -45.736003) (xy 167.144066 -45.733966)
			(xy 167.089223 -45.723836) (xy 167.036439 -45.705829) (xy 166.986839 -45.680328) (xy 166.941481 -45.647877)
			(xy 166.901332 -45.609168) (xy 166.867246 -45.565025) (xy 166.83995 -45.51639) (xy 166.820027 -45.464299)
			(xy 166.807901 -45.409862) (xy 166.80383 -45.35424) (xy 162.844278 -45.35424) (xy 162.812703 -45.38948)
			(xy 162.769835 -45.425155) (xy 162.722229 -45.454209) (xy 162.6709 -45.476021) (xy 162.616943 -45.490127)
			(xy 162.561506 -45.496227) (xy 162.505772 -45.49419) (xy 162.450929 -45.48406) (xy 162.398145 -45.466053)
			(xy 162.348545 -45.440552) (xy 162.303187 -45.408101) (xy 162.263038 -45.369392) (xy 162.228952 -45.325249)
			(xy 162.201656 -45.276614) (xy 162.181733 -45.224523) (xy 162.169607 -45.170086) (xy 162.165536 -45.114464)
			(xy 154.959304 -45.114464) (xy 154.959304 -46.082204) (xy 160.152588 -46.082204) (xy 160.153081 -46.054953)
			(xy 160.160837 -46.001006) (xy 160.176192 -45.948711) (xy 160.198832 -45.899134) (xy 160.228298 -45.853284)
			(xy 160.263988 -45.812094) (xy 160.305178 -45.776402) (xy 160.351027 -45.746936) (xy 160.400604 -45.724295)
			(xy 160.452898 -45.708939) (xy 160.506845 -45.701182) (xy 160.534096 -45.700696) (xy 160.560998 -45.701161)
			(xy 160.614268 -45.708733) (xy 160.665947 -45.723711) (xy 160.715008 -45.745801) (xy 160.760481 -45.774563)
			(xy 160.801462 -45.809427) (xy 160.83714 -45.849702) (xy 160.852358 -45.871892) (xy 160.85947 -45.882814)
			(xy 160.88233 -45.894752) (xy 160.994598 -45.89272) (xy 161.01695 -45.879766) (xy 161.023808 -45.86859)
			(xy 161.038738 -45.844994) (xy 161.074415 -45.802042) (xy 161.115972 -45.764749) (xy 161.162521 -45.733911)
			(xy 161.213067 -45.710187) (xy 161.266531 -45.694083) (xy 161.321772 -45.685943) (xy 161.34969 -45.685456)
			(xy 161.376683 -45.685923) (xy 161.430131 -45.693527) (xy 161.481974 -45.708586) (xy 161.531179 -45.730799)
			(xy 161.576763 -45.759722) (xy 161.597594 -45.776896) (xy 161.605722 -45.784008) (xy 161.626296 -45.790104)
			(xy 161.71164 -45.779182) (xy 161.72218 -45.777388) (xy 161.740465 -45.766348) (xy 161.746946 -45.757846)
			(xy 161.762277 -45.736599) (xy 161.797868 -45.698146) (xy 161.838389 -45.664929) (xy 161.883076 -45.637572)
			(xy 161.931087 -45.616592) (xy 161.98152 -45.602382) (xy 162.033422 -45.595211) (xy 162.05962 -45.594778)
			(xy 162.086869 -45.595294) (xy 162.140813 -45.603052) (xy 162.193103 -45.618408) (xy 162.242676 -45.64105)
			(xy 162.288522 -45.670516) (xy 162.329708 -45.706206) (xy 162.365396 -45.747394) (xy 162.39486 -45.793242)
			(xy 162.417499 -45.842816) (xy 162.432852 -45.895107) (xy 162.440608 -45.949051) (xy 162.440608 -46.003549)
			(xy 162.432852 -46.057493) (xy 162.417499 -46.109784) (xy 162.39486 -46.159358) (xy 162.365396 -46.205206)
			(xy 162.329708 -46.246394) (xy 162.288522 -46.282084) (xy 162.242676 -46.31155) (xy 162.193103 -46.334192)
			(xy 162.140813 -46.349548) (xy 162.086869 -46.357306) (xy 162.05962 -46.357794) (xy 162.032628 -46.357309)
			(xy 161.979181 -46.349707) (xy 161.927338 -46.334652) (xy 161.878133 -46.312444) (xy 161.832548 -46.283525)
			(xy 161.811716 -46.266354) (xy 161.803588 -46.259242) (xy 161.783014 -46.253146) (xy 161.69767 -46.264068)
			(xy 161.687124 -46.265835) (xy 161.668843 -46.276896) (xy 161.662364 -46.285404) (xy 161.644753 -46.309706)
			(xy 161.603156 -46.352964) (xy 161.57956 -46.37151) (xy 161.571686 -46.377352) (xy 161.561272 -46.394878)
			(xy 161.548064 -46.485302) (xy 161.55289 -46.504606) (xy 161.558732 -46.51248) (xy 161.558732 -46.512734)
			(xy 161.57623 -46.537482) (xy 161.604035 -46.591333) (xy 161.622973 -46.648904) (xy 161.630176 -46.693836)
			(xy 166.7764 -46.693836) (xy 166.776886 -46.666585) (xy 166.784642 -46.612637) (xy 166.799997 -46.560342)
			(xy 166.822639 -46.510765) (xy 166.852105 -46.464915) (xy 166.887796 -46.423724) (xy 166.928987 -46.388033)
			(xy 166.974837 -46.358567) (xy 167.024414 -46.335925) (xy 167.076709 -46.32057) (xy 167.130657 -46.312814)
			(xy 167.185159 -46.312814) (xy 167.239107 -46.32057) (xy 167.291402 -46.335925) (xy 167.340979 -46.358567)
			(xy 167.386829 -46.388033) (xy 167.42802 -46.423724) (xy 167.463711 -46.464915) (xy 167.493177 -46.510765)
			(xy 167.515819 -46.560342) (xy 167.531174 -46.612637) (xy 167.53893 -46.666585) (xy 167.539416 -46.693836)
			(xy 167.538941 -46.720263) (xy 167.531632 -46.772611) (xy 167.517159 -46.823446) (xy 167.4958 -46.871793)
			(xy 167.482266 -46.894496) (xy 167.482012 -46.89475) (xy 167.476675 -46.904768) (xy 167.474419 -46.927318)
			(xy 167.477694 -46.938184) (xy 167.503856 -47.01286) (xy 167.508238 -47.023376) (xy 167.524328 -47.039464)
			(xy 167.534844 -47.043848) (xy 167.535098 -47.043848) (xy 167.559618 -47.052888) (xy 167.606069 -47.076837)
			(xy 167.648819 -47.106898) (xy 167.68707 -47.14251) (xy 167.720104 -47.183006) (xy 167.747306 -47.22763)
			(xy 167.768167 -47.275548) (xy 167.782296 -47.325863) (xy 167.789429 -47.377635) (xy 167.78986 -47.403766)
			(xy 167.789374 -47.431017) (xy 167.787851 -47.441612) (xy 169.06189 -47.441612) (xy 169.065961 -47.38599)
			(xy 169.078087 -47.331553) (xy 169.09801 -47.279462) (xy 169.125306 -47.230827) (xy 169.159392 -47.186684)
			(xy 169.199541 -47.147975) (xy 169.244899 -47.115524) (xy 169.294499 -47.090023) (xy 169.347283 -47.072016)
			(xy 169.402126 -47.061886) (xy 169.45786 -47.059849) (xy 169.513297 -47.065949) (xy 169.567254 -47.080055)
			(xy 169.618583 -47.101867) (xy 169.666189 -47.130921) (xy 169.709057 -47.166596) (xy 169.746274 -47.208133)
			(xy 169.777047 -47.254646) (xy 169.800719 -47.305143) (xy 169.816787 -47.35855) (xy 169.824907 -47.413726)
			(xy 169.825416 -47.441612) (xy 169.824907 -47.469498) (xy 169.816787 -47.524674) (xy 169.800719 -47.578081)
			(xy 169.777047 -47.628578) (xy 169.746274 -47.675091) (xy 169.709057 -47.716628) (xy 169.666189 -47.752303)
			(xy 169.618583 -47.781357) (xy 169.567254 -47.803169) (xy 169.513297 -47.817275) (xy 169.45786 -47.823375)
			(xy 169.402126 -47.821338) (xy 169.347283 -47.811208) (xy 169.294499 -47.793201) (xy 169.244899 -47.7677)
			(xy 169.199541 -47.735249) (xy 169.159392 -47.69654) (xy 169.125306 -47.652397) (xy 169.09801 -47.603762)
			(xy 169.078087 -47.551671) (xy 169.065961 -47.497234) (xy 169.06189 -47.441612) (xy 167.787851 -47.441612)
			(xy 167.781618 -47.484965) (xy 167.766263 -47.53726) (xy 167.743621 -47.586837) (xy 167.714155 -47.632687)
			(xy 167.678464 -47.673878) (xy 167.637273 -47.709569) (xy 167.591423 -47.739035) (xy 167.541846 -47.761677)
			(xy 167.489551 -47.777032) (xy 167.435603 -47.784788) (xy 167.381101 -47.784788) (xy 167.327153 -47.777032)
			(xy 167.274858 -47.761677) (xy 167.225281 -47.739035) (xy 167.179431 -47.709569) (xy 167.13824 -47.673878)
			(xy 167.102549 -47.632687) (xy 167.073083 -47.586837) (xy 167.050441 -47.53726) (xy 167.035086 -47.484965)
			(xy 167.02733 -47.431017) (xy 167.026844 -47.403766) (xy 167.027312 -47.377338) (xy 167.034622 -47.32499)
			(xy 167.049096 -47.274155) (xy 167.070458 -47.225809) (xy 167.083994 -47.203106) (xy 167.084248 -47.202852)
			(xy 167.089583 -47.192834) (xy 167.091842 -47.170284) (xy 167.088566 -47.159418) (xy 167.062404 -47.084742)
			(xy 167.058039 -47.074217) (xy 167.041938 -47.058132) (xy 167.031416 -47.053754) (xy 167.031162 -47.053754)
			(xy 167.006656 -47.044678) (xy 166.960203 -47.020737) (xy 166.917451 -46.990682) (xy 166.879199 -46.955076)
			(xy 166.846162 -46.914584) (xy 166.818958 -46.869963) (xy 166.798096 -46.822048) (xy 166.783965 -46.771736)
			(xy 166.776831 -46.719966) (xy 166.7764 -46.693836) (xy 161.630176 -46.693836) (xy 161.632566 -46.708745)
			(xy 161.633154 -46.739048) (xy 161.632667 -46.766298) (xy 161.624905 -46.820244) (xy 161.609546 -46.872536)
			(xy 161.586903 -46.92211) (xy 161.557436 -46.967958) (xy 161.521745 -47.009146) (xy 161.480556 -47.044837)
			(xy 161.434708 -47.074304) (xy 161.385134 -47.096947) (xy 161.332842 -47.112306) (xy 161.278896 -47.120067)
			(xy 161.251646 -47.120556) (xy 161.225612 -47.120132) (xy 161.174028 -47.113038) (xy 161.123886 -47.099003)
			(xy 161.076116 -47.078287) (xy 161.031602 -47.051274) (xy 161.011108 -47.035212) (xy 161.003355 -47.029463)
			(xy 160.984941 -47.023727) (xy 160.975294 -47.024036) (xy 160.895538 -47.030386) (xy 160.877758 -47.039022)
			(xy 160.871408 -47.046388) (xy 160.853246 -47.066052) (xy 160.812334 -47.100573) (xy 160.767001 -47.129039)
			(xy 160.718136 -47.150894) (xy 160.666697 -47.165707) (xy 160.613693 -47.173189) (xy 160.586928 -47.173642)
			(xy 160.559679 -47.173096) (xy 160.505735 -47.165344) (xy 160.453444 -47.149994) (xy 160.403869 -47.127359)
			(xy 160.35802 -47.097899) (xy 160.31683 -47.062213) (xy 160.281139 -47.02103) (xy 160.251671 -46.975185)
			(xy 160.229028 -46.925614) (xy 160.213669 -46.873325) (xy 160.205909 -46.819383) (xy 160.20542 -46.792134)
			(xy 160.205939 -46.76336) (xy 160.214591 -46.706465) (xy 160.231688 -46.651514) (xy 160.256843 -46.599754)
			(xy 160.289485 -46.552359) (xy 160.308798 -46.531022) (xy 160.316164 -46.523148) (xy 160.323276 -46.503336)
			(xy 160.31591 -46.40707) (xy 160.306004 -46.388274) (xy 160.297622 -46.38167) (xy 160.275438 -46.363445)
			(xy 160.236228 -46.32151) (xy 160.203742 -46.274174) (xy 160.178713 -46.222506) (xy 160.161707 -46.167672)
			(xy 160.153106 -46.110909) (xy 160.152588 -46.082204) (xy 154.959304 -46.082204) (xy 154.959304 -48.30699)
			(xy 166.65397 -48.30699) (xy 166.658041 -48.251368) (xy 166.670167 -48.196931) (xy 166.69009 -48.14484)
			(xy 166.717386 -48.096205) (xy 166.751472 -48.052062) (xy 166.791621 -48.013353) (xy 166.836979 -47.980902)
			(xy 166.886579 -47.955401) (xy 166.939363 -47.937394) (xy 166.994206 -47.927264) (xy 167.04994 -47.925227)
			(xy 167.105377 -47.931327) (xy 167.159334 -47.945433) (xy 167.210663 -47.967245) (xy 167.258269 -47.996299)
			(xy 167.301137 -48.031974) (xy 167.338354 -48.073511) (xy 167.369127 -48.120024) (xy 167.392799 -48.170521)
			(xy 167.408867 -48.223928) (xy 167.416987 -48.279104) (xy 167.417496 -48.30699) (xy 167.416987 -48.334876)
			(xy 167.408867 -48.390052) (xy 167.392799 -48.443459) (xy 167.369127 -48.493956) (xy 167.338354 -48.540469)
			(xy 167.301137 -48.582006) (xy 167.258269 -48.617681) (xy 167.210663 -48.646735) (xy 167.159334 -48.668547)
			(xy 167.105377 -48.682653) (xy 167.04994 -48.688753) (xy 166.994206 -48.686716) (xy 166.939363 -48.676586)
			(xy 166.886579 -48.658579) (xy 166.836979 -48.633078) (xy 166.791621 -48.600627) (xy 166.751472 -48.561918)
			(xy 166.717386 -48.517775) (xy 166.69009 -48.46914) (xy 166.670167 -48.417049) (xy 166.658041 -48.362612)
			(xy 166.65397 -48.30699) (xy 154.959304 -48.30699) (xy 154.959304 -48.753014) (xy 163.268404 -48.753014)
			(xy 163.272475 -48.697392) (xy 163.284601 -48.642955) (xy 163.304524 -48.590864) (xy 163.33182 -48.542229)
			(xy 163.365906 -48.498086) (xy 163.406055 -48.459377) (xy 163.451413 -48.426926) (xy 163.501013 -48.401425)
			(xy 163.553797 -48.383418) (xy 163.60864 -48.373288) (xy 163.664374 -48.371251) (xy 163.719811 -48.377351)
			(xy 163.773768 -48.391457) (xy 163.825097 -48.413269) (xy 163.872703 -48.442323) (xy 163.915571 -48.477998)
			(xy 163.952788 -48.519535) (xy 163.983561 -48.566048) (xy 164.007233 -48.616545) (xy 164.023301 -48.669952)
			(xy 164.031421 -48.725128) (xy 164.03193 -48.753014) (xy 164.031421 -48.7809) (xy 164.023301 -48.836076)
			(xy 164.007233 -48.889483) (xy 164.005837 -48.89246) (xy 165.31412 -48.89246) (xy 165.318191 -48.836838)
			(xy 165.330317 -48.782401) (xy 165.35024 -48.73031) (xy 165.377536 -48.681675) (xy 165.411622 -48.637532)
			(xy 165.451771 -48.598823) (xy 165.497129 -48.566372) (xy 165.546729 -48.540871) (xy 165.599513 -48.522864)
			(xy 165.654356 -48.512734) (xy 165.71009 -48.510697) (xy 165.765527 -48.516797) (xy 165.819484 -48.530903)
			(xy 165.870813 -48.552715) (xy 165.918419 -48.581769) (xy 165.961287 -48.617444) (xy 165.998504 -48.658981)
			(xy 166.029277 -48.705494) (xy 166.052949 -48.755991) (xy 166.069017 -48.809398) (xy 166.077137 -48.864574)
			(xy 166.077646 -48.89246) (xy 166.077137 -48.920346) (xy 166.074699 -48.93691) (xy 169.033188 -48.93691)
			(xy 169.037259 -48.881288) (xy 169.049385 -48.826851) (xy 169.069308 -48.77476) (xy 169.096604 -48.726125)
			(xy 169.13069 -48.681982) (xy 169.170839 -48.643273) (xy 169.216197 -48.610822) (xy 169.265797 -48.585321)
			(xy 169.318581 -48.567314) (xy 169.373424 -48.557184) (xy 169.429158 -48.555147) (xy 169.484595 -48.561247)
			(xy 169.538552 -48.575353) (xy 169.589881 -48.597165) (xy 169.637487 -48.626219) (xy 169.680355 -48.661894)
			(xy 169.717572 -48.703431) (xy 169.748345 -48.749944) (xy 169.772017 -48.800441) (xy 169.788085 -48.853848)
			(xy 169.796205 -48.909024) (xy 169.796714 -48.93691) (xy 169.796205 -48.964796) (xy 169.788085 -49.019972)
			(xy 169.772017 -49.073379) (xy 169.748345 -49.123876) (xy 169.717572 -49.170389) (xy 169.680355 -49.211926)
			(xy 169.637487 -49.247601) (xy 169.589881 -49.276655) (xy 169.538552 -49.298467) (xy 169.484595 -49.312573)
			(xy 169.429158 -49.318673) (xy 169.373424 -49.316636) (xy 169.318581 -49.306506) (xy 169.265797 -49.288499)
			(xy 169.216197 -49.262998) (xy 169.170839 -49.230547) (xy 169.13069 -49.191838) (xy 169.096604 -49.147695)
			(xy 169.069308 -49.09906) (xy 169.049385 -49.046969) (xy 169.037259 -48.992532) (xy 169.033188 -48.93691)
			(xy 166.074699 -48.93691) (xy 166.069017 -48.975522) (xy 166.052949 -49.028929) (xy 166.029277 -49.079426)
			(xy 165.998504 -49.125939) (xy 165.961287 -49.167476) (xy 165.918419 -49.203151) (xy 165.870813 -49.232205)
			(xy 165.819484 -49.254017) (xy 165.765527 -49.268123) (xy 165.71009 -49.274223) (xy 165.654356 -49.272186)
			(xy 165.599513 -49.262056) (xy 165.546729 -49.244049) (xy 165.497129 -49.218548) (xy 165.451771 -49.186097)
			(xy 165.411622 -49.147388) (xy 165.377536 -49.103245) (xy 165.35024 -49.05461) (xy 165.330317 -49.002519)
			(xy 165.318191 -48.948082) (xy 165.31412 -48.89246) (xy 164.005837 -48.89246) (xy 163.983561 -48.93998)
			(xy 163.952788 -48.986493) (xy 163.915571 -49.02803) (xy 163.872703 -49.063705) (xy 163.825097 -49.092759)
			(xy 163.773768 -49.114571) (xy 163.719811 -49.128677) (xy 163.664374 -49.134777) (xy 163.60864 -49.13274)
			(xy 163.553797 -49.12261) (xy 163.501013 -49.104603) (xy 163.451413 -49.079102) (xy 163.406055 -49.046651)
			(xy 163.365906 -49.007942) (xy 163.33182 -48.963799) (xy 163.304524 -48.915164) (xy 163.284601 -48.863073)
			(xy 163.272475 -48.808636) (xy 163.268404 -48.753014) (xy 154.959304 -48.753014) (xy 154.959304 -49.95291)
			(xy 169.033188 -49.95291) (xy 169.037259 -49.897288) (xy 169.049385 -49.842851) (xy 169.069308 -49.79076)
			(xy 169.096604 -49.742125) (xy 169.13069 -49.697982) (xy 169.170839 -49.659273) (xy 169.216197 -49.626822)
			(xy 169.265797 -49.601321) (xy 169.318581 -49.583314) (xy 169.373424 -49.573184) (xy 169.429158 -49.571147)
			(xy 169.484595 -49.577247) (xy 169.538552 -49.591353) (xy 169.563496 -49.601953) (xy 174.212959 -49.601953)
			(xy 174.212959 -49.547447) (xy 174.220717 -49.493495) (xy 174.236073 -49.441197) (xy 174.258716 -49.391617)
			(xy 174.288185 -49.345764) (xy 174.32388 -49.304571) (xy 174.365073 -49.268878) (xy 174.410927 -49.23941)
			(xy 174.460508 -49.216769) (xy 174.512807 -49.201414) (xy 174.566759 -49.193659) (xy 174.594012 -49.193196)
			(xy 174.621382 -49.193656) (xy 174.675562 -49.201475) (xy 174.728065 -49.216966) (xy 174.777812 -49.239809)
			(xy 174.823778 -49.269534) (xy 174.84471 -49.287176) (xy 174.844964 -49.28743) (xy 174.852054 -49.293011)
			(xy 174.868968 -49.29926) (xy 174.877984 -49.299622) (xy 174.94504 -49.299622) (xy 174.954058 -49.299279)
			(xy 174.970975 -49.293021) (xy 174.97806 -49.28743) (xy 174.97806 -49.287176) (xy 174.978314 -49.287176)
			(xy 174.999247 -49.269535) (xy 175.045215 -49.239811) (xy 175.094961 -49.216965) (xy 175.147463 -49.201469)
			(xy 175.201641 -49.19364) (xy 175.256383 -49.19364) (xy 175.310561 -49.201469) (xy 175.363063 -49.216965)
			(xy 175.412809 -49.239811) (xy 175.458777 -49.269535) (xy 175.47971 -49.287176) (xy 175.479964 -49.28743)
			(xy 175.487054 -49.293011) (xy 175.503968 -49.29926) (xy 175.512984 -49.299622) (xy 175.58004 -49.299622)
			(xy 175.589058 -49.299279) (xy 175.605975 -49.293021) (xy 175.61306 -49.28743) (xy 175.61306 -49.287176)
			(xy 175.613314 -49.287176) (xy 175.634247 -49.269535) (xy 175.680215 -49.239811) (xy 175.729961 -49.216965)
			(xy 175.782463 -49.201469) (xy 175.836641 -49.19364) (xy 175.891383 -49.19364) (xy 175.945561 -49.201469)
			(xy 175.998063 -49.216965) (xy 176.047809 -49.239811) (xy 176.093777 -49.269535) (xy 176.11471 -49.287176)
			(xy 176.114964 -49.28743) (xy 176.122054 -49.293011) (xy 176.138968 -49.29926) (xy 176.147984 -49.299622)
			(xy 176.21504 -49.299622) (xy 176.224058 -49.299279) (xy 176.240975 -49.293021) (xy 176.24806 -49.28743)
			(xy 176.24806 -49.287176) (xy 176.248314 -49.287176) (xy 176.269265 -49.26956) (xy 176.315233 -49.239846)
			(xy 176.364976 -49.217006) (xy 176.417472 -49.201509) (xy 176.471644 -49.193674) (xy 176.499012 -49.193196)
			(xy 176.526263 -49.193675) (xy 176.58021 -49.201433) (xy 176.632504 -49.216789) (xy 176.68208 -49.239431)
			(xy 176.727929 -49.268898) (xy 176.769119 -49.30459) (xy 176.804809 -49.34578) (xy 176.834275 -49.39163)
			(xy 176.856915 -49.441207) (xy 176.87227 -49.493502) (xy 176.880026 -49.547449) (xy 176.880026 -49.601951)
			(xy 176.87227 -49.655898) (xy 176.856915 -49.708193) (xy 176.834275 -49.75777) (xy 176.804809 -49.80362)
			(xy 176.769119 -49.84481) (xy 176.727929 -49.880502) (xy 176.68208 -49.909969) (xy 176.632504 -49.932611)
			(xy 176.58021 -49.947967) (xy 176.526263 -49.955725) (xy 176.499012 -49.956212) (xy 176.471642 -49.955736)
			(xy 176.417464 -49.94792) (xy 176.364961 -49.932433) (xy 176.315214 -49.909594) (xy 176.269246 -49.879872)
			(xy 176.248314 -49.862232) (xy 176.24806 -49.861978) (xy 176.240962 -49.856408) (xy 176.224054 -49.850152)
			(xy 176.21504 -49.849786) (xy 176.147984 -49.849786) (xy 176.138967 -49.850139) (xy 176.12205 -49.85639)
			(xy 176.114964 -49.861978) (xy 176.11471 -49.862232) (xy 176.093777 -49.879873) (xy 176.047809 -49.909597)
			(xy 175.998063 -49.932443) (xy 175.945561 -49.947939) (xy 175.891383 -49.955768) (xy 175.836641 -49.955768)
			(xy 175.782463 -49.947939) (xy 175.729961 -49.932443) (xy 175.680215 -49.909597) (xy 175.634247 -49.879873)
			(xy 175.613314 -49.862232) (xy 175.61306 -49.861978) (xy 175.605962 -49.856408) (xy 175.589054 -49.850152)
			(xy 175.58004 -49.849786) (xy 175.512984 -49.849786) (xy 175.503967 -49.850139) (xy 175.48705 -49.85639)
			(xy 175.479964 -49.861978) (xy 175.479964 -49.862232) (xy 175.47971 -49.862232) (xy 175.458777 -49.879873)
			(xy 175.412809 -49.909597) (xy 175.363063 -49.932443) (xy 175.310561 -49.947939) (xy 175.256383 -49.955768)
			(xy 175.201641 -49.955768) (xy 175.147463 -49.947939) (xy 175.094961 -49.932443) (xy 175.045215 -49.909597)
			(xy 174.999247 -49.879873) (xy 174.978314 -49.862232) (xy 174.97806 -49.861978) (xy 174.970962 -49.856408)
			(xy 174.954054 -49.850152) (xy 174.94504 -49.849786) (xy 174.877984 -49.849786) (xy 174.868967 -49.850139)
			(xy 174.85205 -49.85639) (xy 174.844964 -49.861978) (xy 174.844964 -49.862232) (xy 174.84471 -49.862232)
			(xy 174.823789 -49.879885) (xy 174.777813 -49.909594) (xy 174.728062 -49.932426) (xy 174.675559 -49.947914)
			(xy 174.621382 -49.955739) (xy 174.594012 -49.956212) (xy 174.566759 -49.955741) (xy 174.512807 -49.947986)
			(xy 174.460508 -49.932631) (xy 174.410927 -49.90999) (xy 174.365073 -49.880522) (xy 174.32388 -49.844829)
			(xy 174.288185 -49.803636) (xy 174.258716 -49.757783) (xy 174.236073 -49.708203) (xy 174.220717 -49.655905)
			(xy 174.212959 -49.601953) (xy 169.563496 -49.601953) (xy 169.589881 -49.613165) (xy 169.637487 -49.642219)
			(xy 169.680355 -49.677894) (xy 169.717572 -49.719431) (xy 169.748345 -49.765944) (xy 169.772017 -49.816441)
			(xy 169.788085 -49.869848) (xy 169.796205 -49.925024) (xy 169.796714 -49.95291) (xy 169.796205 -49.980796)
			(xy 169.788085 -50.035972) (xy 169.772017 -50.089379) (xy 169.748345 -50.139876) (xy 169.717572 -50.186389)
			(xy 169.680355 -50.227926) (xy 169.637487 -50.263601) (xy 169.589881 -50.292655) (xy 169.538552 -50.314467)
			(xy 169.484595 -50.328573) (xy 169.429158 -50.334673) (xy 169.373424 -50.332636) (xy 169.318581 -50.322506)
			(xy 169.265797 -50.304499) (xy 169.216197 -50.278998) (xy 169.170839 -50.246547) (xy 169.13069 -50.207838)
			(xy 169.096604 -50.163695) (xy 169.069308 -50.11506) (xy 169.049385 -50.062969) (xy 169.037259 -50.008532)
			(xy 169.033188 -49.95291) (xy 154.959304 -49.95291) (xy 154.959304 -51.019456) (xy 166.84955 -51.019456)
			(xy 166.853621 -50.963834) (xy 166.865747 -50.909397) (xy 166.88567 -50.857306) (xy 166.912966 -50.808671)
			(xy 166.947052 -50.764528) (xy 166.987201 -50.725819) (xy 167.032559 -50.693368) (xy 167.082159 -50.667867)
			(xy 167.134943 -50.64986) (xy 167.189786 -50.63973) (xy 167.24552 -50.637693) (xy 167.300957 -50.643793)
			(xy 167.354914 -50.657899) (xy 167.406243 -50.679711) (xy 167.453849 -50.708765) (xy 167.496717 -50.74444)
			(xy 167.533934 -50.785977) (xy 167.564707 -50.83249) (xy 167.588379 -50.882987) (xy 167.604447 -50.936394)
			(xy 167.612567 -50.99157) (xy 167.613076 -51.019456) (xy 167.612567 -51.047342) (xy 167.604447 -51.102518)
			(xy 167.588379 -51.155925) (xy 167.564707 -51.206422) (xy 167.539851 -51.243992) (xy 175.233076 -51.243992)
			(xy 175.233519 -51.216621) (xy 175.241339 -51.16244) (xy 175.256833 -51.109936) (xy 175.27968 -51.060189)
			(xy 175.309411 -51.014224) (xy 175.327056 -50.993294) (xy 175.32731 -50.99304) (xy 175.332887 -50.985947)
			(xy 175.339139 -50.969035) (xy 175.339502 -50.96002) (xy 175.339502 -50.892964) (xy 175.339162 -50.883945)
			(xy 175.332902 -50.867029) (xy 175.32731 -50.859944) (xy 175.327056 -50.859944) (xy 175.327056 -50.85969)
			(xy 175.309392 -50.838778) (xy 175.279685 -50.792799) (xy 175.256854 -50.743047) (xy 175.241369 -50.690542)
			(xy 175.233547 -50.636362) (xy 175.233076 -50.608992) (xy 175.23357 -50.581741) (xy 175.241327 -50.527795)
			(xy 175.256683 -50.475501) (xy 175.279324 -50.425925) (xy 175.308789 -50.380075) (xy 175.34448 -50.338886)
			(xy 175.385669 -50.303194) (xy 175.431518 -50.273728) (xy 175.481094 -50.251086) (xy 175.533387 -50.235729)
			(xy 175.587333 -50.227971) (xy 175.614584 -50.227484) (xy 175.643502 -50.227982) (xy 175.700676 -50.236711)
			(xy 175.755876 -50.25397) (xy 175.807839 -50.279366) (xy 175.855372 -50.312315) (xy 175.897386 -50.352061)
			(xy 175.915574 -50.37455) (xy 175.923194 -50.383344) (xy 175.944085 -50.393533) (xy 175.955706 -50.394108)
			(xy 176.035462 -50.394108) (xy 176.047096 -50.393587) (xy 176.068005 -50.383385) (xy 176.075594 -50.37455)
			(xy 176.093776 -50.352059) (xy 176.135799 -50.312327) (xy 176.183336 -50.27939) (xy 176.235299 -50.254003)
			(xy 176.290498 -50.236748) (xy 176.347668 -50.228019) (xy 176.376584 -50.227484) (xy 176.403836 -50.22797)
			(xy 176.457786 -50.235725) (xy 176.510083 -50.251078) (xy 176.559662 -50.273718) (xy 176.605515 -50.303184)
			(xy 176.646708 -50.338875) (xy 176.682402 -50.380066) (xy 176.71187 -50.425917) (xy 176.734513 -50.475495)
			(xy 176.74987 -50.527791) (xy 176.757628 -50.58174) (xy 176.758092 -50.608992) (xy 176.757622 -50.635306)
			(xy 176.750388 -50.687434) (xy 176.736069 -50.738077) (xy 176.714938 -50.786276) (xy 176.687392 -50.83112)
			(xy 176.653953 -50.871759) (xy 176.634902 -50.889916) (xy 176.627492 -50.89743) (xy 176.618972 -50.916716)
			(xy 176.618392 -50.927254) (xy 176.618392 -51.00193) (xy 176.618948 -51.012476) (xy 176.627465 -51.031772)
			(xy 176.634902 -51.039268) (xy 176.653984 -51.057397) (xy 176.687439 -51.098033) (xy 176.714994 -51.142878)
			(xy 176.736128 -51.191084) (xy 176.750439 -51.241736) (xy 176.757657 -51.293874) (xy 176.758092 -51.320192)
			(xy 176.757637 -51.347445) (xy 176.749881 -51.401397) (xy 176.734525 -51.453696) (xy 176.711882 -51.503278)
			(xy 176.682414 -51.549132) (xy 176.646719 -51.590325) (xy 176.605525 -51.626018) (xy 176.559671 -51.655486)
			(xy 176.510089 -51.678128) (xy 176.45779 -51.693483) (xy 176.403837 -51.701238) (xy 176.376584 -51.7017)
			(xy 176.348918 -51.7012) (xy 176.294169 -51.693199) (xy 176.241147 -51.67738) (xy 176.190963 -51.654075)
			(xy 176.144667 -51.623772) (xy 176.103229 -51.587105) (xy 176.067517 -51.544842) (xy 176.05248 -51.521614)
			(xy 176.045862 -51.511922) (xy 176.025987 -51.499487) (xy 176.01438 -51.497738) (xy 175.93437 -51.489864)
			(xy 175.922731 -51.489217) (xy 175.900893 -51.497307) (xy 175.89246 -51.505358) (xy 175.892206 -51.505612)
			(xy 175.874107 -51.524175) (xy 175.833779 -51.556755) (xy 175.789408 -51.58357) (xy 175.741813 -51.604126)
			(xy 175.691872 -51.618043) (xy 175.640506 -51.625065) (xy 175.614584 -51.6255) (xy 175.587332 -51.625037)
			(xy 175.533383 -51.617278) (xy 175.481087 -51.601921) (xy 175.43151 -51.579277) (xy 175.385659 -51.549808)
			(xy 175.344469 -51.514114) (xy 175.308777 -51.472922) (xy 175.279311 -51.427069) (xy 175.256671 -51.37749)
			(xy 175.241317 -51.325193) (xy 175.233561 -51.271244) (xy 175.233076 -51.243992) (xy 167.539851 -51.243992)
			(xy 167.533934 -51.252935) (xy 167.496717 -51.294472) (xy 167.453849 -51.330147) (xy 167.406243 -51.359201)
			(xy 167.354914 -51.381013) (xy 167.300957 -51.395119) (xy 167.24552 -51.401219) (xy 167.189786 -51.399182)
			(xy 167.134943 -51.389052) (xy 167.082159 -51.371045) (xy 167.032559 -51.345544) (xy 166.987201 -51.313093)
			(xy 166.947052 -51.274384) (xy 166.912966 -51.230241) (xy 166.88567 -51.181606) (xy 166.865747 -51.129515)
			(xy 166.853621 -51.075078) (xy 166.84955 -51.019456) (xy 154.959304 -51.019456) (xy 154.959304 -52.035456)
			(xy 169.041316 -52.035456) (xy 169.045387 -51.979834) (xy 169.057513 -51.925397) (xy 169.077436 -51.873306)
			(xy 169.104732 -51.824671) (xy 169.138818 -51.780528) (xy 169.178967 -51.741819) (xy 169.224325 -51.709368)
			(xy 169.273925 -51.683867) (xy 169.326709 -51.66586) (xy 169.381552 -51.65573) (xy 169.437286 -51.653693)
			(xy 169.492723 -51.659793) (xy 169.54668 -51.673899) (xy 169.598009 -51.695711) (xy 169.645615 -51.724765)
			(xy 169.688483 -51.76044) (xy 169.7257 -51.801977) (xy 169.756473 -51.84849) (xy 169.780145 -51.898987)
			(xy 169.796213 -51.952394) (xy 169.804333 -52.00757) (xy 169.804842 -52.035456) (xy 169.804333 -52.063342)
			(xy 169.796213 -52.118518) (xy 169.780145 -52.171925) (xy 169.756473 -52.222422) (xy 169.7257 -52.268935)
			(xy 169.688483 -52.310472) (xy 169.645615 -52.346147) (xy 169.598009 -52.375201) (xy 169.54668 -52.397013)
			(xy 169.492723 -52.411119) (xy 169.437286 -52.417219) (xy 169.381552 -52.415182) (xy 169.326709 -52.405052)
			(xy 169.273925 -52.387045) (xy 169.224325 -52.361544) (xy 169.178967 -52.329093) (xy 169.138818 -52.290384)
			(xy 169.104732 -52.246241) (xy 169.077436 -52.197606) (xy 169.057513 -52.145515) (xy 169.045387 -52.091078)
			(xy 169.041316 -52.035456) (xy 154.959304 -52.035456) (xy 154.959304 -54.731412) (xy 155.62072 -54.731412)
			(xy 155.621188 -54.704042) (xy 155.629005 -54.649863) (xy 155.644493 -54.597359) (xy 155.667334 -54.547612)
			(xy 155.697059 -54.501646) (xy 155.7147 -54.480714) (xy 155.714954 -54.48046) (xy 155.720528 -54.473365)
			(xy 155.726781 -54.456455) (xy 155.727146 -54.44744) (xy 155.727146 -54.380384) (xy 155.726808 -54.371365)
			(xy 155.720548 -54.354448) (xy 155.714954 -54.347364) (xy 155.7147 -54.347364) (xy 155.7147 -54.34711)
			(xy 155.697072 -54.326167) (xy 155.667349 -54.2802) (xy 155.644505 -54.230456) (xy 155.629009 -54.177955)
			(xy 155.621179 -54.123779) (xy 155.621178 -54.069039) (xy 155.629005 -54.014862) (xy 155.644498 -53.962361)
			(xy 155.66734 -53.912615) (xy 155.697061 -53.866647) (xy 155.7147 -53.845714) (xy 155.714954 -53.84546)
			(xy 155.720528 -53.838365) (xy 155.726781 -53.821455) (xy 155.727146 -53.81244) (xy 155.727146 -53.745384)
			(xy 155.726808 -53.736365) (xy 155.720548 -53.719448) (xy 155.714954 -53.712364) (xy 155.7147 -53.712364)
			(xy 155.7147 -53.71211) (xy 155.697072 -53.691167) (xy 155.667349 -53.6452) (xy 155.644505 -53.595456)
			(xy 155.629009 -53.542955) (xy 155.621179 -53.488779) (xy 155.621178 -53.434039) (xy 155.629005 -53.379862)
			(xy 155.644498 -53.327361) (xy 155.66734 -53.277615) (xy 155.697061 -53.231647) (xy 155.7147 -53.210714)
			(xy 155.714954 -53.21046) (xy 155.720528 -53.203365) (xy 155.726781 -53.186455) (xy 155.727146 -53.17744)
			(xy 155.727146 -53.110384) (xy 155.726808 -53.101365) (xy 155.720548 -53.084448) (xy 155.714954 -53.077364)
			(xy 155.7147 -53.077364) (xy 155.7147 -53.07711) (xy 155.697052 -53.056185) (xy 155.667342 -53.01021)
			(xy 155.644507 -52.960461) (xy 155.629018 -52.907959) (xy 155.621193 -52.853782) (xy 155.62072 -52.826412)
			(xy 155.621206 -52.799161) (xy 155.628962 -52.745213) (xy 155.644317 -52.692918) (xy 155.666959 -52.643341)
			(xy 155.696425 -52.597491) (xy 155.732116 -52.5563) (xy 155.773307 -52.520609) (xy 155.819157 -52.491143)
			(xy 155.868734 -52.468501) (xy 155.921029 -52.453146) (xy 155.974977 -52.44539) (xy 156.029479 -52.44539)
			(xy 156.083427 -52.453146) (xy 156.135722 -52.468501) (xy 156.185299 -52.491143) (xy 156.231149 -52.520609)
			(xy 156.27234 -52.5563) (xy 156.308031 -52.597491) (xy 156.337497 -52.643341) (xy 156.360139 -52.692918)
			(xy 156.375494 -52.745213) (xy 156.38325 -52.799161) (xy 156.383736 -52.826412) (xy 156.383293 -52.853783)
			(xy 156.375472 -52.907964) (xy 156.359978 -52.960468) (xy 156.337131 -53.010214) (xy 156.3074 -53.05618)
			(xy 156.289756 -53.07711) (xy 156.289502 -53.077364) (xy 156.283925 -53.084457) (xy 156.277672 -53.101369)
			(xy 156.27731 -53.110384) (xy 156.27731 -53.17744) (xy 156.277646 -53.186459) (xy 156.283908 -53.203376)
			(xy 156.289502 -53.21046) (xy 156.289756 -53.21046) (xy 156.289756 -53.210714) (xy 156.307409 -53.231637)
			(xy 156.337135 -53.277606) (xy 156.35998 -53.327354) (xy 156.375477 -53.379857) (xy 156.383304 -53.434038)
			(xy 156.383303 -53.48878) (xy 156.375473 -53.54296) (xy 156.359974 -53.595463) (xy 156.337126 -53.64521)
			(xy 156.307398 -53.691178) (xy 156.289756 -53.71211) (xy 156.289502 -53.712364) (xy 156.283925 -53.719457)
			(xy 156.277672 -53.736369) (xy 156.27731 -53.745384) (xy 156.27731 -53.81244) (xy 156.277646 -53.821459)
			(xy 156.283908 -53.838376) (xy 156.289502 -53.84546) (xy 156.289756 -53.84546) (xy 156.289756 -53.845714)
			(xy 156.307409 -53.866637) (xy 156.337135 -53.912606) (xy 156.35998 -53.962354) (xy 156.375477 -54.014857)
			(xy 156.383304 -54.069038) (xy 156.383303 -54.12378) (xy 156.375473 -54.17796) (xy 156.359974 -54.230463)
			(xy 156.337126 -54.28021) (xy 156.307398 -54.326178) (xy 156.289756 -54.34711) (xy 156.289502 -54.347364)
			(xy 156.283925 -54.354457) (xy 156.277672 -54.371369) (xy 156.27731 -54.380384) (xy 156.27731 -54.44744)
			(xy 156.277646 -54.456459) (xy 156.283908 -54.473376) (xy 156.289502 -54.48046) (xy 156.289756 -54.48046)
			(xy 156.289756 -54.480714) (xy 156.307361 -54.501673) (xy 156.33708 -54.547638) (xy 156.359923 -54.597378)
			(xy 156.375422 -54.649873) (xy 156.383258 -54.704045) (xy 156.383736 -54.731412) (xy 156.38325 -54.758663)
			(xy 156.378586 -54.791102) (xy 158.276544 -54.791102) (xy 158.277001 -54.763731) (xy 158.284819 -54.709551)
			(xy 158.30031 -54.657048) (xy 158.323154 -54.607301) (xy 158.352881 -54.561335) (xy 158.370524 -54.540404)
			(xy 158.370778 -54.54015) (xy 158.376359 -54.53306) (xy 158.382607 -54.516146) (xy 158.38297 -54.50713)
			(xy 158.38297 -54.440074) (xy 158.382632 -54.431055) (xy 158.376372 -54.414138) (xy 158.370778 -54.407054)
			(xy 158.370524 -54.407054) (xy 158.370524 -54.4068) (xy 158.352885 -54.385866) (xy 158.323161 -54.339898)
			(xy 158.300315 -54.290152) (xy 158.284819 -54.23765) (xy 158.27699 -54.183472) (xy 158.27699 -54.128731)
			(xy 158.284819 -54.074553) (xy 158.300314 -54.022051) (xy 158.323159 -53.972305) (xy 158.352884 -53.926337)
			(xy 158.370524 -53.905404) (xy 158.370778 -53.90515) (xy 158.376359 -53.89806) (xy 158.382607 -53.881146)
			(xy 158.38297 -53.87213) (xy 158.38297 -53.805074) (xy 158.382632 -53.796055) (xy 158.376372 -53.779138)
			(xy 158.370778 -53.772054) (xy 158.370524 -53.772054) (xy 158.370524 -53.7718) (xy 158.352885 -53.750866)
			(xy 158.323161 -53.704898) (xy 158.300315 -53.655152) (xy 158.284819 -53.60265) (xy 158.27699 -53.548472)
			(xy 158.27699 -53.493731) (xy 158.284819 -53.439553) (xy 158.300314 -53.387051) (xy 158.323159 -53.337305)
			(xy 158.352884 -53.291337) (xy 158.370524 -53.270404) (xy 158.370778 -53.27015) (xy 158.376359 -53.26306)
			(xy 158.382607 -53.246146) (xy 158.38297 -53.23713) (xy 158.38297 -53.170074) (xy 158.382632 -53.161055)
			(xy 158.376372 -53.144138) (xy 158.370778 -53.137054) (xy 158.370524 -53.137054) (xy 158.370524 -53.1368)
			(xy 158.352875 -53.115876) (xy 158.323164 -53.069901) (xy 158.30033 -53.020152) (xy 158.284841 -52.967649)
			(xy 158.277016 -52.913472) (xy 158.276544 -52.886102) (xy 158.27703 -52.858851) (xy 158.284786 -52.804903)
			(xy 158.300141 -52.752608) (xy 158.322783 -52.703031) (xy 158.352249 -52.657181) (xy 158.38794 -52.61599)
			(xy 158.429131 -52.580299) (xy 158.474981 -52.550833) (xy 158.524558 -52.528191) (xy 158.576853 -52.512836)
			(xy 158.630801 -52.50508) (xy 158.685303 -52.50508) (xy 158.739251 -52.512836) (xy 158.791546 -52.528191)
			(xy 158.830655 -52.546052) (xy 163.779673 -52.546052) (xy 163.779673 -52.491548) (xy 163.78743 -52.437599)
			(xy 163.802786 -52.385303) (xy 163.825428 -52.335725) (xy 163.854895 -52.289873) (xy 163.890588 -52.248682)
			(xy 163.93178 -52.21299) (xy 163.977632 -52.183524) (xy 164.02721 -52.160883) (xy 164.079507 -52.145528)
			(xy 164.133456 -52.137773) (xy 164.160708 -52.13731) (xy 164.188079 -52.137769) (xy 164.242258 -52.145588)
			(xy 164.294761 -52.161079) (xy 164.344508 -52.183922) (xy 164.390475 -52.213648) (xy 164.411406 -52.23129)
			(xy 164.41166 -52.231544) (xy 164.41875 -52.237125) (xy 164.435664 -52.243374) (xy 164.44468 -52.243736)
			(xy 164.511736 -52.243736) (xy 164.520754 -52.243388) (xy 164.53767 -52.237134) (xy 164.544756 -52.231544)
			(xy 164.544756 -52.23129) (xy 164.54501 -52.23129) (xy 164.565943 -52.213649) (xy 164.611911 -52.183925)
			(xy 164.661657 -52.161079) (xy 164.714159 -52.145583) (xy 164.768337 -52.137754) (xy 164.823079 -52.137754)
			(xy 164.877257 -52.145583) (xy 164.929759 -52.161079) (xy 164.979505 -52.183925) (xy 165.025473 -52.213649)
			(xy 165.046406 -52.23129) (xy 165.04666 -52.231544) (xy 165.05375 -52.237125) (xy 165.070664 -52.243374)
			(xy 165.07968 -52.243736) (xy 165.146736 -52.243736) (xy 165.155754 -52.243388) (xy 165.17267 -52.237134)
			(xy 165.179756 -52.231544) (xy 165.179756 -52.23129) (xy 165.18001 -52.23129) (xy 165.200926 -52.213631)
			(xy 165.246904 -52.183923) (xy 165.296655 -52.161091) (xy 165.349159 -52.145604) (xy 165.403338 -52.137781)
			(xy 165.430708 -52.13731) (xy 165.45796 -52.13776) (xy 165.51191 -52.145518) (xy 165.564206 -52.160875)
			(xy 165.613784 -52.183517) (xy 165.659636 -52.212985) (xy 165.700827 -52.248678) (xy 165.73652 -52.28987)
			(xy 165.765986 -52.335723) (xy 165.788628 -52.385302) (xy 165.803984 -52.437598) (xy 165.81174 -52.491548)
			(xy 165.81174 -52.546052) (xy 165.805796 -52.587398) (xy 166.855392 -52.587398) (xy 166.859463 -52.531776)
			(xy 166.871589 -52.477339) (xy 166.891512 -52.425248) (xy 166.918808 -52.376613) (xy 166.952894 -52.33247)
			(xy 166.993043 -52.293761) (xy 167.038401 -52.26131) (xy 167.088001 -52.235809) (xy 167.140785 -52.217802)
			(xy 167.195628 -52.207672) (xy 167.251362 -52.205635) (xy 167.306799 -52.211735) (xy 167.360756 -52.225841)
			(xy 167.412085 -52.247653) (xy 167.459691 -52.276707) (xy 167.502559 -52.312382) (xy 167.539776 -52.353919)
			(xy 167.570549 -52.400432) (xy 167.594221 -52.450929) (xy 167.610289 -52.504336) (xy 167.617885 -52.555952)
			(xy 174.683879 -52.555952) (xy 174.683879 -52.501448) (xy 174.691637 -52.447498) (xy 174.706993 -52.395201)
			(xy 174.729636 -52.345622) (xy 174.759105 -52.29977) (xy 174.794799 -52.25858) (xy 174.835993 -52.222888)
			(xy 174.881847 -52.193423) (xy 174.931427 -52.170783) (xy 174.983725 -52.155431) (xy 175.037676 -52.147677)
			(xy 175.064928 -52.147216) (xy 175.092299 -52.147662) (xy 175.146479 -52.155484) (xy 175.198983 -52.170978)
			(xy 175.248729 -52.193824) (xy 175.294695 -52.223553) (xy 175.315626 -52.241196) (xy 175.31588 -52.24145)
			(xy 175.322964 -52.24704) (xy 175.339883 -52.253284) (xy 175.3489 -52.253642) (xy 175.415956 -52.253642)
			(xy 175.424972 -52.253277) (xy 175.44189 -52.247036) (xy 175.448976 -52.24145) (xy 175.448976 -52.241196)
			(xy 175.44923 -52.241196) (xy 175.470177 -52.223576) (xy 175.516146 -52.193861) (xy 175.56589 -52.171022)
			(xy 175.618387 -52.155526) (xy 175.67256 -52.147693) (xy 175.699928 -52.147216) (xy 175.72718 -52.147656)
			(xy 175.781128 -52.155416) (xy 175.833422 -52.170775) (xy 175.882999 -52.193419) (xy 175.928849 -52.222888)
			(xy 175.970038 -52.258581) (xy 176.005729 -52.299773) (xy 176.035195 -52.345625) (xy 176.057835 -52.395204)
			(xy 176.07319 -52.4475) (xy 176.080946 -52.501448) (xy 176.080946 -52.555952) (xy 176.07319 -52.6099)
			(xy 176.057835 -52.662196) (xy 176.035195 -52.711775) (xy 176.005729 -52.757627) (xy 175.970038 -52.798819)
			(xy 175.928849 -52.834512) (xy 175.882999 -52.863981) (xy 175.833422 -52.886625) (xy 175.781128 -52.901984)
			(xy 175.72718 -52.909744) (xy 175.699928 -52.910232) (xy 175.672558 -52.909766) (xy 175.618378 -52.901951)
			(xy 175.565874 -52.886463) (xy 175.516127 -52.86362) (xy 175.470161 -52.833894) (xy 175.44923 -52.816252)
			(xy 175.448976 -52.815998) (xy 175.441901 -52.810395) (xy 175.424975 -52.804158) (xy 175.415956 -52.803806)
			(xy 175.3489 -52.803806) (xy 175.339883 -52.804162) (xy 175.322966 -52.81041) (xy 175.31588 -52.815998)
			(xy 175.31588 -52.816252) (xy 175.315626 -52.816252) (xy 175.294689 -52.833885) (xy 175.248718 -52.863599)
			(xy 175.198972 -52.886437) (xy 175.146472 -52.90193) (xy 175.092297 -52.909758) (xy 175.064928 -52.910232)
			(xy 175.037676 -52.909723) (xy 174.983725 -52.901969) (xy 174.931427 -52.886617) (xy 174.881847 -52.863977)
			(xy 174.835993 -52.834512) (xy 174.794799 -52.79882) (xy 174.759105 -52.75763) (xy 174.729636 -52.711778)
			(xy 174.706993 -52.662199) (xy 174.691637 -52.609902) (xy 174.683879 -52.555952) (xy 167.617885 -52.555952)
			(xy 167.618409 -52.559512) (xy 167.618918 -52.587398) (xy 167.618409 -52.615284) (xy 167.610289 -52.67046)
			(xy 167.594221 -52.723867) (xy 167.570549 -52.774364) (xy 167.539776 -52.820877) (xy 167.502559 -52.862414)
			(xy 167.459691 -52.898089) (xy 167.412085 -52.927143) (xy 167.360756 -52.948955) (xy 167.306799 -52.963061)
			(xy 167.251362 -52.969161) (xy 167.195628 -52.967124) (xy 167.140785 -52.956994) (xy 167.088001 -52.938987)
			(xy 167.038401 -52.913486) (xy 166.993043 -52.881035) (xy 166.952894 -52.842326) (xy 166.918808 -52.798183)
			(xy 166.891512 -52.749548) (xy 166.871589 -52.697457) (xy 166.859463 -52.64302) (xy 166.855392 -52.587398)
			(xy 165.805796 -52.587398) (xy 165.803984 -52.600002) (xy 165.788628 -52.652298) (xy 165.765986 -52.701877)
			(xy 165.73652 -52.74773) (xy 165.700827 -52.788922) (xy 165.659636 -52.824615) (xy 165.613784 -52.854083)
			(xy 165.564206 -52.876725) (xy 165.51191 -52.892082) (xy 165.45796 -52.89984) (xy 165.430708 -52.900326)
			(xy 165.403337 -52.899873) (xy 165.349157 -52.892055) (xy 165.296653 -52.876564) (xy 165.246906 -52.853719)
			(xy 165.20094 -52.82399) (xy 165.18001 -52.806346) (xy 165.179756 -52.806092) (xy 165.172658 -52.800522)
			(xy 165.15575 -52.794266) (xy 165.146736 -52.7939) (xy 165.07968 -52.7939) (xy 165.070662 -52.794248)
			(xy 165.053745 -52.800502) (xy 165.04666 -52.806092) (xy 165.046406 -52.806346) (xy 165.025473 -52.823987)
			(xy 164.979505 -52.853711) (xy 164.929759 -52.876557) (xy 164.877257 -52.892053) (xy 164.823079 -52.899882)
			(xy 164.768337 -52.899882) (xy 164.714159 -52.892053) (xy 164.661657 -52.876557) (xy 164.611911 -52.853711)
			(xy 164.565943 -52.823987) (xy 164.54501 -52.806346) (xy 164.544756 -52.806092) (xy 164.537658 -52.800522)
			(xy 164.52075 -52.794266) (xy 164.511736 -52.7939) (xy 164.44468 -52.7939) (xy 164.435662 -52.794248)
			(xy 164.418745 -52.800502) (xy 164.41166 -52.806092) (xy 164.41166 -52.806346) (xy 164.411406 -52.806346)
			(xy 164.390476 -52.823987) (xy 164.344503 -52.853701) (xy 164.294755 -52.876537) (xy 164.242254 -52.892027)
			(xy 164.188077 -52.899854) (xy 164.160708 -52.900326) (xy 164.133456 -52.899827) (xy 164.079507 -52.892072)
			(xy 164.02721 -52.876717) (xy 163.977632 -52.854076) (xy 163.93178 -52.82461) (xy 163.890588 -52.788918)
			(xy 163.854895 -52.747727) (xy 163.825428 -52.701875) (xy 163.802786 -52.652297) (xy 163.78743 -52.600001)
			(xy 163.779673 -52.546052) (xy 158.830655 -52.546052) (xy 158.841123 -52.550833) (xy 158.886973 -52.580299)
			(xy 158.928164 -52.61599) (xy 158.963855 -52.657181) (xy 158.993321 -52.703031) (xy 159.015963 -52.752608)
			(xy 159.031318 -52.804903) (xy 159.039074 -52.858851) (xy 159.03956 -52.886102) (xy 159.039105 -52.913473)
			(xy 159.031286 -52.967653) (xy 159.015795 -53.020156) (xy 158.99295 -53.069903) (xy 158.963223 -53.115869)
			(xy 158.94558 -53.1368) (xy 158.945326 -53.137054) (xy 158.939744 -53.144143) (xy 158.933496 -53.161058)
			(xy 158.933134 -53.170074) (xy 158.933134 -53.23713) (xy 158.933469 -53.246149) (xy 158.939731 -53.263066)
			(xy 158.945326 -53.27015) (xy 158.94558 -53.27015) (xy 158.94558 -53.270404) (xy 158.963222 -53.291335)
			(xy 158.992947 -53.337304) (xy 159.015791 -53.38705) (xy 159.031287 -53.439552) (xy 159.039115 -53.493731)
			(xy 159.039115 -53.548472) (xy 159.031287 -53.602651) (xy 159.01579 -53.655153) (xy 158.992945 -53.704899)
			(xy 158.963221 -53.750867) (xy 158.94665 -53.77053) (xy 159.310832 -53.77053) (xy 159.31136 -53.741613)
			(xy 159.320085 -53.684442) (xy 159.33734 -53.629243) (xy 159.36273 -53.577281) (xy 159.395673 -53.529747)
			(xy 159.435413 -53.48773) (xy 159.457898 -53.46954) (xy 159.466677 -53.461905) (xy 159.476876 -53.441026)
			(xy 159.477456 -53.429408) (xy 159.477456 -53.349652) (xy 159.476946 -53.338016) (xy 159.466738 -53.317106)
			(xy 159.457898 -53.30952) (xy 159.435424 -53.291318) (xy 159.395688 -53.249301) (xy 159.362748 -53.201768)
			(xy 159.337358 -53.149809) (xy 159.3201 -53.094613) (xy 159.311368 -53.037445) (xy 159.310832 -53.00853)
			(xy 159.311283 -52.981276) (xy 159.319037 -52.927323) (xy 159.334392 -52.875022) (xy 159.357033 -52.825439)
			(xy 159.386502 -52.779584) (xy 159.422197 -52.73839) (xy 159.463392 -52.702696) (xy 159.509248 -52.673229)
			(xy 159.558831 -52.650588) (xy 159.611132 -52.635235) (xy 159.665086 -52.627483) (xy 159.69234 -52.627022)
			(xy 159.718655 -52.627456) (xy 159.770785 -52.634696) (xy 159.821429 -52.649022) (xy 159.869628 -52.67016)
			(xy 159.914471 -52.697713) (xy 159.955109 -52.731158) (xy 159.973264 -52.750212) (xy 159.980795 -52.757602)
			(xy 160.000068 -52.766133) (xy 160.010602 -52.766722) (xy 160.085278 -52.766722) (xy 160.095827 -52.766188)
			(xy 160.115122 -52.757655) (xy 160.122616 -52.750212) (xy 160.140773 -52.731158) (xy 160.181402 -52.6977)
			(xy 160.226242 -52.670141) (xy 160.274443 -52.649002) (xy 160.32509 -52.634685) (xy 160.377224 -52.62746)
			(xy 160.40354 -52.627022) (xy 160.430794 -52.627441) (xy 160.484745 -52.635203) (xy 160.537043 -52.650565)
			(xy 160.586622 -52.673213) (xy 160.632474 -52.702686) (xy 160.673665 -52.738385) (xy 160.709356 -52.779582)
			(xy 160.73882 -52.825439) (xy 160.761459 -52.875023) (xy 160.776811 -52.927323) (xy 160.784564 -52.981276)
			(xy 160.785048 -53.00853) (xy 160.784583 -53.036197) (xy 160.776578 -53.090949) (xy 160.760755 -53.143973)
			(xy 160.737445 -53.194158) (xy 160.707136 -53.240453) (xy 160.670462 -53.28189) (xy 160.628193 -53.317599)
			(xy 160.604962 -53.332634) (xy 160.595274 -53.339257) (xy 160.582835 -53.359128) (xy 160.581086 -53.370734)
			(xy 160.573212 -53.450744) (xy 160.572572 -53.462382) (xy 160.580659 -53.484219) (xy 160.588706 -53.492654)
			(xy 160.58896 -53.492908) (xy 160.60752 -53.51101) (xy 160.640102 -53.551337) (xy 160.666919 -53.595706)
			(xy 160.687475 -53.643301) (xy 160.701393 -53.693242) (xy 160.708414 -53.744608) (xy 160.708848 -53.77053)
			(xy 160.70835 -53.79778) (xy 160.700591 -53.851725) (xy 160.685234 -53.904017) (xy 160.662592 -53.953592)
			(xy 160.633126 -53.99944) (xy 160.597436 -54.040629) (xy 160.556248 -54.07632) (xy 160.510401 -54.105787)
			(xy 160.460827 -54.12843) (xy 160.408535 -54.143789) (xy 160.35459 -54.15155) (xy 160.32734 -54.152038)
			(xy 160.29997 -54.151564) (xy 160.245791 -54.14375) (xy 160.193287 -54.128264) (xy 160.14354 -54.105424)
			(xy 160.097573 -54.075699) (xy 160.076642 -54.058058) (xy 160.076388 -54.057804) (xy 160.069309 -54.052207)
			(xy 160.052386 -54.045966) (xy 160.043368 -54.045612) (xy 159.976312 -54.045612) (xy 159.967295 -54.045972)
			(xy 159.950378 -54.052217) (xy 159.943292 -54.057804) (xy 159.943292 -54.058058) (xy 159.943038 -54.058058)
			(xy 159.922097 -54.075686) (xy 159.876127 -54.105401) (xy 159.826382 -54.12824) (xy 159.773883 -54.143733)
			(xy 159.719709 -54.151563) (xy 159.69234 -54.152038) (xy 159.665089 -54.151508) (xy 159.611143 -54.143757)
			(xy 159.558848 -54.128407) (xy 159.50927 -54.105772) (xy 159.463418 -54.076311) (xy 159.422226 -54.040624)
			(xy 159.386531 -53.999438) (xy 159.357062 -53.953592) (xy 159.334417 -53.904018) (xy 159.319058 -53.851726)
			(xy 159.311297 -53.79778) (xy 159.310832 -53.77053) (xy 158.94665 -53.77053) (xy 158.94558 -53.7718)
			(xy 158.945326 -53.772054) (xy 158.939744 -53.779143) (xy 158.933496 -53.796058) (xy 158.933134 -53.805074)
			(xy 158.933134 -53.87213) (xy 158.933469 -53.881149) (xy 158.939731 -53.898066) (xy 158.945326 -53.90515)
			(xy 158.94558 -53.90515) (xy 158.94558 -53.905404) (xy 158.963222 -53.926335) (xy 158.992947 -53.972304)
			(xy 159.015791 -54.02205) (xy 159.031287 -54.074552) (xy 159.039115 -54.128731) (xy 159.039115 -54.183472)
			(xy 159.031287 -54.237651) (xy 159.01579 -54.290153) (xy 159.001998 -54.320186) (xy 161.230564 -54.320186)
			(xy 161.231006 -54.292815) (xy 161.238827 -54.238634) (xy 161.254321 -54.18613) (xy 161.277169 -54.136383)
			(xy 161.3069 -54.090418) (xy 161.324544 -54.069488) (xy 161.324798 -54.069234) (xy 161.330376 -54.062142)
			(xy 161.336628 -54.045229) (xy 161.33699 -54.036214) (xy 161.33699 -53.969158) (xy 161.336607 -53.960144)
			(xy 161.330378 -53.943226) (xy 161.324798 -53.936138) (xy 161.324544 -53.936138) (xy 161.324544 -53.935884)
			(xy 161.306938 -53.914925) (xy 161.277219 -53.868961) (xy 161.254376 -53.81922) (xy 161.238878 -53.766725)
			(xy 161.231042 -53.712553) (xy 161.230564 -53.685186) (xy 161.23105 -53.657935) (xy 161.238806 -53.603987)
			(xy 161.254161 -53.551692) (xy 161.276803 -53.502115) (xy 161.306269 -53.456265) (xy 161.34196 -53.415074)
			(xy 161.383151 -53.379383) (xy 161.429001 -53.349917) (xy 161.478578 -53.327275) (xy 161.530873 -53.31192)
			(xy 161.584821 -53.304164) (xy 161.639323 -53.304164) (xy 161.693271 -53.31192) (xy 161.745566 -53.327275)
			(xy 161.795143 -53.349917) (xy 161.840993 -53.379383) (xy 161.882184 -53.415074) (xy 161.917875 -53.456265)
			(xy 161.947341 -53.502115) (xy 161.969983 -53.551692) (xy 161.985338 -53.603987) (xy 161.993094 -53.657935)
			(xy 161.99358 -53.685186) (xy 161.993111 -53.712556) (xy 161.985294 -53.766735) (xy 161.969806 -53.819239)
			(xy 161.946965 -53.868986) (xy 161.917241 -53.914952) (xy 161.8996 -53.935884) (xy 161.899346 -53.936138)
			(xy 161.893773 -53.943233) (xy 161.887519 -53.960144) (xy 161.887154 -53.969158) (xy 161.887154 -54.036214)
			(xy 161.887493 -54.045233) (xy 161.893752 -54.06215) (xy 161.899346 -54.069234) (xy 161.8996 -54.069234)
			(xy 161.8996 -54.069488) (xy 161.917247 -54.090414) (xy 161.946958 -54.136388) (xy 161.969792 -54.186137)
			(xy 161.985281 -54.238639) (xy 161.993107 -54.292816) (xy 161.99358 -54.320186) (xy 161.993094 -54.347437)
			(xy 161.985338 -54.401385) (xy 161.969983 -54.45368) (xy 161.947341 -54.503257) (xy 161.917875 -54.549107)
			(xy 161.882184 -54.590298) (xy 161.840993 -54.625989) (xy 161.795143 -54.655455) (xy 161.745566 -54.678097)
			(xy 161.693271 -54.693452) (xy 161.639323 -54.701208) (xy 161.584821 -54.701208) (xy 161.530873 -54.693452)
			(xy 161.478578 -54.678097) (xy 161.429001 -54.655455) (xy 161.383151 -54.625989) (xy 161.34196 -54.590298)
			(xy 161.306269 -54.549107) (xy 161.276803 -54.503257) (xy 161.254161 -54.45368) (xy 161.238806 -54.401385)
			(xy 161.23105 -54.347437) (xy 161.230564 -54.320186) (xy 159.001998 -54.320186) (xy 158.992945 -54.339899)
			(xy 158.963221 -54.385867) (xy 158.94558 -54.4068) (xy 158.945326 -54.407054) (xy 158.939744 -54.414143)
			(xy 158.933496 -54.431058) (xy 158.933134 -54.440074) (xy 158.933134 -54.50713) (xy 158.933469 -54.516149)
			(xy 158.939731 -54.533066) (xy 158.945326 -54.54015) (xy 158.94558 -54.54015) (xy 158.94558 -54.540404)
			(xy 158.963231 -54.561326) (xy 158.992942 -54.607301) (xy 159.015776 -54.657051) (xy 159.031264 -54.709554)
			(xy 159.039088 -54.763732) (xy 159.039205 -54.770528) (xy 162.171126 -54.770528) (xy 162.171602 -54.743158)
			(xy 162.179417 -54.688979) (xy 162.194903 -54.636476) (xy 162.217743 -54.586729) (xy 162.247465 -54.540762)
			(xy 162.265106 -54.51983) (xy 162.26536 -54.519576) (xy 162.27097 -54.512506) (xy 162.277201 -54.495576)
			(xy 162.277552 -54.486556) (xy 162.277552 -54.4195) (xy 162.277205 -54.410482) (xy 162.270952 -54.393565)
			(xy 162.26536 -54.38648) (xy 162.265106 -54.38648) (xy 162.265106 -54.386226) (xy 162.247467 -54.365294)
			(xy 162.217755 -54.319321) (xy 162.194919 -54.269574) (xy 162.179428 -54.217073) (xy 162.1716 -54.162897)
			(xy 162.171126 -54.135528) (xy 162.171612 -54.108277) (xy 162.179368 -54.054329) (xy 162.194723 -54.002034)
			(xy 162.217365 -53.952457) (xy 162.246831 -53.906607) (xy 162.282522 -53.865416) (xy 162.323713 -53.829725)
			(xy 162.369563 -53.800259) (xy 162.41914 -53.777617) (xy 162.471435 -53.762262) (xy 162.525383 -53.754506)
			(xy 162.579885 -53.754506) (xy 162.633833 -53.762262) (xy 162.686128 -53.777617) (xy 162.735705 -53.800259)
			(xy 162.781555 -53.829725) (xy 162.822746 -53.865416) (xy 162.858437 -53.906607) (xy 162.887903 -53.952457)
			(xy 162.892978 -53.96357) (xy 166.872156 -53.96357) (xy 166.876227 -53.907948) (xy 166.888353 -53.853511)
			(xy 166.908276 -53.80142) (xy 166.935572 -53.752785) (xy 166.969658 -53.708642) (xy 167.009807 -53.669933)
			(xy 167.055165 -53.637482) (xy 167.104765 -53.611981) (xy 167.157549 -53.593974) (xy 167.212392 -53.583844)
			(xy 167.268126 -53.581807) (xy 167.323563 -53.587907) (xy 167.37752 -53.602013) (xy 167.428849 -53.623825)
			(xy 167.476455 -53.652879) (xy 167.519323 -53.688554) (xy 167.55654 -53.730091) (xy 167.587313 -53.776604)
			(xy 167.610985 -53.827101) (xy 167.627053 -53.880508) (xy 167.635173 -53.935684) (xy 167.635682 -53.96357)
			(xy 167.635173 -53.991456) (xy 167.627053 -54.046632) (xy 167.610985 -54.100039) (xy 167.587313 -54.150536)
			(xy 167.55654 -54.197049) (xy 167.519323 -54.238586) (xy 167.476455 -54.274261) (xy 167.428849 -54.303315)
			(xy 167.37752 -54.325127) (xy 167.323563 -54.339233) (xy 167.268126 -54.345333) (xy 167.212392 -54.343296)
			(xy 167.157549 -54.333166) (xy 167.104765 -54.315159) (xy 167.055165 -54.289658) (xy 167.009807 -54.257207)
			(xy 166.969658 -54.218498) (xy 166.935572 -54.174355) (xy 166.908276 -54.12572) (xy 166.888353 -54.073629)
			(xy 166.876227 -54.019192) (xy 166.872156 -53.96357) (xy 162.892978 -53.96357) (xy 162.910545 -54.002034)
			(xy 162.9259 -54.054329) (xy 162.933656 -54.108277) (xy 162.934142 -54.135528) (xy 162.933706 -54.162899)
			(xy 162.925883 -54.21708) (xy 162.910388 -54.269584) (xy 162.887539 -54.319331) (xy 162.857807 -54.365296)
			(xy 162.840162 -54.386226) (xy 162.839908 -54.38648) (xy 162.834325 -54.393569) (xy 162.828076 -54.410484)
			(xy 162.827716 -54.4195) (xy 162.827716 -54.486556) (xy 162.828091 -54.495571) (xy 162.834326 -54.512488)
			(xy 162.839908 -54.519576) (xy 162.840162 -54.519576) (xy 162.840162 -54.51983) (xy 162.857776 -54.540783)
			(xy 162.887493 -54.586749) (xy 162.910334 -54.636491) (xy 162.925831 -54.688988) (xy 162.933665 -54.74316)
			(xy 162.934142 -54.770528) (xy 162.933656 -54.797779) (xy 162.9259 -54.851727) (xy 162.910545 -54.904022)
			(xy 162.887903 -54.953599) (xy 162.858437 -54.999449) (xy 162.822746 -55.04064) (xy 162.781555 -55.076331)
			(xy 162.735705 -55.105797) (xy 162.686128 -55.128439) (xy 162.633833 -55.143794) (xy 162.579885 -55.15155)
			(xy 162.525383 -55.15155) (xy 162.471435 -55.143794) (xy 162.41914 -55.128439) (xy 162.369563 -55.105797)
			(xy 162.323713 -55.076331) (xy 162.282522 -55.04064) (xy 162.246831 -54.999449) (xy 162.217365 -54.953599)
			(xy 162.194723 -54.904022) (xy 162.179368 -54.851727) (xy 162.171612 -54.797779) (xy 162.171126 -54.770528)
			(xy 159.039205 -54.770528) (xy 159.03956 -54.791102) (xy 159.039074 -54.818353) (xy 159.031318 -54.872301)
			(xy 159.015963 -54.924596) (xy 158.993321 -54.974173) (xy 158.963855 -55.020023) (xy 158.928164 -55.061214)
			(xy 158.886973 -55.096905) (xy 158.841123 -55.126371) (xy 158.791546 -55.149013) (xy 158.739251 -55.164368)
			(xy 158.685303 -55.172124) (xy 158.630801 -55.172124) (xy 158.576853 -55.164368) (xy 158.524558 -55.149013)
			(xy 158.474981 -55.126371) (xy 158.429131 -55.096905) (xy 158.38794 -55.061214) (xy 158.352249 -55.020023)
			(xy 158.322783 -54.974173) (xy 158.300141 -54.924596) (xy 158.284786 -54.872301) (xy 158.27703 -54.818353)
			(xy 158.276544 -54.791102) (xy 156.378586 -54.791102) (xy 156.375494 -54.812611) (xy 156.360139 -54.864906)
			(xy 156.337497 -54.914483) (xy 156.308031 -54.960333) (xy 156.27234 -55.001524) (xy 156.231149 -55.037215)
			(xy 156.185299 -55.066681) (xy 156.135722 -55.089323) (xy 156.083427 -55.104678) (xy 156.029479 -55.112434)
			(xy 155.974977 -55.112434) (xy 155.921029 -55.104678) (xy 155.868734 -55.089323) (xy 155.819157 -55.066681)
			(xy 155.773307 -55.037215) (xy 155.732116 -55.001524) (xy 155.696425 -54.960333) (xy 155.666959 -54.914483)
			(xy 155.644317 -54.864906) (xy 155.628962 -54.812611) (xy 155.621206 -54.758663) (xy 155.62072 -54.731412)
			(xy 154.959304 -54.731412) (xy 154.959304 -57.002934) (xy 163.66363 -57.002934) (xy 163.664128 -56.974842)
			(xy 163.672352 -56.919264) (xy 163.688641 -56.865494) (xy 163.712642 -56.814696) (xy 163.743837 -56.767969)
			(xy 163.78155 -56.726324) (xy 163.824965 -56.690663) (xy 163.848796 -56.675782) (xy 163.857686 -56.670448)
			(xy 163.869878 -56.65343) (xy 163.890198 -56.560212) (xy 163.88588 -56.539638) (xy 163.880038 -56.531002)
			(xy 163.864041 -56.506936) (xy 163.838697 -56.455006) (xy 163.82147 -56.399848) (xy 163.812754 -56.342724)
			(xy 163.81222 -56.313832) (xy 163.812685 -56.286579) (xy 163.820439 -56.232626) (xy 163.835792 -56.180327)
			(xy 163.858433 -56.130745) (xy 163.8879 -56.08489) (xy 163.923594 -56.043697) (xy 163.964787 -56.008002)
			(xy 164.010641 -55.978535) (xy 164.060223 -55.955893) (xy 164.112522 -55.940539) (xy 164.166475 -55.932785)
			(xy 164.193728 -55.932324) (xy 164.221099 -55.932768) (xy 164.275279 -55.94059) (xy 164.327783 -55.956084)
			(xy 164.377529 -55.978931) (xy 164.423495 -56.00866) (xy 164.444426 -56.026304) (xy 164.44468 -56.026558)
			(xy 164.451763 -56.032149) (xy 164.468683 -56.038392) (xy 164.4777 -56.03875) (xy 164.544756 -56.03875)
			(xy 164.553772 -56.038383) (xy 164.57069 -56.032144) (xy 164.577776 -56.026558) (xy 164.577776 -56.026304)
			(xy 164.57803 -56.026304) (xy 164.598963 -56.008663) (xy 164.644931 -55.978939) (xy 164.694677 -55.956093)
			(xy 164.747179 -55.940597) (xy 164.801357 -55.932768) (xy 164.856099 -55.932768) (xy 164.910277 -55.940597)
			(xy 164.962779 -55.956093) (xy 165.012525 -55.978939) (xy 165.058493 -56.008663) (xy 165.079426 -56.026304)
			(xy 165.07968 -56.026558) (xy 165.086763 -56.032149) (xy 165.103683 -56.038392) (xy 165.1127 -56.03875)
			(xy 165.179756 -56.03875) (xy 165.188772 -56.038383) (xy 165.20569 -56.032144) (xy 165.212776 -56.026558)
			(xy 165.212776 -56.026304) (xy 165.21303 -56.026304) (xy 165.233978 -56.008685) (xy 165.279946 -55.97897)
			(xy 165.32969 -55.95613) (xy 165.382187 -55.940634) (xy 165.43636 -55.932801) (xy 165.463728 -55.932324)
			(xy 165.49098 -55.932748) (xy 165.544929 -55.940508) (xy 165.597225 -55.955867) (xy 165.646803 -55.978512)
			(xy 165.692654 -56.007981) (xy 165.733844 -56.043676) (xy 165.769536 -56.084869) (xy 165.799002 -56.130722)
			(xy 165.821643 -56.180301) (xy 165.836998 -56.232598) (xy 165.844754 -56.286548) (xy 165.844754 -56.341052)
			(xy 165.836998 -56.395002) (xy 165.821643 -56.447299) (xy 165.799002 -56.496878) (xy 165.769536 -56.542731)
			(xy 165.733844 -56.583924) (xy 165.692654 -56.619619) (xy 165.646803 -56.649088) (xy 165.597225 -56.671733)
			(xy 165.544929 -56.687092) (xy 165.49098 -56.694852) (xy 165.463728 -56.69534) (xy 165.436358 -56.694872)
			(xy 165.382178 -56.687057) (xy 165.329674 -56.671569) (xy 165.279927 -56.648727) (xy 165.233961 -56.619002)
			(xy 165.21303 -56.60136) (xy 165.212776 -56.601106) (xy 165.2057 -56.595504) (xy 165.188775 -56.589266)
			(xy 165.179756 -56.588914) (xy 165.1127 -56.588914) (xy 165.103683 -56.589268) (xy 165.086766 -56.595517)
			(xy 165.07968 -56.601106) (xy 165.07968 -56.60136) (xy 165.079426 -56.60136) (xy 165.058493 -56.619001)
			(xy 165.012525 -56.648725) (xy 164.962779 -56.671571) (xy 164.910277 -56.687067) (xy 164.856099 -56.694896)
			(xy 164.801357 -56.694896) (xy 164.747179 -56.687067) (xy 164.694677 -56.671571) (xy 164.644931 -56.648725)
			(xy 164.598963 -56.619001) (xy 164.57803 -56.60136) (xy 164.577776 -56.601106) (xy 164.5707 -56.595504)
			(xy 164.553775 -56.589266) (xy 164.544756 -56.588914) (xy 164.4777 -56.588914) (xy 164.468683 -56.589268)
			(xy 164.451766 -56.595517) (xy 164.44468 -56.601106) (xy 164.444172 -56.60136) (xy 164.431437 -56.612303)
			(xy 164.404346 -56.632145) (xy 164.39007 -56.640984) (xy 164.38118 -56.646318) (xy 164.368988 -56.663336)
			(xy 164.348668 -56.756554) (xy 164.352986 -56.777128) (xy 164.358828 -56.785764) (xy 164.374818 -56.809834)
			(xy 164.400162 -56.861764) (xy 164.417391 -56.91692) (xy 164.426109 -56.974042) (xy 164.426646 -57.002934)
			(xy 164.42616 -57.030185) (xy 164.418404 -57.084133) (xy 164.403049 -57.136428) (xy 164.380407 -57.186005)
			(xy 164.350941 -57.231855) (xy 164.31525 -57.273046) (xy 164.274059 -57.308737) (xy 164.228209 -57.338203)
			(xy 164.178632 -57.360845) (xy 164.126337 -57.3762) (xy 164.072389 -57.383956) (xy 164.017887 -57.383956)
			(xy 163.963939 -57.3762) (xy 163.911644 -57.360845) (xy 163.862067 -57.338203) (xy 163.816217 -57.308737)
			(xy 163.775026 -57.273046) (xy 163.739335 -57.231855) (xy 163.709869 -57.186005) (xy 163.687227 -57.136428)
			(xy 163.671872 -57.084133) (xy 163.664116 -57.030185) (xy 163.66363 -57.002934) (xy 154.959304 -57.002934)
			(xy 154.959304 -58.679334) (xy 164.09543 -58.679334) (xy 164.095844 -58.653018) (xy 164.103088 -58.600887)
			(xy 164.117417 -58.550243) (xy 164.13856 -58.502044) (xy 164.166116 -58.457202) (xy 164.199564 -58.416565)
			(xy 164.21862 -58.39841) (xy 164.226022 -58.390889) (xy 164.234546 -58.371608) (xy 164.23513 -58.361072)
			(xy 164.23513 -58.286396) (xy 164.234608 -58.275846) (xy 164.226067 -58.256551) (xy 164.21862 -58.249058)
			(xy 164.199555 -58.230912) (xy 164.166098 -58.190281) (xy 164.13854 -58.145439) (xy 164.117403 -58.097236)
			(xy 164.103088 -58.046586) (xy 164.095866 -57.994451) (xy 164.09543 -57.968134) (xy 164.095916 -57.940883)
			(xy 164.103672 -57.886935) (xy 164.119027 -57.83464) (xy 164.141669 -57.785063) (xy 164.171135 -57.739213)
			(xy 164.206826 -57.698022) (xy 164.248017 -57.662331) (xy 164.293867 -57.632865) (xy 164.343444 -57.610223)
			(xy 164.395739 -57.594868) (xy 164.449687 -57.587112) (xy 164.504189 -57.587112) (xy 164.558137 -57.594868)
			(xy 164.610432 -57.610223) (xy 164.660009 -57.632865) (xy 164.705859 -57.662331) (xy 164.74705 -57.698022)
			(xy 164.782741 -57.739213) (xy 164.812207 -57.785063) (xy 164.834849 -57.83464) (xy 164.850204 -57.886935)
			(xy 164.85796 -57.940883) (xy 164.858446 -57.968134) (xy 164.858018 -57.99445) (xy 164.850778 -58.04658)
			(xy 164.836452 -58.097225) (xy 164.815312 -58.145424) (xy 164.787758 -58.190266) (xy 164.754312 -58.230903)
			(xy 164.735256 -58.249058) (xy 164.727879 -58.256601) (xy 164.719339 -58.275864) (xy 164.718746 -58.286396)
			(xy 164.718746 -58.361072) (xy 164.719263 -58.371623) (xy 164.727805 -58.390919) (xy 164.735256 -58.39841)
			(xy 164.75432 -58.416557) (xy 164.787774 -58.45719) (xy 164.815331 -58.502032) (xy 164.836467 -58.550234)
			(xy 164.850783 -58.600883) (xy 164.858008 -58.653018) (xy 164.858446 -58.679334) (xy 164.85796 -58.706585)
			(xy 164.850204 -58.760533) (xy 164.834849 -58.812828) (xy 164.812207 -58.862405) (xy 164.782741 -58.908255)
			(xy 164.74705 -58.949446) (xy 164.705859 -58.985137) (xy 164.660009 -59.014603) (xy 164.610432 -59.037245)
			(xy 164.558137 -59.0526) (xy 164.504189 -59.060356) (xy 164.449687 -59.060356) (xy 164.395739 -59.0526)
			(xy 164.343444 -59.037245) (xy 164.293867 -59.014603) (xy 164.248017 -58.985137) (xy 164.206826 -58.949446)
			(xy 164.171135 -58.908255) (xy 164.141669 -58.862405) (xy 164.119027 -58.812828) (xy 164.103672 -58.760533)
			(xy 164.095916 -58.706585) (xy 164.09543 -58.679334) (xy 154.959304 -58.679334) (xy 154.959304 -60.01925)
			(xy 164.235884 -60.01925) (xy 164.235884 -59.96475) (xy 164.24364 -59.910803) (xy 164.258994 -59.85851)
			(xy 164.281635 -59.808934) (xy 164.3111 -59.763085) (xy 164.34679 -59.721895) (xy 164.387978 -59.686204)
			(xy 164.433827 -59.656738) (xy 164.483403 -59.634097) (xy 164.535696 -59.618742) (xy 164.589642 -59.610984)
			(xy 164.616892 -59.610498) (xy 164.644262 -59.610969) (xy 164.698441 -59.618786) (xy 164.750944 -59.634274)
			(xy 164.800691 -59.657114) (xy 164.846658 -59.686837) (xy 164.86759 -59.704478) (xy 164.867844 -59.704732)
			(xy 164.87494 -59.710305) (xy 164.89185 -59.716559) (xy 164.900864 -59.716924) (xy 164.96792 -59.716924)
			(xy 164.976937 -59.716572) (xy 164.993854 -59.71032) (xy 165.00094 -59.704732) (xy 165.00094 -59.704478)
			(xy 165.001194 -59.704478) (xy 165.022127 -59.686837) (xy 165.068095 -59.657113) (xy 165.117841 -59.634267)
			(xy 165.170343 -59.618771) (xy 165.224521 -59.610942) (xy 165.279263 -59.610942) (xy 165.333441 -59.618771)
			(xy 165.385943 -59.634267) (xy 165.435689 -59.657113) (xy 165.481657 -59.686837) (xy 165.50259 -59.704478)
			(xy 165.502844 -59.704732) (xy 165.50994 -59.710305) (xy 165.52685 -59.716559) (xy 165.535864 -59.716924)
			(xy 165.60292 -59.716924) (xy 165.611937 -59.716572) (xy 165.628854 -59.71032) (xy 165.63594 -59.704732)
			(xy 165.63594 -59.704478) (xy 165.636194 -59.704478) (xy 165.657115 -59.686825) (xy 165.703091 -59.657116)
			(xy 165.752841 -59.634283) (xy 165.805344 -59.618795) (xy 165.859522 -59.61097) (xy 165.886892 -59.610498)
			(xy 165.914146 -59.610949) (xy 165.968098 -59.618705) (xy 166.020398 -59.634061) (xy 166.06998 -59.656703)
			(xy 166.115835 -59.686171) (xy 166.157029 -59.721865) (xy 166.192724 -59.763059) (xy 166.222193 -59.808913)
			(xy 166.244837 -59.858495) (xy 166.260193 -59.910794) (xy 166.267951 -59.964746) (xy 166.267951 -60.019254)
			(xy 166.260193 -60.073206) (xy 166.244837 -60.125505) (xy 166.222193 -60.175087) (xy 166.192724 -60.220941)
			(xy 166.157029 -60.262135) (xy 166.115835 -60.297829) (xy 166.06998 -60.327297) (xy 166.020398 -60.349939)
			(xy 165.968098 -60.365295) (xy 165.914146 -60.373051) (xy 165.886892 -60.373514) (xy 165.859522 -60.373049)
			(xy 165.805343 -60.365231) (xy 165.75284 -60.349741) (xy 165.703093 -60.326899) (xy 165.657126 -60.297175)
			(xy 165.636194 -60.279534) (xy 165.63594 -60.27928) (xy 165.628848 -60.273702) (xy 165.611935 -60.267451)
			(xy 165.60292 -60.267088) (xy 165.535864 -60.267088) (xy 165.526846 -60.26743) (xy 165.509929 -60.273688)
			(xy 165.502844 -60.27928) (xy 165.50259 -60.279534) (xy 165.481657 -60.297175) (xy 165.435689 -60.326899)
			(xy 165.385943 -60.349745) (xy 165.333441 -60.365241) (xy 165.279263 -60.37307) (xy 165.224521 -60.37307)
			(xy 165.170343 -60.365241) (xy 165.117841 -60.349745) (xy 165.068095 -60.326899) (xy 165.022127 -60.297175)
			(xy 165.001194 -60.279534) (xy 165.00094 -60.27928) (xy 164.993848 -60.273702) (xy 164.976935 -60.267451)
			(xy 164.96792 -60.267088) (xy 164.900864 -60.267088) (xy 164.891846 -60.26743) (xy 164.874929 -60.273688)
			(xy 164.867844 -60.27928) (xy 164.867844 -60.279534) (xy 164.86759 -60.279534) (xy 164.846677 -60.297197)
			(xy 164.800698 -60.326904) (xy 164.750946 -60.349735) (xy 164.698441 -60.36522) (xy 164.644262 -60.373043)
			(xy 164.616892 -60.373514) (xy 164.589642 -60.373016) (xy 164.535696 -60.365258) (xy 164.483403 -60.349903)
			(xy 164.433827 -60.327262) (xy 164.387978 -60.297796) (xy 164.34679 -60.262105) (xy 164.3111 -60.220915)
			(xy 164.281635 -60.175066) (xy 164.258994 -60.12549) (xy 164.24364 -60.073197) (xy 164.235884 -60.01925)
			(xy 154.959304 -60.01925) (xy 154.959304 -63.213552) (xy 164.220865 -63.213552) (xy 164.220865 -63.159048)
			(xy 164.228622 -63.105098) (xy 164.243978 -63.052801) (xy 164.266621 -63.003221) (xy 164.296088 -62.957369)
			(xy 164.331782 -62.916177) (xy 164.372974 -62.880485) (xy 164.418827 -62.851018) (xy 164.468406 -62.828376)
			(xy 164.520703 -62.813021) (xy 164.574654 -62.805265) (xy 164.601906 -62.804802) (xy 164.629276 -62.805264)
			(xy 164.683456 -62.813083) (xy 164.735959 -62.828573) (xy 164.785706 -62.851415) (xy 164.831672 -62.881141)
			(xy 164.852604 -62.898782) (xy 164.852858 -62.899036) (xy 164.859949 -62.904615) (xy 164.876863 -62.910865)
			(xy 164.885878 -62.911228) (xy 164.952934 -62.911228) (xy 164.961952 -62.910881) (xy 164.978868 -62.904626)
			(xy 164.985954 -62.899036) (xy 164.985954 -62.898782) (xy 164.986208 -62.898782) (xy 165.007141 -62.881141)
			(xy 165.053109 -62.851417) (xy 165.102855 -62.828571) (xy 165.155357 -62.813075) (xy 165.209535 -62.805246)
			(xy 165.264277 -62.805246) (xy 165.318455 -62.813075) (xy 165.370957 -62.828571) (xy 165.420703 -62.851417)
			(xy 165.466671 -62.881141) (xy 165.487604 -62.898782) (xy 165.487858 -62.899036) (xy 165.494949 -62.904615)
			(xy 165.511863 -62.910865) (xy 165.520878 -62.911228) (xy 165.587934 -62.911228) (xy 165.596952 -62.910881)
			(xy 165.613868 -62.904626) (xy 165.620954 -62.899036) (xy 165.620954 -62.898782) (xy 165.621208 -62.898782)
			(xy 165.642124 -62.881123) (xy 165.688101 -62.851415) (xy 165.737853 -62.828583) (xy 165.790357 -62.813096)
			(xy 165.844536 -62.805273) (xy 165.871906 -62.804802) (xy 165.899158 -62.805268) (xy 165.953106 -62.813026)
			(xy 166.005402 -62.828382) (xy 166.054979 -62.851024) (xy 166.10083 -62.880491) (xy 166.142021 -62.916183)
			(xy 166.177713 -62.957375) (xy 166.207179 -63.003226) (xy 166.22982 -63.052804) (xy 166.245176 -63.1051)
			(xy 166.252932 -63.159048) (xy 166.252932 -63.213552) (xy 166.245176 -63.2675) (xy 166.22982 -63.319796)
			(xy 166.207179 -63.369374) (xy 166.177713 -63.415225) (xy 166.142021 -63.456417) (xy 166.10083 -63.492109)
			(xy 166.054979 -63.521576) (xy 166.005402 -63.544218) (xy 165.953106 -63.559574) (xy 165.899158 -63.567332)
			(xy 165.871906 -63.567818) (xy 165.844535 -63.567368) (xy 165.790354 -63.55955) (xy 165.73785 -63.544058)
			(xy 165.688104 -63.521212) (xy 165.642138 -63.491482) (xy 165.621208 -63.473838) (xy 165.620954 -63.473584)
			(xy 165.613857 -63.468012) (xy 165.596948 -63.461757) (xy 165.587934 -63.461392) (xy 165.520878 -63.461392)
			(xy 165.51186 -63.46174) (xy 165.494944 -63.467994) (xy 165.487858 -63.473584) (xy 165.487604 -63.473838)
			(xy 165.466671 -63.491479) (xy 165.420703 -63.521203) (xy 165.370957 -63.544049) (xy 165.318455 -63.559545)
			(xy 165.264277 -63.567374) (xy 165.209535 -63.567374) (xy 165.155357 -63.559545) (xy 165.102855 -63.544049)
			(xy 165.053109 -63.521203) (xy 165.007141 -63.491479) (xy 164.986208 -63.473838) (xy 164.985954 -63.473584)
			(xy 164.978857 -63.468012) (xy 164.961948 -63.461757) (xy 164.952934 -63.461392) (xy 164.885878 -63.461392)
			(xy 164.87686 -63.46174) (xy 164.859944 -63.467994) (xy 164.852858 -63.473584) (xy 164.852858 -63.473838)
			(xy 164.852604 -63.473838) (xy 164.831686 -63.491495) (xy 164.785709 -63.521203) (xy 164.735958 -63.544035)
			(xy 164.683454 -63.559522) (xy 164.629276 -63.567346) (xy 164.601906 -63.567818) (xy 164.574654 -63.567335)
			(xy 164.520703 -63.559579) (xy 164.468406 -63.544224) (xy 164.418827 -63.521582) (xy 164.372974 -63.492115)
			(xy 164.331782 -63.456423) (xy 164.296088 -63.415231) (xy 164.266621 -63.369379) (xy 164.243978 -63.319799)
			(xy 164.228622 -63.267502) (xy 164.220865 -63.213552) (xy 154.959304 -63.213552) (xy 154.959304 -67.12895)
			(xy 156.466798 -67.12895) (xy 156.466798 -67.07445) (xy 156.474554 -67.020506) (xy 156.489908 -66.968215)
			(xy 156.512548 -66.918641) (xy 156.542012 -66.872793) (xy 156.577701 -66.831605) (xy 156.618888 -66.795915)
			(xy 156.664735 -66.766451) (xy 156.714309 -66.74381) (xy 156.7666 -66.728455) (xy 156.820544 -66.720699)
			(xy 156.847794 -66.720212) (xy 156.875164 -66.720679) (xy 156.929343 -66.728496) (xy 156.981847 -66.743985)
			(xy 157.031594 -66.766826) (xy 157.07756 -66.796551) (xy 157.098492 -66.814192) (xy 157.098746 -66.814446)
			(xy 157.10584 -66.820022) (xy 157.122751 -66.826274) (xy 157.131766 -66.826638) (xy 157.198822 -66.826638)
			(xy 157.207839 -66.826283) (xy 157.224756 -66.820033) (xy 157.231842 -66.814446) (xy 157.231842 -66.814192)
			(xy 157.232096 -66.814192) (xy 157.253018 -66.79654) (xy 157.298993 -66.76683) (xy 157.348744 -66.743997)
			(xy 157.401247 -66.728509) (xy 157.455424 -66.720684) (xy 157.482794 -66.720212) (xy 157.510049 -66.720634)
			(xy 157.564003 -66.728391) (xy 157.616304 -66.743748) (xy 157.665888 -66.766391) (xy 157.711744 -66.79586)
			(xy 157.75294 -66.831556) (xy 157.788636 -66.872751) (xy 157.818106 -66.918607) (xy 157.84075 -66.96819)
			(xy 157.856108 -67.020491) (xy 157.863865 -67.074445) (xy 157.863865 -67.128955) (xy 157.856108 -67.182909)
			(xy 157.84075 -67.23521) (xy 157.818106 -67.284793) (xy 157.788636 -67.330649) (xy 157.75294 -67.371844)
			(xy 157.711744 -67.40754) (xy 157.665888 -67.437009) (xy 157.616304 -67.459652) (xy 157.564003 -67.475009)
			(xy 157.510049 -67.482766) (xy 157.482794 -67.483228) (xy 157.455423 -67.482783) (xy 157.401242 -67.474963)
			(xy 157.348738 -67.45947) (xy 157.298991 -67.436623) (xy 157.253026 -67.406892) (xy 157.232096 -67.389248)
			(xy 157.231842 -67.388994) (xy 157.224748 -67.383418) (xy 157.207837 -67.377165) (xy 157.198822 -67.376802)
			(xy 157.131766 -67.376802) (xy 157.122747 -67.377142) (xy 157.105831 -67.383402) (xy 157.098746 -67.388994)
			(xy 157.098746 -67.389248) (xy 157.098492 -67.389248) (xy 157.077567 -67.406896) (xy 157.031593 -67.436608)
			(xy 156.981844 -67.459443) (xy 156.929341 -67.474932) (xy 156.875164 -67.482757) (xy 156.847794 -67.483228)
			(xy 156.820544 -67.482701) (xy 156.7666 -67.474945) (xy 156.714309 -67.45959) (xy 156.664735 -67.436949)
			(xy 156.618888 -67.407485) (xy 156.577701 -67.371795) (xy 156.542012 -67.330607) (xy 156.512548 -67.284759)
			(xy 156.489908 -67.235185) (xy 156.474554 -67.182894) (xy 156.466798 -67.12895) (xy 154.959304 -67.12895)
			(xy 154.959304 -67.488054) (xy 160.87928 -67.488054) (xy 160.883351 -67.432432) (xy 160.895477 -67.377995)
			(xy 160.9154 -67.325904) (xy 160.942696 -67.277269) (xy 160.976782 -67.233126) (xy 161.016931 -67.194417)
			(xy 161.062289 -67.161966) (xy 161.111889 -67.136465) (xy 161.164673 -67.118458) (xy 161.219516 -67.108328)
			(xy 161.27525 -67.106291) (xy 161.330687 -67.112391) (xy 161.384644 -67.126497) (xy 161.435973 -67.148309)
			(xy 161.483579 -67.177363) (xy 161.526447 -67.213038) (xy 161.563664 -67.254575) (xy 161.594437 -67.301088)
			(xy 161.618109 -67.351585) (xy 161.634177 -67.404992) (xy 161.642297 -67.460168) (xy 161.642806 -67.488054)
			(xy 161.642297 -67.51594) (xy 161.639112 -67.537584) (xy 162.171378 -67.537584) (xy 162.175449 -67.481962)
			(xy 162.187575 -67.427525) (xy 162.207498 -67.375434) (xy 162.234794 -67.326799) (xy 162.26888 -67.282656)
			(xy 162.309029 -67.243947) (xy 162.354387 -67.211496) (xy 162.403987 -67.185995) (xy 162.456771 -67.167988)
			(xy 162.511614 -67.157858) (xy 162.567348 -67.155821) (xy 162.622785 -67.161921) (xy 162.676742 -67.176027)
			(xy 162.728071 -67.197839) (xy 162.775677 -67.226893) (xy 162.818545 -67.262568) (xy 162.855762 -67.304105)
			(xy 162.886535 -67.350618) (xy 162.910207 -67.401115) (xy 162.926275 -67.454522) (xy 162.934395 -67.509698)
			(xy 162.934904 -67.537584) (xy 162.934395 -67.56547) (xy 162.93035 -67.592956) (xy 163.445442 -67.592956)
			(xy 163.449513 -67.537334) (xy 163.461639 -67.482897) (xy 163.481562 -67.430806) (xy 163.508858 -67.382171)
			(xy 163.542944 -67.338028) (xy 163.583093 -67.299319) (xy 163.628451 -67.266868) (xy 163.678051 -67.241367)
			(xy 163.730835 -67.22336) (xy 163.785678 -67.21323) (xy 163.841412 -67.211193) (xy 163.896849 -67.217293)
			(xy 163.950806 -67.231399) (xy 164.002135 -67.253211) (xy 164.049741 -67.282265) (xy 164.092609 -67.31794)
			(xy 164.129826 -67.359477) (xy 164.160599 -67.40599) (xy 164.184271 -67.456487) (xy 164.200339 -67.509894)
			(xy 164.208456 -67.565048) (xy 166.546816 -67.565048) (xy 166.546816 -67.510552) (xy 166.554571 -67.456611)
			(xy 166.569924 -67.404323) (xy 166.592562 -67.354752) (xy 166.622024 -67.308907) (xy 166.65771 -67.267721)
			(xy 166.698894 -67.232033) (xy 166.744738 -67.20257) (xy 166.794308 -67.17993) (xy 166.846596 -67.164575)
			(xy 166.900536 -67.156817) (xy 166.927784 -67.15633) (xy 166.955154 -67.156798) (xy 167.009334 -67.164614)
			(xy 167.061837 -67.180103) (xy 167.111584 -67.202944) (xy 167.157551 -67.232669) (xy 167.178482 -67.25031)
			(xy 167.178736 -67.250564) (xy 167.185831 -67.256137) (xy 167.202742 -67.26239) (xy 167.211756 -67.262756)
			(xy 167.278812 -67.262756) (xy 167.287831 -67.262414) (xy 167.304748 -67.256157) (xy 167.311832 -67.250564)
			(xy 167.311832 -67.25031) (xy 167.312086 -67.25031) (xy 167.333014 -67.232666) (xy 167.378988 -67.202954)
			(xy 167.428736 -67.180119) (xy 167.481238 -67.164629) (xy 167.535415 -67.156803) (xy 167.562784 -67.15633)
			(xy 167.59004 -67.156716) (xy 167.643998 -67.164472) (xy 167.696303 -67.179828) (xy 167.745891 -67.202472)
			(xy 167.79175 -67.231942) (xy 167.832949 -67.26764) (xy 167.868648 -67.308837) (xy 167.898121 -67.354695)
			(xy 167.920766 -67.404282) (xy 167.936125 -67.456586) (xy 167.943883 -67.510544) (xy 167.943883 -67.565056)
			(xy 167.936125 -67.619014) (xy 167.920766 -67.671318) (xy 167.898121 -67.720905) (xy 167.868648 -67.766763)
			(xy 167.832949 -67.80796) (xy 167.79175 -67.843658) (xy 167.745891 -67.873128) (xy 167.696303 -67.895772)
			(xy 167.643998 -67.911128) (xy 167.59004 -67.918884) (xy 167.562784 -67.919346) (xy 167.535413 -67.918902)
			(xy 167.481232 -67.911081) (xy 167.428728 -67.895588) (xy 167.378982 -67.872741) (xy 167.333016 -67.84301)
			(xy 167.312086 -67.825366) (xy 167.311832 -67.825112) (xy 167.304739 -67.819534) (xy 167.287827 -67.813282)
			(xy 167.278812 -67.81292) (xy 167.211756 -67.81292) (xy 167.202741 -67.8133) (xy 167.185824 -67.819531)
			(xy 167.178736 -67.825112) (xy 167.178736 -67.825366) (xy 167.178482 -67.825366) (xy 167.157525 -67.842975)
			(xy 167.11156 -67.872692) (xy 167.061819 -67.895535) (xy 167.009323 -67.911033) (xy 166.955152 -67.918868)
			(xy 166.927784 -67.919346) (xy 166.900536 -67.918783) (xy 166.846596 -67.911025) (xy 166.794308 -67.89567)
			(xy 166.744738 -67.87303) (xy 166.698894 -67.843567) (xy 166.65771 -67.807879) (xy 166.622024 -67.766693)
			(xy 166.592562 -67.720848) (xy 166.569924 -67.671277) (xy 166.554571 -67.618989) (xy 166.546816 -67.565048)
			(xy 164.208456 -67.565048) (xy 164.208459 -67.56507) (xy 164.208968 -67.592956) (xy 164.208459 -67.620842)
			(xy 164.200339 -67.676018) (xy 164.184271 -67.729425) (xy 164.160599 -67.779922) (xy 164.129826 -67.826435)
			(xy 164.092609 -67.867972) (xy 164.049741 -67.903647) (xy 164.002135 -67.932701) (xy 163.950806 -67.954513)
			(xy 163.896849 -67.968619) (xy 163.841412 -67.974719) (xy 163.785678 -67.972682) (xy 163.730835 -67.962552)
			(xy 163.678051 -67.944545) (xy 163.628451 -67.919044) (xy 163.583093 -67.886593) (xy 163.542944 -67.847884)
			(xy 163.508858 -67.803741) (xy 163.481562 -67.755106) (xy 163.461639 -67.703015) (xy 163.449513 -67.648578)
			(xy 163.445442 -67.592956) (xy 162.93035 -67.592956) (xy 162.926275 -67.620646) (xy 162.910207 -67.674053)
			(xy 162.886535 -67.72455) (xy 162.855762 -67.771063) (xy 162.818545 -67.8126) (xy 162.775677 -67.848275)
			(xy 162.728071 -67.877329) (xy 162.676742 -67.899141) (xy 162.622785 -67.913247) (xy 162.567348 -67.919347)
			(xy 162.511614 -67.91731) (xy 162.456771 -67.90718) (xy 162.403987 -67.889173) (xy 162.354387 -67.863672)
			(xy 162.309029 -67.831221) (xy 162.26888 -67.792512) (xy 162.234794 -67.748369) (xy 162.207498 -67.699734)
			(xy 162.187575 -67.647643) (xy 162.175449 -67.593206) (xy 162.171378 -67.537584) (xy 161.639112 -67.537584)
			(xy 161.634177 -67.571116) (xy 161.618109 -67.624523) (xy 161.594437 -67.67502) (xy 161.563664 -67.721533)
			(xy 161.526447 -67.76307) (xy 161.483579 -67.798745) (xy 161.435973 -67.827799) (xy 161.384644 -67.849611)
			(xy 161.330687 -67.863717) (xy 161.27525 -67.869817) (xy 161.219516 -67.86778) (xy 161.164673 -67.85765)
			(xy 161.111889 -67.839643) (xy 161.062289 -67.814142) (xy 161.016931 -67.781691) (xy 160.976782 -67.742982)
			(xy 160.942696 -67.698839) (xy 160.9154 -67.650204) (xy 160.895477 -67.598113) (xy 160.883351 -67.543676)
			(xy 160.87928 -67.488054) (xy 154.959304 -67.488054) (xy 154.959304 -68.586604) (xy 158.725362 -68.586604)
			(xy 158.725815 -68.559233) (xy 158.733634 -68.505053) (xy 158.749125 -68.452549) (xy 158.77197 -68.402802)
			(xy 158.801699 -68.356837) (xy 158.819342 -68.335906) (xy 158.819596 -68.335652) (xy 158.825167 -68.328554)
			(xy 158.831423 -68.311646) (xy 158.831788 -68.302632) (xy 158.831788 -68.235576) (xy 158.831445 -68.226558)
			(xy 158.825188 -68.209641) (xy 158.819596 -68.202556) (xy 158.819342 -68.202556) (xy 158.819342 -68.202302)
			(xy 158.801697 -68.181375) (xy 158.771985 -68.135401) (xy 158.749149 -68.085653) (xy 158.73366 -68.033151)
			(xy 158.725834 -67.978974) (xy 158.725362 -67.951604) (xy 158.725881 -67.924354) (xy 158.733637 -67.870409)
			(xy 158.74899 -67.818117) (xy 158.771628 -67.768542) (xy 158.801091 -67.722693) (xy 158.836779 -67.681503)
			(xy 158.877966 -67.645812) (xy 158.923812 -67.616345) (xy 158.973385 -67.593702) (xy 159.025676 -67.578344)
			(xy 159.07962 -67.570584) (xy 159.10687 -67.570096) (xy 159.133185 -67.570518) (xy 159.185316 -67.577762)
			(xy 159.235959 -67.59209) (xy 159.284158 -67.613231) (xy 159.329001 -67.640785) (xy 159.369639 -67.674231)
			(xy 159.387794 -67.693286) (xy 159.395318 -67.700685) (xy 159.414596 -67.709211) (xy 159.425132 -67.709796)
			(xy 159.499808 -67.709796) (xy 159.51036 -67.709286) (xy 159.529655 -67.700738) (xy 159.537146 -67.693286)
			(xy 159.555283 -67.674212) (xy 159.595917 -67.640757) (xy 159.640762 -67.613201) (xy 159.688966 -67.592066)
			(xy 159.739616 -67.577752) (xy 159.791753 -67.570532) (xy 159.81807 -67.570096) (xy 159.84544 -67.570581)
			(xy 159.899618 -67.578394) (xy 159.952121 -67.593879) (xy 160.001868 -67.616716) (xy 160.047836 -67.646437)
			(xy 160.068768 -67.664076) (xy 160.069022 -67.66433) (xy 160.076096 -67.669935) (xy 160.093022 -67.67617)
			(xy 160.102042 -67.676522) (xy 160.169098 -67.676522) (xy 160.178114 -67.676159) (xy 160.195031 -67.669915)
			(xy 160.202118 -67.66433) (xy 160.202118 -67.664076) (xy 160.202372 -67.664076) (xy 160.223301 -67.646433)
			(xy 160.269275 -67.616722) (xy 160.319023 -67.593888) (xy 160.371524 -67.578397) (xy 160.425701 -67.57057)
			(xy 160.45307 -67.570096) (xy 160.480322 -67.570583) (xy 160.534273 -67.578336) (xy 160.58657 -67.593689)
			(xy 160.636151 -67.616328) (xy 160.682004 -67.645793) (xy 160.723197 -67.681484) (xy 160.758891 -67.722675)
			(xy 160.78836 -67.768527) (xy 160.811002 -67.818105) (xy 160.826358 -67.870402) (xy 160.834115 -67.924352)
			(xy 160.834578 -67.951604) (xy 160.83412 -67.978975) (xy 160.826301 -68.033154) (xy 160.81081 -68.085658)
			(xy 160.787967 -68.135404) (xy 160.75824 -68.181371) (xy 160.740598 -68.202302) (xy 160.740344 -68.202556)
			(xy 160.734763 -68.209646) (xy 160.728514 -68.22656) (xy 160.728152 -68.235576) (xy 160.728152 -68.302632)
			(xy 160.728482 -68.311652) (xy 160.734747 -68.328569) (xy 160.740344 -68.335652) (xy 160.740598 -68.335652)
			(xy 160.740598 -68.335906) (xy 160.758253 -68.356825) (xy 160.787963 -68.402802) (xy 160.810795 -68.452552)
			(xy 160.826283 -68.505056) (xy 160.834106 -68.559234) (xy 160.834578 -68.586604) (xy 160.834148 -68.613858)
			(xy 160.82639 -68.667812) (xy 160.811032 -68.720112) (xy 160.794399 -68.75653) (xy 164.270436 -68.75653)
			(xy 164.270911 -68.72916) (xy 164.278725 -68.674981) (xy 164.294212 -68.622478) (xy 164.317052 -68.572731)
			(xy 164.346775 -68.526764) (xy 164.364416 -68.505832) (xy 164.36467 -68.505578) (xy 164.37028 -68.498508)
			(xy 164.376511 -68.481578) (xy 164.376862 -68.472558) (xy 164.376862 -68.405502) (xy 164.376512 -68.396484)
			(xy 164.37026 -68.379567) (xy 164.36467 -68.372482) (xy 164.364416 -68.372482) (xy 164.364416 -68.372228)
			(xy 164.346779 -68.351294) (xy 164.317066 -68.305322) (xy 164.29423 -68.255575) (xy 164.278738 -68.203075)
			(xy 164.27091 -68.148899) (xy 164.270436 -68.12153) (xy 164.270883 -68.094276) (xy 164.278637 -68.040322)
			(xy 164.293992 -67.988021) (xy 164.316634 -67.938438) (xy 164.346103 -67.892583) (xy 164.381799 -67.851389)
			(xy 164.422994 -67.815695) (xy 164.468851 -67.786227) (xy 164.518434 -67.763587) (xy 164.570736 -67.748234)
			(xy 164.62469 -67.740482) (xy 164.651944 -67.740022) (xy 164.679313 -67.740516) (xy 164.733491 -67.748326)
			(xy 164.785994 -67.763808) (xy 164.835742 -67.786644) (xy 164.88171 -67.816363) (xy 164.902642 -67.834002)
			(xy 164.902896 -67.834256) (xy 164.909975 -67.839854) (xy 164.926898 -67.846092) (xy 164.935916 -67.846448)
			(xy 165.002972 -67.846448) (xy 165.011989 -67.846089) (xy 165.028906 -67.839844) (xy 165.035992 -67.834256)
			(xy 165.035992 -67.834002) (xy 165.036246 -67.834002) (xy 165.057188 -67.816375) (xy 165.103158 -67.786661)
			(xy 165.152903 -67.763823) (xy 165.205401 -67.748329) (xy 165.259575 -67.740498) (xy 165.286944 -67.740022)
			(xy 165.313259 -67.740453) (xy 165.36539 -67.747694) (xy 165.416033 -67.76202) (xy 165.464232 -67.783159)
			(xy 165.509075 -67.810712) (xy 165.549713 -67.844157) (xy 165.567868 -67.863212) (xy 165.575398 -67.870603)
			(xy 165.594672 -67.879133) (xy 165.605206 -67.879722) (xy 165.679882 -67.879722) (xy 165.690431 -67.87919)
			(xy 165.709726 -67.870656) (xy 165.71722 -67.863212) (xy 165.735375 -67.844156) (xy 165.776005 -67.810698)
			(xy 165.820845 -67.783139) (xy 165.869046 -67.762001) (xy 165.919694 -67.747684) (xy 165.971828 -67.74046)
			(xy 165.998144 -67.740022) (xy 166.025398 -67.740437) (xy 166.07935 -67.7482) (xy 166.131647 -67.763562)
			(xy 166.181227 -67.786211) (xy 166.227078 -67.815685) (xy 166.268269 -67.851383) (xy 166.30396 -67.892581)
			(xy 166.333425 -67.938438) (xy 166.356063 -67.988022) (xy 166.371415 -68.040323) (xy 166.379168 -68.094276)
			(xy 166.379652 -68.12153) (xy 166.379215 -68.148901) (xy 166.371392 -68.203082) (xy 166.355897 -68.255586)
			(xy 166.333048 -68.305333) (xy 166.303317 -68.351298) (xy 166.285672 -68.372228) (xy 166.285418 -68.372482)
			(xy 166.279835 -68.379571) (xy 166.273586 -68.396486) (xy 166.273226 -68.405502) (xy 166.273226 -68.472558)
			(xy 166.273598 -68.481574) (xy 166.279834 -68.498491) (xy 166.285418 -68.505578) (xy 166.285672 -68.505578)
			(xy 166.285672 -68.505832) (xy 166.303288 -68.526782) (xy 166.333005 -68.57275) (xy 166.355845 -68.622493)
			(xy 166.371342 -68.674989) (xy 166.379175 -68.729162) (xy 166.379652 -68.75653) (xy 166.37915 -68.78378)
			(xy 166.371391 -68.837725) (xy 166.356034 -68.890017) (xy 166.333393 -68.939591) (xy 166.303927 -68.985439)
			(xy 166.268238 -69.026628) (xy 166.22705 -69.062319) (xy 166.181203 -69.091786) (xy 166.13163 -69.114429)
			(xy 166.079339 -69.129788) (xy 166.025394 -69.137549) (xy 165.998144 -69.138038) (xy 165.971828 -69.137628)
			(xy 165.919696 -69.130384) (xy 165.869051 -69.116055) (xy 165.820852 -69.094912) (xy 165.77601 -69.067355)
			(xy 165.735374 -69.033905) (xy 165.71722 -69.014848) (xy 165.709686 -69.00746) (xy 165.690416 -68.998926)
			(xy 165.679882 -68.998338) (xy 165.605206 -68.998338) (xy 165.594653 -68.998846) (xy 165.575358 -69.007395)
			(xy 165.567868 -69.014848) (xy 165.54973 -69.033921) (xy 165.509096 -69.067375) (xy 165.464251 -69.09493)
			(xy 165.416047 -69.116065) (xy 165.365397 -69.130379) (xy 165.313261 -69.137601) (xy 165.286944 -69.138038)
			(xy 165.259574 -69.137561) (xy 165.205395 -69.129748) (xy 165.152891 -69.114263) (xy 165.103144 -69.091423)
			(xy 165.057177 -69.061699) (xy 165.036246 -69.044058) (xy 165.035992 -69.043804) (xy 165.028912 -69.038208)
			(xy 165.01199 -69.031967) (xy 165.002972 -69.031612) (xy 164.935916 -69.031612) (xy 164.9269 -69.031974)
			(xy 164.909982 -69.038218) (xy 164.902896 -69.043804) (xy 164.902896 -69.044058) (xy 164.902642 -69.044058)
			(xy 164.8817 -69.061684) (xy 164.83573 -69.0914) (xy 164.785985 -69.114239) (xy 164.733487 -69.129733)
			(xy 164.679313 -69.137563) (xy 164.651944 -69.138038) (xy 164.624694 -69.137504) (xy 164.570747 -69.129754)
			(xy 164.518452 -69.114405) (xy 164.468874 -69.09177) (xy 164.423022 -69.062309) (xy 164.38183 -69.026623)
			(xy 164.346135 -68.985437) (xy 164.316666 -68.939591) (xy 164.294021 -68.890017) (xy 164.278662 -68.837726)
			(xy 164.270901 -68.78378) (xy 164.270436 -68.75653) (xy 160.794399 -68.75653) (xy 160.788387 -68.769694)
			(xy 160.758916 -68.815549) (xy 160.723218 -68.856742) (xy 160.682022 -68.892436) (xy 160.636165 -68.921903)
			(xy 160.58658 -68.944544) (xy 160.534279 -68.959897) (xy 160.480324 -68.967651) (xy 160.45307 -68.968112)
			(xy 160.425699 -68.967661) (xy 160.37152 -68.959839) (xy 160.319017 -68.944346) (xy 160.26927 -68.921501)
			(xy 160.223304 -68.891774) (xy 160.202372 -68.874132) (xy 160.202118 -68.873878) (xy 160.195032 -68.86829)
			(xy 160.178115 -68.862045) (xy 160.169098 -68.861686) (xy 160.102042 -68.861686) (xy 160.093028 -68.862066)
			(xy 160.076111 -68.868298) (xy 160.069022 -68.873878) (xy 160.069022 -68.874132) (xy 160.068768 -68.874132)
			(xy 160.047825 -68.891758) (xy 160.001855 -68.92147) (xy 159.95211 -68.944308) (xy 159.899612 -68.959803)
			(xy 159.845438 -68.967635) (xy 159.81807 -68.968112) (xy 159.791756 -68.967661) (xy 159.739626 -68.960422)
			(xy 159.688984 -68.9461) (xy 159.640785 -68.924964) (xy 159.595942 -68.897415) (xy 159.555302 -68.863974)
			(xy 159.537146 -68.844922) (xy 159.529643 -68.837498) (xy 159.510349 -68.828986) (xy 159.499808 -68.828412)
			(xy 159.425132 -68.828412) (xy 159.414582 -68.828941) (xy 159.395287 -68.837476) (xy 159.387794 -68.844922)
			(xy 159.369639 -68.863978) (xy 159.329008 -68.897434) (xy 159.284168 -68.924992) (xy 159.235967 -68.946131)
			(xy 159.18532 -68.960448) (xy 159.133186 -68.967673) (xy 159.10687 -68.968112) (xy 159.079618 -68.96765)
			(xy 159.02567 -68.95989) (xy 158.973375 -68.944531) (xy 158.923798 -68.921887) (xy 158.877948 -68.892418)
			(xy 158.836758 -68.856724) (xy 158.801067 -68.815531) (xy 158.771601 -68.769679) (xy 158.74896 -68.720101)
			(xy 158.733605 -68.667805) (xy 158.725848 -68.613856) (xy 158.725362 -68.586604) (xy 154.959304 -68.586604)
			(xy 154.959304 -71.555864) (xy 161.29457 -71.555864) (xy 161.298641 -71.500242) (xy 161.310767 -71.445805)
			(xy 161.33069 -71.393714) (xy 161.357986 -71.345079) (xy 161.392072 -71.300936) (xy 161.432221 -71.262227)
			(xy 161.477579 -71.229776) (xy 161.527179 -71.204275) (xy 161.579963 -71.186268) (xy 161.634806 -71.176138)
			(xy 161.69054 -71.174101) (xy 161.745977 -71.180201) (xy 161.799934 -71.194307) (xy 161.851263 -71.216119)
			(xy 161.898869 -71.245173) (xy 161.941737 -71.280848) (xy 161.978954 -71.322385) (xy 162.009727 -71.368898)
			(xy 162.033399 -71.419395) (xy 162.049467 -71.472802) (xy 162.057587 -71.527978) (xy 162.058096 -71.555864)
			(xy 162.057587 -71.58375) (xy 162.051748 -71.623428) (xy 162.803584 -71.623428) (xy 162.807655 -71.567806)
			(xy 162.819781 -71.513369) (xy 162.839704 -71.461278) (xy 162.867 -71.412643) (xy 162.901086 -71.3685)
			(xy 162.941235 -71.329791) (xy 162.986593 -71.29734) (xy 163.036193 -71.271839) (xy 163.088977 -71.253832)
			(xy 163.14382 -71.243702) (xy 163.199554 -71.241665) (xy 163.254991 -71.247765) (xy 163.308948 -71.261871)
			(xy 163.360277 -71.283683) (xy 163.407883 -71.312737) (xy 163.450751 -71.348412) (xy 163.487968 -71.389949)
			(xy 163.518741 -71.436462) (xy 163.542413 -71.486959) (xy 163.558481 -71.540366) (xy 163.566601 -71.595542)
			(xy 163.56711 -71.623428) (xy 163.566601 -71.651314) (xy 163.558481 -71.70649) (xy 163.542413 -71.759897)
			(xy 163.518741 -71.810394) (xy 163.487968 -71.856907) (xy 163.450751 -71.898444) (xy 163.407883 -71.934119)
			(xy 163.360277 -71.963173) (xy 163.308948 -71.984985) (xy 163.254991 -71.999091) (xy 163.199554 -72.005191)
			(xy 163.14382 -72.003154) (xy 163.088977 -71.993024) (xy 163.036193 -71.975017) (xy 162.986593 -71.949516)
			(xy 162.941235 -71.917065) (xy 162.901086 -71.878356) (xy 162.867 -71.834213) (xy 162.839704 -71.785578)
			(xy 162.819781 -71.733487) (xy 162.807655 -71.67905) (xy 162.803584 -71.623428) (xy 162.051748 -71.623428)
			(xy 162.049467 -71.638926) (xy 162.033399 -71.692333) (xy 162.009727 -71.74283) (xy 161.978954 -71.789343)
			(xy 161.941737 -71.83088) (xy 161.898869 -71.866555) (xy 161.851263 -71.895609) (xy 161.799934 -71.917421)
			(xy 161.745977 -71.931527) (xy 161.69054 -71.937627) (xy 161.634806 -71.93559) (xy 161.579963 -71.92546)
			(xy 161.527179 -71.907453) (xy 161.477579 -71.881952) (xy 161.432221 -71.849501) (xy 161.392072 -71.810792)
			(xy 161.357986 -71.766649) (xy 161.33069 -71.718014) (xy 161.310767 -71.665923) (xy 161.298641 -71.611486)
			(xy 161.29457 -71.555864) (xy 154.959304 -71.555864) (xy 154.959304 -75.712066) (xy 154.958776 -75.73809)
			(xy 154.950608 -75.789493) (xy 154.934514 -75.83899) (xy 154.910889 -75.885367) (xy 154.880312 -75.927487)
			(xy 154.862276 -75.946254) (xy 150.587964 -80.220312) (xy 150.58381 -80.224749) (xy 150.577521 -80.235147)
			(xy 150.575518 -80.240886) (xy 150.574452 -80.244605) (xy 150.573306 -80.252257) (xy 150.573232 -80.256126)
			(xy 150.573232 -85.9663) (xy 150.572586 -85.995169) (xy 150.562557 -86.052032) (xy 150.542852 -86.106305)
			(xy 150.514065 -86.156357) (xy 150.496016 -86.178898) (xy 150.495 -86.188804) (xy 150.495 -86.847172)
			(xy 150.494564 -86.857236) (xy 150.486831 -86.875822) (xy 150.480014 -86.88324) (xy 144.776444 -92.58681)
			(xy 144.773738 -92.589661) (xy 144.769146 -92.59604) (xy 144.7673 -92.59951) (xy 144.764713 -92.604936)
			(xy 144.761882 -92.616616) (xy 144.761712 -92.622624) (xy 144.761712 -94.779338) (xy 144.76159 -94.784292)
			(xy 144.759665 -94.79401) (xy 144.757902 -94.798642) (xy 144.750536 -94.816168) (xy 144.747234 -94.829884)
			(xy 144.74698 -94.834964) (xy 144.74698 -95.17507) (xy 145.281648 -95.17507) (xy 145.285719 -95.119448)
			(xy 145.297845 -95.065011) (xy 145.317768 -95.01292) (xy 145.345064 -94.964285) (xy 145.37915 -94.920142)
			(xy 145.419299 -94.881433) (xy 145.464657 -94.848982) (xy 145.514257 -94.823481) (xy 145.567041 -94.805474)
			(xy 145.621884 -94.795344) (xy 145.677618 -94.793307) (xy 145.733055 -94.799407) (xy 145.787012 -94.813513)
			(xy 145.838341 -94.835325) (xy 145.885947 -94.864379) (xy 145.928815 -94.900054) (xy 145.966032 -94.941591)
			(xy 145.996805 -94.988104) (xy 146.020477 -95.038601) (xy 146.036545 -95.092008) (xy 146.044665 -95.147184)
			(xy 146.045174 -95.17507) (xy 146.044665 -95.202956) (xy 146.036545 -95.258132) (xy 146.035536 -95.261486)
			(xy 163.375394 -95.261486) (xy 163.375394 -95.168314) (xy 163.383515 -95.075496) (xy 163.399694 -94.983738)
			(xy 163.423808 -94.893741) (xy 163.455675 -94.806187) (xy 163.495052 -94.721744) (xy 163.541638 -94.641054)
			(xy 163.595079 -94.564731) (xy 163.654969 -94.493357) (xy 163.720852 -94.427473) (xy 163.792226 -94.367583)
			(xy 163.868549 -94.314141) (xy 163.949238 -94.267554) (xy 164.033681 -94.228178) (xy 164.121235 -94.19631)
			(xy 164.211233 -94.172195) (xy 164.30299 -94.156015) (xy 164.395808 -94.147894) (xy 164.442394 -94.147386)
			(xy 164.442648 -94.147386) (xy 164.489237 -94.1478) (xy 164.582061 -94.155925) (xy 164.673824 -94.172109)
			(xy 164.763826 -94.196229) (xy 164.851385 -94.228101) (xy 164.935832 -94.267483) (xy 165.016526 -94.314074)
			(xy 165.092852 -94.367522) (xy 165.164229 -94.427418) (xy 165.230115 -94.493306) (xy 165.290008 -94.564687)
			(xy 165.343451 -94.641015) (xy 165.390039 -94.721711) (xy 165.429417 -94.80616) (xy 165.461286 -94.893719)
			(xy 165.485401 -94.983723) (xy 165.501581 -95.075487) (xy 165.509702 -95.168311) (xy 165.509702 -95.261489)
			(xy 165.501581 -95.354313) (xy 165.485401 -95.446077) (xy 165.461286 -95.536081) (xy 165.429417 -95.62364)
			(xy 165.390039 -95.708089) (xy 165.343451 -95.788785) (xy 165.290008 -95.865113) (xy 165.230115 -95.936494)
			(xy 165.164229 -96.002382) (xy 165.092852 -96.062278) (xy 165.016526 -96.115726) (xy 164.935832 -96.162317)
			(xy 164.851385 -96.201699) (xy 164.763826 -96.233571) (xy 164.673824 -96.257691) (xy 164.582061 -96.273875)
			(xy 164.489237 -96.282) (xy 164.442648 -96.28251) (xy 164.442394 -96.28251) (xy 164.395808 -96.281906)
			(xy 164.30299 -96.273785) (xy 164.211233 -96.257605) (xy 164.121235 -96.23349) (xy 164.033681 -96.201622)
			(xy 163.949238 -96.162246) (xy 163.868549 -96.115659) (xy 163.792226 -96.062217) (xy 163.720852 -96.002327)
			(xy 163.654969 -95.936443) (xy 163.595079 -95.865069) (xy 163.541638 -95.788746) (xy 163.495052 -95.708056)
			(xy 163.455675 -95.623613) (xy 163.423808 -95.536059) (xy 163.399694 -95.446062) (xy 163.383515 -95.354304)
			(xy 163.375394 -95.261486) (xy 146.035536 -95.261486) (xy 146.020477 -95.311539) (xy 145.996805 -95.362036)
			(xy 145.966032 -95.408549) (xy 145.928815 -95.450086) (xy 145.885947 -95.485761) (xy 145.838341 -95.514815)
			(xy 145.787012 -95.536627) (xy 145.733055 -95.550733) (xy 145.677618 -95.556833) (xy 145.621884 -95.554796)
			(xy 145.567041 -95.544666) (xy 145.514257 -95.526659) (xy 145.464657 -95.501158) (xy 145.419299 -95.468707)
			(xy 145.37915 -95.429998) (xy 145.345064 -95.385855) (xy 145.317768 -95.33722) (xy 145.297845 -95.285129)
			(xy 145.285719 -95.230692) (xy 145.281648 -95.17507) (xy 144.74698 -95.17507) (xy 144.74698 -95.6437)
			(xy 144.747488 -95.653352) (xy 144.75079 -95.660972) (xy 144.752553 -95.664838) (xy 144.757153 -95.671982)
			(xy 144.759934 -95.675196) (xy 144.78127 -95.698564) (xy 144.783775 -95.701127) (xy 144.789384 -95.705591)
			(xy 144.792446 -95.707454) (xy 144.802352 -95.712788) (xy 144.810734 -95.713804) (xy 144.811242 -95.713804)
			(xy 144.81302 -95.714058) (xy 144.827887 -95.716149) (xy 144.857259 -95.722376) (xy 144.871694 -95.726504)
			(xy 144.882883 -95.729848) (xy 144.904869 -95.73773) (xy 144.915636 -95.742252) (xy 144.940174 -95.753345)
			(xy 144.986126 -95.781422) (xy 145.027673 -95.815683) (xy 145.063988 -95.855446) (xy 145.09435 -95.899921)
			(xy 145.118155 -95.948225) (xy 145.134931 -95.999396) (xy 145.144343 -96.052418) (xy 145.14576 -96.07931)
			(xy 145.14576 -96.082866) (xy 145.14595 -96.11072) (xy 145.139428 -96.1644) (xy 153.32532 -96.1644)
			(xy 153.329391 -96.108778) (xy 153.341517 -96.054341) (xy 153.36144 -96.00225) (xy 153.388736 -95.953615)
			(xy 153.422822 -95.909472) (xy 153.462971 -95.870763) (xy 153.508329 -95.838312) (xy 153.557929 -95.812811)
			(xy 153.610713 -95.794804) (xy 153.665556 -95.784674) (xy 153.72129 -95.782637) (xy 153.776727 -95.788737)
			(xy 153.830684 -95.802843) (xy 153.882013 -95.824655) (xy 153.929619 -95.853709) (xy 153.972487 -95.889384)
			(xy 154.009704 -95.930921) (xy 154.040477 -95.977434) (xy 154.064149 -96.027931) (xy 154.080217 -96.081338)
			(xy 154.088337 -96.136514) (xy 154.088846 -96.1644) (xy 154.088337 -96.192286) (xy 154.080217 -96.247462)
			(xy 154.064149 -96.300869) (xy 154.040477 -96.351366) (xy 154.009704 -96.397879) (xy 153.972487 -96.439416)
			(xy 153.929619 -96.475091) (xy 153.882013 -96.504145) (xy 153.830684 -96.525957) (xy 153.776727 -96.540063)
			(xy 153.72129 -96.546163) (xy 153.665556 -96.544126) (xy 153.610713 -96.533996) (xy 153.557929 -96.515989)
			(xy 153.508329 -96.490488) (xy 153.462971 -96.458037) (xy 153.422822 -96.419328) (xy 153.388736 -96.375185)
			(xy 153.36144 -96.32655) (xy 153.341517 -96.274459) (xy 153.329391 -96.220022) (xy 153.32532 -96.1644)
			(xy 145.139428 -96.1644) (xy 145.139232 -96.166012) (xy 145.124546 -96.21974) (xy 145.102204 -96.270762)
			(xy 145.072682 -96.317994) (xy 145.036607 -96.360432) (xy 144.994746 -96.397174) (xy 144.947987 -96.42744)
			(xy 144.897324 -96.450586) (xy 144.843835 -96.46612) (xy 144.816322 -96.47047) (xy 144.814798 -96.470724)
			(xy 144.811242 -96.471232) (xy 144.80159 -96.47428) (xy 144.801082 -96.474534) (xy 144.788636 -96.480376)
			(xy 144.781016 -96.486472) (xy 144.768824 -96.499934) (xy 144.760696 -96.508824) (xy 144.757585 -96.512396)
			(xy 144.752593 -96.520446) (xy 144.75079 -96.524826) (xy 144.74698 -96.534478) (xy 144.74698 -97.1804)
			(xy 153.32532 -97.1804) (xy 153.329391 -97.124778) (xy 153.341517 -97.070341) (xy 153.36144 -97.01825)
			(xy 153.388736 -96.969615) (xy 153.422822 -96.925472) (xy 153.462971 -96.886763) (xy 153.508329 -96.854312)
			(xy 153.557929 -96.828811) (xy 153.610713 -96.810804) (xy 153.665556 -96.800674) (xy 153.72129 -96.798637)
			(xy 153.776727 -96.804737) (xy 153.830684 -96.818843) (xy 153.882013 -96.840655) (xy 153.929619 -96.869709)
			(xy 153.972487 -96.905384) (xy 154.009704 -96.946921) (xy 154.040477 -96.993434) (xy 154.064149 -97.043931)
			(xy 154.067686 -97.055686) (xy 167.705276 -97.055686) (xy 167.709347 -97.000064) (xy 167.721473 -96.945627)
			(xy 167.741396 -96.893536) (xy 167.768692 -96.844901) (xy 167.802778 -96.800758) (xy 167.842927 -96.762049)
			(xy 167.888285 -96.729598) (xy 167.937885 -96.704097) (xy 167.990669 -96.68609) (xy 168.045512 -96.67596)
			(xy 168.101246 -96.673923) (xy 168.156683 -96.680023) (xy 168.21064 -96.694129) (xy 168.261969 -96.715941)
			(xy 168.309575 -96.744995) (xy 168.352443 -96.78067) (xy 168.38966 -96.822207) (xy 168.420433 -96.86872)
			(xy 168.444105 -96.919217) (xy 168.460173 -96.972624) (xy 168.468293 -97.0278) (xy 168.468802 -97.055686)
			(xy 168.468293 -97.083572) (xy 168.460173 -97.138748) (xy 168.444105 -97.192155) (xy 168.420433 -97.242652)
			(xy 168.38966 -97.289165) (xy 168.352443 -97.330702) (xy 168.309575 -97.366377) (xy 168.261969 -97.395431)
			(xy 168.21064 -97.417243) (xy 168.156683 -97.431349) (xy 168.101246 -97.437449) (xy 168.045512 -97.435412)
			(xy 167.990669 -97.425282) (xy 167.937885 -97.407275) (xy 167.888285 -97.381774) (xy 167.842927 -97.349323)
			(xy 167.802778 -97.310614) (xy 167.768692 -97.266471) (xy 167.741396 -97.217836) (xy 167.721473 -97.165745)
			(xy 167.709347 -97.111308) (xy 167.705276 -97.055686) (xy 154.067686 -97.055686) (xy 154.080217 -97.097338)
			(xy 154.088337 -97.152514) (xy 154.088846 -97.1804) (xy 154.088337 -97.208286) (xy 154.080217 -97.263462)
			(xy 154.064149 -97.316869) (xy 154.040477 -97.367366) (xy 154.009704 -97.413879) (xy 153.972487 -97.455416)
			(xy 153.929619 -97.491091) (xy 153.882013 -97.520145) (xy 153.830684 -97.541957) (xy 153.776727 -97.556063)
			(xy 153.72129 -97.562163) (xy 153.665556 -97.560126) (xy 153.610713 -97.549996) (xy 153.557929 -97.531989)
			(xy 153.508329 -97.506488) (xy 153.462971 -97.474037) (xy 153.422822 -97.435328) (xy 153.388736 -97.391185)
			(xy 153.36144 -97.34255) (xy 153.341517 -97.290459) (xy 153.329391 -97.236022) (xy 153.32532 -97.1804)
			(xy 144.74698 -97.1804) (xy 144.74698 -100.177854) (xy 153.409904 -100.177854) (xy 153.409904 -99.314254)
			(xy 153.410394 -99.28427) (xy 153.418222 -99.224814) (xy 153.433743 -99.166889) (xy 153.456692 -99.111485)
			(xy 153.486676 -99.059551) (xy 153.523182 -99.011975) (xy 153.565587 -98.96957) (xy 153.613163 -98.933064)
			(xy 153.665097 -98.90308) (xy 153.720501 -98.880131) (xy 153.778426 -98.86461) (xy 153.837882 -98.856782)
			(xy 153.89785 -98.856782) (xy 153.957306 -98.86461) (xy 154.015231 -98.880131) (xy 154.070635 -98.90308)
			(xy 154.122569 -98.933064) (xy 154.170145 -98.96957) (xy 154.21255 -99.011975) (xy 154.249056 -99.059551)
			(xy 154.27904 -99.111485) (xy 154.301989 -99.166889) (xy 154.31751 -99.224814) (xy 154.325338 -99.28427)
			(xy 154.325828 -99.314254) (xy 154.325828 -100.177854) (xy 154.325338 -100.207838) (xy 154.31751 -100.267294)
			(xy 154.301989 -100.325219) (xy 154.27904 -100.380623) (xy 154.249056 -100.432557) (xy 154.21255 -100.480133)
			(xy 154.170145 -100.522538) (xy 154.122569 -100.559044) (xy 154.070635 -100.589028) (xy 154.015231 -100.611977)
			(xy 153.957306 -100.627498) (xy 153.89785 -100.635326) (xy 153.837882 -100.635326) (xy 153.778426 -100.627498)
			(xy 153.720501 -100.611977) (xy 153.665097 -100.589028) (xy 153.613163 -100.559044) (xy 153.565587 -100.522538)
			(xy 153.523182 -100.480133) (xy 153.486676 -100.432557) (xy 153.456692 -100.380623) (xy 153.433743 -100.325219)
			(xy 153.418222 -100.267294) (xy 153.410394 -100.207838) (xy 153.409904 -100.177854) (xy 144.74698 -100.177854)
			(xy 144.74698 -101.984302) (xy 151.377396 -101.984302) (xy 151.377396 -101.120702) (xy 151.377886 -101.090718)
			(xy 151.385714 -101.031262) (xy 151.401235 -100.973337) (xy 151.424184 -100.917933) (xy 151.454168 -100.865999)
			(xy 151.490674 -100.818423) (xy 151.533079 -100.776018) (xy 151.580655 -100.739512) (xy 151.632589 -100.709528)
			(xy 151.687993 -100.686579) (xy 151.745918 -100.671058) (xy 151.805374 -100.66323) (xy 151.865342 -100.66323)
			(xy 151.924798 -100.671058) (xy 151.982723 -100.686579) (xy 152.038127 -100.709528) (xy 152.090061 -100.739512)
			(xy 152.137637 -100.776018) (xy 152.180042 -100.818423) (xy 152.216548 -100.865999) (xy 152.246532 -100.917933)
			(xy 152.269481 -100.973337) (xy 152.285002 -101.031262) (xy 152.29283 -101.090718) (xy 152.29332 -101.120702)
			(xy 152.29332 -101.984302) (xy 152.29283 -102.014286) (xy 152.285002 -102.073742) (xy 152.269481 -102.131667)
			(xy 152.246532 -102.187071) (xy 152.216548 -102.239005) (xy 152.180042 -102.286581) (xy 152.137637 -102.328986)
			(xy 152.090061 -102.365492) (xy 152.038127 -102.395476) (xy 151.982723 -102.418425) (xy 151.924798 -102.433946)
			(xy 151.865342 -102.441774) (xy 151.805374 -102.441774) (xy 151.745918 -102.433946) (xy 151.687993 -102.418425)
			(xy 151.632589 -102.395476) (xy 151.580655 -102.365492) (xy 151.533079 -102.328986) (xy 151.490674 -102.286581)
			(xy 151.454168 -102.239005) (xy 151.424184 -102.187071) (xy 151.401235 -102.131667) (xy 151.385714 -102.073742)
			(xy 151.377886 -102.014286) (xy 151.377396 -101.984302) (xy 144.74698 -101.984302) (xy 144.74698 -103.777796)
			(xy 153.409904 -103.777796) (xy 153.409904 -102.914196) (xy 153.410394 -102.884212) (xy 153.418222 -102.824756)
			(xy 153.433743 -102.766831) (xy 153.456692 -102.711427) (xy 153.486676 -102.659493) (xy 153.523182 -102.611917)
			(xy 153.565587 -102.569512) (xy 153.613163 -102.533006) (xy 153.665097 -102.503022) (xy 153.720501 -102.480073)
			(xy 153.778426 -102.464552) (xy 153.837882 -102.456724) (xy 153.89785 -102.456724) (xy 153.957306 -102.464552)
			(xy 154.015231 -102.480073) (xy 154.070635 -102.503022) (xy 154.122569 -102.533006) (xy 154.170145 -102.569512)
			(xy 154.21255 -102.611917) (xy 154.249056 -102.659493) (xy 154.27904 -102.711427) (xy 154.301989 -102.766831)
			(xy 154.31751 -102.824756) (xy 154.325338 -102.884212) (xy 154.325828 -102.914196) (xy 154.325828 -103.777796)
			(xy 154.325338 -103.80778) (xy 154.31751 -103.867236) (xy 154.301989 -103.925161) (xy 154.27904 -103.980565)
			(xy 154.249056 -104.032499) (xy 154.21255 -104.080075) (xy 154.170145 -104.12248) (xy 154.122569 -104.158986)
			(xy 154.070635 -104.18897) (xy 154.015231 -104.211919) (xy 153.957306 -104.22744) (xy 153.89785 -104.235268)
			(xy 153.837882 -104.235268) (xy 153.778426 -104.22744) (xy 153.720501 -104.211919) (xy 153.665097 -104.18897)
			(xy 153.613163 -104.158986) (xy 153.565587 -104.12248) (xy 153.523182 -104.080075) (xy 153.486676 -104.032499)
			(xy 153.456692 -103.980565) (xy 153.433743 -103.925161) (xy 153.418222 -103.867236) (xy 153.410394 -103.80778)
			(xy 153.409904 -103.777796) (xy 144.74698 -103.777796) (xy 144.74698 -105.584498) (xy 150.767796 -105.584498)
			(xy 150.767796 -104.720898) (xy 150.768286 -104.690914) (xy 150.776114 -104.631458) (xy 150.791635 -104.573533)
			(xy 150.814584 -104.518129) (xy 150.844568 -104.466195) (xy 150.881074 -104.418619) (xy 150.923479 -104.376214)
			(xy 150.971055 -104.339708) (xy 151.022989 -104.309724) (xy 151.078393 -104.286775) (xy 151.136318 -104.271254)
			(xy 151.195774 -104.263426) (xy 151.255742 -104.263426) (xy 151.315198 -104.271254) (xy 151.373123 -104.286775)
			(xy 151.428527 -104.309724) (xy 151.480461 -104.339708) (xy 151.528037 -104.376214) (xy 151.570442 -104.418619)
			(xy 151.606948 -104.466195) (xy 151.636932 -104.518129) (xy 151.659881 -104.573533) (xy 151.675402 -104.631458)
			(xy 151.68323 -104.690914) (xy 151.68372 -104.720898) (xy 151.68372 -105.584498) (xy 151.68323 -105.614482)
			(xy 151.675402 -105.673938) (xy 151.659881 -105.731863) (xy 151.636932 -105.787267) (xy 151.606948 -105.839201)
			(xy 151.570442 -105.886777) (xy 151.528037 -105.929182) (xy 151.480461 -105.965688) (xy 151.428527 -105.995672)
			(xy 151.373123 -106.018621) (xy 151.315198 -106.034142) (xy 151.255742 -106.04197) (xy 151.195774 -106.04197)
			(xy 151.136318 -106.034142) (xy 151.078393 -106.018621) (xy 151.022989 -105.995672) (xy 150.971055 -105.965688)
			(xy 150.923479 -105.929182) (xy 150.881074 -105.886777) (xy 150.844568 -105.839201) (xy 150.814584 -105.787267)
			(xy 150.791635 -105.731863) (xy 150.776114 -105.673938) (xy 150.768286 -105.614482) (xy 150.767796 -105.584498)
			(xy 144.74698 -105.584498) (xy 144.74698 -108.4453) (xy 144.747996 -108.454698) (xy 144.747996 -108.455206)
			(xy 144.749703 -108.462364) (xy 144.75654 -108.475386) (xy 144.761458 -108.48086) (xy 146.307556 -110.026958)
			(xy 146.313234 -110.032154) (xy 146.326938 -110.039141) (xy 146.33448 -110.040674) (xy 146.334988 -110.040674)
			(xy 146.343116 -110.041436) (xy 149.570186 -110.041436) (xy 149.575498 -110.041249) (xy 149.585872 -110.038951)
			(xy 149.59076 -110.036864) (xy 149.681692 -109.9439) (xy 149.721201 -109.90459) (xy 149.80751 -109.834068)
			(xy 149.853904 -109.803184) (xy 149.893474 -109.7783) (xy 149.976414 -109.735175) (xy 150.019512 -109.717078)
			(xy 150.747984 -109.42066) (xy 150.756027 -109.41699) (xy 150.769151 -109.405164) (xy 150.773638 -109.397546)
			(xy 150.775924 -109.39272) (xy 150.788624 -109.365542) (xy 150.792315 -109.356584) (xy 150.793363 -109.337253)
			(xy 150.790656 -109.32795) (xy 150.78964 -109.32414) (xy 150.789386 -109.323632) (xy 150.788624 -109.321346)
			(xy 150.788624 -109.32033) (xy 150.788116 -109.318806) (xy 150.786592 -109.314234) (xy 150.786338 -109.313218)
			(xy 150.78329 -109.302042) (xy 150.78329 -109.301788) (xy 150.782274 -109.298486) (xy 150.782274 -109.298232)
			(xy 150.781258 -109.294422) (xy 150.781258 -109.293914) (xy 150.781004 -109.293406) (xy 150.781004 -109.293152)
			(xy 150.77948 -109.287056) (xy 150.777956 -109.280198) (xy 150.777956 -109.279944) (xy 150.77694 -109.27588)
			(xy 150.77694 -109.275118) (xy 150.775924 -109.270292) (xy 150.772368 -109.248702) (xy 150.768812 -109.213904)
			(xy 150.767796 -109.18444) (xy 150.767796 -108.32084) (xy 150.768286 -108.290856) (xy 150.776114 -108.2314)
			(xy 150.791635 -108.173475) (xy 150.814584 -108.118071) (xy 150.844568 -108.066137) (xy 150.881074 -108.018561)
			(xy 150.923479 -107.976156) (xy 150.971055 -107.93965) (xy 151.022989 -107.909666) (xy 151.078393 -107.886717)
			(xy 151.136318 -107.871196) (xy 151.195774 -107.863368) (xy 151.255742 -107.863368) (xy 151.315198 -107.871196)
			(xy 151.373123 -107.886717) (xy 151.428527 -107.909666) (xy 151.480461 -107.93965) (xy 151.528037 -107.976156)
			(xy 151.570442 -108.018561) (xy 151.606948 -108.066137) (xy 151.636932 -108.118071) (xy 151.659881 -108.173475)
			(xy 151.675402 -108.2314) (xy 151.68323 -108.290856) (xy 151.68372 -108.32084) (xy 151.68372 -108.820204)
			(xy 151.684432 -108.829409) (xy 151.691566 -108.846422) (xy 151.704282 -108.859788) (xy 151.712422 -108.864146)
			(xy 151.7396 -108.864146) (xy 151.747728 -108.863384) (xy 151.748236 -108.863384) (xy 151.755754 -108.861782)
			(xy 151.76944 -108.854803) (xy 151.77516 -108.849668) (xy 151.893524 -108.731304) (xy 151.928258 -108.697324)
			(xy 152.003324 -108.635614) (xy 152.043384 -108.608114) (xy 153.435304 -107.677966) (xy 153.443432 -107.672378)
			(xy 153.448766 -107.664758) (xy 153.451553 -107.660629) (xy 153.455644 -107.651547) (xy 153.456894 -107.646724)
			(xy 153.458672 -107.63885) (xy 153.458672 -107.638342) (xy 153.464006 -107.616498) (xy 153.464006 -107.604306)
			(xy 153.462482 -107.59821) (xy 153.461974 -107.595924) (xy 153.458672 -107.583478) (xy 153.456386 -107.578906)
			(xy 153.44175 -107.547456) (xy 153.421064 -107.481245) (xy 153.41058 -107.412675) (xy 153.409904 -107.377992)
			(xy 153.409904 -106.514138) (xy 153.410394 -106.484154) (xy 153.418222 -106.424698) (xy 153.433743 -106.366773)
			(xy 153.456692 -106.311369) (xy 153.486676 -106.259435) (xy 153.523182 -106.211859) (xy 153.565587 -106.169454)
			(xy 153.613163 -106.132948) (xy 153.665097 -106.102964) (xy 153.720501 -106.080015) (xy 153.778426 -106.064494)
			(xy 153.837882 -106.056666) (xy 153.89785 -106.056666) (xy 153.957306 -106.064494) (xy 154.015231 -106.080015)
			(xy 154.070635 -106.102964) (xy 154.122569 -106.132948) (xy 154.170145 -106.169454) (xy 154.21255 -106.211859)
			(xy 154.249056 -106.259435) (xy 154.27904 -106.311369) (xy 154.301989 -106.366773) (xy 154.31751 -106.424698)
			(xy 154.325338 -106.484154) (xy 154.325828 -106.514138) (xy 154.325828 -106.98988) (xy 154.326495 -106.998608)
			(xy 154.332958 -107.014864) (xy 154.344516 -107.027994) (xy 154.35199 -107.032552) (xy 154.40152 -107.032552)
			(xy 154.404822 -107.03052) (xy 154.451812 -106.999278) (xy 154.518868 -106.954828) (xy 154.5209 -106.953558)
			(xy 160.289748 -102.35819) (xy 160.312204 -102.340572) (xy 160.358843 -102.307659) (xy 160.382966 -102.292404)
			(xy 160.413446 -102.274116) (xy 160.4645 -102.246938) (xy 160.493964 -102.232206) (xy 160.502854 -102.226872)
			(xy 162.718496 -100.01123) (xy 162.725893 -100.00438) (xy 162.744491 -99.996639) (xy 162.754564 -99.996244)
			(xy 164.964364 -99.996244) (xy 164.970231 -99.996091) (xy 164.981651 -99.993393) (xy 164.98697 -99.99091)
			(xy 165.410134 -99.779328) (xy 167.330882 -98.819208) (xy 167.3352 -98.814382) (xy 167.355774 -98.78568)
			(xy 167.357806 -98.774758) (xy 167.3631 -98.748843) (xy 167.379893 -98.698686) (xy 167.403457 -98.651331)
			(xy 167.433338 -98.607687) (xy 167.468964 -98.568591) (xy 167.509652 -98.534793) (xy 167.554619 -98.506943)
			(xy 167.603004 -98.485574) (xy 167.653877 -98.471096) (xy 167.706263 -98.463788) (xy 167.73271 -98.463354)
			(xy 167.733218 -98.463354) (xy 167.767254 -98.465132) (xy 167.777922 -98.466148) (xy 167.805618 -98.469914)
			(xy 167.859573 -98.484503) (xy 167.910824 -98.506804) (xy 167.958275 -98.53634) (xy 168.000911 -98.572482)
			(xy 168.01973 -98.593148) (xy 168.023374 -98.59707) (xy 168.03195 -98.603474) (xy 168.036748 -98.605848)
			(xy 168.037764 -98.606356) (xy 169.282872 -98.606356) (xy 169.290238 -98.603308) (xy 169.297096 -98.596196)
			(xy 169.30243 -98.590862) (xy 169.320577 -98.571231) (xy 169.361409 -98.536727) (xy 169.40665 -98.508247)
			(xy 169.455416 -98.486346) (xy 169.506758 -98.471452) (xy 169.559674 -98.463853) (xy 169.586402 -98.463354)
			(xy 169.604156 -98.463497) (xy 169.63952 -98.466674) (xy 169.657014 -98.469704) (xy 169.66311 -98.470212)
			(xy 169.681427 -98.458712) (xy 169.718906 -98.437115) (xy 169.73804 -98.427032) (xy 169.780608 -98.40561)
			(xy 169.869027 -98.37005) (xy 169.960434 -98.343083) (xy 170.053995 -98.324955) (xy 170.148859 -98.31583)
			(xy 170.19651 -98.315272) (xy 170.197018 -98.315272) (xy 170.233848 -98.316034) (xy 170.234356 -98.316034)
			(xy 170.248834 -98.316796) (xy 170.251374 -98.316796) (xy 170.269662 -98.317812) (xy 170.278806 -98.310446)
			(xy 171.177966 -97.411286) (xy 171.183154 -97.405605) (xy 171.190125 -97.391898) (xy 171.191682 -97.384362)
			(xy 171.191682 -97.383854) (xy 171.192444 -97.375726) (xy 171.192444 -89.97823) (xy 171.191428 -89.968324)
			(xy 171.191428 -89.96807) (xy 171.18838 -89.953084) (xy 171.184824 -89.94521) (xy 171.177712 -89.937336)
			(xy 171.177204 -89.936828) (xy 171.17568 -89.93505) (xy 171.173902 -89.932764) (xy 169.88536 -88.644222)
			(xy 169.882507 -88.641519) (xy 169.876126 -88.636931) (xy 169.87266 -88.635078) (xy 169.867233 -88.632496)
			(xy 169.855553 -88.629672) (xy 169.849546 -88.62949) (xy 169.304716 -88.62949) (xy 169.294693 -88.629073)
			(xy 169.276173 -88.621406) (xy 169.261998 -88.607232) (xy 169.254328 -88.588713) (xy 169.253916 -88.57869)
			(xy 169.253916 -80.923384) (xy 169.254407 -80.91338) (xy 169.26207 -80.894896) (xy 169.276223 -80.880752)
			(xy 169.294711 -80.873101) (xy 169.304716 -80.872584) (xy 169.539412 -80.872584) (xy 169.551256 -80.871962)
			(xy 169.572441 -80.861361) (xy 169.580052 -80.852264) (xy 169.580052 -67.617594) (xy 169.579891 -67.611583)
			(xy 169.577079 -67.599894) (xy 169.574464 -67.59448) (xy 169.572623 -67.591007) (xy 169.568027 -67.58463)
			(xy 169.56532 -67.58178) (xy 167.792654 -65.809114) (xy 167.789801 -65.806411) (xy 167.783419 -65.801825)
			(xy 167.779954 -65.79997) (xy 167.774527 -65.797389) (xy 167.762847 -65.794567) (xy 167.75684 -65.794382)
			(xy 164.312092 -65.794382) (xy 164.306081 -65.794544) (xy 164.294394 -65.797359) (xy 164.288978 -65.79997)
			(xy 164.285503 -65.801809) (xy 164.279123 -65.806401) (xy 164.276278 -65.809114) (xy 164.206936 -65.878456)
			(xy 164.188166 -65.89649) (xy 164.14605 -65.927075) (xy 164.099674 -65.950705) (xy 164.050177 -65.966802)
			(xy 163.998772 -65.974971) (xy 163.972748 -65.975484) (xy 163.1569 -65.975484) (xy 163.130878 -65.974953)
			(xy 163.079478 -65.96678) (xy 163.029984 -65.950681) (xy 162.983612 -65.927052) (xy 162.941497 -65.896472)
			(xy 162.922712 -65.878456) (xy 162.517836 -65.47358) (xy 162.507168 -65.46723) (xy 162.501326 -65.465452)
			(xy 162.474015 -65.456424) (xy 162.422266 -65.431316) (xy 162.374872 -65.398726) (xy 162.332904 -65.359392)
			(xy 162.297316 -65.314205) (xy 162.268911 -65.26419) (xy 162.248335 -65.210478) (xy 162.236052 -65.154286)
			(xy 162.232341 -65.096887) (xy 162.234372 -65.068196) (xy 162.234626 -65.066164) (xy 162.234626 -65.065402)
			(xy 162.235896 -65.052956) (xy 162.233102 -65.041526) (xy 162.231455 -65.036453) (xy 162.226336 -65.027098)
			(xy 162.222942 -65.022984) (xy 162.178746 -64.9732) (xy 162.170618 -64.964056) (xy 162.16592 -64.959719)
			(xy 162.154864 -64.953308) (xy 162.148774 -64.951356) (xy 162.148266 -64.951102) (xy 162.140392 -64.948816)
			(xy 161.615374 -64.948816) (xy 161.611768 -64.948881) (xy 161.60463 -64.949902) (xy 161.60115 -64.950848)
			(xy 161.596578 -64.952372) (xy 161.587434 -64.956182) (xy 160.560512 -65.983104) (xy 160.54705 -65.995804)
			(xy 160.546034 -65.99682) (xy 160.527436 -66.01371) (xy 160.486101 -66.042262) (xy 160.440939 -66.064266)
			(xy 160.392979 -66.07922) (xy 160.343315 -66.086783) (xy 160.318196 -66.087244) (xy 157.017466 -66.087244)
			(xy 157.013656 -66.089276) (xy 156.985165 -66.104272) (xy 156.924402 -66.125546) (xy 156.860934 -66.13634)
			(xy 156.828744 -66.137028) (xy 156.801488 -66.136568) (xy 156.747529 -66.128816) (xy 156.695223 -66.113463)
			(xy 156.645635 -66.090822) (xy 156.599774 -66.061353) (xy 156.558574 -66.025658) (xy 156.522873 -65.984462)
			(xy 156.4934 -65.938604) (xy 156.470753 -65.889018) (xy 156.455394 -65.836714) (xy 156.447635 -65.782756)
			(xy 156.447635 -65.728244) (xy 156.455394 -65.674286) (xy 156.470753 -65.621982) (xy 156.4934 -65.572396)
			(xy 156.522873 -65.526538) (xy 156.558574 -65.485342) (xy 156.599774 -65.449647) (xy 156.645635 -65.420178)
			(xy 156.695223 -65.397537) (xy 156.747529 -65.382184) (xy 156.801488 -65.374432) (xy 156.828744 -65.374012)
			(xy 156.860936 -65.374674) (xy 156.924409 -65.385465) (xy 156.985173 -65.406749) (xy 157.013656 -65.421764)
			(xy 157.017466 -65.423796) (xy 160.1597 -65.423796) (xy 160.168844 -65.423034) (xy 160.176332 -65.421398)
			(xy 160.189898 -65.414281) (xy 160.195514 -65.409064) (xy 161.165286 -64.439038) (xy 161.222182 -64.382142)
			(xy 161.241897 -64.363288) (xy 161.286316 -64.331627) (xy 161.310574 -64.31915) (xy 161.318194 -64.31534)
			(xy 161.488374 -64.14516) (xy 161.495773 -64.138318) (xy 161.514373 -64.130602) (xy 161.524442 -64.130174)
			(xy 166.899844 -64.130174) (xy 166.907972 -64.129412) (xy 166.90848 -64.129412) (xy 166.916002 -64.127818)
			(xy 166.929702 -64.120853) (xy 166.935404 -64.115696) (xy 167.419782 -63.631318) (xy 167.424761 -63.625887)
			(xy 167.4316 -63.612846) (xy 167.433244 -63.605664) (xy 167.433244 -63.605156) (xy 167.43426 -63.595758)
			(xy 167.43426 -58.103262) (xy 167.434195 -58.099657) (xy 167.433171 -58.092519) (xy 167.432228 -58.089038)
			(xy 167.430704 -58.084466) (xy 167.426894 -58.075322) (xy 167.17518 -57.823608) (xy 167.159707 -57.807607)
			(xy 167.132871 -57.772096) (xy 167.111191 -57.733222) (xy 167.10279 -57.71261) (xy 167.101774 -57.709816)
			(xy 167.095932 -57.700418) (xy 167.095678 -57.69991) (xy 167.080273 -57.678515) (xy 167.055722 -57.631861)
			(xy 167.038863 -57.581911) (xy 167.030119 -57.529922) (xy 167.029384 -57.503568) (xy 167.029384 -56.577992)
			(xy 167.02531 -56.572854) (xy 167.015016 -56.56474) (xy 167.009064 -56.56199) (xy 166.916608 -56.528208)
			(xy 166.909234 -56.525741) (xy 166.893712 -56.524966) (xy 166.886128 -56.526684) (xy 166.878762 -56.528716)
			(xy 166.865554 -56.537098) (xy 166.860474 -56.543194) (xy 166.84222 -56.564014) (xy 166.800736 -56.600687)
			(xy 166.754395 -56.630992) (xy 166.704167 -56.654294) (xy 166.651103 -56.670107) (xy 166.596313 -56.678099)
			(xy 166.568628 -56.678576) (xy 166.541376 -56.678115) (xy 166.487427 -56.670362) (xy 166.43513 -56.655009)
			(xy 166.38555 -56.63237) (xy 166.339698 -56.602905) (xy 166.298505 -56.567215) (xy 166.262811 -56.526025)
			(xy 166.233343 -56.480174) (xy 166.210701 -56.430596) (xy 166.195344 -56.378301) (xy 166.187587 -56.324352)
			(xy 166.187587 -56.269848) (xy 166.195344 -56.215899) (xy 166.210701 -56.163604) (xy 166.233343 -56.114026)
			(xy 166.262811 -56.068175) (xy 166.298505 -56.026985) (xy 166.339698 -55.991295) (xy 166.38555 -55.96183)
			(xy 166.43513 -55.939191) (xy 166.487427 -55.923838) (xy 166.541376 -55.916085) (xy 166.568628 -55.91556)
			(xy 166.595483 -55.916019) (xy 166.648663 -55.923549) (xy 166.700263 -55.938458) (xy 166.749264 -55.960451)
			(xy 166.7947 -55.989093) (xy 166.835674 -56.02382) (xy 166.85387 -56.043576) (xy 166.854124 -56.04383)
			(xy 166.855394 -56.045354) (xy 166.855902 -56.045862) (xy 166.860728 -56.051196) (xy 166.876476 -56.06161)
			(xy 166.885718 -56.066299) (xy 166.906289 -56.068652) (xy 166.916354 -56.066182) (xy 166.972996 -56.045608)
			(xy 167.00627 -56.033416) (xy 167.013069 -56.030662) (xy 167.024807 -56.021878) (xy 167.029384 -56.016144)
			(xy 167.029384 -55.113428) (xy 167.029868 -55.08734) (xy 167.038032 -55.035807) (xy 167.054162 -54.986188)
			(xy 167.077862 -54.939705) (xy 167.108546 -54.897506) (xy 167.126666 -54.878732) (xy 169.050716 -52.954682)
			(xy 169.057066 -52.944014) (xy 169.058844 -52.938172) (xy 169.067279 -52.912592) (xy 169.090337 -52.863915)
			(xy 169.120009 -52.818964) (xy 169.155706 -52.77863) (xy 169.196719 -52.743716) (xy 169.242233 -52.714913)
			(xy 169.291344 -52.692796) (xy 169.343076 -52.677802) (xy 169.396403 -52.67023) (xy 169.450265 -52.67023)
			(xy 169.503592 -52.677802) (xy 169.555324 -52.692796) (xy 169.604435 -52.714913) (xy 169.649949 -52.743716)
			(xy 169.690962 -52.77863) (xy 169.726659 -52.818964) (xy 169.756331 -52.863915) (xy 169.779389 -52.912592)
			(xy 169.787824 -52.938172) (xy 169.789602 -52.944014) (xy 169.795952 -52.954682) (xy 170.284394 -53.443124)
			(xy 170.297603 -53.456699) (xy 170.321155 -53.486365) (xy 170.327692 -53.496552) (xy 174.233564 -53.496552)
			(xy 174.233564 -53.442048) (xy 174.24132 -53.3881) (xy 174.256675 -53.335804) (xy 174.279316 -53.286226)
			(xy 174.308782 -53.240375) (xy 174.344474 -53.199183) (xy 174.385664 -53.163491) (xy 174.431514 -53.134023)
			(xy 174.481091 -53.11138) (xy 174.533386 -53.096023) (xy 174.587334 -53.088265) (xy 174.614586 -53.087778)
			(xy 174.641957 -53.088233) (xy 174.696137 -53.096051) (xy 174.748641 -53.111541) (xy 174.798388 -53.134386)
			(xy 174.844353 -53.164114) (xy 174.865284 -53.181758) (xy 174.865538 -53.182012) (xy 174.872637 -53.18758)
			(xy 174.889544 -53.193838) (xy 174.898558 -53.194204) (xy 174.965614 -53.194204) (xy 174.974631 -53.193853)
			(xy 174.991548 -53.187601) (xy 174.998634 -53.182012) (xy 174.998634 -53.181758) (xy 174.998888 -53.181758)
			(xy 175.019808 -53.164104) (xy 175.065785 -53.134396) (xy 175.115535 -53.111563) (xy 175.168039 -53.096075)
			(xy 175.222216 -53.08825) (xy 175.249586 -53.087778) (xy 175.276839 -53.088268) (xy 175.330789 -53.096023)
			(xy 175.383087 -53.111378) (xy 175.432667 -53.134019) (xy 175.47852 -53.163485) (xy 175.519713 -53.199177)
			(xy 175.555407 -53.240369) (xy 175.584875 -53.286221) (xy 175.607517 -53.3358) (xy 175.622874 -53.388097)
			(xy 175.630631 -53.442048) (xy 175.630631 -53.496552) (xy 175.622874 -53.550503) (xy 175.607517 -53.6028)
			(xy 175.584875 -53.652379) (xy 175.555407 -53.698231) (xy 175.519713 -53.739423) (xy 175.47852 -53.775115)
			(xy 175.432667 -53.804581) (xy 175.383087 -53.827222) (xy 175.330789 -53.842577) (xy 175.276839 -53.850332)
			(xy 175.249586 -53.850794) (xy 175.222215 -53.850338) (xy 175.168036 -53.842518) (xy 175.115533 -53.827026)
			(xy 175.065786 -53.804183) (xy 175.019819 -53.774456) (xy 174.998888 -53.756814) (xy 174.998634 -53.75656)
			(xy 174.991545 -53.750977) (xy 174.97463 -53.744729) (xy 174.965614 -53.744368) (xy 174.898558 -53.744368)
			(xy 174.889545 -53.74476) (xy 174.872628 -53.750984) (xy 174.865538 -53.75656) (xy 174.865538 -53.756814)
			(xy 174.865284 -53.756814) (xy 174.844333 -53.774429) (xy 174.798365 -53.804144) (xy 174.748622 -53.826985)
			(xy 174.696126 -53.842481) (xy 174.641954 -53.850316) (xy 174.614586 -53.850794) (xy 174.587334 -53.850335)
			(xy 174.533386 -53.842577) (xy 174.481091 -53.82722) (xy 174.431514 -53.804577) (xy 174.385664 -53.775109)
			(xy 174.344474 -53.739417) (xy 174.308782 -53.698225) (xy 174.279316 -53.652374) (xy 174.256675 -53.602796)
			(xy 174.24132 -53.5505) (xy 174.233564 -53.496552) (xy 170.327692 -53.496552) (xy 170.331384 -53.502306)
			(xy 170.334432 -53.507386) (xy 170.459654 -53.632608) (xy 170.477212 -53.650822) (xy 170.506955 -53.691744)
			(xy 170.529925 -53.736817) (xy 170.545555 -53.78493) (xy 170.55346 -53.834898) (xy 170.553888 -53.860192)
			(xy 170.553888 -54.453028) (xy 170.553395 -54.463031) (xy 170.54573 -54.481511) (xy 170.531578 -54.495652)
			(xy 170.513091 -54.503303) (xy 170.503088 -54.503828) (xy 170.194986 -54.503828) (xy 170.188975 -54.503991)
			(xy 170.17729 -54.506809) (xy 170.171872 -54.509416) (xy 170.168399 -54.511257) (xy 170.162022 -54.515852)
			(xy 170.159172 -54.51856) (xy 169.870628 -54.807104) (xy 169.851857 -54.825135) (xy 169.809739 -54.855715)
			(xy 169.763363 -54.879341) (xy 169.713866 -54.895434) (xy 169.662463 -54.9036) (xy 169.63644 -54.904132)
			(xy 169.305478 -54.904132) (xy 169.3037 -54.905402) (xy 169.300906 -54.907688) (xy 169.226992 -54.981602)
			(xy 169.22623 -54.982618) (xy 169.220595 -54.989051) (xy 172.001168 -54.989051) (xy 172.001168 -54.934549)
			(xy 172.008924 -54.880602) (xy 172.024278 -54.828307) (xy 172.046919 -54.77873) (xy 172.076384 -54.732879)
			(xy 172.112074 -54.691688) (xy 172.153263 -54.655996) (xy 172.199112 -54.626528) (xy 172.248688 -54.603885)
			(xy 172.300982 -54.588528) (xy 172.354929 -54.580769) (xy 172.38218 -54.580282) (xy 172.410271 -54.580793)
			(xy 172.465847 -54.589017) (xy 172.519616 -54.605305) (xy 172.570413 -54.629305) (xy 172.61714 -54.660498)
			(xy 172.658786 -54.698208) (xy 172.694449 -54.741619) (xy 172.709332 -54.765448) (xy 172.714666 -54.774338)
			(xy 172.731684 -54.78653) (xy 172.824902 -54.80685) (xy 172.845476 -54.802532) (xy 172.854112 -54.79669)
			(xy 172.87817 -54.780681) (xy 172.930104 -54.755341) (xy 172.985264 -54.738118) (xy 173.042389 -54.729405)
			(xy 173.071282 -54.728872) (xy 173.098532 -54.729395) (xy 173.152477 -54.737148) (xy 173.20477 -54.7525)
			(xy 173.254346 -54.775138) (xy 173.300195 -54.8046) (xy 173.341385 -54.840288) (xy 173.377077 -54.881474)
			(xy 173.406544 -54.927321) (xy 173.429186 -54.976894) (xy 173.444543 -55.029186) (xy 173.452302 -55.08313)
			(xy 173.45279 -55.11038) (xy 173.452315 -55.13775) (xy 173.444499 -55.191929) (xy 173.429013 -55.244432)
			(xy 173.406173 -55.294179) (xy 173.37645 -55.340146) (xy 173.35881 -55.361078) (xy 173.358556 -55.361332)
			(xy 173.352986 -55.36843) (xy 173.346731 -55.385338) (xy 173.346364 -55.394352) (xy 173.346364 -55.461408)
			(xy 173.346725 -55.470424) (xy 173.35297 -55.487341) (xy 173.358556 -55.494428) (xy 173.35881 -55.494428)
			(xy 173.35881 -55.494682) (xy 173.37643 -55.515631) (xy 173.406152 -55.561597) (xy 173.428997 -55.611341)
			(xy 173.444493 -55.66384) (xy 173.452323 -55.718016) (xy 173.452325 -55.772754) (xy 173.444499 -55.82693)
			(xy 173.429007 -55.879431) (xy 173.406167 -55.929176) (xy 173.376448 -55.975145) (xy 173.35881 -55.996078)
			(xy 173.358556 -55.996332) (xy 173.352986 -56.00343) (xy 173.346731 -56.020338) (xy 173.346364 -56.029352)
			(xy 173.346364 -56.096408) (xy 173.346725 -56.105424) (xy 173.35297 -56.122341) (xy 173.358556 -56.129428)
			(xy 173.35881 -56.129428) (xy 173.35881 -56.129682) (xy 173.376456 -56.150609) (xy 173.406166 -56.196583)
			(xy 173.429001 -56.246332) (xy 173.44449 -56.298834) (xy 173.452317 -56.35301) (xy 173.45279 -56.38038)
			(xy 173.452304 -56.407631) (xy 173.444548 -56.461579) (xy 173.429193 -56.513874) (xy 173.406551 -56.563451)
			(xy 173.377085 -56.609301) (xy 173.341394 -56.650492) (xy 173.300203 -56.686183) (xy 173.254353 -56.715649)
			(xy 173.204776 -56.738291) (xy 173.152481 -56.753646) (xy 173.098533 -56.761402) (xy 173.044031 -56.761402)
			(xy 172.990083 -56.753646) (xy 172.937788 -56.738291) (xy 172.888211 -56.715649) (xy 172.842361 -56.686183)
			(xy 172.80117 -56.650492) (xy 172.765479 -56.609301) (xy 172.736013 -56.563451) (xy 172.713371 -56.513874)
			(xy 172.698016 -56.461579) (xy 172.69026 -56.407631) (xy 172.689774 -56.38038) (xy 172.69021 -56.353008)
			(xy 172.698033 -56.298827) (xy 172.713528 -56.246323) (xy 172.736376 -56.196577) (xy 172.766109 -56.150612)
			(xy 172.783754 -56.129682) (xy 172.784008 -56.129428) (xy 172.78959 -56.122338) (xy 172.795839 -56.105424)
			(xy 172.7962 -56.096408) (xy 172.7962 -56.029352) (xy 172.795818 -56.020338) (xy 172.789588 -56.003421)
			(xy 172.784008 -55.996332) (xy 172.783754 -55.996332) (xy 172.783754 -55.996078) (xy 172.766093 -55.975162)
			(xy 172.736367 -55.929192) (xy 172.713521 -55.879443) (xy 172.698025 -55.826938) (xy 172.690197 -55.772757)
			(xy 172.6902 -55.718013) (xy 172.698031 -55.663832) (xy 172.713531 -55.611329) (xy 172.736381 -55.561582)
			(xy 172.766111 -55.515614) (xy 172.783754 -55.494682) (xy 172.784008 -55.494428) (xy 172.78959 -55.487338)
			(xy 172.795839 -55.470424) (xy 172.7962 -55.461408) (xy 172.7962 -55.394352) (xy 172.795818 -55.385338)
			(xy 172.789588 -55.368421) (xy 172.784008 -55.361332) (xy 172.783754 -55.360824) (xy 172.772808 -55.348091)
			(xy 172.752968 -55.320999) (xy 172.74413 -55.306722) (xy 172.738796 -55.297832) (xy 172.721778 -55.28564)
			(xy 172.62856 -55.26532) (xy 172.607986 -55.269638) (xy 172.59935 -55.27548) (xy 172.575273 -55.291459)
			(xy 172.523346 -55.316807) (xy 172.468192 -55.334038) (xy 172.411071 -55.34276) (xy 172.38218 -55.343298)
			(xy 172.354929 -55.342831) (xy 172.300982 -55.335072) (xy 172.248688 -55.319715) (xy 172.199112 -55.297072)
			(xy 172.153263 -55.267604) (xy 172.112074 -55.231912) (xy 172.076384 -55.190721) (xy 172.046919 -55.14487)
			(xy 172.024278 -55.095293) (xy 172.008924 -55.042998) (xy 172.001168 -54.989051) (xy 169.220595 -54.989051)
			(xy 169.220462 -54.989203) (xy 169.21331 -55.00517) (xy 169.21226 -55.01386) (xy 169.21226 -55.420851)
			(xy 170.324768 -55.420851) (xy 170.324768 -55.366349) (xy 170.332524 -55.312402) (xy 170.347878 -55.260107)
			(xy 170.370519 -55.21053) (xy 170.399984 -55.164679) (xy 170.435674 -55.123488) (xy 170.476863 -55.087796)
			(xy 170.522712 -55.058328) (xy 170.572288 -55.035685) (xy 170.624582 -55.020328) (xy 170.678529 -55.012569)
			(xy 170.70578 -55.012082) (xy 170.732093 -55.012569) (xy 170.784221 -55.0198) (xy 170.834863 -55.034116)
			(xy 170.883062 -55.055245) (xy 170.927906 -55.082787) (xy 170.968547 -55.116222) (xy 170.986704 -55.135272)
			(xy 170.994226 -55.142673) (xy 171.013506 -55.151199) (xy 171.024042 -55.151782) (xy 171.098718 -55.151782)
			(xy 171.109265 -55.151227) (xy 171.128561 -55.142711) (xy 171.136056 -55.135272) (xy 171.154186 -55.116191)
			(xy 171.194822 -55.082737) (xy 171.239668 -55.055182) (xy 171.287873 -55.034048) (xy 171.338525 -55.019736)
			(xy 171.390662 -55.012517) (xy 171.41698 -55.012082) (xy 171.444233 -55.012564) (xy 171.498185 -55.020318)
			(xy 171.550484 -55.035672) (xy 171.600065 -55.058313) (xy 171.645919 -55.08778) (xy 171.687113 -55.123472)
			(xy 171.722808 -55.164665) (xy 171.752277 -55.210517) (xy 171.774921 -55.260098) (xy 171.790277 -55.312396)
			(xy 171.798035 -55.366347) (xy 171.798035 -55.420853) (xy 171.790277 -55.474804) (xy 171.774921 -55.527102)
			(xy 171.752277 -55.576683) (xy 171.722808 -55.622535) (xy 171.687113 -55.663728) (xy 171.645919 -55.69942)
			(xy 171.600065 -55.728887) (xy 171.550484 -55.751528) (xy 171.498185 -55.766882) (xy 171.444233 -55.774636)
			(xy 171.41698 -55.775098) (xy 171.390666 -55.774645) (xy 171.338536 -55.767407) (xy 171.287893 -55.753085)
			(xy 171.239694 -55.73195) (xy 171.194851 -55.704402) (xy 171.154212 -55.670961) (xy 171.136056 -55.651908)
			(xy 171.128552 -55.644486) (xy 171.109259 -55.635973) (xy 171.098718 -55.635398) (xy 171.024042 -55.635398)
			(xy 171.013493 -55.635937) (xy 170.994198 -55.644465) (xy 170.986704 -55.651908) (xy 170.968541 -55.670956)
			(xy 170.927913 -55.704414) (xy 170.883074 -55.731973) (xy 170.834875 -55.753113) (xy 170.784229 -55.767432)
			(xy 170.732096 -55.774658) (xy 170.70578 -55.775098) (xy 170.678529 -55.774631) (xy 170.624582 -55.766872)
			(xy 170.572288 -55.751515) (xy 170.522712 -55.728872) (xy 170.476863 -55.699404) (xy 170.435674 -55.663712)
			(xy 170.399984 -55.622521) (xy 170.370519 -55.57667) (xy 170.347878 -55.527093) (xy 170.332524 -55.474798)
			(xy 170.324768 -55.420851) (xy 169.21226 -55.420851) (xy 169.21226 -56.441594) (xy 169.213276 -56.451246)
			(xy 169.214905 -56.458489) (xy 169.221749 -56.471655) (xy 169.226738 -56.477154) (xy 169.535856 -56.786272)
			(xy 169.55389 -56.805042) (xy 169.584473 -56.847158) (xy 169.608103 -56.893534) (xy 169.624199 -56.943032)
			(xy 169.632366 -56.994436) (xy 169.632884 -57.02046) (xy 169.632884 -57.48528) (xy 172.706028 -57.48528)
			(xy 172.710099 -57.429658) (xy 172.722225 -57.375221) (xy 172.742148 -57.32313) (xy 172.769444 -57.274495)
			(xy 172.80353 -57.230352) (xy 172.843679 -57.191643) (xy 172.889037 -57.159192) (xy 172.938637 -57.133691)
			(xy 172.991421 -57.115684) (xy 173.046264 -57.105554) (xy 173.101998 -57.103517) (xy 173.157435 -57.109617)
			(xy 173.211392 -57.123723) (xy 173.262721 -57.145535) (xy 173.310327 -57.174589) (xy 173.353195 -57.210264)
			(xy 173.390412 -57.251801) (xy 173.421185 -57.298314) (xy 173.444857 -57.348811) (xy 173.460925 -57.402218)
			(xy 173.469045 -57.457394) (xy 173.469554 -57.48528) (xy 173.469045 -57.513166) (xy 173.460925 -57.568342)
			(xy 173.444857 -57.621749) (xy 173.421185 -57.672246) (xy 173.390412 -57.718759) (xy 173.353195 -57.760296)
			(xy 173.310327 -57.795971) (xy 173.262721 -57.825025) (xy 173.211392 -57.846837) (xy 173.157435 -57.860943)
			(xy 173.101998 -57.867043) (xy 173.046264 -57.865006) (xy 172.991421 -57.854876) (xy 172.938637 -57.836869)
			(xy 172.889037 -57.811368) (xy 172.843679 -57.778917) (xy 172.80353 -57.740208) (xy 172.769444 -57.696065)
			(xy 172.742148 -57.64743) (xy 172.722225 -57.595339) (xy 172.710099 -57.540902) (xy 172.706028 -57.48528)
			(xy 169.632884 -57.48528) (xy 169.632884 -58.561224) (xy 174.662336 -58.561224) (xy 174.666407 -58.505602)
			(xy 174.678533 -58.451165) (xy 174.698456 -58.399074) (xy 174.725752 -58.350439) (xy 174.759838 -58.306296)
			(xy 174.799987 -58.267587) (xy 174.845345 -58.235136) (xy 174.894945 -58.209635) (xy 174.947729 -58.191628)
			(xy 175.002572 -58.181498) (xy 175.058306 -58.179461) (xy 175.113743 -58.185561) (xy 175.1677 -58.199667)
			(xy 175.219029 -58.221479) (xy 175.266635 -58.250533) (xy 175.309503 -58.286208) (xy 175.34672 -58.327745)
			(xy 175.377493 -58.374258) (xy 175.401165 -58.424755) (xy 175.417233 -58.478162) (xy 175.425353 -58.533338)
			(xy 175.425862 -58.561224) (xy 175.425353 -58.58911) (xy 175.417233 -58.644286) (xy 175.401165 -58.697693)
			(xy 175.377493 -58.74819) (xy 175.34672 -58.794703) (xy 175.309503 -58.83624) (xy 175.266635 -58.871915)
			(xy 175.219029 -58.900969) (xy 175.1677 -58.922781) (xy 175.113743 -58.936887) (xy 175.058306 -58.942987)
			(xy 175.002572 -58.94095) (xy 174.947729 -58.93082) (xy 174.894945 -58.912813) (xy 174.845345 -58.887312)
			(xy 174.799987 -58.854861) (xy 174.759838 -58.816152) (xy 174.725752 -58.772009) (xy 174.698456 -58.723374)
			(xy 174.678533 -58.671283) (xy 174.666407 -58.616846) (xy 174.662336 -58.561224) (xy 169.632884 -58.561224)
			(xy 169.632884 -59.174634) (xy 173.1932 -59.174634) (xy 173.197271 -59.119012) (xy 173.209397 -59.064575)
			(xy 173.22932 -59.012484) (xy 173.256616 -58.963849) (xy 173.290702 -58.919706) (xy 173.330851 -58.880997)
			(xy 173.376209 -58.848546) (xy 173.425809 -58.823045) (xy 173.478593 -58.805038) (xy 173.533436 -58.794908)
			(xy 173.58917 -58.792871) (xy 173.644607 -58.798971) (xy 173.698564 -58.813077) (xy 173.749893 -58.834889)
			(xy 173.797499 -58.863943) (xy 173.840367 -58.899618) (xy 173.877584 -58.941155) (xy 173.908357 -58.987668)
			(xy 173.932029 -59.038165) (xy 173.948097 -59.091572) (xy 173.956217 -59.146748) (xy 173.956726 -59.174634)
			(xy 173.956217 -59.20252) (xy 173.948097 -59.257696) (xy 173.932029 -59.311103) (xy 173.908357 -59.3616)
			(xy 173.877584 -59.408113) (xy 173.840367 -59.44965) (xy 173.797499 -59.485325) (xy 173.749893 -59.514379)
			(xy 173.698564 -59.536191) (xy 173.644607 -59.550297) (xy 173.58917 -59.556397) (xy 173.533436 -59.55436)
			(xy 173.478593 -59.54423) (xy 173.425809 -59.526223) (xy 173.376209 -59.500722) (xy 173.330851 -59.468271)
			(xy 173.290702 -59.429562) (xy 173.256616 -59.385419) (xy 173.22932 -59.336784) (xy 173.209397 -59.284693)
			(xy 173.197271 -59.230256) (xy 173.1932 -59.174634) (xy 169.632884 -59.174634) (xy 169.632884 -60.633356)
			(xy 175.89703 -60.633356) (xy 175.901101 -60.577734) (xy 175.913227 -60.523297) (xy 175.93315 -60.471206)
			(xy 175.960446 -60.422571) (xy 175.994532 -60.378428) (xy 176.034681 -60.339719) (xy 176.080039 -60.307268)
			(xy 176.129639 -60.281767) (xy 176.182423 -60.26376) (xy 176.237266 -60.25363) (xy 176.293 -60.251593)
			(xy 176.348437 -60.257693) (xy 176.402394 -60.271799) (xy 176.453723 -60.293611) (xy 176.501329 -60.322665)
			(xy 176.544197 -60.35834) (xy 176.581414 -60.399877) (xy 176.612187 -60.44639) (xy 176.635859 -60.496887)
			(xy 176.651927 -60.550294) (xy 176.660047 -60.60547) (xy 176.660556 -60.633356) (xy 176.660047 -60.661242)
			(xy 176.651927 -60.716418) (xy 176.635859 -60.769825) (xy 176.612187 -60.820322) (xy 176.581414 -60.866835)
			(xy 176.544197 -60.908372) (xy 176.501329 -60.944047) (xy 176.453723 -60.973101) (xy 176.402394 -60.994913)
			(xy 176.348437 -61.009019) (xy 176.293 -61.015119) (xy 176.237266 -61.013082) (xy 176.182423 -61.002952)
			(xy 176.129639 -60.984945) (xy 176.080039 -60.959444) (xy 176.034681 -60.926993) (xy 175.994532 -60.888284)
			(xy 175.960446 -60.844141) (xy 175.93315 -60.795506) (xy 175.913227 -60.743415) (xy 175.901101 -60.688978)
			(xy 175.89703 -60.633356) (xy 169.632884 -60.633356) (xy 169.632884 -61.487812) (xy 174.404526 -61.487812)
			(xy 174.408597 -61.43219) (xy 174.420723 -61.377753) (xy 174.440646 -61.325662) (xy 174.467942 -61.277027)
			(xy 174.502028 -61.232884) (xy 174.542177 -61.194175) (xy 174.587535 -61.161724) (xy 174.637135 -61.136223)
			(xy 174.689919 -61.118216) (xy 174.744762 -61.108086) (xy 174.800496 -61.106049) (xy 174.855933 -61.112149)
			(xy 174.90989 -61.126255) (xy 174.961219 -61.148067) (xy 175.008825 -61.177121) (xy 175.051693 -61.212796)
			(xy 175.08891 -61.254333) (xy 175.119683 -61.300846) (xy 175.143355 -61.351343) (xy 175.159423 -61.40475)
			(xy 175.167543 -61.459926) (xy 175.168052 -61.487812) (xy 175.167543 -61.515698) (xy 175.159423 -61.570874)
			(xy 175.143355 -61.624281) (xy 175.119683 -61.674778) (xy 175.08891 -61.721291) (xy 175.051693 -61.762828)
			(xy 175.008825 -61.798503) (xy 174.961219 -61.827557) (xy 174.90989 -61.849369) (xy 174.855933 -61.863475)
			(xy 174.800496 -61.869575) (xy 174.744762 -61.867538) (xy 174.689919 -61.857408) (xy 174.637135 -61.839401)
			(xy 174.587535 -61.8139) (xy 174.542177 -61.781449) (xy 174.502028 -61.74274) (xy 174.467942 -61.698597)
			(xy 174.440646 -61.649962) (xy 174.420723 -61.597871) (xy 174.408597 -61.543434) (xy 174.404526 -61.487812)
			(xy 169.632884 -61.487812) (xy 169.632884 -62.121034) (xy 172.3423 -62.121034) (xy 172.346371 -62.065412)
			(xy 172.358497 -62.010975) (xy 172.37842 -61.958884) (xy 172.405716 -61.910249) (xy 172.439802 -61.866106)
			(xy 172.479951 -61.827397) (xy 172.525309 -61.794946) (xy 172.574909 -61.769445) (xy 172.627693 -61.751438)
			(xy 172.682536 -61.741308) (xy 172.73827 -61.739271) (xy 172.793707 -61.745371) (xy 172.847664 -61.759477)
			(xy 172.898993 -61.781289) (xy 172.946599 -61.810343) (xy 172.989467 -61.846018) (xy 173.026684 -61.887555)
			(xy 173.057457 -61.934068) (xy 173.081129 -61.984565) (xy 173.097197 -62.037972) (xy 173.105317 -62.093148)
			(xy 173.105826 -62.121034) (xy 173.105317 -62.14892) (xy 173.097197 -62.204096) (xy 173.081129 -62.257503)
			(xy 173.057457 -62.308) (xy 173.026684 -62.354513) (xy 172.989467 -62.39605) (xy 172.946599 -62.431725)
			(xy 172.898993 -62.460779) (xy 172.847664 -62.482591) (xy 172.793707 -62.496697) (xy 172.73827 -62.502797)
			(xy 172.682536 -62.50076) (xy 172.627693 -62.49063) (xy 172.574909 -62.472623) (xy 172.525309 -62.447122)
			(xy 172.479951 -62.414671) (xy 172.439802 -62.375962) (xy 172.405716 -62.331819) (xy 172.37842 -62.283184)
			(xy 172.358497 -62.231093) (xy 172.346371 -62.176656) (xy 172.3423 -62.121034) (xy 169.632884 -62.121034)
			(xy 169.632884 -62.66561) (xy 169.635443 -62.668881) (xy 169.641445 -62.674621) (xy 169.644822 -62.67704)
			(xy 169.656252 -62.684914) (xy 169.671492 -62.695582) (xy 169.672 -62.695582) (xy 169.71645 -62.725808)
			(xy 169.721137 -62.728559) (xy 169.73139 -62.732156) (xy 169.73677 -62.73292) (xy 169.748708 -62.734444)
			(xy 169.751248 -62.733682) (xy 169.756836 -62.731396) (xy 169.760646 -62.729872) (xy 169.782451 -62.721912)
			(xy 169.827504 -62.710728) (xy 169.87358 -62.705081) (xy 169.89679 -62.704726) (xy 169.906442 -62.704726)
			(xy 169.933252 -62.70584) (xy 169.98618 -62.71466) (xy 170.03735 -62.730812) (xy 170.085751 -62.753976)
			(xy 170.130426 -62.783696) (xy 170.170496 -62.819385) (xy 170.205167 -62.860337) (xy 170.233756 -62.905745)
			(xy 170.255698 -62.954712) (xy 170.27056 -63.006271) (xy 170.278048 -63.059405) (xy 170.278552 -63.086234)
			(xy 170.278064 -63.113485) (xy 170.270304 -63.167431) (xy 170.254946 -63.219724) (xy 170.232304 -63.2693)
			(xy 170.229648 -63.273432) (xy 171.67682 -63.273432) (xy 171.680891 -63.21781) (xy 171.693017 -63.163373)
			(xy 171.71294 -63.111282) (xy 171.740236 -63.062647) (xy 171.774322 -63.018504) (xy 171.814471 -62.979795)
			(xy 171.859829 -62.947344) (xy 171.909429 -62.921843) (xy 171.962213 -62.903836) (xy 172.017056 -62.893706)
			(xy 172.07279 -62.891669) (xy 172.128227 -62.897769) (xy 172.182184 -62.911875) (xy 172.233513 -62.933687)
			(xy 172.281119 -62.962741) (xy 172.323987 -62.998416) (xy 172.361204 -63.039953) (xy 172.391977 -63.086466)
			(xy 172.415649 -63.136963) (xy 172.431717 -63.19037) (xy 172.439837 -63.245546) (xy 172.440346 -63.273432)
			(xy 172.439837 -63.301318) (xy 172.431717 -63.356494) (xy 172.415649 -63.409901) (xy 172.391977 -63.460398)
			(xy 172.361204 -63.506911) (xy 172.323987 -63.548448) (xy 172.281119 -63.584123) (xy 172.233513 -63.613177)
			(xy 172.182184 -63.634989) (xy 172.128227 -63.649095) (xy 172.07279 -63.655195) (xy 172.017056 -63.653158)
			(xy 171.962213 -63.643028) (xy 171.909429 -63.625021) (xy 171.859829 -63.59952) (xy 171.814471 -63.567069)
			(xy 171.774322 -63.52836) (xy 171.740236 -63.484217) (xy 171.71294 -63.435582) (xy 171.693017 -63.383491)
			(xy 171.680891 -63.329054) (xy 171.67682 -63.273432) (xy 170.229648 -63.273432) (xy 170.202837 -63.315149)
			(xy 170.167146 -63.356339) (xy 170.125957 -63.392031) (xy 170.080109 -63.421499) (xy 170.030534 -63.444143)
			(xy 169.978241 -63.459502) (xy 169.924295 -63.467263) (xy 169.897044 -63.467742) (xy 169.89679 -63.467742)
			(xy 169.873579 -63.467402) (xy 169.827499 -63.461769) (xy 169.782446 -63.450574) (xy 169.760646 -63.442596)
			(xy 169.756836 -63.441072) (xy 169.751248 -63.438786) (xy 169.748708 -63.438024) (xy 169.73677 -63.439548)
			(xy 169.731405 -63.440377) (xy 169.721157 -63.443955) (xy 169.71645 -63.44666) (xy 169.672 -63.476886)
			(xy 169.671492 -63.476886) (xy 169.656252 -63.487554) (xy 169.644822 -63.495428) (xy 169.641444 -63.497844)
			(xy 169.635448 -63.50359) (xy 169.632884 -63.506858) (xy 169.632884 -64.312292) (xy 175.005998 -64.312292)
			(xy 175.010069 -64.25667) (xy 175.022195 -64.202233) (xy 175.042118 -64.150142) (xy 175.069414 -64.101507)
			(xy 175.1035 -64.057364) (xy 175.143649 -64.018655) (xy 175.189007 -63.986204) (xy 175.238607 -63.960703)
			(xy 175.291391 -63.942696) (xy 175.346234 -63.932566) (xy 175.401968 -63.930529) (xy 175.457405 -63.936629)
			(xy 175.511362 -63.950735) (xy 175.562691 -63.972547) (xy 175.610297 -64.001601) (xy 175.653165 -64.037276)
			(xy 175.690382 -64.078813) (xy 175.721155 -64.125326) (xy 175.744827 -64.175823) (xy 175.760895 -64.22923)
			(xy 175.769015 -64.284406) (xy 175.769524 -64.312292) (xy 175.769015 -64.340178) (xy 175.760895 -64.395354)
			(xy 175.744827 -64.448761) (xy 175.721155 -64.499258) (xy 175.690382 -64.545771) (xy 175.653165 -64.587308)
			(xy 175.610297 -64.622983) (xy 175.562691 -64.652037) (xy 175.511362 -64.673849) (xy 175.457405 -64.687955)
			(xy 175.401968 -64.694055) (xy 175.346234 -64.692018) (xy 175.291391 -64.681888) (xy 175.238607 -64.663881)
			(xy 175.189007 -64.63838) (xy 175.143649 -64.605929) (xy 175.1035 -64.56722) (xy 175.069414 -64.523077)
			(xy 175.042118 -64.474442) (xy 175.022195 -64.422351) (xy 175.010069 -64.367914) (xy 175.005998 -64.312292)
			(xy 169.632884 -64.312292) (xy 169.632884 -65.6844) (xy 169.633392 -65.691512) (xy 169.63481 -65.699471)
			(xy 169.641924 -65.713979) (xy 169.647362 -65.71996) (xy 170.664632 -66.736976) (xy 170.682667 -66.755745)
			(xy 170.713252 -66.797861) (xy 170.736883 -66.844237) (xy 170.752979 -66.893735) (xy 170.761146 -66.94514)
			(xy 170.76166 -66.971164) (xy 170.76166 -80.852264) (xy 170.769262 -80.861372) (xy 170.790453 -80.871971)
			(xy 170.8023 -80.872584) (xy 174.771812 -80.872584) (xy 174.782734 -80.871314) (xy 174.793656 -80.869028)
			(xy 176.364646 -79.298038) (xy 176.369626 -79.292535) (xy 176.376455 -79.279366) (xy 176.378108 -79.27213)
			(xy 176.379124 -79.262478) (xy 176.379124 -63.136272) (xy 176.378616 -63.135002) (xy 176.321974 -63.092584)
			(xy 176.321466 -63.092584) (xy 176.300638 -63.07709) (xy 176.291632 -63.071759) (xy 176.271029 -63.068215)
			(xy 176.26076 -63.070232) (xy 176.25822 -63.070994) (xy 176.231122 -63.07871) (xy 176.175393 -63.086996)
			(xy 176.147222 -63.087504) (xy 176.119968 -63.087042) (xy 176.066015 -63.079288) (xy 176.013715 -63.063934)
			(xy 175.964132 -63.041292) (xy 175.918277 -63.011825) (xy 175.877082 -62.976131) (xy 175.841386 -62.934938)
			(xy 175.811916 -62.889084) (xy 175.789273 -62.839502) (xy 175.773916 -62.787202) (xy 175.766159 -62.73325)
			(xy 175.765714 -62.705996) (xy 175.766195 -62.678826) (xy 175.773906 -62.625037) (xy 175.789172 -62.572886)
			(xy 175.811684 -62.523429) (xy 175.840986 -62.477666) (xy 175.876485 -62.436525) (xy 175.917463 -62.400838)
			(xy 175.96309 -62.371326) (xy 176.012443 -62.348587) (xy 176.064523 -62.333082) (xy 176.118277 -62.325124)
			(xy 176.145444 -62.324488) (xy 176.14773 -62.324488) (xy 176.172114 -62.32525) (xy 176.172876 -62.32525)
			(xy 176.174654 -62.325504) (xy 176.176178 -62.325504) (xy 176.207166 -62.32906) (xy 176.232539 -62.333541)
			(xy 176.281857 -62.348456) (xy 176.305464 -62.358778) (xy 176.305718 -62.359032) (xy 176.305972 -62.359032)
			(xy 176.307242 -62.35954) (xy 176.317402 -62.364366) (xy 176.32807 -62.364366) (xy 176.335253 -62.364125)
			(xy 176.349054 -62.360136) (xy 176.355248 -62.356492) (xy 176.355502 -62.356238) (xy 176.362547 -62.351389)
			(xy 176.373173 -62.337999) (xy 176.378801 -62.321859) (xy 176.379124 -62.313312) (xy 176.379124 -62.254384)
			(xy 176.378949 -62.248233) (xy 176.375983 -62.236292) (xy 176.373282 -62.230762) (xy 176.35982 -62.203867)
			(xy 176.340583 -62.146886) (xy 176.330499 -62.087596) (xy 176.329594 -62.057534) (xy 176.329594 -62.048136)
			(xy 176.330289 -62.021187) (xy 176.338334 -61.967882) (xy 176.353802 -61.916241) (xy 176.376386 -61.867291)
			(xy 176.405635 -61.822008) (xy 176.440967 -61.781293) (xy 176.481679 -61.745957) (xy 176.526959 -61.716703)
			(xy 176.575907 -61.694115) (xy 176.627547 -61.678642) (xy 176.680851 -61.670592) (xy 176.7078 -61.66993)
			(xy 176.716944 -61.66993) (xy 176.747051 -61.670796) (xy 176.806435 -61.680853) (xy 176.863497 -61.700126)
			(xy 176.890426 -61.713618) (xy 176.895958 -61.716308) (xy 176.907899 -61.719251) (xy 176.914048 -61.71946)
			(xy 177.061622 -61.71946) (xy 177.0715 -61.719001) (xy 177.089803 -61.711563) (xy 177.097182 -61.704982)
			(xy 177.256948 -61.545216) (xy 177.58029 -61.222128) (xy 177.586857 -61.215006) (xy 177.594555 -61.197246)
			(xy 177.595276 -61.187584) (xy 177.595276 -58.834528) (xy 177.591466 -58.82767) (xy 177.587967 -58.821969)
			(xy 177.578575 -58.812452) (xy 177.572924 -58.808874) (xy 177.53965 -58.789316) (xy 177.5333 -58.786268)
			(xy 177.532792 -58.786268) (xy 177.529307 -58.7849) (xy 177.522037 -58.78311) (xy 177.518314 -58.782712)
			(xy 177.517806 -58.782712) (xy 177.513996 -58.782458) (xy 177.485294 -58.782458) (xy 177.475134 -58.784744)
			(xy 177.468784 -58.7883) (xy 177.441439 -58.801837) (xy 177.383511 -58.820987) (xy 177.323269 -58.830651)
			(xy 177.292762 -58.831226) (xy 177.290984 -58.831226) (xy 177.263732 -58.830739) (xy 177.209784 -58.82298)
			(xy 177.157488 -58.807623) (xy 177.107911 -58.78498) (xy 177.06206 -58.755512) (xy 177.02087 -58.719819)
			(xy 176.985179 -58.678627) (xy 176.955712 -58.632775) (xy 176.933071 -58.583197) (xy 176.917716 -58.530901)
			(xy 176.90996 -58.476952) (xy 176.90996 -58.422448) (xy 176.917716 -58.368499) (xy 176.933071 -58.316203)
			(xy 176.955712 -58.266625) (xy 176.985179 -58.220773) (xy 177.02087 -58.179581) (xy 177.06206 -58.143888)
			(xy 177.107911 -58.11442) (xy 177.157488 -58.091777) (xy 177.209784 -58.07642) (xy 177.263732 -58.068661)
			(xy 177.290984 -58.06821) (xy 177.291746 -58.06821) (xy 177.316067 -58.06859) (xy 177.364315 -58.074769)
			(xy 177.411386 -58.087035) (xy 177.456514 -58.105188) (xy 177.477928 -58.116724) (xy 177.478182 -58.116978)
			(xy 177.480976 -58.118502) (xy 177.486315 -58.120898) (xy 177.497731 -58.123461) (xy 177.503582 -58.123582)
			(xy 177.517044 -58.123328) (xy 177.531776 -58.114692) (xy 177.532284 -58.114438) (xy 177.569876 -58.09234)
			(xy 177.580798 -58.083958) (xy 177.585526 -58.078821) (xy 177.592229 -58.06658) (xy 177.594006 -58.059828)
			(xy 177.595276 -58.048398) (xy 177.595276 -54.913022) (xy 177.594885 -54.903496) (xy 177.587937 -54.885756)
			(xy 177.574991 -54.871778) (xy 177.566574 -54.867302) (xy 177.563526 -54.866032) (xy 177.556355 -54.863329)
			(xy 177.541103 -54.861917) (xy 177.533554 -54.863238) (xy 177.52695 -54.864508) (xy 177.51425 -54.871366)
			(xy 174.51832 -57.867296) (xy 175.743106 -57.867296) (xy 175.747177 -57.811674) (xy 175.759303 -57.757237)
			(xy 175.779226 -57.705146) (xy 175.806522 -57.656511) (xy 175.840608 -57.612368) (xy 175.880757 -57.573659)
			(xy 175.926115 -57.541208) (xy 175.975715 -57.515707) (xy 176.028499 -57.4977) (xy 176.083342 -57.48757)
			(xy 176.139076 -57.485533) (xy 176.194513 -57.491633) (xy 176.24847 -57.505739) (xy 176.299799 -57.527551)
			(xy 176.347405 -57.556605) (xy 176.390273 -57.59228) (xy 176.42749 -57.633817) (xy 176.458263 -57.68033)
			(xy 176.481935 -57.730827) (xy 176.498003 -57.784234) (xy 176.506123 -57.83941) (xy 176.506632 -57.867296)
			(xy 176.506123 -57.895182) (xy 176.498003 -57.950358) (xy 176.481935 -58.003765) (xy 176.458263 -58.054262)
			(xy 176.42749 -58.100775) (xy 176.390273 -58.142312) (xy 176.347405 -58.177987) (xy 176.299799 -58.207041)
			(xy 176.24847 -58.228853) (xy 176.194513 -58.242959) (xy 176.139076 -58.249059) (xy 176.083342 -58.247022)
			(xy 176.028499 -58.236892) (xy 175.975715 -58.218885) (xy 175.926115 -58.193384) (xy 175.880757 -58.160933)
			(xy 175.840608 -58.122224) (xy 175.806522 -58.078081) (xy 175.779226 -58.029446) (xy 175.759303 -57.977355)
			(xy 175.747177 -57.922918) (xy 175.743106 -57.867296) (xy 174.51832 -57.867296) (xy 174.212758 -58.172858)
			(xy 174.206408 -58.183526) (xy 174.20463 -58.189368) (xy 174.196181 -58.214935) (xy 174.173101 -58.263583)
			(xy 174.143415 -58.308507) (xy 174.107712 -58.348813) (xy 174.066699 -58.383704) (xy 174.021192 -58.412487)
			(xy 173.972092 -58.43459) (xy 173.920374 -58.449576) (xy 173.867063 -58.457147) (xy 173.84014 -58.457592)
			(xy 173.812886 -58.457131) (xy 173.758931 -58.449379) (xy 173.70663 -58.434026) (xy 173.657045 -58.411386)
			(xy 173.611188 -58.381919) (xy 173.569992 -58.346225) (xy 173.534296 -58.305031) (xy 173.504826 -58.259176)
			(xy 173.482182 -58.209593) (xy 173.466826 -58.157292) (xy 173.45907 -58.103338) (xy 173.458632 -58.076084)
			(xy 173.458378 -58.076084) (xy 173.458835 -58.049147) (xy 173.4664 -57.995807) (xy 173.481392 -57.944061)
			(xy 173.503512 -57.894938) (xy 173.532321 -57.849414) (xy 173.567246 -57.808395) (xy 173.607592 -57.772694)
			(xy 173.652559 -57.743023) (xy 173.701252 -57.719971) (xy 173.726856 -57.711594) (xy 173.72711 -57.711594)
			(xy 173.732943 -57.709581) (xy 173.743475 -57.703156) (xy 173.747938 -57.698894) (xy 177.222404 -54.224682)
			(xy 177.226738 -54.220053) (xy 177.233174 -54.209132) (xy 177.235104 -54.203092) (xy 177.23605 -54.199612)
			(xy 177.237065 -54.192473) (xy 177.237136 -54.188868) (xy 177.237136 -46.105318) (xy 177.236965 -46.099309)
			(xy 177.234137 -46.08763) (xy 177.231548 -46.082204) (xy 177.229708 -46.07873) (xy 177.225113 -46.072353)
			(xy 177.222404 -46.069504) (xy 171.461176 -40.308276) (xy 171.455842 -40.303704) (xy 168.566592 -40.303704)
			(xy 168.562782 -40.305736) (xy 168.53429 -40.320731) (xy 168.473528 -40.342007) (xy 168.41006 -40.352803)
			(xy 168.37787 -40.353488) (xy 168.350621 -40.353) (xy 168.296677 -40.34524) (xy 168.244387 -40.329882)
			(xy 168.194815 -40.307239) (xy 168.14897 -40.277771) (xy 168.107785 -40.242079) (xy 168.072099 -40.20089)
			(xy 168.042637 -40.155041) (xy 168.020001 -40.105466) (xy 168.00465 -40.053174) (xy 167.996897 -39.999229)
			(xy 167.996362 -39.97198) (xy 167.996843 -39.944821) (xy 168.004549 -39.891053) (xy 168.019803 -39.838921)
			(xy 168.042296 -39.78948) (xy 168.071574 -39.743728) (xy 168.107045 -39.702591) (xy 168.147992 -39.666901)
			(xy 168.193586 -39.637378) (xy 168.242906 -39.61462) (xy 168.294956 -39.599087) (xy 168.348682 -39.591093)
			(xy 168.375838 -39.590472) (xy 168.378632 -39.590472) (xy 168.410695 -39.591195) (xy 168.473902 -39.602032)
			(xy 168.534415 -39.623263) (xy 168.562782 -39.638224) (xy 168.566592 -39.640256) (xy 171.148502 -39.640256)
			(xy 171.158546 -39.63983) (xy 171.177094 -39.63212) (xy 171.191262 -39.617881) (xy 171.195492 -39.60876)
			(xy 171.206922 -39.581074) (xy 171.205652 -39.574724) (xy 171.042584 -39.41191) (xy 167.840914 -36.210494)
			(xy 167.838628 -36.208716) (xy 166.83863 -36.208716) (xy 166.82974 -36.216844) (xy 166.797228 -36.261802)
			(xy 166.780718 -36.284916) (xy 166.776977 -36.291024) (xy 166.772706 -36.304688) (xy 166.772336 -36.31184)
			(xy 166.772336 -36.331906) (xy 166.774622 -36.339526) (xy 166.782786 -36.367329) (xy 166.791581 -36.424601)
			(xy 166.792148 -36.453572) (xy 166.791664 -36.480826) (xy 166.783911 -36.534778) (xy 166.768559 -36.587079)
			(xy 166.74592 -36.636662) (xy 166.716455 -36.682519) (xy 166.680764 -36.723716) (xy 166.639573 -36.759414)
			(xy 166.593722 -36.788887) (xy 166.544143 -36.811535) (xy 166.491845 -36.826897) (xy 166.437894 -36.834659)
			(xy 166.41064 -36.83508) (xy 166.383514 -36.834605) (xy 166.32981 -36.826925) (xy 166.277735 -36.811714)
			(xy 166.228341 -36.789279) (xy 166.182623 -36.760072) (xy 166.141504 -36.724683) (xy 166.105813 -36.683825)
			(xy 166.076271 -36.638324) (xy 166.053473 -36.589095) (xy 166.037879 -36.537134) (xy 166.029804 -36.483487)
			(xy 166.029132 -36.456366) (xy 166.029132 -36.45281) (xy 166.029693 -36.423839) (xy 166.038499 -36.366569)
			(xy 166.046658 -36.338764) (xy 166.04742 -36.336224) (xy 166.048944 -36.331398) (xy 166.050468 -36.318444)
			(xy 166.050739 -36.31029) (xy 166.046738 -36.294482) (xy 166.042594 -36.287456) (xy 166.023544 -36.260786)
			(xy 165.992556 -36.21786) (xy 165.983158 -36.208716) (xy 165.460426 -36.208716) (xy 165.454584 -36.211764)
			(xy 165.451282 -36.213288) (xy 165.423481 -36.227426) (xy 165.36442 -36.247463) (xy 165.302887 -36.257633)
			(xy 165.271704 -36.258246) (xy 165.270942 -36.258246) (xy 165.243684 -36.257786) (xy 165.189724 -36.250033)
			(xy 165.137415 -36.234679) (xy 165.087825 -36.212037) (xy 165.041962 -36.182567) (xy 165.00076 -36.14687)
			(xy 164.965058 -36.105672) (xy 164.935583 -36.059812) (xy 164.912936 -36.010224) (xy 164.897576 -35.957918)
			(xy 164.889817 -35.903958) (xy 164.889817 -35.849442) (xy 164.897576 -35.795482) (xy 164.912936 -35.743176)
			(xy 164.935583 -35.693588) (xy 164.965058 -35.647728) (xy 165.00076 -35.60653) (xy 165.041962 -35.570833)
			(xy 165.087825 -35.541363) (xy 165.137415 -35.518721) (xy 165.189724 -35.503367) (xy 165.243684 -35.495614)
			(xy 165.270942 -35.49523) (xy 165.271704 -35.49523) (xy 165.302885 -35.495871) (xy 165.364413 -35.506043)
			(xy 165.423474 -35.526067) (xy 165.451282 -35.540188) (xy 165.454584 -35.541712) (xy 165.460426 -35.54476)
			(xy 167.675052 -35.54476) (xy 167.684145 -35.54434) (xy 167.701156 -35.537895) (xy 167.71484 -35.52591)
			(xy 167.719502 -35.51809) (xy 167.730424 -35.491928) (xy 167.730424 -35.48888) (xy 167.726868 -35.480244)
			(xy 167.724973 -35.475766) (xy 167.719737 -35.467574) (xy 167.716454 -35.463988) (xy 167.510968 -35.258756)
			(xy 165.656514 -33.404302) (xy 165.638957 -33.386087) (xy 165.609216 -33.345165) (xy 165.586247 -33.300092)
			(xy 165.570617 -33.251979) (xy 165.562711 -33.202012) (xy 165.56228 -33.176718) (xy 165.56228 -33.114488)
			(xy 165.562026 -33.11017) (xy 165.562026 -33.109662) (xy 165.561772 -33.099756) (xy 165.561772 -28.8417)
			(xy 165.561352 -28.831681) (xy 165.553681 -28.813169) (xy 165.539508 -28.799003) (xy 165.520991 -28.791343)
			(xy 165.510972 -28.7909) (xy 163.146994 -28.7909) (xy 163.121704 -28.790404) (xy 163.071747 -28.782495)
			(xy 163.02364 -28.766872) (xy 162.978568 -28.743919) (xy 162.937639 -28.714202) (xy 162.91941 -28.696666)
			(xy 162.001708 -27.77871) (xy 161.996003 -27.773373) (xy 161.982166 -27.766141) (xy 161.97453 -27.764486)
			(xy 161.96564 -27.763724) (xy 161.8107 -27.763724) (xy 161.801037 -27.764203) (xy 161.783123 -27.771466)
			(xy 161.769171 -27.784846) (xy 161.764726 -27.793442) (xy 161.752788 -27.821128) (xy 161.727388 -27.88031)
			(xy 161.725482 -27.885171) (xy 161.723438 -27.895409) (xy 161.723324 -27.90063) (xy 161.73704 -27.934666)
			(xy 161.743136 -27.941524) (xy 161.76193 -27.962673) (xy 161.794705 -28.008794) (xy 161.821545 -28.058603)
			(xy 161.84204 -28.111341) (xy 161.855878 -28.166203) (xy 161.862847 -28.222352) (xy 161.863278 -28.250642)
			(xy 161.863024 -28.734512) (xy 161.863024 -29.114242) (xy 161.862534 -29.14421) (xy 161.854711 -29.203632)
			(xy 161.839198 -29.261525) (xy 161.816262 -29.316898) (xy 161.786295 -29.368804) (xy 161.749808 -29.416354)
			(xy 161.707428 -29.458734) (xy 161.659878 -29.495221) (xy 161.607972 -29.525188) (xy 161.552599 -29.548124)
			(xy 161.494706 -29.563637) (xy 161.435284 -29.57146) (xy 161.375348 -29.57146) (xy 161.315926 -29.563637)
			(xy 161.258033 -29.548124) (xy 161.20266 -29.525188) (xy 161.150754 -29.495221) (xy 161.103204 -29.458734)
			(xy 161.060824 -29.416354) (xy 161.024337 -29.368804) (xy 160.99437 -29.316898) (xy 160.971434 -29.261525)
			(xy 160.955921 -29.203632) (xy 160.948098 -29.14421) (xy 160.947608 -29.114242) (xy 160.947608 -28.734512)
			(xy 160.947354 -28.250642) (xy 160.947779 -28.222353) (xy 160.954759 -28.166207) (xy 160.968606 -28.11135)
			(xy 160.989107 -28.058617) (xy 161.015952 -28.008813) (xy 161.048729 -27.962697) (xy 161.067496 -27.941524)
			(xy 161.073592 -27.934666) (xy 161.087308 -27.90063) (xy 161.087247 -27.895404) (xy 161.085203 -27.885156)
			(xy 161.083244 -27.88031) (xy 161.057844 -27.821128) (xy 161.045906 -27.793442) (xy 161.04151 -27.784816)
			(xy 161.027537 -27.771438) (xy 161.009602 -27.764189) (xy 160.999932 -27.763724) (xy 160.934146 -27.763724)
			(xy 160.908123 -27.763196) (xy 160.85672 -27.755028) (xy 160.807224 -27.738933) (xy 160.760849 -27.715305)
			(xy 160.718733 -27.684724) (xy 160.699958 -27.666696) (xy 159.648652 -26.615136) (xy 159.644734 -26.61139)
			(xy 159.635637 -26.605501) (xy 159.630618 -26.603452) (xy 159.620108 -26.600113) (xy 159.598135 -26.60171)
			(xy 159.5882 -26.6065) (xy 159.584136 -26.608786) (xy 159.570731 -26.618605) (xy 159.550608 -26.645022)
			(xy 159.540054 -26.676508) (xy 159.539432 -26.693114) (xy 159.539432 -27.342846) (xy 159.538942 -27.37283)
			(xy 159.531114 -27.432286) (xy 159.515593 -27.490211) (xy 159.492644 -27.545615) (xy 159.46266 -27.597549)
			(xy 159.426154 -27.645125) (xy 159.383749 -27.68753) (xy 159.336173 -27.724036) (xy 159.284239 -27.75402)
			(xy 159.228835 -27.776969) (xy 159.17091 -27.79249) (xy 159.111454 -27.800318) (xy 159.051486 -27.800318)
			(xy 158.99203 -27.79249) (xy 158.934105 -27.776969) (xy 158.878701 -27.75402) (xy 158.826767 -27.724036)
			(xy 158.779191 -27.68753) (xy 158.736786 -27.645125) (xy 158.70028 -27.597549) (xy 158.670296 -27.545615)
			(xy 158.647347 -27.490211) (xy 158.631826 -27.432286) (xy 158.623998 -27.37283) (xy 158.623508 -27.342846)
			(xy 158.623508 -26.479246) (xy 158.624039 -26.448026) (xy 158.632523 -26.386164) (xy 158.649324 -26.326026)
			(xy 158.674134 -26.268726) (xy 158.706492 -26.215324) (xy 158.7458 -26.166808) (xy 158.79133 -26.124077)
			(xy 158.842238 -26.087922) (xy 158.897583 -26.059012) (xy 158.926784 -26.047954) (xy 158.937198 -26.044144)
			(xy 158.952438 -26.029412) (xy 158.95574 -26.025602) (xy 158.958818 -26.021651) (xy 158.963555 -26.012828)
			(xy 158.965138 -26.008076) (xy 158.967932 -25.99563) (xy 158.967932 -25.995122) (xy 158.97352 -25.970992)
			(xy 158.974793 -25.961252) (xy 158.970745 -25.942049) (xy 158.965646 -25.933654) (xy 158.963614 -25.93086)
			(xy 158.95955 -25.926288) (xy 158.770066 -25.736804) (xy 158.767213 -25.734101) (xy 158.760831 -25.729514)
			(xy 158.757366 -25.72766) (xy 158.75194 -25.725073) (xy 158.74026 -25.722244) (xy 158.734252 -25.722072)
			(xy 156.480002 -25.722072) (xy 156.47416 -25.72512) (xy 156.468572 -25.727914) (xy 156.441072 -25.741687)
			(xy 156.382736 -25.761164) (xy 156.322031 -25.771029) (xy 156.29128 -25.771602) (xy 156.26403 -25.771115)
			(xy 156.210085 -25.763356) (xy 156.157793 -25.747999) (xy 156.108218 -25.725357) (xy 156.062371 -25.69589)
			(xy 156.021183 -25.660198) (xy 155.985495 -25.619008) (xy 155.956031 -25.573159) (xy 155.933392 -25.523583)
			(xy 155.918038 -25.47129) (xy 155.910283 -25.417344) (xy 155.909772 -25.390094) (xy 155.91026 -25.362164)
			(xy 155.918406 -25.306901) (xy 155.934523 -25.253416) (xy 155.958267 -25.202854) (xy 155.98913 -25.156294)
			(xy 156.026452 -25.114731) (xy 156.069436 -25.079056) (xy 156.117163 -25.050029) (xy 156.168611 -25.028272)
			(xy 156.195522 -25.020778) (xy 156.20238 -25.019) (xy 156.209238 -25.014936) (xy 156.219144 -25.007316)
			(xy 156.227272 -24.999188) (xy 156.235178 -24.990339) (xy 156.242583 -24.967826) (xy 156.241496 -24.956008)
			(xy 155.889706 -24.604218) (xy 155.864559 -24.578276) (xy 155.820144 -24.52129) (xy 155.783063 -24.459281)
			(xy 155.753878 -24.393187) (xy 155.733032 -24.324009) (xy 155.726384 -24.288496) (xy 155.72232 -24.263858)
			(xy 155.718265 -24.26015) (xy 155.708911 -24.254389) (xy 155.703778 -24.252428) (xy 155.636722 -24.231092)
			(xy 155.636214 -24.231092) (xy 155.624022 -24.227282) (xy 155.615386 -24.225504) (xy 155.608782 -24.224996)
			(xy 155.603194 -24.224996) (xy 155.59405 -24.228806) (xy 155.589485 -24.230812) (xy 155.581168 -24.236308)
			(xy 155.57754 -24.239728) (xy 155.392628 -24.42464) (xy 155.373858 -24.442675) (xy 155.331743 -24.473259)
			(xy 155.285367 -24.49689) (xy 155.235869 -24.512987) (xy 155.184464 -24.521154) (xy 155.15844 -24.521668)
			(xy 153.96972 -24.521668) (xy 153.96591 -24.5237) (xy 153.937419 -24.538699) (xy 153.876657 -24.559981)
			(xy 153.813188 -24.570782) (xy 153.780998 -24.571452) (xy 153.753746 -24.570966) (xy 153.699796 -24.56321)
			(xy 153.647499 -24.547855) (xy 153.597919 -24.525214) (xy 153.552066 -24.495748) (xy 153.510872 -24.460058)
			(xy 153.475177 -24.418868) (xy 153.445706 -24.373018) (xy 153.42306 -24.323441) (xy 153.407699 -24.271145)
			(xy 153.399937 -24.217196) (xy 153.39949 -24.189944) (xy 153.399966 -24.162783) (xy 153.407665 -24.109009)
			(xy 153.422914 -24.056871) (xy 153.445404 -24.007424) (xy 153.474681 -23.961666) (xy 153.510152 -23.920524)
			(xy 153.551101 -23.884829) (xy 153.596698 -23.855303) (xy 153.646023 -23.832544) (xy 153.698077 -23.817012)
			(xy 153.751808 -23.80902) (xy 153.778966 -23.808436) (xy 153.78176 -23.808436) (xy 153.813822 -23.809162)
			(xy 153.877026 -23.820005) (xy 153.937535 -23.841242) (xy 153.96591 -23.856188) (xy 153.96972 -23.85822)
			(xy 154.999436 -23.85822) (xy 155.005446 -23.858054) (xy 155.01713 -23.855235) (xy 155.02255 -23.852632)
			(xy 155.026024 -23.850792) (xy 155.032402 -23.846197) (xy 155.03525 -23.843488) (xy 155.154122 -23.724616)
			(xy 155.154815 -23.718729) (xy 155.153796 -23.706924) (xy 155.15209 -23.701248) (xy 155.142946 -23.673562)
			(xy 155.142946 -23.673054) (xy 155.12161 -23.603712) (xy 155.114244 -23.597108) (xy 155.089606 -23.59279)
			(xy 155.056758 -23.586395) (xy 154.992682 -23.56708) (xy 154.931226 -23.540586) (xy 154.873191 -23.507258)
			(xy 154.819333 -23.467532) (xy 154.770355 -23.421926) (xy 154.726896 -23.371033) (xy 154.689522 -23.315517)
			(xy 154.65872 -23.256103) (xy 154.646376 -23.224998) (xy 154.637994 -23.203154) (xy 154.633961 -23.200571)
			(xy 154.625137 -23.196851) (xy 154.620468 -23.195788) (xy 154.571192 -23.185374) (xy 154.570684 -23.185374)
			(xy 154.53487 -23.177754) (xy 154.520646 -23.178008) (xy 154.259026 -23.439628) (xy 154.23545 -23.462576)
			(xy 154.18401 -23.503598) (xy 154.128301 -23.538602) (xy 154.069022 -23.567149) (xy 154.00692 -23.588879)
			(xy 153.942776 -23.603519) (xy 153.877395 -23.610886) (xy 153.844498 -23.611332) (xy 153.80907 -23.610797)
			(xy 153.73873 -23.602256) (xy 153.669933 -23.585299) (xy 153.603682 -23.560173) (xy 153.540942 -23.527244)
			(xy 153.482628 -23.486993) (xy 153.429592 -23.440007) (xy 153.382605 -23.38697) (xy 153.342355 -23.328657)
			(xy 153.309426 -23.265917) (xy 153.2843 -23.199665) (xy 153.267343 -23.130868) (xy 153.258803 -23.060528)
			(xy 153.258266 -23.0251) (xy 153.258727 -22.992204) (xy 153.266093 -22.926825) (xy 153.280734 -22.862682)
			(xy 153.302463 -22.800582) (xy 153.331009 -22.741305) (xy 153.366013 -22.685597) (xy 153.407034 -22.634158)
			(xy 153.42997 -22.610572) (xy 153.92273 -22.117812) (xy 153.946304 -22.094861) (xy 153.997742 -22.053833)
			(xy 154.053451 -22.018822) (xy 154.112729 -21.990268) (xy 154.174832 -21.968532) (xy 154.238977 -21.953886)
			(xy 154.30436 -21.946514) (xy 154.337258 -21.946108) (xy 154.358594 -21.946616) (xy 158.169102 -21.946616)
			(xy 158.170626 -21.94433) (xy 158.171642 -21.942806) (xy 158.202122 -21.892514) (xy 158.202122 -21.892006)
			(xy 158.217616 -21.866098) (xy 158.222442 -21.85416) (xy 158.223966 -21.842476) (xy 158.22422 -21.830792)
			(xy 158.218632 -21.818854) (xy 158.218124 -21.817838) (xy 158.204223 -21.790283) (xy 158.184538 -21.731793)
			(xy 158.174537 -21.670894) (xy 158.173928 -21.640038) (xy 158.173928 -21.63572) (xy 158.174696 -21.607317)
			(xy 158.183608 -21.551205) (xy 158.200745 -21.497035) (xy 158.225729 -21.446006) (xy 158.258007 -21.399249)
			(xy 158.277052 -21.378164) (xy 158.28391 -21.371052) (xy 158.287466 -21.362162) (xy 158.290006 -21.353018)
			(xy 158.290768 -21.344128) (xy 158.290768 -21.27377) (xy 158.290704 -21.269636) (xy 158.289434 -21.261468)
			(xy 158.288228 -21.257514) (xy 158.287466 -21.255736) (xy 158.284164 -21.2471) (xy 158.277052 -21.23948)
			(xy 158.257778 -21.218154) (xy 158.225207 -21.170792) (xy 158.200111 -21.119079) (xy 158.183056 -21.064186)
			(xy 158.17443 -21.007356) (xy 158.174428 -20.949876) (xy 158.183049 -20.893045) (xy 158.200099 -20.838151)
			(xy 158.225191 -20.786436) (xy 158.257758 -20.739071) (xy 158.277052 -20.717764) (xy 158.284164 -20.710144)
			(xy 158.287466 -20.701508) (xy 158.288228 -20.69973) (xy 158.28946 -20.695781) (xy 158.290737 -20.68761)
			(xy 158.290768 -20.683474) (xy 158.290768 -20.61337) (xy 158.290704 -20.609236) (xy 158.289434 -20.601068)
			(xy 158.288228 -20.597114) (xy 158.287466 -20.595336) (xy 158.284164 -20.5867) (xy 158.277052 -20.57908)
			(xy 158.257778 -20.557754) (xy 158.225207 -20.510392) (xy 158.200111 -20.458679) (xy 158.183056 -20.403786)
			(xy 158.17443 -20.346956) (xy 158.174428 -20.289476) (xy 158.183049 -20.232645) (xy 158.200099 -20.177751)
			(xy 158.225191 -20.126036) (xy 158.257758 -20.078671) (xy 158.277052 -20.057364) (xy 158.284164 -20.049744)
			(xy 158.287466 -20.041108) (xy 158.288228 -20.03933) (xy 158.28946 -20.035381) (xy 158.290737 -20.02721)
			(xy 158.290768 -20.023074) (xy 158.290768 -19.95297) (xy 158.290704 -19.948836) (xy 158.289434 -19.940668)
			(xy 158.288228 -19.936714) (xy 158.287466 -19.934936) (xy 158.284164 -19.9263) (xy 158.277052 -19.91868)
			(xy 158.257778 -19.897354) (xy 158.225207 -19.849992) (xy 158.200111 -19.798279) (xy 158.183056 -19.743386)
			(xy 158.17443 -19.686556) (xy 158.174428 -19.629076) (xy 158.183049 -19.572245) (xy 158.200099 -19.517351)
			(xy 158.225191 -19.465636) (xy 158.257758 -19.418271) (xy 158.277052 -19.396964) (xy 158.284164 -19.389344)
			(xy 158.287466 -19.380708) (xy 158.288228 -19.37893) (xy 158.28946 -19.374981) (xy 158.290737 -19.36681)
			(xy 158.290768 -19.362674) (xy 158.290768 -19.29257) (xy 158.290704 -19.288436) (xy 158.289434 -19.280268)
			(xy 158.288228 -19.276314) (xy 158.287466 -19.274536) (xy 158.284164 -19.2659) (xy 158.277052 -19.25828)
			(xy 158.257783 -19.236952) (xy 158.225221 -19.189588) (xy 158.200131 -19.137877) (xy 158.183082 -19.082987)
			(xy 158.174458 -19.02616) (xy 158.173928 -18.997422) (xy 158.174414 -18.970171) (xy 158.18217 -18.916223)
			(xy 158.197525 -18.863928) (xy 158.220167 -18.814351) (xy 158.249633 -18.768501) (xy 158.285324 -18.72731)
			(xy 158.326515 -18.691619) (xy 158.372365 -18.662153) (xy 158.421942 -18.639511) (xy 158.474237 -18.624156)
			(xy 158.528185 -18.6164) (xy 158.582687 -18.6164) (xy 158.636635 -18.624156) (xy 158.68893 -18.639511)
			(xy 158.738507 -18.662153) (xy 158.784357 -18.691619) (xy 158.825548 -18.72731) (xy 158.861239 -18.768501)
			(xy 158.890705 -18.814351) (xy 158.913347 -18.863928) (xy 158.928702 -18.916223) (xy 158.936458 -18.970171)
			(xy 158.936944 -18.997422) (xy 158.936421 -19.02616) (xy 158.927795 -19.082985) (xy 158.91074 -19.137873)
			(xy 158.885644 -19.189581) (xy 158.853073 -19.236938) (xy 158.83382 -19.25828) (xy 158.826708 -19.2659)
			(xy 158.823406 -19.274536) (xy 158.822644 -19.276314) (xy 158.821414 -19.280263) (xy 158.820143 -19.288434)
			(xy 158.820104 -19.29257) (xy 158.820104 -19.362674) (xy 158.820171 -19.366807) (xy 158.821447 -19.374974)
			(xy 158.822644 -19.37893) (xy 158.823406 -19.380708) (xy 158.826708 -19.389344) (xy 158.83382 -19.396964)
			(xy 158.853087 -19.418292) (xy 158.885645 -19.465655) (xy 158.910731 -19.517366) (xy 158.927776 -19.572254)
			(xy 158.936395 -19.629079) (xy 158.936392 -19.686553) (xy 158.927769 -19.743377) (xy 158.910719 -19.798264)
			(xy 158.885629 -19.849973) (xy 158.853067 -19.897333) (xy 158.83382 -19.91868) (xy 158.826708 -19.9263)
			(xy 158.823406 -19.934936) (xy 158.822644 -19.936714) (xy 158.821414 -19.940663) (xy 158.820143 -19.948834)
			(xy 158.820104 -19.95297) (xy 158.820104 -20.023074) (xy 158.820171 -20.027207) (xy 158.821447 -20.035374)
			(xy 158.822644 -20.03933) (xy 158.823406 -20.041108) (xy 158.826708 -20.049744) (xy 158.83382 -20.057364)
			(xy 158.853087 -20.078692) (xy 158.885645 -20.126055) (xy 158.910731 -20.177766) (xy 158.927776 -20.232654)
			(xy 158.936395 -20.289479) (xy 158.936392 -20.346953) (xy 158.927769 -20.403777) (xy 158.910719 -20.458664)
			(xy 158.885629 -20.510373) (xy 158.853067 -20.557733) (xy 158.83382 -20.57908) (xy 158.826708 -20.5867)
			(xy 158.823406 -20.595336) (xy 158.822644 -20.597114) (xy 158.821414 -20.601063) (xy 158.820143 -20.609234)
			(xy 158.820104 -20.61337) (xy 158.820104 -20.683474) (xy 158.820171 -20.687607) (xy 158.821447 -20.695774)
			(xy 158.822644 -20.69973) (xy 158.823406 -20.701508) (xy 158.826708 -20.710144) (xy 158.83382 -20.717764)
			(xy 158.853087 -20.739092) (xy 158.885645 -20.786455) (xy 158.910731 -20.838166) (xy 158.927776 -20.893054)
			(xy 158.936395 -20.949879) (xy 158.936392 -21.007353) (xy 158.927769 -21.064177) (xy 158.910719 -21.119064)
			(xy 158.885629 -21.170773) (xy 158.853067 -21.218133) (xy 158.83382 -21.23948) (xy 158.826708 -21.2471)
			(xy 158.823406 -21.255736) (xy 158.822644 -21.257514) (xy 158.821414 -21.261463) (xy 158.820143 -21.269634)
			(xy 158.820104 -21.27377) (xy 158.820104 -21.344128) (xy 158.820866 -21.353018) (xy 158.823406 -21.362162)
			(xy 158.826962 -21.371052) (xy 158.834328 -21.378672) (xy 158.853272 -21.399718) (xy 158.885372 -21.446365)
			(xy 158.910224 -21.497244) (xy 158.927282 -21.551238) (xy 158.936171 -21.60716) (xy 158.936944 -21.635466)
			(xy 158.936944 -21.63953) (xy 158.936343 -21.67047) (xy 158.926366 -21.73154) (xy 158.906676 -21.790204)
			(xy 158.892748 -21.817838) (xy 158.891224 -21.820632) (xy 158.889102 -21.825769) (xy 158.886918 -21.836664)
			(xy 158.886906 -21.842222) (xy 158.88716 -21.855684) (xy 158.90875 -21.892006) (xy 158.90875 -21.892514)
			(xy 158.93923 -21.942552) (xy 158.942024 -21.946616) (xy 163.352734 -21.946616) (xy 163.360443 -21.946387)
			(xy 163.375179 -21.941861) (xy 163.38169 -21.937726) (xy 163.385754 -21.934424) (xy 163.728908 -21.59127)
			(xy 163.729416 -21.583904) (xy 163.729416 -21.567902) (xy 163.726368 -21.556218) (xy 163.72205 -21.547836)
			(xy 163.708518 -21.520574) (xy 163.689324 -21.462819) (xy 163.679538 -21.402751) (xy 163.67887 -21.372322)
			(xy 163.67887 -21.36394) (xy 163.679865 -21.337046) (xy 163.688485 -21.283923) (xy 163.704487 -21.23254)
			(xy 163.727553 -21.183916) (xy 163.757226 -21.139018) (xy 163.792915 -21.098736) (xy 163.833912 -21.063872)
			(xy 163.879403 -21.035116) (xy 163.928485 -21.013041) (xy 163.980183 -20.998085) (xy 164.033469 -20.990545)
			(xy 164.060378 -20.990052) (xy 164.060632 -20.990052) (xy 164.076634 -20.990306) (xy 164.087302 -20.990814)
			(xy 164.096446 -20.987258) (xy 164.100811 -20.985507) (xy 164.108864 -20.980651) (xy 164.112448 -20.977606)
			(xy 164.126164 -20.964652) (xy 164.126672 -20.964144) (xy 164.168582 -20.923758) (xy 164.172392 -20.919186)
			(xy 164.172392 -19.452844) (xy 164.17294 -19.417114) (xy 164.181661 -19.346188) (xy 164.198941 -19.276848)
			(xy 164.224526 -19.210125) (xy 164.258034 -19.147008) (xy 164.298969 -19.088434) (xy 164.346723 -19.035272)
			(xy 164.373306 -19.011392) (xy 164.389816 -18.997168) (xy 164.390324 -18.991326) (xy 164.390832 -18.971514)
			(xy 164.392102 -18.922238) (xy 164.392102 -18.92046) (xy 164.39261 -18.906744) (xy 164.35959 -18.873978)
			(xy 164.344096 -18.858738) (xy 164.317388 -18.831161) (xy 164.27068 -18.770235) (xy 164.232332 -18.703729)
			(xy 164.217096 -18.668492) (xy 164.203066 -18.633086) (xy 164.183246 -18.55955) (xy 164.173127 -18.484066)
			(xy 164.172392 -18.445988) (xy 164.172392 -18.44421) (xy 164.172926 -18.408796) (xy 164.181462 -18.338485)
			(xy 164.198411 -18.269715) (xy 164.223525 -18.203489) (xy 164.256438 -18.140773) (xy 164.296671 -18.082482)
			(xy 164.343637 -18.029465) (xy 164.396651 -17.982496) (xy 164.454939 -17.942259) (xy 164.517653 -17.909341)
			(xy 164.583877 -17.884222) (xy 164.652645 -17.867269) (xy 164.722956 -17.858728) (xy 164.75837 -17.858232)
			(xy 164.767768 -17.858232) (xy 164.804563 -17.85943) (xy 164.877439 -17.869875) (xy 164.948437 -17.889349)
			(xy 164.982652 -17.902936) (xy 165.017881 -17.918188) (xy 165.084383 -17.956539) (xy 165.145312 -18.00324)
			(xy 165.172898 -18.029936) (xy 165.503606 -18.360898) (xy 165.74135 -18.598642) (xy 165.764248 -18.622206)
			(xy 165.805202 -18.673589) (xy 165.84015 -18.729232) (xy 165.868654 -18.788435) (xy 165.890355 -18.850456)
			(xy 165.90498 -18.914515) (xy 165.912347 -18.979808) (xy 165.9128 -19.012662) (xy 165.9128 -21.474684)
			(xy 165.915732 -21.478426) (xy 165.92277 -21.484815) (xy 165.92677 -21.487384) (xy 165.932612 -21.49094)
			(xy 166.019988 -21.527516) (xy 166.026604 -21.530024) (xy 166.040651 -21.531687) (xy 166.047674 -21.530818)
			(xy 166.636954 -20.941538) (xy 166.637461 -20.937744) (xy 166.637463 -20.930091) (xy 166.636954 -20.926298)
			(xy 166.636954 -20.925536) (xy 166.63162 -20.892516) (xy 166.623746 -20.842986) (xy 166.620909 -20.83192)
			(xy 166.607022 -20.813808) (xy 166.597076 -20.808188) (xy 166.590218 -20.804632) (xy 166.564442 -20.79026)
			(xy 166.517265 -20.754809) (xy 166.476102 -20.712523) (xy 166.441931 -20.66441) (xy 166.415566 -20.611614)
			(xy 166.397634 -20.555392) (xy 166.388563 -20.49708) (xy 166.388034 -20.467574) (xy 166.388499 -20.440323)
			(xy 166.396259 -20.386378) (xy 166.411618 -20.334085) (xy 166.434263 -20.284511) (xy 166.463732 -20.238664)
			(xy 166.499426 -20.197478) (xy 166.540619 -20.161791) (xy 166.586471 -20.13233) (xy 166.636049 -20.109694)
			(xy 166.688344 -20.094345) (xy 166.742291 -20.086594) (xy 166.769542 -20.086066) (xy 166.796506 -20.086534)
			(xy 166.849897 -20.094132) (xy 166.901686 -20.10917) (xy 166.950843 -20.13135) (xy 166.996388 -20.160228)
			(xy 167.037413 -20.195231) (xy 167.073103 -20.235661) (xy 167.102745 -20.280712) (xy 167.12575 -20.329488)
			(xy 167.14166 -20.381016) (xy 167.150156 -20.434271) (xy 167.15105 -20.461224) (xy 167.15105 -20.461986)
			(xy 167.151304 -20.46605) (xy 167.160194 -20.4851) (xy 167.192198 -20.513294) (xy 167.199487 -20.519069)
			(xy 167.216939 -20.525449) (xy 167.226234 -20.52574) (xy 167.231568 -20.525486) (xy 167.232838 -20.525232)
			(xy 167.238426 -20.524724) (xy 167.23995 -20.524724) (xy 167.254831 -20.523293) (xy 167.284691 -20.521767)
			(xy 167.29964 -20.521676) (xy 168.572688 -20.521676) (xy 168.605542 -20.522136) (xy 168.670837 -20.529491)
			(xy 168.734898 -20.54411) (xy 168.79692 -20.565809) (xy 168.856122 -20.594315) (xy 168.911761 -20.62927)
			(xy 168.963136 -20.670235) (xy 168.986708 -20.693126) (xy 169.018712 -20.72513) (xy 173.28059 -20.72513)
			(xy 173.28456 -20.594996) (xy 173.296456 -20.465346) (xy 173.316235 -20.336663) (xy 173.343821 -20.209424)
			(xy 173.379114 -20.084105) (xy 173.42198 -19.961169) (xy 173.472262 -19.841076) (xy 173.529771 -19.724272)
			(xy 173.594295 -19.61119) (xy 173.665592 -19.502253) (xy 173.743397 -19.397865) (xy 173.827422 -19.298414)
			(xy 173.917354 -19.204271) (xy 174.012858 -19.115786) (xy 174.113578 -19.033287) (xy 174.21914 -18.957082)
			(xy 174.329152 -18.887455) (xy 174.443204 -18.824664) (xy 174.560872 -18.768942) (xy 174.681718 -18.720498)
			(xy 174.805293 -18.679511) (xy 174.931136 -18.646134) (xy 175.058781 -18.620491) (xy 175.187751 -18.602677)
			(xy 175.317567 -18.592759) (xy 175.447746 -18.590774) (xy 175.577805 -18.596728) (xy 175.707258 -18.610601)
			(xy 175.835625 -18.632339) (xy 175.962428 -18.661863) (xy 176.087195 -18.699062) (xy 176.209462 -18.743798)
			(xy 176.328775 -18.795906) (xy 176.444688 -18.855189) (xy 176.556773 -18.92143) (xy 176.66461 -18.99438)
			(xy 176.767799 -19.073768) (xy 176.865957 -19.1593) (xy 176.958718 -19.250657) (xy 177.045737 -19.347499)
			(xy 177.12669 -19.449466) (xy 177.201276 -19.556178) (xy 177.269217 -19.667239) (xy 177.330262 -19.782235)
			(xy 177.384183 -19.900739) (xy 177.430778 -20.02231) (xy 177.469876 -20.146495) (xy 177.50133 -20.272833)
			(xy 177.525024 -20.400854) (xy 177.540868 -20.53008) (xy 177.548806 -20.660033) (xy 177.549302 -20.72513)
			(xy 177.548806 -20.790227) (xy 177.540868 -20.92018) (xy 177.525024 -21.049406) (xy 177.50133 -21.177427)
			(xy 177.469876 -21.303765) (xy 177.430778 -21.42795) (xy 177.384183 -21.549521) (xy 177.330262 -21.668025)
			(xy 177.269217 -21.783021) (xy 177.201276 -21.894082) (xy 177.12669 -22.000794) (xy 177.045737 -22.102761)
			(xy 176.958718 -22.199603) (xy 176.865957 -22.29096) (xy 176.767799 -22.376492) (xy 176.66461 -22.45588)
			(xy 176.556773 -22.52883) (xy 176.444688 -22.595071) (xy 176.328775 -22.654354) (xy 176.209462 -22.706462)
			(xy 176.087195 -22.751198) (xy 175.962428 -22.788397) (xy 175.835625 -22.817921) (xy 175.707258 -22.839659)
			(xy 175.577805 -22.853532) (xy 175.447746 -22.859486) (xy 175.317567 -22.857501) (xy 175.187751 -22.847583)
			(xy 175.058781 -22.829769) (xy 174.931136 -22.804126) (xy 174.805293 -22.770749) (xy 174.681718 -22.729762)
			(xy 174.560872 -22.681318) (xy 174.443204 -22.625596) (xy 174.329152 -22.562805) (xy 174.21914 -22.493178)
			(xy 174.113578 -22.416973) (xy 174.012858 -22.334474) (xy 173.917354 -22.245989) (xy 173.827422 -22.151846)
			(xy 173.743397 -22.052395) (xy 173.665592 -21.948007) (xy 173.594295 -21.83907) (xy 173.529771 -21.725988)
			(xy 173.472262 -21.609184) (xy 173.42198 -21.489091) (xy 173.379114 -21.366155) (xy 173.343821 -21.240836)
			(xy 173.316235 -21.113597) (xy 173.296456 -20.984914) (xy 173.28456 -20.855264) (xy 173.28059 -20.72513)
			(xy 169.018712 -20.72513) (xy 169.299382 -21.0058) (xy 169.734992 -21.441156) (xy 169.757938 -21.464711)
			(xy 169.798957 -21.51611) (xy 169.83396 -21.571781) (xy 169.862506 -21.631024) (xy 169.884235 -21.693091)
			(xy 169.898874 -21.757202) (xy 169.906238 -21.822549) (xy 169.906579 -21.847048) (xy 170.172886 -21.847048)
			(xy 170.176957 -21.791426) (xy 170.189083 -21.736989) (xy 170.209006 -21.684898) (xy 170.236302 -21.636263)
			(xy 170.270388 -21.59212) (xy 170.310537 -21.553411) (xy 170.355895 -21.52096) (xy 170.405495 -21.495459)
			(xy 170.458279 -21.477452) (xy 170.513122 -21.467322) (xy 170.568856 -21.465285) (xy 170.624293 -21.471385)
			(xy 170.67825 -21.485491) (xy 170.729579 -21.507303) (xy 170.777185 -21.536357) (xy 170.820053 -21.572032)
			(xy 170.85727 -21.613569) (xy 170.888043 -21.660082) (xy 170.911715 -21.710579) (xy 170.927783 -21.763986)
			(xy 170.935903 -21.819162) (xy 170.936412 -21.847048) (xy 170.935903 -21.874934) (xy 170.927783 -21.93011)
			(xy 170.911715 -21.983517) (xy 170.888043 -22.034014) (xy 170.85727 -22.080527) (xy 170.820053 -22.122064)
			(xy 170.777185 -22.157739) (xy 170.729579 -22.186793) (xy 170.67825 -22.208605) (xy 170.624293 -22.222711)
			(xy 170.568856 -22.228811) (xy 170.513122 -22.226774) (xy 170.458279 -22.216644) (xy 170.405495 -22.198637)
			(xy 170.355895 -22.173136) (xy 170.310537 -22.140685) (xy 170.270388 -22.101976) (xy 170.236302 -22.057833)
			(xy 170.209006 -22.009198) (xy 170.189083 -21.957107) (xy 170.176957 -21.90267) (xy 170.172886 -21.847048)
			(xy 169.906579 -21.847048) (xy 169.906696 -21.85543) (xy 169.906696 -21.869908) (xy 169.906442 -21.87575)
			(xy 169.904753 -21.910354) (xy 169.89424 -21.978835) (xy 169.87572 -22.045597) (xy 169.849453 -22.109708)
			(xy 169.815806 -22.170272) (xy 169.775248 -22.226444) (xy 169.728346 -22.277437) (xy 169.675754 -22.322541)
			(xy 169.618209 -22.361125) (xy 169.556514 -22.392649) (xy 169.491529 -22.416675) (xy 169.424165 -22.432865)
			(xy 169.35536 -22.440995) (xy 169.320718 -22.441408) (xy 169.287844 -22.440981) (xy 169.222505 -22.433651)
			(xy 169.1584 -22.419048) (xy 169.096333 -22.397355) (xy 169.037088 -22.368846) (xy 168.981409 -22.33388)
			(xy 168.929997 -22.292896) (xy 168.906444 -22.269958) (xy 168.84777 -22.211284) (xy 168.841928 -22.210776)
			(xy 168.829482 -22.210776) (xy 168.820466 -22.211138) (xy 168.803553 -22.217388) (xy 168.796462 -22.222968)
			(xy 168.794938 -22.224238) (xy 168.768502 -22.245838) (xy 168.711495 -22.283398) (xy 168.650507 -22.314076)
			(xy 168.586366 -22.337457) (xy 168.519943 -22.353222) (xy 168.452137 -22.361159) (xy 168.418002 -22.361652)
			(xy 168.26103 -22.361652) (xy 168.252394 -22.369272) (xy 168.232582 -22.393656) (xy 168.199562 -22.43455)
			(xy 168.197022 -22.438614) (xy 168.193212 -22.447758) (xy 168.189148 -22.463506) (xy 168.191688 -22.474936)
			(xy 168.195535 -22.494203) (xy 168.199736 -22.533269) (xy 168.20007 -22.552914) (xy 168.20007 -22.553422)
			(xy 168.20007 -22.559264) (xy 168.199307 -22.586807) (xy 168.190834 -22.641249) (xy 168.17462 -22.693907)
			(xy 168.151003 -22.743687) (xy 168.120474 -22.789554) (xy 168.083668 -22.830554) (xy 168.041348 -22.865837)
			(xy 167.994396 -22.894667) (xy 167.943786 -22.916448) (xy 167.89057 -22.930724) (xy 167.863266 -22.934422)
			(xy 167.849042 -22.935946) (xy 167.815768 -22.937216) (xy 167.813736 -22.937216) (xy 167.788704 -22.936489)
			(xy 167.739146 -22.929277) (xy 167.690958 -22.915642) (xy 167.644969 -22.895818) (xy 167.60197 -22.870147)
			(xy 167.582088 -22.85492) (xy 167.565324 -22.84095) (xy 167.5638 -22.83968) (xy 167.562022 -22.838156)
			(xy 167.553894 -22.832822) (xy 167.543476 -22.827184) (xy 167.519899 -22.825202) (xy 167.508682 -22.829012)
			(xy 167.484806 -22.839426) (xy 167.484298 -22.839426) (xy 167.423338 -22.866604) (xy 167.421306 -22.86762)
			(xy 167.40759 -22.874478) (xy 167.402764 -22.882352) (xy 167.402764 -23.965154) (xy 168.177462 -23.965154)
			(xy 168.181533 -23.909532) (xy 168.193659 -23.855095) (xy 168.213582 -23.803004) (xy 168.240878 -23.754369)
			(xy 168.274964 -23.710226) (xy 168.315113 -23.671517) (xy 168.360471 -23.639066) (xy 168.410071 -23.613565)
			(xy 168.462855 -23.595558) (xy 168.517698 -23.585428) (xy 168.573432 -23.583391) (xy 168.628869 -23.589491)
			(xy 168.682826 -23.603597) (xy 168.734155 -23.625409) (xy 168.781761 -23.654463) (xy 168.824629 -23.690138)
			(xy 168.861846 -23.731675) (xy 168.892619 -23.778188) (xy 168.916291 -23.828685) (xy 168.932359 -23.882092)
			(xy 168.940479 -23.937268) (xy 168.940654 -23.946866) (xy 169.180508 -23.946866) (xy 169.184579 -23.891244)
			(xy 169.196705 -23.836807) (xy 169.216628 -23.784716) (xy 169.243924 -23.736081) (xy 169.27801 -23.691938)
			(xy 169.318159 -23.653229) (xy 169.363517 -23.620778) (xy 169.413117 -23.595277) (xy 169.465901 -23.57727)
			(xy 169.520744 -23.56714) (xy 169.576478 -23.565103) (xy 169.631915 -23.571203) (xy 169.685872 -23.585309)
			(xy 169.737201 -23.607121) (xy 169.784807 -23.636175) (xy 169.827675 -23.67185) (xy 169.864892 -23.713387)
			(xy 169.895665 -23.7599) (xy 169.919337 -23.810397) (xy 169.935405 -23.863804) (xy 169.943525 -23.91898)
			(xy 169.944034 -23.946866) (xy 169.943594 -23.970996) (xy 170.172886 -23.970996) (xy 170.176957 -23.915374)
			(xy 170.189083 -23.860937) (xy 170.209006 -23.808846) (xy 170.236302 -23.760211) (xy 170.270388 -23.716068)
			(xy 170.310537 -23.677359) (xy 170.355895 -23.644908) (xy 170.405495 -23.619407) (xy 170.458279 -23.6014)
			(xy 170.513122 -23.59127) (xy 170.568856 -23.589233) (xy 170.624293 -23.595333) (xy 170.67825 -23.609439)
			(xy 170.729579 -23.631251) (xy 170.777185 -23.660305) (xy 170.820053 -23.69598) (xy 170.85727 -23.737517)
			(xy 170.888043 -23.78403) (xy 170.911715 -23.834527) (xy 170.927783 -23.887934) (xy 170.935903 -23.94311)
			(xy 170.936412 -23.970996) (xy 170.935903 -23.998882) (xy 170.927783 -24.054058) (xy 170.911715 -24.107465)
			(xy 170.888043 -24.157962) (xy 170.85727 -24.204475) (xy 170.820053 -24.246012) (xy 170.777185 -24.281687)
			(xy 170.729579 -24.310741) (xy 170.67825 -24.332553) (xy 170.624293 -24.346659) (xy 170.568856 -24.352759)
			(xy 170.513122 -24.350722) (xy 170.458279 -24.340592) (xy 170.405495 -24.322585) (xy 170.355895 -24.297084)
			(xy 170.310537 -24.264633) (xy 170.270388 -24.225924) (xy 170.236302 -24.181781) (xy 170.209006 -24.133146)
			(xy 170.189083 -24.081055) (xy 170.176957 -24.026618) (xy 170.172886 -23.970996) (xy 169.943594 -23.970996)
			(xy 169.943525 -23.974752) (xy 169.935405 -24.029928) (xy 169.919337 -24.083335) (xy 169.895665 -24.133832)
			(xy 169.864892 -24.180345) (xy 169.827675 -24.221882) (xy 169.784807 -24.257557) (xy 169.737201 -24.286611)
			(xy 169.685872 -24.308423) (xy 169.631915 -24.322529) (xy 169.576478 -24.328629) (xy 169.520744 -24.326592)
			(xy 169.465901 -24.316462) (xy 169.413117 -24.298455) (xy 169.363517 -24.272954) (xy 169.318159 -24.240503)
			(xy 169.27801 -24.201794) (xy 169.243924 -24.157651) (xy 169.216628 -24.109016) (xy 169.196705 -24.056925)
			(xy 169.184579 -24.002488) (xy 169.180508 -23.946866) (xy 168.940654 -23.946866) (xy 168.940988 -23.965154)
			(xy 168.940479 -23.99304) (xy 168.932359 -24.048216) (xy 168.916291 -24.101623) (xy 168.892619 -24.15212)
			(xy 168.861846 -24.198633) (xy 168.824629 -24.24017) (xy 168.781761 -24.275845) (xy 168.734155 -24.304899)
			(xy 168.682826 -24.326711) (xy 168.628869 -24.340817) (xy 168.573432 -24.346917) (xy 168.517698 -24.34488)
			(xy 168.462855 -24.33475) (xy 168.410071 -24.316743) (xy 168.360471 -24.291242) (xy 168.315113 -24.258791)
			(xy 168.274964 -24.220082) (xy 168.240878 -24.175939) (xy 168.213582 -24.127304) (xy 168.193659 -24.075213)
			(xy 168.181533 -24.020776) (xy 168.177462 -23.965154) (xy 167.402764 -23.965154) (xy 167.402764 -24.807418)
			(xy 174.471328 -24.807418) (xy 174.475399 -24.751796) (xy 174.487525 -24.697359) (xy 174.507448 -24.645268)
			(xy 174.534744 -24.596633) (xy 174.56883 -24.55249) (xy 174.608979 -24.513781) (xy 174.654337 -24.48133)
			(xy 174.703937 -24.455829) (xy 174.756721 -24.437822) (xy 174.811564 -24.427692) (xy 174.867298 -24.425655)
			(xy 174.922735 -24.431755) (xy 174.976692 -24.445861) (xy 175.028021 -24.467673) (xy 175.075627 -24.496727)
			(xy 175.118495 -24.532402) (xy 175.155712 -24.573939) (xy 175.186485 -24.620452) (xy 175.210157 -24.670949)
			(xy 175.226225 -24.724356) (xy 175.234345 -24.779532) (xy 175.234854 -24.807418) (xy 175.234345 -24.835304)
			(xy 175.226225 -24.89048) (xy 175.210157 -24.943887) (xy 175.186485 -24.994384) (xy 175.155712 -25.040897)
			(xy 175.118495 -25.082434) (xy 175.075627 -25.118109) (xy 175.028021 -25.147163) (xy 174.976692 -25.168975)
			(xy 174.922735 -25.183081) (xy 174.867298 -25.189181) (xy 174.811564 -25.187144) (xy 174.756721 -25.177014)
			(xy 174.703937 -25.159007) (xy 174.654337 -25.133506) (xy 174.608979 -25.101055) (xy 174.56883 -25.062346)
			(xy 174.534744 -25.018203) (xy 174.507448 -24.969568) (xy 174.487525 -24.917477) (xy 174.475399 -24.86304)
			(xy 174.471328 -24.807418) (xy 167.402764 -24.807418) (xy 167.402764 -25.912572) (xy 167.402837 -25.916782)
			(xy 167.404239 -25.925084) (xy 167.405558 -25.929082) (xy 167.408098 -25.936448) (xy 167.41267 -25.942544)
			(xy 167.438578 -25.950418) (xy 167.462143 -25.95815) (xy 167.507223 -25.978824) (xy 167.549288 -26.005097)
			(xy 167.58422 -26.03373) (xy 173.367952 -26.03373) (xy 173.372023 -25.978108) (xy 173.384149 -25.923671)
			(xy 173.404072 -25.87158) (xy 173.431368 -25.822945) (xy 173.465454 -25.778802) (xy 173.505603 -25.740093)
			(xy 173.550961 -25.707642) (xy 173.600561 -25.682141) (xy 173.653345 -25.664134) (xy 173.708188 -25.654004)
			(xy 173.763922 -25.651967) (xy 173.819359 -25.658067) (xy 173.873316 -25.672173) (xy 173.924645 -25.693985)
			(xy 173.972251 -25.723039) (xy 174.015119 -25.758714) (xy 174.052336 -25.800251) (xy 174.083109 -25.846764)
			(xy 174.106781 -25.897261) (xy 174.122849 -25.950668) (xy 174.130969 -26.005844) (xy 174.131478 -26.03373)
			(xy 174.130969 -26.061616) (xy 174.122849 -26.116792) (xy 174.106781 -26.170199) (xy 174.083109 -26.220696)
			(xy 174.052336 -26.267209) (xy 174.015119 -26.308746) (xy 173.972251 -26.344421) (xy 173.924645 -26.373475)
			(xy 173.873316 -26.395287) (xy 173.819359 -26.409393) (xy 173.763922 -26.415493) (xy 173.708188 -26.413456)
			(xy 173.653345 -26.403326) (xy 173.600561 -26.385319) (xy 173.550961 -26.359818) (xy 173.505603 -26.327367)
			(xy 173.465454 -26.288658) (xy 173.431368 -26.244515) (xy 173.404072 -26.19588) (xy 173.384149 -26.143789)
			(xy 173.372023 -26.089352) (xy 173.367952 -26.03373) (xy 167.58422 -26.03373) (xy 167.587644 -26.036537)
			(xy 167.604948 -26.054304) (xy 167.62617 -26.077634) (xy 167.661512 -26.129866) (xy 167.68791 -26.18714)
			(xy 167.696896 -26.217372) (xy 167.699182 -26.2255) (xy 168.814496 -27.340814) (xy 168.832525 -27.359586)
			(xy 168.8631 -27.401704) (xy 168.886721 -27.448081) (xy 168.902808 -27.497578) (xy 168.910968 -27.54898)
			(xy 168.911524 -27.575002) (xy 168.911524 -28.139136) (xy 170.498006 -28.139136) (xy 170.502077 -28.083514)
			(xy 170.514203 -28.029077) (xy 170.534126 -27.976986) (xy 170.561422 -27.928351) (xy 170.595508 -27.884208)
			(xy 170.635657 -27.845499) (xy 170.681015 -27.813048) (xy 170.730615 -27.787547) (xy 170.783399 -27.76954)
			(xy 170.838242 -27.75941) (xy 170.893976 -27.757373) (xy 170.949413 -27.763473) (xy 171.00337 -27.777579)
			(xy 171.054699 -27.799391) (xy 171.102305 -27.828445) (xy 171.145173 -27.86412) (xy 171.18239 -27.905657)
			(xy 171.213163 -27.95217) (xy 171.236835 -28.002667) (xy 171.252903 -28.056074) (xy 171.261023 -28.11125)
			(xy 171.261532 -28.139136) (xy 171.768006 -28.139136) (xy 171.772077 -28.083514) (xy 171.784203 -28.029077)
			(xy 171.804126 -27.976986) (xy 171.831422 -27.928351) (xy 171.865508 -27.884208) (xy 171.905657 -27.845499)
			(xy 171.951015 -27.813048) (xy 172.000615 -27.787547) (xy 172.053399 -27.76954) (xy 172.108242 -27.75941)
			(xy 172.163976 -27.757373) (xy 172.219413 -27.763473) (xy 172.27337 -27.777579) (xy 172.324699 -27.799391)
			(xy 172.372305 -27.828445) (xy 172.415173 -27.86412) (xy 172.45239 -27.905657) (xy 172.483163 -27.95217)
			(xy 172.506835 -28.002667) (xy 172.522903 -28.056074) (xy 172.531023 -28.11125) (xy 172.531532 -28.139136)
			(xy 172.531023 -28.167022) (xy 172.522903 -28.222198) (xy 172.506835 -28.275605) (xy 172.483163 -28.326102)
			(xy 172.45239 -28.372615) (xy 172.415173 -28.414152) (xy 172.372305 -28.449827) (xy 172.324699 -28.478881)
			(xy 172.27337 -28.500693) (xy 172.219413 -28.514799) (xy 172.163976 -28.520899) (xy 172.108242 -28.518862)
			(xy 172.053399 -28.508732) (xy 172.000615 -28.490725) (xy 171.951015 -28.465224) (xy 171.905657 -28.432773)
			(xy 171.865508 -28.394064) (xy 171.831422 -28.349921) (xy 171.804126 -28.301286) (xy 171.784203 -28.249195)
			(xy 171.772077 -28.194758) (xy 171.768006 -28.139136) (xy 171.261532 -28.139136) (xy 171.261023 -28.167022)
			(xy 171.252903 -28.222198) (xy 171.236835 -28.275605) (xy 171.213163 -28.326102) (xy 171.18239 -28.372615)
			(xy 171.145173 -28.414152) (xy 171.102305 -28.449827) (xy 171.054699 -28.478881) (xy 171.00337 -28.500693)
			(xy 170.949413 -28.514799) (xy 170.893976 -28.520899) (xy 170.838242 -28.518862) (xy 170.783399 -28.508732)
			(xy 170.730615 -28.490725) (xy 170.681015 -28.465224) (xy 170.635657 -28.432773) (xy 170.595508 -28.394064)
			(xy 170.561422 -28.349921) (xy 170.534126 -28.301286) (xy 170.514203 -28.249195) (xy 170.502077 -28.194758)
			(xy 170.498006 -28.139136) (xy 168.911524 -28.139136) (xy 168.911524 -29.289756) (xy 168.91204 -29.299946)
			(xy 168.92006 -29.318688) (xy 168.934707 -29.332868) (xy 168.944036 -29.337) (xy 169.032682 -29.37129)
			(xy 169.039906 -29.373805) (xy 169.05516 -29.374854) (xy 169.062654 -29.373322) (xy 169.07002 -29.371544)
			(xy 169.082974 -29.363924) (xy 169.088308 -29.358082) (xy 169.106463 -29.338799) (xy 169.14718 -29.304931)
			(xy 169.192191 -29.277023) (xy 169.240631 -29.255612) (xy 169.291568 -29.24111) (xy 169.344021 -29.233796)
			(xy 169.370502 -29.233368) (xy 169.397754 -29.233854) (xy 169.451703 -29.241611) (xy 169.503998 -29.256966)
			(xy 169.553577 -29.279607) (xy 169.599429 -29.309072) (xy 169.640621 -29.344764) (xy 169.676314 -29.385954)
			(xy 169.705783 -29.431804) (xy 169.728427 -29.481381) (xy 169.743785 -29.533676) (xy 169.751545 -29.587624)
			(xy 169.75201 -29.614876) (xy 169.751518 -29.642905) (xy 169.743325 -29.698362) (xy 169.72711 -29.752025)
			(xy 169.703223 -29.80274) (xy 169.672177 -29.849416) (xy 169.634639 -29.891052) (xy 169.613326 -29.909262)
			(xy 169.609008 -29.912564) (xy 169.60215 -29.9212) (xy 169.590466 -29.94533) (xy 169.58812 -29.950552)
			(xy 169.585549 -29.961706) (xy 169.585386 -29.967428) (xy 169.585386 -30.024324) (xy 169.585531 -30.03005)
			(xy 169.58809 -30.041211) (xy 169.590466 -30.046422) (xy 169.60215 -30.070552) (xy 169.609008 -30.079188)
			(xy 169.613326 -30.08249) (xy 169.634623 -30.100717) (xy 169.672162 -30.142347) (xy 169.703208 -30.189021)
			(xy 169.727093 -30.239733) (xy 169.743304 -30.293394) (xy 169.751492 -30.348848) (xy 169.75201 -30.376876)
			(xy 169.751548 -30.40413) (xy 169.743794 -30.458084) (xy 169.72844 -30.510384) (xy 169.705799 -30.559968)
			(xy 169.676332 -30.605824) (xy 169.640638 -30.64702) (xy 169.599445 -30.682716) (xy 169.553591 -30.712187)
			(xy 169.504009 -30.734831) (xy 169.451709 -30.750189) (xy 169.397756 -30.757946) (xy 169.370502 -30.758384)
			(xy 169.369994 -30.758384) (xy 169.343568 -30.757914) (xy 169.291228 -30.750578) (xy 169.240401 -30.736089)
			(xy 169.192059 -30.714724) (xy 169.147129 -30.686892) (xy 169.10647 -30.653126) (xy 169.088308 -30.633924)
			(xy 169.082933 -30.62835) (xy 169.069618 -30.620459) (xy 169.062146 -30.61843) (xy 169.055034 -30.616652)
			(xy 169.040048 -30.617668) (xy 168.944036 -30.654752) (xy 168.934667 -30.658831) (xy 168.919968 -30.672999)
			(xy 168.911981 -30.691788) (xy 168.911524 -30.701996) (xy 168.911524 -31.567882) (xy 169.09872 -31.567882)
			(xy 169.102791 -31.51226) (xy 169.114917 -31.457823) (xy 169.13484 -31.405732) (xy 169.162136 -31.357097)
			(xy 169.196222 -31.312954) (xy 169.236371 -31.274245) (xy 169.281729 -31.241794) (xy 169.331329 -31.216293)
			(xy 169.384113 -31.198286) (xy 169.438956 -31.188156) (xy 169.49469 -31.186119) (xy 169.550127 -31.192219)
			(xy 169.604084 -31.206325) (xy 169.655413 -31.228137) (xy 169.703019 -31.257191) (xy 169.745887 -31.292866)
			(xy 169.783104 -31.334403) (xy 169.813877 -31.380916) (xy 169.837549 -31.431413) (xy 169.853617 -31.48482)
			(xy 169.861737 -31.539996) (xy 169.862246 -31.567882) (xy 169.861737 -31.595768) (xy 169.853617 -31.650944)
			(xy 169.837549 -31.704351) (xy 169.830557 -31.719266) (xy 170.385484 -31.719266) (xy 170.389555 -31.663644)
			(xy 170.401681 -31.609207) (xy 170.421604 -31.557116) (xy 170.4489 -31.508481) (xy 170.482986 -31.464338)
			(xy 170.523135 -31.425629) (xy 170.568493 -31.393178) (xy 170.618093 -31.367677) (xy 170.670877 -31.34967)
			(xy 170.72572 -31.33954) (xy 170.781454 -31.337503) (xy 170.836891 -31.343603) (xy 170.890848 -31.357709)
			(xy 170.942177 -31.379521) (xy 170.989783 -31.408575) (xy 171.032651 -31.44425) (xy 171.069868 -31.485787)
			(xy 171.100641 -31.5323) (xy 171.124313 -31.582797) (xy 171.140381 -31.636204) (xy 171.144531 -31.664402)
			(xy 171.661072 -31.664402) (xy 171.665143 -31.60878) (xy 171.677269 -31.554343) (xy 171.697192 -31.502252)
			(xy 171.724488 -31.453617) (xy 171.758574 -31.409474) (xy 171.798723 -31.370765) (xy 171.844081 -31.338314)
			(xy 171.893681 -31.312813) (xy 171.946465 -31.294806) (xy 172.001308 -31.284676) (xy 172.057042 -31.282639)
			(xy 172.112479 -31.288739) (xy 172.166436 -31.302845) (xy 172.217765 -31.324657) (xy 172.265371 -31.353711)
			(xy 172.308239 -31.389386) (xy 172.345456 -31.430923) (xy 172.376229 -31.477436) (xy 172.399901 -31.527933)
			(xy 172.415969 -31.58134) (xy 172.424089 -31.636516) (xy 172.424598 -31.664402) (xy 172.424089 -31.692288)
			(xy 172.415969 -31.747464) (xy 172.399901 -31.800871) (xy 172.376229 -31.851368) (xy 172.345456 -31.897881)
			(xy 172.308239 -31.939418) (xy 172.265371 -31.975093) (xy 172.217765 -32.004147) (xy 172.166436 -32.025959)
			(xy 172.112479 -32.040065) (xy 172.057042 -32.046165) (xy 172.001308 -32.044128) (xy 171.946465 -32.033998)
			(xy 171.893681 -32.015991) (xy 171.844081 -31.99049) (xy 171.798723 -31.958039) (xy 171.758574 -31.91933)
			(xy 171.724488 -31.875187) (xy 171.697192 -31.826552) (xy 171.677269 -31.774461) (xy 171.665143 -31.720024)
			(xy 171.661072 -31.664402) (xy 171.144531 -31.664402) (xy 171.148501 -31.69138) (xy 171.14901 -31.719266)
			(xy 171.148501 -31.747152) (xy 171.140381 -31.802328) (xy 171.124313 -31.855735) (xy 171.100641 -31.906232)
			(xy 171.069868 -31.952745) (xy 171.032651 -31.994282) (xy 170.989783 -32.029957) (xy 170.942177 -32.059011)
			(xy 170.890848 -32.080823) (xy 170.836891 -32.094929) (xy 170.781454 -32.101029) (xy 170.72572 -32.098992)
			(xy 170.670877 -32.088862) (xy 170.618093 -32.070855) (xy 170.568493 -32.045354) (xy 170.523135 -32.012903)
			(xy 170.482986 -31.974194) (xy 170.4489 -31.930051) (xy 170.421604 -31.881416) (xy 170.401681 -31.829325)
			(xy 170.389555 -31.774888) (xy 170.385484 -31.719266) (xy 169.830557 -31.719266) (xy 169.813877 -31.754848)
			(xy 169.783104 -31.801361) (xy 169.745887 -31.842898) (xy 169.703019 -31.878573) (xy 169.655413 -31.907627)
			(xy 169.604084 -31.929439) (xy 169.550127 -31.943545) (xy 169.49469 -31.949645) (xy 169.438956 -31.947608)
			(xy 169.384113 -31.937478) (xy 169.331329 -31.919471) (xy 169.281729 -31.89397) (xy 169.236371 -31.861519)
			(xy 169.196222 -31.82281) (xy 169.162136 -31.778667) (xy 169.13484 -31.730032) (xy 169.114917 -31.677941)
			(xy 169.102791 -31.623504) (xy 169.09872 -31.567882) (xy 168.911524 -31.567882) (xy 168.911524 -33.023556)
			(xy 168.911692 -33.029565) (xy 168.914518 -33.041246) (xy 168.917112 -33.04667) (xy 168.918949 -33.050146)
			(xy 168.923539 -33.056528) (xy 168.926256 -33.05937) (xy 171.131738 -35.264852) (xy 172.002448 -35.264852)
			(xy 172.006519 -35.20923) (xy 172.018645 -35.154793) (xy 172.038568 -35.102702) (xy 172.065864 -35.054067)
			(xy 172.09995 -35.009924) (xy 172.140099 -34.971215) (xy 172.185457 -34.938764) (xy 172.235057 -34.913263)
			(xy 172.287841 -34.895256) (xy 172.342684 -34.885126) (xy 172.398418 -34.883089) (xy 172.453855 -34.889189)
			(xy 172.507812 -34.903295) (xy 172.559141 -34.925107) (xy 172.606747 -34.954161) (xy 172.649615 -34.989836)
			(xy 172.686832 -35.031373) (xy 172.717605 -35.077886) (xy 172.741277 -35.128383) (xy 172.757345 -35.18179)
			(xy 172.765465 -35.236966) (xy 172.765974 -35.264852) (xy 172.765465 -35.292738) (xy 172.757345 -35.347914)
			(xy 172.741277 -35.401321) (xy 172.717605 -35.451818) (xy 172.686832 -35.498331) (xy 172.649615 -35.539868)
			(xy 172.606747 -35.575543) (xy 172.559141 -35.604597) (xy 172.507812 -35.626409) (xy 172.453855 -35.640515)
			(xy 172.398418 -35.646615) (xy 172.342684 -35.644578) (xy 172.287841 -35.634448) (xy 172.235057 -35.616441)
			(xy 172.185457 -35.59094) (xy 172.140099 -35.558489) (xy 172.09995 -35.51978) (xy 172.065864 -35.475637)
			(xy 172.038568 -35.427002) (xy 172.018645 -35.374911) (xy 172.006519 -35.320474) (xy 172.002448 -35.264852)
			(xy 171.131738 -35.264852) (xy 172.153834 -36.286948) (xy 173.300388 -36.286948) (xy 173.304459 -36.231326)
			(xy 173.316585 -36.176889) (xy 173.336508 -36.124798) (xy 173.363804 -36.076163) (xy 173.39789 -36.03202)
			(xy 173.438039 -35.993311) (xy 173.483397 -35.96086) (xy 173.532997 -35.935359) (xy 173.585781 -35.917352)
			(xy 173.640624 -35.907222) (xy 173.696358 -35.905185) (xy 173.751795 -35.911285) (xy 173.805752 -35.925391)
			(xy 173.857081 -35.947203) (xy 173.904687 -35.976257) (xy 173.947555 -36.011932) (xy 173.984772 -36.053469)
			(xy 174.015545 -36.099982) (xy 174.039217 -36.150479) (xy 174.055285 -36.203886) (xy 174.063405 -36.259062)
			(xy 174.063914 -36.286948) (xy 174.063405 -36.314834) (xy 174.055285 -36.37001) (xy 174.039217 -36.423417)
			(xy 174.015545 -36.473914) (xy 173.984772 -36.520427) (xy 173.947555 -36.561964) (xy 173.904687 -36.597639)
			(xy 173.857081 -36.626693) (xy 173.805752 -36.648505) (xy 173.751795 -36.662611) (xy 173.696358 -36.668711)
			(xy 173.640624 -36.666674) (xy 173.585781 -36.656544) (xy 173.532997 -36.638537) (xy 173.483397 -36.613036)
			(xy 173.438039 -36.580585) (xy 173.39789 -36.541876) (xy 173.363804 -36.497733) (xy 173.336508 -36.449098)
			(xy 173.316585 -36.397007) (xy 173.304459 -36.34257) (xy 173.300388 -36.286948) (xy 172.153834 -36.286948)
			(xy 173.461934 -37.595048) (xy 173.470548 -37.602853) (xy 173.492508 -37.610402) (xy 173.504098 -37.609526)
			(xy 173.583346 -37.600128) (xy 173.589092 -37.599285) (xy 173.600004 -37.595319) (xy 173.604936 -37.592254)
			(xy 173.608746 -37.589714) (xy 173.617128 -37.581586) (xy 173.620684 -37.575998) (xy 173.635625 -37.55238)
			(xy 173.671325 -37.509382) (xy 173.712911 -37.472046) (xy 173.759494 -37.441171) (xy 173.81008 -37.417415)
			(xy 173.863589 -37.401286) (xy 173.918877 -37.393129) (xy 173.94682 -37.39261) (xy 173.97407 -37.393098)
			(xy 174.028014 -37.400857) (xy 174.080306 -37.416214) (xy 174.129879 -37.438856) (xy 174.175726 -37.468323)
			(xy 174.216912 -37.504015) (xy 174.2526 -37.545205) (xy 174.282062 -37.591054) (xy 174.3047 -37.64063)
			(xy 174.320052 -37.692923) (xy 174.327805 -37.746868) (xy 174.328328 -37.774118) (xy 174.327846 -37.802066)
			(xy 174.319704 -37.857365) (xy 174.303584 -37.910884) (xy 174.279829 -37.96148) (xy 174.248947 -38.00807)
			(xy 174.2116 -38.049657) (xy 174.168587 -38.085351) (xy 174.14494 -38.100254) (xy 174.139352 -38.10381)
			(xy 174.13478 -38.108636) (xy 174.12843 -38.116256) (xy 174.125636 -38.121082) (xy 174.121572 -38.13175)
			(xy 174.111412 -38.21684) (xy 174.110504 -38.228252) (xy 174.117781 -38.249935) (xy 174.125382 -38.258496)
			(xy 174.770288 -38.903148) (xy 175.087788 -39.220648) (xy 175.094471 -39.226767) (xy 175.110961 -39.234249)
			(xy 175.129025 -39.235511) (xy 175.137826 -39.233348) (xy 175.14316 -39.231062) (xy 175.149979 -39.227977)
			(xy 175.161604 -39.218562) (xy 175.16602 -39.21252) (xy 175.16983 -39.206932) (xy 175.174148 -39.192454)
			(xy 175.174148 -36.734496) (xy 175.173958 -36.728551) (xy 175.171132 -36.717) (xy 175.16856 -36.711636)
			(xy 175.166274 -36.707318) (xy 175.158356 -36.693366) (xy 175.144624 -36.66437) (xy 175.138842 -36.649406)
			(xy 175.137572 -36.64585) (xy 175.134778 -36.637722) (xy 175.134524 -36.637214) (xy 175.133762 -36.634674)
			(xy 175.133508 -36.633912) (xy 175.132746 -36.631626) (xy 175.132238 -36.630102) (xy 175.131476 -36.62807)
			(xy 175.13046 -36.625022) (xy 175.12919 -36.621974) (xy 175.127226 -36.618145) (xy 175.122242 -36.61113)
			(xy 175.119284 -36.608004) (xy 173.628812 -35.117532) (xy 173.61078 -35.098761) (xy 173.580199 -35.056645)
			(xy 173.556571 -35.010268) (xy 173.540476 -34.960771) (xy 173.532309 -34.909368) (xy 173.531784 -34.883344)
			(xy 173.531784 -32.411162) (xy 173.522894 -32.402018) (xy 173.51502 -32.395414) (xy 173.493176 -32.377634)
			(xy 173.461172 -32.351472) (xy 173.453298 -32.345376) (xy 173.42993 -32.350202) (xy 173.429676 -32.350202)
			(xy 173.412993 -32.353667) (xy 173.379316 -32.35888) (xy 173.362366 -32.360616) (xy 173.348872 -32.361802)
			(xy 173.32181 -32.363071) (xy 173.308264 -32.363156) (xy 173.261528 -32.363156) (xy 173.261528 -32.361378)
			(xy 173.228081 -32.358235) (xy 173.162164 -32.345253) (xy 173.098166 -32.324813) (xy 173.036928 -32.297184)
			(xy 172.979253 -32.262729) (xy 172.9259 -32.221901) (xy 172.877569 -32.175235) (xy 172.834896 -32.123345)
			(xy 172.798441 -32.066914) (xy 172.768683 -32.006681) (xy 172.746013 -31.943439) (xy 172.730729 -31.878018)
			(xy 172.723032 -31.811277) (xy 172.72254 -31.777686) (xy 172.72254 -30.776164) (xy 172.719746 -30.772862)
			(xy 172.715682 -30.76829) (xy 172.638212 -30.720284) (xy 172.630639 -30.716166) (xy 172.613745 -30.712792)
			(xy 172.596697 -30.715266) (xy 172.588936 -30.719014) (xy 172.586396 -30.720284) (xy 172.578014 -30.724348)
			(xy 172.57014 -30.727904) (xy 172.54498 -30.738839) (xy 172.492346 -30.754297) (xy 172.438056 -30.762164)
			(xy 172.410628 -30.762702) (xy 172.383066 -30.762236) (xy 172.328503 -30.754394) (xy 172.275611 -30.738866)
			(xy 172.225468 -30.715969) (xy 172.179094 -30.686168) (xy 172.137433 -30.650069) (xy 172.101335 -30.60841)
			(xy 172.071533 -30.562036) (xy 172.048635 -30.511893) (xy 172.033107 -30.459001) (xy 172.025265 -30.404438)
			(xy 172.024802 -30.376876) (xy 172.025312 -30.348467) (xy 172.033666 -30.292267) (xy 172.050189 -30.237905)
			(xy 172.074523 -30.186562) (xy 172.106138 -30.139352) (xy 172.144348 -30.097302) (xy 172.166026 -30.078934)
			(xy 172.166534 -30.078426) (xy 172.172122 -30.0736) (xy 172.176186 -30.070298) (xy 172.179742 -30.066234)
			(xy 172.185584 -30.057344) (xy 172.192188 -30.04312) (xy 172.193855 -30.038668) (xy 172.195643 -30.029331)
			(xy 172.195744 -30.024578) (xy 172.195744 -29.967682) (xy 172.195602 -29.962242) (xy 172.193295 -29.95161)
			(xy 172.191172 -29.9466) (xy 172.18787 -29.939742) (xy 172.18787 -29.939234) (xy 172.181012 -29.925518)
			(xy 172.17263 -29.914088) (xy 172.167804 -29.909262) (xy 172.166026 -29.907738) (xy 172.145001 -29.889499)
			(xy 172.107939 -29.847972) (xy 172.0773 -29.801506) (xy 172.05373 -29.751083) (xy 172.03773 -29.697773)
			(xy 172.029639 -29.642706) (xy 172.02912 -29.614876) (xy 172.029585 -29.587625) (xy 172.037345 -29.533678)
			(xy 172.052703 -29.481385) (xy 172.075348 -29.431809) (xy 172.104817 -29.385961) (xy 172.140511 -29.344774)
			(xy 172.181703 -29.309085) (xy 172.227555 -29.279623) (xy 172.277134 -29.256985) (xy 172.329429 -29.241634)
			(xy 172.383377 -29.233881) (xy 172.410628 -29.233368) (xy 172.410882 -29.233368) (xy 172.439819 -29.233897)
			(xy 172.49703 -29.242632) (xy 172.552262 -29.259917) (xy 172.604245 -29.285357) (xy 172.628306 -29.30144)
			(xy 172.62856 -29.301694) (xy 172.633181 -29.304767) (xy 172.643436 -29.308999) (xy 172.64888 -29.310076)
			(xy 172.65904 -29.311854) (xy 172.747432 -29.288232) (xy 172.756072 -29.285106) (xy 172.770519 -29.273773)
			(xy 172.775626 -29.266134) (xy 172.777912 -29.261308) (xy 172.792743 -29.230915) (xy 172.828387 -29.173439)
			(xy 172.870404 -29.120444) (xy 172.89399 -29.096208) (xy 175.33239 -26.657808) (xy 175.337382 -26.652311)
			(xy 175.344236 -26.639146) (xy 175.345852 -26.6319) (xy 175.346868 -26.622248) (xy 175.346868 -24.158194)
			(xy 175.347364 -24.124094) (xy 175.355281 -24.056354) (xy 175.37101 -23.989991) (xy 175.394336 -23.925903)
			(xy 175.424944 -23.864957) (xy 175.462421 -23.807976) (xy 175.50626 -23.755731) (xy 175.555867 -23.708928)
			(xy 175.610573 -23.668202) (xy 175.669637 -23.634101) (xy 175.73226 -23.607088) (xy 175.797596 -23.587528)
			(xy 175.86476 -23.575685) (xy 175.932846 -23.57172) (xy 176.000932 -23.575685) (xy 176.068096 -23.587528)
			(xy 176.133432 -23.607088) (xy 176.196055 -23.634101) (xy 176.255119 -23.668202) (xy 176.309825 -23.708928)
			(xy 176.359432 -23.755731) (xy 176.403271 -23.807976) (xy 176.440748 -23.864957) (xy 176.471356 -23.925903)
			(xy 176.494682 -23.989991) (xy 176.510411 -24.056354) (xy 176.518328 -24.124094) (xy 176.518824 -24.158194)
			(xy 176.518824 -24.807418) (xy 176.720244 -24.807418) (xy 176.724315 -24.751796) (xy 176.736441 -24.697359)
			(xy 176.756364 -24.645268) (xy 176.78366 -24.596633) (xy 176.817746 -24.55249) (xy 176.857895 -24.513781)
			(xy 176.903253 -24.48133) (xy 176.952853 -24.455829) (xy 177.005637 -24.437822) (xy 177.06048 -24.427692)
			(xy 177.116214 -24.425655) (xy 177.171651 -24.431755) (xy 177.225608 -24.445861) (xy 177.276937 -24.467673)
			(xy 177.324543 -24.496727) (xy 177.367411 -24.532402) (xy 177.404628 -24.573939) (xy 177.435401 -24.620452)
			(xy 177.459073 -24.670949) (xy 177.475141 -24.724356) (xy 177.483261 -24.779532) (xy 177.48377 -24.807418)
			(xy 177.483261 -24.835304) (xy 177.475141 -24.89048) (xy 177.459073 -24.943887) (xy 177.435401 -24.994384)
			(xy 177.404628 -25.040897) (xy 177.367411 -25.082434) (xy 177.324543 -25.118109) (xy 177.276937 -25.147163)
			(xy 177.225608 -25.168975) (xy 177.171651 -25.183081) (xy 177.116214 -25.189181) (xy 177.06048 -25.187144)
			(xy 177.005637 -25.177014) (xy 176.952853 -25.159007) (xy 176.903253 -25.133506) (xy 176.857895 -25.101055)
			(xy 176.817746 -25.062346) (xy 176.78366 -25.018203) (xy 176.756364 -24.969568) (xy 176.736441 -24.917477)
			(xy 176.724315 -24.86304) (xy 176.720244 -24.807418) (xy 176.518824 -24.807418) (xy 176.518824 -26.724102)
			(xy 176.521085 -26.727027) (xy 176.526316 -26.732251) (xy 176.529238 -26.734516) (xy 176.823878 -26.734516)
			(xy 176.826418 -26.734516) (xy 176.831778 -26.734089) (xy 176.842154 -26.731275) (xy 176.846992 -26.728928)
			(xy 176.870614 -26.716228) (xy 176.876456 -26.713434) (xy 176.876964 -26.71318) (xy 176.885854 -26.70556)
			(xy 176.889664 -26.700226) (xy 176.895051 -26.691799) (xy 176.89954 -26.672328) (xy 176.896289 -26.652612)
			(xy 176.885787 -26.635613) (xy 176.87798 -26.62936) (xy 176.872138 -26.625296) (xy 176.866042 -26.62301)
			(xy 176.839348 -26.61224) (xy 176.789284 -26.583838) (xy 176.744052 -26.548241) (xy 176.704677 -26.506256)
			(xy 176.672053 -26.458835) (xy 176.646919 -26.407052) (xy 176.629845 -26.352083) (xy 176.621218 -26.295174)
			(xy 176.620678 -26.266394) (xy 176.621164 -26.239143) (xy 176.62892 -26.185195) (xy 176.644275 -26.1329)
			(xy 176.666917 -26.083323) (xy 176.696383 -26.037473) (xy 176.732074 -25.996282) (xy 176.773265 -25.960591)
			(xy 176.819115 -25.931125) (xy 176.868692 -25.908483) (xy 176.920987 -25.893128) (xy 176.974935 -25.885372)
			(xy 177.029437 -25.885372) (xy 177.083385 -25.893128) (xy 177.13568 -25.908483) (xy 177.185257 -25.931125)
			(xy 177.231107 -25.960591) (xy 177.272298 -25.996282) (xy 177.307989 -26.037473) (xy 177.337455 -26.083323)
			(xy 177.360097 -26.1329) (xy 177.375452 -26.185195) (xy 177.383208 -26.239143) (xy 177.383694 -26.266394)
			(xy 177.38316 -26.295311) (xy 177.374434 -26.352482) (xy 177.35718 -26.407682) (xy 177.331795 -26.459647)
			(xy 177.298858 -26.507185) (xy 177.259125 -26.549209) (xy 177.236628 -26.567384) (xy 177.232056 -26.57094)
			(xy 177.222658 -26.58237) (xy 177.220367 -26.585228) (xy 177.216545 -26.591477) (xy 177.215038 -26.594816)
			(xy 177.215038 -26.595324) (xy 177.212928 -26.600592) (xy 177.21087 -26.611749) (xy 177.210974 -26.617422)
			(xy 177.212244 -26.643838) (xy 177.212244 -26.644346) (xy 177.215038 -26.690574) (xy 177.217832 -26.702766)
			(xy 177.223928 -26.713942) (xy 177.226917 -26.718651) (xy 177.234615 -26.72672) (xy 177.239168 -26.729944)
			(xy 177.240184 -26.730706) (xy 177.241708 -26.731468) (xy 177.266228 -26.746625) (xy 177.310924 -26.783027)
			(xy 177.34977 -26.825616) (xy 177.381919 -26.873462) (xy 177.40667 -26.925522) (xy 177.423481 -26.980659)
			(xy 177.431988 -27.037672) (xy 177.432462 -27.066494) (xy 177.431989 -27.094345) (xy 177.424062 -27.149481)
			(xy 177.408369 -27.202927) (xy 177.385229 -27.253595) (xy 177.355113 -27.300454) (xy 177.318635 -27.342551)
			(xy 177.276537 -27.379027) (xy 177.229676 -27.40914) (xy 177.179006 -27.432277) (xy 177.125559 -27.447967)
			(xy 177.070423 -27.455891) (xy 177.042572 -27.456384) (xy 177.042318 -27.456384) (xy 177.016998 -27.455978)
			(xy 176.966782 -27.449429) (xy 176.917833 -27.436452) (xy 176.870968 -27.417263) (xy 176.84877 -27.405076)
			(xy 176.842928 -27.401774) (xy 176.836832 -27.40025) (xy 176.823878 -27.398472) (xy 176.699164 -27.398472)
			(xy 176.689199 -27.398952) (xy 176.670764 -27.406529) (xy 176.66335 -27.413204) (xy 175.11014 -28.965906)
			(xy 174.95372 -29.12237) (xy 176.706784 -29.12237) (xy 176.706784 -28.25877) (xy 176.707274 -28.228786)
			(xy 176.715102 -28.16933) (xy 176.730623 -28.111405) (xy 176.753572 -28.056001) (xy 176.783556 -28.004067)
			(xy 176.820062 -27.956491) (xy 176.862467 -27.914086) (xy 176.910043 -27.87758) (xy 176.961977 -27.847596)
			(xy 177.017381 -27.824647) (xy 177.075306 -27.809126) (xy 177.134762 -27.801298) (xy 177.19473 -27.801298)
			(xy 177.254186 -27.809126) (xy 177.312111 -27.824647) (xy 177.367515 -27.847596) (xy 177.419449 -27.87758)
			(xy 177.467025 -27.914086) (xy 177.50943 -27.956491) (xy 177.545936 -28.004067) (xy 177.57592 -28.056001)
			(xy 177.598869 -28.111405) (xy 177.61439 -28.16933) (xy 177.622218 -28.228786) (xy 177.622708 -28.25877)
			(xy 177.622708 -29.12237) (xy 177.622218 -29.152354) (xy 177.61439 -29.21181) (xy 177.598869 -29.269735)
			(xy 177.57592 -29.325139) (xy 177.545936 -29.377073) (xy 177.50943 -29.424649) (xy 177.467025 -29.467054)
			(xy 177.419449 -29.50356) (xy 177.367515 -29.533544) (xy 177.312111 -29.556493) (xy 177.254186 -29.572014)
			(xy 177.19473 -29.579842) (xy 177.134762 -29.579842) (xy 177.075306 -29.572014) (xy 177.017381 -29.556493)
			(xy 176.961977 -29.533544) (xy 176.910043 -29.50356) (xy 176.862467 -29.467054) (xy 176.820062 -29.424649)
			(xy 176.783556 -29.377073) (xy 176.753572 -29.325139) (xy 176.730623 -29.269735) (xy 176.715102 -29.21181)
			(xy 176.707274 -29.152354) (xy 176.706784 -29.12237) (xy 174.95372 -29.12237) (xy 174.200058 -29.876242)
			(xy 174.195232 -29.88183) (xy 174.195232 -30.922468) (xy 174.852584 -30.922468) (xy 174.852584 -30.058868)
			(xy 174.853074 -30.028884) (xy 174.860902 -29.969428) (xy 174.876423 -29.911503) (xy 174.899372 -29.856099)
			(xy 174.929356 -29.804165) (xy 174.965862 -29.756589) (xy 175.008267 -29.714184) (xy 175.055843 -29.677678)
			(xy 175.107777 -29.647694) (xy 175.163181 -29.624745) (xy 175.221106 -29.609224) (xy 175.280562 -29.601396)
			(xy 175.34053 -29.601396) (xy 175.399986 -29.609224) (xy 175.457911 -29.624745) (xy 175.513315 -29.647694)
			(xy 175.565249 -29.677678) (xy 175.612825 -29.714184) (xy 175.65523 -29.756589) (xy 175.691736 -29.804165)
			(xy 175.72172 -29.856099) (xy 175.744669 -29.911503) (xy 175.76019 -29.969428) (xy 175.768018 -30.028884)
			(xy 175.768508 -30.058868) (xy 175.768508 -30.92069) (xy 189.589664 -30.92069) (xy 189.589664 -30.05709)
			(xy 189.590154 -30.027122) (xy 189.597977 -29.9677) (xy 189.61349 -29.909807) (xy 189.636426 -29.854434)
			(xy 189.666393 -29.802528) (xy 189.70288 -29.754978) (xy 189.74526 -29.712598) (xy 189.79281 -29.676111)
			(xy 189.844716 -29.646144) (xy 189.900089 -29.623208) (xy 189.957982 -29.607695) (xy 190.017404 -29.599872)
			(xy 190.07734 -29.599872) (xy 190.136762 -29.607695) (xy 190.194655 -29.623208) (xy 190.250028 -29.646144)
			(xy 190.301934 -29.676111) (xy 190.349484 -29.712598) (xy 190.391864 -29.754978) (xy 190.428351 -29.802528)
			(xy 190.458318 -29.854434) (xy 190.481254 -29.909807) (xy 190.496767 -29.9677) (xy 190.50459 -30.027122)
			(xy 190.50508 -30.05709) (xy 190.50508 -30.92069) (xy 190.50459 -30.950658) (xy 190.496767 -31.01008)
			(xy 190.481254 -31.067973) (xy 190.458318 -31.123346) (xy 190.428351 -31.175252) (xy 190.391864 -31.222802)
			(xy 190.349484 -31.265182) (xy 190.301934 -31.301669) (xy 190.250028 -31.331636) (xy 190.194655 -31.354572)
			(xy 190.136762 -31.370085) (xy 190.07734 -31.377908) (xy 190.017404 -31.377908) (xy 189.957982 -31.370085)
			(xy 189.900089 -31.354572) (xy 189.844716 -31.331636) (xy 189.79281 -31.301669) (xy 189.74526 -31.265182)
			(xy 189.70288 -31.222802) (xy 189.666393 -31.175252) (xy 189.636426 -31.123346) (xy 189.61349 -31.067973)
			(xy 189.597977 -31.01008) (xy 189.590154 -30.950658) (xy 189.589664 -30.92069) (xy 175.768508 -30.92069)
			(xy 175.768508 -30.922468) (xy 175.768018 -30.952452) (xy 175.76019 -31.011908) (xy 175.744669 -31.069833)
			(xy 175.72172 -31.125237) (xy 175.691736 -31.177171) (xy 175.65523 -31.224747) (xy 175.612825 -31.267152)
			(xy 175.565249 -31.303658) (xy 175.513315 -31.333642) (xy 175.457911 -31.356591) (xy 175.399986 -31.372112)
			(xy 175.34053 -31.37994) (xy 175.280562 -31.37994) (xy 175.221106 -31.372112) (xy 175.163181 -31.356591)
			(xy 175.107777 -31.333642) (xy 175.055843 -31.303658) (xy 175.008267 -31.267152) (xy 174.965862 -31.224747)
			(xy 174.929356 -31.177171) (xy 174.899372 -31.125237) (xy 174.876423 -31.069833) (xy 174.860902 -31.011908)
			(xy 174.853074 -30.952452) (xy 174.852584 -30.922468) (xy 174.195232 -30.922468) (xy 174.195232 -32.722312)
			(xy 176.706784 -32.722312) (xy 176.706784 -31.858712) (xy 176.707274 -31.828728) (xy 176.715102 -31.769272)
			(xy 176.730623 -31.711347) (xy 176.753572 -31.655943) (xy 176.783556 -31.604009) (xy 176.820062 -31.556433)
			(xy 176.862467 -31.514028) (xy 176.910043 -31.477522) (xy 176.961977 -31.447538) (xy 177.017381 -31.424589)
			(xy 177.075306 -31.409068) (xy 177.134762 -31.40124) (xy 177.19473 -31.40124) (xy 177.254186 -31.409068)
			(xy 177.312111 -31.424589) (xy 177.367515 -31.447538) (xy 177.419449 -31.477522) (xy 177.467025 -31.514028)
			(xy 177.50943 -31.556433) (xy 177.545936 -31.604009) (xy 177.57592 -31.655943) (xy 177.598869 -31.711347)
			(xy 177.61439 -31.769272) (xy 177.622218 -31.828728) (xy 177.622708 -31.858712) (xy 177.622708 -32.714184)
			(xy 186.947556 -32.714184) (xy 186.947556 -31.850584) (xy 186.948046 -31.820616) (xy 186.955869 -31.761194)
			(xy 186.971382 -31.703301) (xy 186.994318 -31.647928) (xy 187.024285 -31.596022) (xy 187.060772 -31.548472)
			(xy 187.103152 -31.506092) (xy 187.150702 -31.469605) (xy 187.202608 -31.439638) (xy 187.257981 -31.416702)
			(xy 187.315874 -31.401189) (xy 187.375296 -31.393366) (xy 187.435232 -31.393366) (xy 187.494654 -31.401189)
			(xy 187.552547 -31.416702) (xy 187.60792 -31.439638) (xy 187.659826 -31.469605) (xy 187.707376 -31.506092)
			(xy 187.749756 -31.548472) (xy 187.786243 -31.596022) (xy 187.81621 -31.647928) (xy 187.839146 -31.703301)
			(xy 187.854659 -31.761194) (xy 187.862482 -31.820616) (xy 187.862972 -31.850584) (xy 187.862972 -32.714184)
			(xy 187.862482 -32.744152) (xy 187.854659 -32.803574) (xy 187.839146 -32.861467) (xy 187.81621 -32.91684)
			(xy 187.786243 -32.968746) (xy 187.749756 -33.016296) (xy 187.707376 -33.058676) (xy 187.659826 -33.095163)
			(xy 187.60792 -33.12513) (xy 187.552547 -33.148066) (xy 187.494654 -33.163579) (xy 187.435232 -33.171402)
			(xy 187.375296 -33.171402) (xy 187.315874 -33.163579) (xy 187.257981 -33.148066) (xy 187.202608 -33.12513)
			(xy 187.150702 -33.095163) (xy 187.103152 -33.058676) (xy 187.060772 -33.016296) (xy 187.024285 -32.968746)
			(xy 186.994318 -32.91684) (xy 186.971382 -32.861467) (xy 186.955869 -32.803574) (xy 186.948046 -32.744152)
			(xy 186.947556 -32.714184) (xy 177.622708 -32.714184) (xy 177.622708 -32.722312) (xy 177.622218 -32.752296)
			(xy 177.61439 -32.811752) (xy 177.598869 -32.869677) (xy 177.57592 -32.925081) (xy 177.545936 -32.977015)
			(xy 177.50943 -33.024591) (xy 177.467025 -33.066996) (xy 177.419449 -33.103502) (xy 177.367515 -33.133486)
			(xy 177.312111 -33.156435) (xy 177.254186 -33.171956) (xy 177.19473 -33.179784) (xy 177.134762 -33.179784)
			(xy 177.075306 -33.171956) (xy 177.017381 -33.156435) (xy 176.961977 -33.133486) (xy 176.910043 -33.103502)
			(xy 176.862467 -33.066996) (xy 176.820062 -33.024591) (xy 176.783556 -32.977015) (xy 176.753572 -32.925081)
			(xy 176.730623 -32.869677) (xy 176.715102 -32.811752) (xy 176.707274 -32.752296) (xy 176.706784 -32.722312)
			(xy 174.195232 -32.722312) (xy 174.195232 -34.52241) (xy 174.852584 -34.52241) (xy 174.852584 -33.65881)
			(xy 174.853074 -33.628826) (xy 174.860902 -33.56937) (xy 174.876423 -33.511445) (xy 174.899372 -33.456041)
			(xy 174.929356 -33.404107) (xy 174.965862 -33.356531) (xy 175.008267 -33.314126) (xy 175.055843 -33.27762)
			(xy 175.107777 -33.247636) (xy 175.163181 -33.224687) (xy 175.221106 -33.209166) (xy 175.280562 -33.201338)
			(xy 175.34053 -33.201338) (xy 175.399986 -33.209166) (xy 175.457911 -33.224687) (xy 175.513315 -33.247636)
			(xy 175.565249 -33.27762) (xy 175.612825 -33.314126) (xy 175.65523 -33.356531) (xy 175.691736 -33.404107)
			(xy 175.72172 -33.456041) (xy 175.744669 -33.511445) (xy 175.76019 -33.56937) (xy 175.768018 -33.628826)
			(xy 175.768508 -33.65881) (xy 175.768508 -34.520886) (xy 189.589664 -34.520886) (xy 189.589664 -33.657286)
			(xy 189.590154 -33.627318) (xy 189.597977 -33.567896) (xy 189.61349 -33.510003) (xy 189.636426 -33.45463)
			(xy 189.666393 -33.402724) (xy 189.70288 -33.355174) (xy 189.74526 -33.312794) (xy 189.79281 -33.276307)
			(xy 189.844716 -33.24634) (xy 189.900089 -33.223404) (xy 189.957982 -33.207891) (xy 190.017404 -33.200068)
			(xy 190.07734 -33.200068) (xy 190.136762 -33.207891) (xy 190.194655 -33.223404) (xy 190.250028 -33.24634)
			(xy 190.301934 -33.276307) (xy 190.349484 -33.312794) (xy 190.391864 -33.355174) (xy 190.428351 -33.402724)
			(xy 190.458318 -33.45463) (xy 190.481254 -33.510003) (xy 190.496767 -33.567896) (xy 190.50459 -33.627318)
			(xy 190.50508 -33.657286) (xy 190.50508 -34.520886) (xy 190.50459 -34.550854) (xy 190.496767 -34.610276)
			(xy 190.481254 -34.668169) (xy 190.458318 -34.723542) (xy 190.428351 -34.775448) (xy 190.391864 -34.822998)
			(xy 190.349484 -34.865378) (xy 190.301934 -34.901865) (xy 190.250028 -34.931832) (xy 190.194655 -34.954768)
			(xy 190.136762 -34.970281) (xy 190.07734 -34.978104) (xy 190.017404 -34.978104) (xy 189.957982 -34.970281)
			(xy 189.900089 -34.954768) (xy 189.844716 -34.931832) (xy 189.79281 -34.901865) (xy 189.74526 -34.865378)
			(xy 189.70288 -34.822998) (xy 189.666393 -34.775448) (xy 189.636426 -34.723542) (xy 189.61349 -34.668169)
			(xy 189.597977 -34.610276) (xy 189.590154 -34.550854) (xy 189.589664 -34.520886) (xy 175.768508 -34.520886)
			(xy 175.768508 -34.52241) (xy 175.768018 -34.552394) (xy 175.76019 -34.61185) (xy 175.744669 -34.669775)
			(xy 175.72172 -34.725179) (xy 175.691736 -34.777113) (xy 175.65523 -34.824689) (xy 175.612825 -34.867094)
			(xy 175.565249 -34.9036) (xy 175.513315 -34.933584) (xy 175.457911 -34.956533) (xy 175.399986 -34.972054)
			(xy 175.34053 -34.979882) (xy 175.280562 -34.979882) (xy 175.221106 -34.972054) (xy 175.163181 -34.956533)
			(xy 175.107777 -34.933584) (xy 175.055843 -34.9036) (xy 175.008267 -34.867094) (xy 174.965862 -34.824689)
			(xy 174.929356 -34.777113) (xy 174.899372 -34.725179) (xy 174.876423 -34.669775) (xy 174.860902 -34.61185)
			(xy 174.853074 -34.552394) (xy 174.852584 -34.52241) (xy 174.195232 -34.52241) (xy 174.195232 -34.72434)
			(xy 174.19574 -34.73196) (xy 174.197191 -34.739796) (xy 174.204301 -34.754049) (xy 174.20971 -34.7599)
			(xy 175.139858 -35.689794) (xy 175.597566 -36.147502) (xy 175.60417 -36.149534) (xy 175.62998 -36.157636)
			(xy 175.679185 -36.180111) (xy 175.724721 -36.209313) (xy 175.765675 -36.244655) (xy 175.801225 -36.285429)
			(xy 175.830657 -36.330817) (xy 175.853382 -36.379907) (xy 175.868943 -36.431716) (xy 175.877028 -36.485203)
			(xy 175.877728 -36.512246) (xy 175.877728 -36.519104) (xy 175.877405 -36.536937) (xy 175.873847 -36.572429)
			(xy 175.870616 -36.58997) (xy 175.869092 -36.597336) (xy 175.868442 -36.60013) (xy 180.098199 -36.60013)
			(xy 180.102204 -36.512222) (xy 180.114187 -36.425042) (xy 180.134047 -36.339313) (xy 180.161622 -36.255745)
			(xy 180.196681 -36.175031) (xy 180.238934 -36.097839) (xy 180.288032 -36.02481) (xy 180.343568 -35.956548)
			(xy 180.40508 -35.893618) (xy 180.472061 -35.836544) (xy 180.543954 -35.785796) (xy 180.620163 -35.741796)
			(xy 180.700058 -35.704909) (xy 180.782977 -35.67544) (xy 180.868232 -35.653633) (xy 180.955116 -35.639669)
			(xy 181.04291 -35.633663) (xy 181.130887 -35.635667) (xy 181.218317 -35.645662) (xy 181.304476 -35.663566)
			(xy 181.38865 -35.68923) (xy 181.470141 -35.722443) (xy 181.548275 -35.762929) (xy 181.622403 -35.810351)
			(xy 181.691911 -35.864318) (xy 181.70521 -35.876738) (xy 186.817252 -35.876738) (xy 186.821323 -35.821116)
			(xy 186.833449 -35.766679) (xy 186.853372 -35.714588) (xy 186.880668 -35.665953) (xy 186.914754 -35.62181)
			(xy 186.954903 -35.583101) (xy 187.000261 -35.55065) (xy 187.049861 -35.525149) (xy 187.102645 -35.507142)
			(xy 187.157488 -35.497012) (xy 187.213222 -35.494975) (xy 187.268659 -35.501075) (xy 187.322616 -35.515181)
			(xy 187.373945 -35.536993) (xy 187.421551 -35.566047) (xy 187.464419 -35.601722) (xy 187.501636 -35.643259)
			(xy 187.532409 -35.689772) (xy 187.556081 -35.740269) (xy 187.572149 -35.793676) (xy 187.580269 -35.848852)
			(xy 187.580778 -35.876738) (xy 187.580269 -35.904624) (xy 187.572149 -35.9598) (xy 187.556081 -36.013207)
			(xy 187.532409 -36.063704) (xy 187.501636 -36.110217) (xy 187.464419 -36.151754) (xy 187.421551 -36.187429)
			(xy 187.373945 -36.216483) (xy 187.322616 -36.238295) (xy 187.268659 -36.252401) (xy 187.213222 -36.258501)
			(xy 187.157488 -36.256464) (xy 187.102645 -36.246334) (xy 187.049861 -36.228327) (xy 187.000261 -36.202826)
			(xy 186.954903 -36.170375) (xy 186.914754 -36.131666) (xy 186.880668 -36.087523) (xy 186.853372 -36.038888)
			(xy 186.833449 -35.986797) (xy 186.821323 -35.93236) (xy 186.817252 -35.876738) (xy 181.70521 -35.876738)
			(xy 181.756225 -35.924383) (xy 181.814809 -35.990047) (xy 181.86718 -36.060766) (xy 181.912903 -36.135954)
			(xy 181.9516 -36.214989) (xy 181.982949 -36.297215) (xy 182.006691 -36.381951) (xy 182.022629 -36.468495)
			(xy 182.026415 -36.50996) (xy 188.71387 -36.50996) (xy 188.717941 -36.454338) (xy 188.730067 -36.399901)
			(xy 188.74999 -36.34781) (xy 188.777286 -36.299175) (xy 188.811372 -36.255032) (xy 188.851521 -36.216323)
			(xy 188.896879 -36.183872) (xy 188.946479 -36.158371) (xy 188.999263 -36.140364) (xy 189.054106 -36.130234)
			(xy 189.10984 -36.128197) (xy 189.165277 -36.134297) (xy 189.219234 -36.148403) (xy 189.270563 -36.170215)
			(xy 189.318169 -36.199269) (xy 189.361037 -36.234944) (xy 189.398254 -36.276481) (xy 189.429027 -36.322994)
			(xy 189.452699 -36.373491) (xy 189.468767 -36.426898) (xy 189.476887 -36.482074) (xy 189.477396 -36.50996)
			(xy 189.476887 -36.537846) (xy 189.468767 -36.593022) (xy 189.452699 -36.646429) (xy 189.429027 -36.696926)
			(xy 189.398254 -36.743439) (xy 189.361037 -36.784976) (xy 189.318169 -36.820651) (xy 189.270563 -36.849705)
			(xy 189.219234 -36.871517) (xy 189.165277 -36.885623) (xy 189.10984 -36.891723) (xy 189.054106 -36.889686)
			(xy 188.999263 -36.879556) (xy 188.946479 -36.861549) (xy 188.896879 -36.836048) (xy 188.851521 -36.803597)
			(xy 188.811372 -36.764888) (xy 188.777286 -36.720745) (xy 188.74999 -36.67211) (xy 188.730067 -36.620019)
			(xy 188.717941 -36.565582) (xy 188.71387 -36.50996) (xy 182.026415 -36.50996) (xy 182.030631 -36.55613)
			(xy 182.031132 -36.60013) (xy 182.030631 -36.64413) (xy 182.022629 -36.731765) (xy 182.006691 -36.818309)
			(xy 181.982949 -36.903045) (xy 181.9516 -36.985271) (xy 181.912903 -37.064306) (xy 181.86718 -37.139494)
			(xy 181.814809 -37.210213) (xy 181.756225 -37.275877) (xy 181.691911 -37.335942) (xy 181.622403 -37.389909)
			(xy 181.548275 -37.437331) (xy 181.475269 -37.47516) (xy 185.859164 -37.47516) (xy 185.863235 -37.419538)
			(xy 185.875361 -37.365101) (xy 185.895284 -37.31301) (xy 185.92258 -37.264375) (xy 185.956666 -37.220232)
			(xy 185.996815 -37.181523) (xy 186.042173 -37.149072) (xy 186.091773 -37.123571) (xy 186.144557 -37.105564)
			(xy 186.1994 -37.095434) (xy 186.255134 -37.093397) (xy 186.310571 -37.099497) (xy 186.364528 -37.113603)
			(xy 186.415857 -37.135415) (xy 186.463463 -37.164469) (xy 186.506331 -37.200144) (xy 186.543548 -37.241681)
			(xy 186.574321 -37.288194) (xy 186.597993 -37.338691) (xy 186.614061 -37.392098) (xy 186.622181 -37.447274)
			(xy 186.62269 -37.47516) (xy 186.622181 -37.503046) (xy 186.614061 -37.558222) (xy 186.597993 -37.611629)
			(xy 186.574321 -37.662126) (xy 186.574168 -37.662358) (xy 188.04839 -37.662358) (xy 188.052461 -37.606736)
			(xy 188.064587 -37.552299) (xy 188.08451 -37.500208) (xy 188.111806 -37.451573) (xy 188.145892 -37.40743)
			(xy 188.186041 -37.368721) (xy 188.231399 -37.33627) (xy 188.280999 -37.310769) (xy 188.333783 -37.292762)
			(xy 188.388626 -37.282632) (xy 188.44436 -37.280595) (xy 188.499797 -37.286695) (xy 188.553754 -37.300801)
			(xy 188.605083 -37.322613) (xy 188.652689 -37.351667) (xy 188.695557 -37.387342) (xy 188.732774 -37.428879)
			(xy 188.763547 -37.475392) (xy 188.787219 -37.525889) (xy 188.803287 -37.579296) (xy 188.811407 -37.634472)
			(xy 188.811916 -37.662358) (xy 188.811407 -37.690244) (xy 188.803287 -37.74542) (xy 188.787219 -37.798827)
			(xy 188.763547 -37.849324) (xy 188.732774 -37.895837) (xy 188.695557 -37.937374) (xy 188.652689 -37.973049)
			(xy 188.605083 -38.002103) (xy 188.553754 -38.023915) (xy 188.499797 -38.038021) (xy 188.44436 -38.044121)
			(xy 188.388626 -38.042084) (xy 188.333783 -38.031954) (xy 188.280999 -38.013947) (xy 188.231399 -37.988446)
			(xy 188.186041 -37.955995) (xy 188.145892 -37.917286) (xy 188.111806 -37.873143) (xy 188.08451 -37.824508)
			(xy 188.064587 -37.772417) (xy 188.052461 -37.71798) (xy 188.04839 -37.662358) (xy 186.574168 -37.662358)
			(xy 186.543548 -37.708639) (xy 186.506331 -37.750176) (xy 186.463463 -37.785851) (xy 186.415857 -37.814905)
			(xy 186.364528 -37.836717) (xy 186.310571 -37.850823) (xy 186.255134 -37.856923) (xy 186.1994 -37.854886)
			(xy 186.144557 -37.844756) (xy 186.091773 -37.826749) (xy 186.042173 -37.801248) (xy 185.996815 -37.768797)
			(xy 185.956666 -37.730088) (xy 185.92258 -37.685945) (xy 185.895284 -37.63731) (xy 185.875361 -37.585219)
			(xy 185.863235 -37.530782) (xy 185.859164 -37.47516) (xy 181.475269 -37.47516) (xy 181.470141 -37.477817)
			(xy 181.38865 -37.51103) (xy 181.304476 -37.536694) (xy 181.218317 -37.554598) (xy 181.130887 -37.564593)
			(xy 181.04291 -37.566597) (xy 180.955116 -37.560591) (xy 180.868232 -37.546627) (xy 180.782977 -37.52482)
			(xy 180.700058 -37.495351) (xy 180.620163 -37.458464) (xy 180.543954 -37.414464) (xy 180.472061 -37.363716)
			(xy 180.40508 -37.306642) (xy 180.343568 -37.243712) (xy 180.288032 -37.17545) (xy 180.238934 -37.102421)
			(xy 180.196681 -37.025229) (xy 180.161622 -36.944515) (xy 180.134047 -36.860947) (xy 180.114187 -36.775218)
			(xy 180.102204 -36.688038) (xy 180.098199 -36.60013) (xy 175.868442 -36.60013) (xy 175.864923 -36.615245)
			(xy 175.853599 -36.65023) (xy 175.846486 -36.667186) (xy 175.846486 -36.667694) (xy 175.842676 -36.675822)
			(xy 175.838104 -36.685982) (xy 175.838104 -38.729948) (xy 191.80102 -38.729948) (xy 191.80102 -38.675452)
			(xy 191.808775 -38.621512) (xy 191.824128 -38.569224) (xy 191.846766 -38.519653) (xy 191.876228 -38.473808)
			(xy 191.911914 -38.432623) (xy 191.953098 -38.396935) (xy 191.998942 -38.367472) (xy 192.048512 -38.344832)
			(xy 192.1008 -38.329478) (xy 192.15474 -38.321721) (xy 192.181988 -38.321234) (xy 192.210293 -38.321717)
			(xy 192.266282 -38.330068) (xy 192.320422 -38.346604) (xy 192.371523 -38.37096) (xy 192.418463 -38.402602)
			(xy 192.46021 -38.440834) (xy 192.495847 -38.484818) (xy 192.510664 -38.50894) (xy 192.518212 -38.521009)
			(xy 192.538841 -38.540613) (xy 192.564084 -38.553754) (xy 192.591975 -38.55941) (xy 192.620342 -38.557139)
			(xy 192.646979 -38.547119) (xy 192.669809 -38.53013) (xy 192.678812 -38.5191) (xy 192.696997 -38.496222)
			(xy 192.73916 -38.455758) (xy 192.786996 -38.422191) (xy 192.839388 -38.396304) (xy 192.895113 -38.378703)
			(xy 192.952869 -38.369797) (xy 192.982088 -38.36924) (xy 193.009345 -38.369606) (xy 193.063304 -38.377363)
			(xy 193.11561 -38.39272) (xy 193.165198 -38.415364) (xy 193.211058 -38.444836) (xy 193.252258 -38.480534)
			(xy 193.287957 -38.521732) (xy 193.31743 -38.567592) (xy 193.340076 -38.617179) (xy 193.355435 -38.669484)
			(xy 193.363193 -38.723443) (xy 193.363193 -38.777957) (xy 193.355435 -38.831916) (xy 193.340076 -38.884221)
			(xy 193.31743 -38.933808) (xy 193.287957 -38.979668) (xy 193.252258 -39.020866) (xy 193.211058 -39.056564)
			(xy 193.165198 -39.086036) (xy 193.11561 -39.10868) (xy 193.063304 -39.124037) (xy 193.009345 -39.131794)
			(xy 192.982088 -39.132256) (xy 192.953785 -39.131718) (xy 192.897798 -39.123377) (xy 192.843659 -39.106852)
			(xy 192.792558 -39.082505) (xy 192.745617 -39.050872) (xy 192.703869 -39.012646) (xy 192.66823 -38.968669)
			(xy 192.653412 -38.94455) (xy 192.645765 -38.93255) (xy 192.625156 -38.912952) (xy 192.599935 -38.89981)
			(xy 192.572064 -38.894147) (xy 192.543714 -38.896404) (xy 192.517091 -38.906405) (xy 192.494266 -38.923372)
			(xy 192.485264 -38.93439) (xy 192.467091 -38.957277) (xy 192.424925 -38.997741) (xy 192.377087 -39.031307)
			(xy 192.324693 -39.057193) (xy 192.268966 -39.074792) (xy 192.211208 -39.083695) (xy 192.181988 -39.08425)
			(xy 192.15474 -39.083679) (xy 192.1008 -39.075922) (xy 192.048512 -39.060568) (xy 191.998942 -39.037928)
			(xy 191.953098 -39.008465) (xy 191.911914 -38.972777) (xy 191.876228 -38.931592) (xy 191.846766 -38.885747)
			(xy 191.824128 -38.836176) (xy 191.808775 -38.783888) (xy 191.80102 -38.729948) (xy 175.838104 -38.729948)
			(xy 175.838104 -38.940994) (xy 175.842676 -38.946328) (xy 178.165103 -41.268755) (xy 183.943927 -41.268755)
			(xy 183.943927 -41.214245) (xy 183.951685 -41.160289) (xy 183.967042 -41.107987) (xy 183.989687 -41.058403)
			(xy 184.019157 -41.012546) (xy 184.054854 -40.97135) (xy 184.096051 -40.935654) (xy 184.141908 -40.906184)
			(xy 184.191493 -40.88354) (xy 184.243795 -40.868183) (xy 184.297751 -40.860427) (xy 184.325006 -40.859964)
			(xy 184.353745 -40.860494) (xy 184.410571 -40.869116) (xy 184.465462 -40.886166) (xy 184.517173 -40.911255)
			(xy 184.564537 -40.943818) (xy 184.585864 -40.963088) (xy 184.592722 -40.969692) (xy 184.610756 -40.976804)
			(xy 184.699656 -40.976804) (xy 184.71769 -40.969692) (xy 184.724548 -40.963088) (xy 184.74588 -40.943823)
			(xy 184.79324 -40.911254) (xy 184.84495 -40.886159) (xy 184.89984 -40.869108) (xy 184.956667 -40.860485)
			(xy 184.985406 -40.859964) (xy 185.012655 -40.860507) (xy 185.066598 -40.868263) (xy 185.118888 -40.883618)
			(xy 185.168461 -40.906258) (xy 185.214307 -40.935722) (xy 185.255494 -40.971411) (xy 185.291182 -41.012598)
			(xy 185.320645 -41.058444) (xy 185.343284 -41.108017) (xy 185.358638 -41.160308) (xy 185.366394 -41.214251)
			(xy 185.366394 -41.268749) (xy 185.358638 -41.322692) (xy 185.343284 -41.374983) (xy 185.320645 -41.424556)
			(xy 185.291182 -41.470402) (xy 185.255494 -41.511589) (xy 185.214307 -41.547278) (xy 185.168461 -41.576742)
			(xy 185.118888 -41.599382) (xy 185.066598 -41.614737) (xy 185.012655 -41.622493) (xy 184.985406 -41.62298)
			(xy 184.956668 -41.622431) (xy 184.899843 -41.613811) (xy 184.844953 -41.596766) (xy 184.793241 -41.571681)
			(xy 184.745877 -41.539123) (xy 184.724548 -41.519856) (xy 184.71769 -41.513252) (xy 184.699656 -41.50614)
			(xy 184.610756 -41.50614) (xy 184.592722 -41.513252) (xy 184.585864 -41.519856) (xy 184.564534 -41.539123)
			(xy 184.517173 -41.57169) (xy 184.465462 -41.596783) (xy 184.410572 -41.613835) (xy 184.353745 -41.622459)
			(xy 184.325006 -41.62298) (xy 184.297751 -41.622573) (xy 184.243795 -41.614817) (xy 184.191493 -41.59946)
			(xy 184.141908 -41.576816) (xy 184.096051 -41.547346) (xy 184.054854 -41.51165) (xy 184.019157 -41.470454)
			(xy 183.989687 -41.424597) (xy 183.967042 -41.375013) (xy 183.951685 -41.322711) (xy 183.943927 -41.268755)
			(xy 178.165103 -41.268755) (xy 180.20157 -43.305222) (xy 186.407298 -43.305222) (xy 186.407777 -43.277852)
			(xy 186.415592 -43.223674) (xy 186.431078 -43.171171) (xy 186.453917 -43.121424) (xy 186.483638 -43.075456)
			(xy 186.501278 -43.054524) (xy 186.501532 -43.05427) (xy 186.507099 -43.04717) (xy 186.513356 -43.030263)
			(xy 186.513724 -43.02125) (xy 186.513724 -42.954194) (xy 186.513364 -42.945178) (xy 186.507118 -42.928261)
			(xy 186.501532 -42.921174) (xy 186.501278 -42.921174) (xy 186.501278 -42.92092) (xy 186.483631 -42.899994)
			(xy 186.453921 -42.854019) (xy 186.431087 -42.80427) (xy 186.415598 -42.751768) (xy 186.407771 -42.697592)
			(xy 186.407298 -42.670222) (xy 186.407836 -42.641484) (xy 186.416455 -42.584657) (xy 186.433502 -42.529766)
			(xy 186.45859 -42.478054) (xy 186.491153 -42.430691) (xy 186.510422 -42.409364) (xy 186.517026 -42.402506)
			(xy 186.524138 -42.384472) (xy 186.524138 -42.295572) (xy 186.517026 -42.277538) (xy 186.510422 -42.27068)
			(xy 186.491173 -42.249334) (xy 186.458607 -42.201975) (xy 186.433515 -42.150266) (xy 186.416463 -42.095378)
			(xy 186.407838 -42.038554) (xy 186.407836 -41.981078) (xy 186.416456 -41.924253) (xy 186.433503 -41.869364)
			(xy 186.458591 -41.817653) (xy 186.491153 -41.770291) (xy 186.510422 -41.748964) (xy 186.517026 -41.742106)
			(xy 186.524138 -41.724072) (xy 186.524138 -41.635172) (xy 186.517026 -41.617138) (xy 186.510422 -41.61028)
			(xy 186.491159 -41.588946) (xy 186.458592 -41.541586) (xy 186.433499 -41.489876) (xy 186.416446 -41.434987)
			(xy 186.407821 -41.37816) (xy 186.407298 -41.349422) (xy 186.407784 -41.322171) (xy 186.41554 -41.268223)
			(xy 186.430895 -41.215928) (xy 186.453537 -41.166351) (xy 186.483003 -41.120501) (xy 186.518694 -41.07931)
			(xy 186.559885 -41.043619) (xy 186.605735 -41.014153) (xy 186.655312 -40.991511) (xy 186.707607 -40.976156)
			(xy 186.761555 -40.9684) (xy 186.816057 -40.9684) (xy 186.839178 -40.971724) (xy 194.694046 -40.971724)
			(xy 194.698117 -40.916102) (xy 194.710243 -40.861665) (xy 194.730166 -40.809574) (xy 194.757462 -40.760939)
			(xy 194.791548 -40.716796) (xy 194.831697 -40.678087) (xy 194.877055 -40.645636) (xy 194.926655 -40.620135)
			(xy 194.979439 -40.602128) (xy 195.034282 -40.591998) (xy 195.090016 -40.589961) (xy 195.145453 -40.596061)
			(xy 195.19941 -40.610167) (xy 195.250739 -40.631979) (xy 195.298345 -40.661033) (xy 195.341213 -40.696708)
			(xy 195.37843 -40.738245) (xy 195.409203 -40.784758) (xy 195.432875 -40.835255) (xy 195.448943 -40.888662)
			(xy 195.457063 -40.943838) (xy 195.457572 -40.971724) (xy 195.457063 -40.99961) (xy 195.448943 -41.054786)
			(xy 195.432875 -41.108193) (xy 195.409203 -41.15869) (xy 195.37843 -41.205203) (xy 195.341213 -41.24674)
			(xy 195.298345 -41.282415) (xy 195.250739 -41.311469) (xy 195.19941 -41.333281) (xy 195.145453 -41.347387)
			(xy 195.090016 -41.353487) (xy 195.034282 -41.35145) (xy 194.979439 -41.34132) (xy 194.926655 -41.323313)
			(xy 194.877055 -41.297812) (xy 194.831697 -41.265361) (xy 194.791548 -41.226652) (xy 194.757462 -41.182509)
			(xy 194.730166 -41.133874) (xy 194.710243 -41.081783) (xy 194.698117 -41.027346) (xy 194.694046 -40.971724)
			(xy 186.839178 -40.971724) (xy 186.870005 -40.976156) (xy 186.9223 -40.991511) (xy 186.971877 -41.014153)
			(xy 187.017727 -41.043619) (xy 187.058918 -41.07931) (xy 187.094609 -41.120501) (xy 187.124075 -41.166351)
			(xy 187.146717 -41.215928) (xy 187.162072 -41.268223) (xy 187.169828 -41.322171) (xy 187.170314 -41.349422)
			(xy 187.1698 -41.378161) (xy 187.161174 -41.434989) (xy 187.144122 -41.48988) (xy 187.119028 -41.541591)
			(xy 187.086461 -41.588953) (xy 187.06719 -41.61028) (xy 187.060586 -41.617138) (xy 187.053474 -41.635172)
			(xy 187.053474 -41.724072) (xy 187.060586 -41.742106) (xy 187.06719 -41.748964) (xy 187.086482 -41.770272)
			(xy 187.119045 -41.817638) (xy 187.144135 -41.869353) (xy 187.161183 -41.924247) (xy 187.169803 -41.981076)
			(xy 187.1698 -42.038556) (xy 187.161175 -42.095385) (xy 187.144123 -42.150277) (xy 187.119029 -42.20199)
			(xy 187.086462 -42.249353) (xy 187.06719 -42.27068) (xy 187.060586 -42.277538) (xy 187.053474 -42.295572)
			(xy 187.053474 -42.384472) (xy 187.060586 -42.402506) (xy 187.06719 -42.409364) (xy 187.086476 -42.430678)
			(xy 187.119039 -42.478044) (xy 187.144128 -42.529759) (xy 187.161175 -42.584653) (xy 187.169795 -42.641482)
			(xy 187.170314 -42.670222) (xy 187.169857 -42.697593) (xy 187.162037 -42.751772) (xy 187.146545 -42.804275)
			(xy 187.125991 -42.849038) (xy 188.992 -42.849038) (xy 188.996071 -42.793416) (xy 189.008197 -42.738979)
			(xy 189.02812 -42.686888) (xy 189.055416 -42.638253) (xy 189.089502 -42.59411) (xy 189.129651 -42.555401)
			(xy 189.175009 -42.52295) (xy 189.224609 -42.497449) (xy 189.277393 -42.479442) (xy 189.332236 -42.469312)
			(xy 189.38797 -42.467275) (xy 189.443407 -42.473375) (xy 189.497364 -42.487481) (xy 189.548693 -42.509293)
			(xy 189.596299 -42.538347) (xy 189.639167 -42.574022) (xy 189.676384 -42.615559) (xy 189.707157 -42.662072)
			(xy 189.730829 -42.712569) (xy 189.746897 -42.765976) (xy 189.755017 -42.821152) (xy 189.755378 -42.84091)
			(xy 195.033136 -42.84091) (xy 195.037207 -42.785288) (xy 195.049333 -42.730851) (xy 195.069256 -42.67876)
			(xy 195.096552 -42.630125) (xy 195.130638 -42.585982) (xy 195.170787 -42.547273) (xy 195.216145 -42.514822)
			(xy 195.265745 -42.489321) (xy 195.318529 -42.471314) (xy 195.373372 -42.461184) (xy 195.429106 -42.459147)
			(xy 195.484543 -42.465247) (xy 195.5385 -42.479353) (xy 195.589829 -42.501165) (xy 195.637435 -42.530219)
			(xy 195.680303 -42.565894) (xy 195.71752 -42.607431) (xy 195.748293 -42.653944) (xy 195.771965 -42.704441)
			(xy 195.788033 -42.757848) (xy 195.796153 -42.813024) (xy 195.796662 -42.84091) (xy 195.796153 -42.868796)
			(xy 195.788033 -42.923972) (xy 195.771965 -42.977379) (xy 195.748293 -43.027876) (xy 195.71752 -43.074389)
			(xy 195.680303 -43.115926) (xy 195.637435 -43.151601) (xy 195.589829 -43.180655) (xy 195.5385 -43.202467)
			(xy 195.484543 -43.216573) (xy 195.429106 -43.222673) (xy 195.373372 -43.220636) (xy 195.318529 -43.210506)
			(xy 195.265745 -43.192499) (xy 195.216145 -43.166998) (xy 195.170787 -43.134547) (xy 195.130638 -43.095838)
			(xy 195.096552 -43.051695) (xy 195.069256 -43.00306) (xy 195.049333 -42.950969) (xy 195.037207 -42.896532)
			(xy 195.033136 -42.84091) (xy 189.755378 -42.84091) (xy 189.755526 -42.849038) (xy 189.755017 -42.876924)
			(xy 189.746897 -42.9321) (xy 189.730829 -42.985507) (xy 189.707157 -43.036004) (xy 189.676384 -43.082517)
			(xy 189.639167 -43.124054) (xy 189.596299 -43.159729) (xy 189.548693 -43.188783) (xy 189.497364 -43.210595)
			(xy 189.443407 -43.224701) (xy 189.38797 -43.230801) (xy 189.332236 -43.228764) (xy 189.277393 -43.218634)
			(xy 189.224609 -43.200627) (xy 189.175009 -43.175126) (xy 189.129651 -43.142675) (xy 189.089502 -43.103966)
			(xy 189.055416 -43.059823) (xy 189.02812 -43.011188) (xy 189.008197 -42.959097) (xy 188.996071 -42.90466)
			(xy 188.992 -42.849038) (xy 187.125991 -42.849038) (xy 187.123702 -42.854022) (xy 187.093976 -42.899988)
			(xy 187.076334 -42.92092) (xy 187.07608 -42.921174) (xy 187.070496 -42.928262) (xy 187.064248 -42.945178)
			(xy 187.063888 -42.954194) (xy 187.063888 -43.02125) (xy 187.064271 -43.030264) (xy 187.070501 -43.047181)
			(xy 187.07608 -43.05427) (xy 187.076334 -43.05427) (xy 187.076334 -43.054524) (xy 187.093956 -43.07547)
			(xy 187.123669 -43.121439) (xy 187.146508 -43.171183) (xy 187.162003 -43.223681) (xy 187.169837 -43.277854)
			(xy 187.170314 -43.305222) (xy 187.169828 -43.332473) (xy 187.162072 -43.386421) (xy 187.146717 -43.438716)
			(xy 187.124075 -43.488293) (xy 187.094609 -43.534143) (xy 187.058918 -43.575334) (xy 187.017727 -43.611025)
			(xy 186.971877 -43.640491) (xy 186.9223 -43.663133) (xy 186.870005 -43.678488) (xy 186.816057 -43.686244)
			(xy 186.761555 -43.686244) (xy 186.707607 -43.678488) (xy 186.655312 -43.663133) (xy 186.605735 -43.640491)
			(xy 186.559885 -43.611025) (xy 186.518694 -43.575334) (xy 186.483003 -43.534143) (xy 186.453537 -43.488293)
			(xy 186.430895 -43.438716) (xy 186.41554 -43.386421) (xy 186.407784 -43.332473) (xy 186.407298 -43.305222)
			(xy 180.20157 -43.305222) (xy 180.632608 -43.73626) (xy 188.313058 -43.73626) (xy 188.317129 -43.680638)
			(xy 188.329255 -43.626201) (xy 188.349178 -43.57411) (xy 188.376474 -43.525475) (xy 188.41056 -43.481332)
			(xy 188.450709 -43.442623) (xy 188.496067 -43.410172) (xy 188.545667 -43.384671) (xy 188.598451 -43.366664)
			(xy 188.653294 -43.356534) (xy 188.709028 -43.354497) (xy 188.764465 -43.360597) (xy 188.818422 -43.374703)
			(xy 188.869751 -43.396515) (xy 188.917357 -43.425569) (xy 188.960225 -43.461244) (xy 188.997442 -43.502781)
			(xy 189.028215 -43.549294) (xy 189.051887 -43.599791) (xy 189.067955 -43.653198) (xy 189.076075 -43.708374)
			(xy 189.076584 -43.73626) (xy 189.076075 -43.764146) (xy 189.067955 -43.819322) (xy 189.056646 -43.85691)
			(xy 192.81978 -43.85691) (xy 192.823851 -43.801288) (xy 192.835977 -43.746851) (xy 192.8559 -43.69476)
			(xy 192.883196 -43.646125) (xy 192.917282 -43.601982) (xy 192.957431 -43.563273) (xy 193.002789 -43.530822)
			(xy 193.052389 -43.505321) (xy 193.105173 -43.487314) (xy 193.160016 -43.477184) (xy 193.21575 -43.475147)
			(xy 193.271187 -43.481247) (xy 193.325144 -43.495353) (xy 193.376473 -43.517165) (xy 193.424079 -43.546219)
			(xy 193.466947 -43.581894) (xy 193.504164 -43.623431) (xy 193.534937 -43.669944) (xy 193.558609 -43.720441)
			(xy 193.574677 -43.773848) (xy 193.582797 -43.829024) (xy 193.583306 -43.85691) (xy 193.582797 -43.884796)
			(xy 193.574677 -43.939972) (xy 193.558609 -43.993379) (xy 193.534937 -44.043876) (xy 193.504164 -44.090389)
			(xy 193.466947 -44.131926) (xy 193.424079 -44.167601) (xy 193.376473 -44.196655) (xy 193.325144 -44.218467)
			(xy 193.271187 -44.232573) (xy 193.21575 -44.238673) (xy 193.160016 -44.236636) (xy 193.105173 -44.226506)
			(xy 193.052389 -44.208499) (xy 193.002789 -44.182998) (xy 192.957431 -44.150547) (xy 192.917282 -44.111838)
			(xy 192.883196 -44.067695) (xy 192.8559 -44.01906) (xy 192.835977 -43.966969) (xy 192.823851 -43.912532)
			(xy 192.81978 -43.85691) (xy 189.056646 -43.85691) (xy 189.051887 -43.872729) (xy 189.028215 -43.923226)
			(xy 188.997442 -43.969739) (xy 188.960225 -44.011276) (xy 188.917357 -44.046951) (xy 188.869751 -44.076005)
			(xy 188.818422 -44.097817) (xy 188.764465 -44.111923) (xy 188.709028 -44.118023) (xy 188.653294 -44.115986)
			(xy 188.598451 -44.105856) (xy 188.545667 -44.087849) (xy 188.496067 -44.062348) (xy 188.450709 -44.029897)
			(xy 188.41056 -43.991188) (xy 188.376474 -43.947045) (xy 188.349178 -43.89841) (xy 188.329255 -43.846319)
			(xy 188.317129 -43.791882) (xy 188.313058 -43.73626) (xy 180.632608 -43.73626) (xy 180.706522 -43.810174)
			(xy 180.707538 -43.81119) (xy 180.726588 -43.830748) (xy 180.741802 -43.8485) (xy 180.767473 -43.887573)
			(xy 180.787223 -43.929947) (xy 180.800637 -43.974732) (xy 180.807433 -44.020987) (xy 180.807868 -44.044362)
			(xy 180.807868 -44.5135) (xy 180.80863 -44.517818) (xy 180.811142 -44.532612) (xy 180.813814 -44.562503)
			(xy 180.813964 -44.577508) (xy 180.813964 -45.114464) (xy 188.165484 -45.114464) (xy 188.169555 -45.058842)
			(xy 188.181681 -45.004405) (xy 188.201604 -44.952314) (xy 188.2289 -44.903679) (xy 188.262986 -44.859536)
			(xy 188.303135 -44.820827) (xy 188.348493 -44.788376) (xy 188.398093 -44.762875) (xy 188.450877 -44.744868)
			(xy 188.50572 -44.734738) (xy 188.561454 -44.732701) (xy 188.616891 -44.738801) (xy 188.670848 -44.752907)
			(xy 188.722177 -44.774719) (xy 188.769783 -44.803773) (xy 188.812651 -44.839448) (xy 188.842633 -44.87291)
			(xy 195.033136 -44.87291) (xy 195.037207 -44.817288) (xy 195.049333 -44.762851) (xy 195.069256 -44.71076)
			(xy 195.096552 -44.662125) (xy 195.130638 -44.617982) (xy 195.170787 -44.579273) (xy 195.216145 -44.546822)
			(xy 195.265745 -44.521321) (xy 195.318529 -44.503314) (xy 195.373372 -44.493184) (xy 195.429106 -44.491147)
			(xy 195.484543 -44.497247) (xy 195.5385 -44.511353) (xy 195.589829 -44.533165) (xy 195.637435 -44.562219)
			(xy 195.680303 -44.597894) (xy 195.71752 -44.639431) (xy 195.748293 -44.685944) (xy 195.771965 -44.736441)
			(xy 195.788033 -44.789848) (xy 195.796153 -44.845024) (xy 195.796662 -44.87291) (xy 195.796153 -44.900796)
			(xy 195.788033 -44.955972) (xy 195.771965 -45.009379) (xy 195.748293 -45.059876) (xy 195.71752 -45.106389)
			(xy 195.680303 -45.147926) (xy 195.637435 -45.183601) (xy 195.589829 -45.212655) (xy 195.5385 -45.234467)
			(xy 195.484543 -45.248573) (xy 195.429106 -45.254673) (xy 195.373372 -45.252636) (xy 195.318529 -45.242506)
			(xy 195.265745 -45.224499) (xy 195.216145 -45.198998) (xy 195.170787 -45.166547) (xy 195.130638 -45.127838)
			(xy 195.096552 -45.083695) (xy 195.069256 -45.03506) (xy 195.049333 -44.982969) (xy 195.037207 -44.928532)
			(xy 195.033136 -44.87291) (xy 188.842633 -44.87291) (xy 188.849868 -44.880985) (xy 188.880641 -44.927498)
			(xy 188.904313 -44.977995) (xy 188.920381 -45.031402) (xy 188.928501 -45.086578) (xy 188.92901 -45.114464)
			(xy 188.928501 -45.14235) (xy 188.920381 -45.197526) (xy 188.904313 -45.250933) (xy 188.880641 -45.30143)
			(xy 188.849868 -45.347943) (xy 188.844226 -45.35424) (xy 192.803778 -45.35424) (xy 192.807849 -45.298618)
			(xy 192.819975 -45.244181) (xy 192.839898 -45.19209) (xy 192.867194 -45.143455) (xy 192.90128 -45.099312)
			(xy 192.941429 -45.060603) (xy 192.986787 -45.028152) (xy 193.036387 -45.002651) (xy 193.089171 -44.984644)
			(xy 193.144014 -44.974514) (xy 193.199748 -44.972477) (xy 193.255185 -44.978577) (xy 193.309142 -44.992683)
			(xy 193.360471 -45.014495) (xy 193.408077 -45.043549) (xy 193.450945 -45.079224) (xy 193.488162 -45.120761)
			(xy 193.518935 -45.167274) (xy 193.542607 -45.217771) (xy 193.558675 -45.271178) (xy 193.566795 -45.326354)
			(xy 193.567304 -45.35424) (xy 193.566795 -45.382126) (xy 193.558675 -45.437302) (xy 193.542607 -45.490709)
			(xy 193.518935 -45.541206) (xy 193.488162 -45.587719) (xy 193.450945 -45.629256) (xy 193.408077 -45.664931)
			(xy 193.360471 -45.693985) (xy 193.309142 -45.715797) (xy 193.255185 -45.729903) (xy 193.199748 -45.736003)
			(xy 193.144014 -45.733966) (xy 193.089171 -45.723836) (xy 193.036387 -45.705829) (xy 192.986787 -45.680328)
			(xy 192.941429 -45.647877) (xy 192.90128 -45.609168) (xy 192.867194 -45.565025) (xy 192.839898 -45.51639)
			(xy 192.819975 -45.464299) (xy 192.807849 -45.409862) (xy 192.803778 -45.35424) (xy 188.844226 -45.35424)
			(xy 188.812651 -45.38948) (xy 188.769783 -45.425155) (xy 188.722177 -45.454209) (xy 188.670848 -45.476021)
			(xy 188.616891 -45.490127) (xy 188.561454 -45.496227) (xy 188.50572 -45.49419) (xy 188.450877 -45.48406)
			(xy 188.398093 -45.466053) (xy 188.348493 -45.440552) (xy 188.303135 -45.408101) (xy 188.262986 -45.369392)
			(xy 188.2289 -45.325249) (xy 188.201604 -45.276614) (xy 188.181681 -45.224523) (xy 188.169555 -45.170086)
			(xy 188.165484 -45.114464) (xy 180.813964 -45.114464) (xy 180.813964 -46.082204) (xy 186.152536 -46.082204)
			(xy 186.152959 -46.054949) (xy 186.160717 -46.000995) (xy 186.176075 -45.948693) (xy 186.19872 -45.89911)
			(xy 186.228191 -45.853255) (xy 186.263889 -45.812061) (xy 186.305087 -45.776367) (xy 186.350945 -45.746901)
			(xy 186.400531 -45.724261) (xy 186.452834 -45.708908) (xy 186.506789 -45.701156) (xy 186.534044 -45.700696)
			(xy 186.560948 -45.701125) (xy 186.614219 -45.708703) (xy 186.665898 -45.723688) (xy 186.71496 -45.745783)
			(xy 186.760432 -45.774551) (xy 186.801413 -45.80942) (xy 186.837089 -45.8497) (xy 186.852306 -45.871892)
			(xy 186.859418 -45.882814) (xy 186.882278 -45.894752) (xy 186.994546 -45.89272) (xy 187.016898 -45.879766)
			(xy 187.023756 -45.86859) (xy 187.038653 -45.844972) (xy 187.074336 -45.802021) (xy 187.115899 -45.764729)
			(xy 187.162453 -45.733893) (xy 187.213004 -45.710172) (xy 187.266473 -45.694073) (xy 187.321718 -45.68594)
			(xy 187.349638 -45.685456) (xy 187.376632 -45.685895) (xy 187.430081 -45.693506) (xy 187.481925 -45.708572)
			(xy 187.531129 -45.730791) (xy 187.576712 -45.75972) (xy 187.597542 -45.776896) (xy 187.60567 -45.784008)
			(xy 187.626244 -45.790104) (xy 187.711588 -45.779182) (xy 187.722134 -45.777412) (xy 187.740416 -45.766355)
			(xy 187.746894 -45.757846) (xy 187.762258 -45.736623) (xy 187.797843 -45.69817) (xy 187.838358 -45.664951)
			(xy 187.88304 -45.637591) (xy 187.931046 -45.616607) (xy 187.981473 -45.602392) (xy 188.033372 -45.595214)
			(xy 188.059568 -45.594778) (xy 188.086821 -45.595267) (xy 188.140774 -45.60302) (xy 188.193074 -45.618373)
			(xy 188.242656 -45.641013) (xy 188.288511 -45.670479) (xy 188.329706 -45.706171) (xy 188.365402 -45.747363)
			(xy 188.394872 -45.793216) (xy 188.417516 -45.842796) (xy 188.432873 -45.895095) (xy 188.440631 -45.949047)
			(xy 188.440631 -46.003553) (xy 188.432873 -46.057505) (xy 188.417516 -46.109804) (xy 188.394872 -46.159384)
			(xy 188.365402 -46.205237) (xy 188.329706 -46.246429) (xy 188.288511 -46.282121) (xy 188.242656 -46.311587)
			(xy 188.193074 -46.334227) (xy 188.140774 -46.34958) (xy 188.086821 -46.357333) (xy 188.059568 -46.357794)
			(xy 188.032575 -46.35734) (xy 187.979127 -46.34973) (xy 187.927284 -46.334668) (xy 187.878079 -46.312453)
			(xy 187.832495 -46.283528) (xy 187.811664 -46.266354) (xy 187.803536 -46.259242) (xy 187.782962 -46.253146)
			(xy 187.697618 -46.264068) (xy 187.687078 -46.265859) (xy 187.668794 -46.276903) (xy 187.662312 -46.285404)
			(xy 187.644694 -46.309701) (xy 187.603102 -46.352962) (xy 187.579508 -46.37151) (xy 187.571634 -46.377352)
			(xy 187.56122 -46.394878) (xy 187.548012 -46.485302) (xy 187.552838 -46.504606) (xy 187.55868 -46.51248)
			(xy 187.55868 -46.512734) (xy 187.576184 -46.537478) (xy 187.603986 -46.591331) (xy 187.622922 -46.648903)
			(xy 187.630125 -46.693836) (xy 192.776348 -46.693836) (xy 192.776834 -46.666585) (xy 192.78459 -46.612637)
			(xy 192.799945 -46.560342) (xy 192.822587 -46.510765) (xy 192.852053 -46.464915) (xy 192.887744 -46.423724)
			(xy 192.928935 -46.388033) (xy 192.974785 -46.358567) (xy 193.024362 -46.335925) (xy 193.076657 -46.32057)
			(xy 193.130605 -46.312814) (xy 193.185107 -46.312814) (xy 193.239055 -46.32057) (xy 193.29135 -46.335925)
			(xy 193.340927 -46.358567) (xy 193.386777 -46.388033) (xy 193.427968 -46.423724) (xy 193.463659 -46.464915)
			(xy 193.493125 -46.510765) (xy 193.515767 -46.560342) (xy 193.531122 -46.612637) (xy 193.538878 -46.666585)
			(xy 193.539364 -46.693836) (xy 193.538896 -46.720264) (xy 193.531586 -46.772611) (xy 193.517111 -46.823446)
			(xy 193.49575 -46.871793) (xy 193.482214 -46.894496) (xy 193.48196 -46.89475) (xy 193.476623 -46.904768)
			(xy 193.474365 -46.927318) (xy 193.477642 -46.938184) (xy 193.503804 -47.01286) (xy 193.508165 -47.023388)
			(xy 193.524269 -47.039471) (xy 193.534792 -47.043848) (xy 193.535046 -47.043848) (xy 193.559555 -47.052918)
			(xy 193.606007 -47.07686) (xy 193.648759 -47.106916) (xy 193.687011 -47.142523) (xy 193.720048 -47.183016)
			(xy 193.747251 -47.227637) (xy 193.768113 -47.275552) (xy 193.782243 -47.325866) (xy 193.789377 -47.377636)
			(xy 193.789808 -47.403766) (xy 193.789322 -47.431017) (xy 193.787799 -47.441612) (xy 195.061838 -47.441612)
			(xy 195.065909 -47.38599) (xy 195.078035 -47.331553) (xy 195.097958 -47.279462) (xy 195.125254 -47.230827)
			(xy 195.15934 -47.186684) (xy 195.199489 -47.147975) (xy 195.244847 -47.115524) (xy 195.294447 -47.090023)
			(xy 195.347231 -47.072016) (xy 195.402074 -47.061886) (xy 195.457808 -47.059849) (xy 195.513245 -47.065949)
			(xy 195.567202 -47.080055) (xy 195.618531 -47.101867) (xy 195.666137 -47.130921) (xy 195.709005 -47.166596)
			(xy 195.746222 -47.208133) (xy 195.776995 -47.254646) (xy 195.800667 -47.305143) (xy 195.816735 -47.35855)
			(xy 195.824855 -47.413726) (xy 195.825364 -47.441612) (xy 195.824855 -47.469498) (xy 195.816735 -47.524674)
			(xy 195.800667 -47.578081) (xy 195.776995 -47.628578) (xy 195.746222 -47.675091) (xy 195.709005 -47.716628)
			(xy 195.666137 -47.752303) (xy 195.618531 -47.781357) (xy 195.567202 -47.803169) (xy 195.513245 -47.817275)
			(xy 195.457808 -47.823375) (xy 195.402074 -47.821338) (xy 195.347231 -47.811208) (xy 195.294447 -47.793201)
			(xy 195.244847 -47.7677) (xy 195.199489 -47.735249) (xy 195.15934 -47.69654) (xy 195.125254 -47.652397)
			(xy 195.097958 -47.603762) (xy 195.078035 -47.551671) (xy 195.065909 -47.497234) (xy 195.061838 -47.441612)
			(xy 193.787799 -47.441612) (xy 193.781566 -47.484965) (xy 193.766211 -47.53726) (xy 193.743569 -47.586837)
			(xy 193.714103 -47.632687) (xy 193.678412 -47.673878) (xy 193.637221 -47.709569) (xy 193.591371 -47.739035)
			(xy 193.541794 -47.761677) (xy 193.489499 -47.777032) (xy 193.435551 -47.784788) (xy 193.381049 -47.784788)
			(xy 193.327101 -47.777032) (xy 193.274806 -47.761677) (xy 193.225229 -47.739035) (xy 193.179379 -47.709569)
			(xy 193.138188 -47.673878) (xy 193.102497 -47.632687) (xy 193.073031 -47.586837) (xy 193.050389 -47.53726)
			(xy 193.035034 -47.484965) (xy 193.027278 -47.431017) (xy 193.026792 -47.403766) (xy 193.027267 -47.377339)
			(xy 193.034576 -47.324991) (xy 193.049049 -47.274156) (xy 193.070408 -47.225809) (xy 193.083942 -47.203106)
			(xy 193.084196 -47.202852) (xy 193.089531 -47.192834) (xy 193.091788 -47.170284) (xy 193.088514 -47.159418)
			(xy 193.062352 -47.084742) (xy 193.057965 -47.074228) (xy 193.041879 -47.058139) (xy 193.031364 -47.053754)
			(xy 193.03111 -47.053754) (xy 193.006593 -47.044708) (xy 192.960141 -47.02076) (xy 192.917391 -46.9907)
			(xy 192.87914 -46.955089) (xy 192.846105 -46.914594) (xy 192.818903 -46.86997) (xy 192.798042 -46.822053)
			(xy 192.783913 -46.771738) (xy 192.776779 -46.719966) (xy 192.776348 -46.693836) (xy 187.630125 -46.693836)
			(xy 187.632515 -46.708745) (xy 187.633102 -46.739048) (xy 187.632667 -46.766301) (xy 187.624904 -46.820251)
			(xy 187.609542 -46.872547) (xy 187.586895 -46.922124) (xy 187.557423 -46.967975) (xy 187.521726 -47.009165)
			(xy 187.480532 -47.044855) (xy 187.434677 -47.074321) (xy 187.385096 -47.096961) (xy 187.332798 -47.112315)
			(xy 187.278847 -47.120071) (xy 187.251594 -47.120556) (xy 187.225561 -47.120105) (xy 187.173978 -47.113018)
			(xy 187.123836 -47.098989) (xy 187.076065 -47.078279) (xy 187.03155 -47.051272) (xy 187.011056 -47.035212)
			(xy 187.003289 -47.029485) (xy 186.984886 -47.023735) (xy 186.975242 -47.024036) (xy 186.895486 -47.030386)
			(xy 186.877706 -47.039022) (xy 186.871356 -47.046388) (xy 186.85317 -47.066029) (xy 186.812263 -47.100551)
			(xy 186.766935 -47.129021) (xy 186.718075 -47.150879) (xy 186.66664 -47.165698) (xy 186.613639 -47.173186)
			(xy 186.586876 -47.173642) (xy 186.559626 -47.173145) (xy 186.50568 -47.165386) (xy 186.453388 -47.150029)
			(xy 186.403813 -47.127388) (xy 186.357964 -47.097922) (xy 186.316775 -47.062232) (xy 186.281084 -47.021044)
			(xy 186.251617 -46.975196) (xy 186.228974 -46.925622) (xy 186.213616 -46.87333) (xy 186.205856 -46.819384)
			(xy 186.205368 -46.792134) (xy 186.205901 -46.76336) (xy 186.214551 -46.706467) (xy 186.231646 -46.651517)
			(xy 186.256797 -46.599757) (xy 186.289435 -46.55236) (xy 186.308746 -46.531022) (xy 186.316112 -46.523148)
			(xy 186.323224 -46.503336) (xy 186.315858 -46.40707) (xy 186.305952 -46.388274) (xy 186.29757 -46.38167)
			(xy 186.275375 -46.363458) (xy 186.236168 -46.321518) (xy 186.203685 -46.27418) (xy 186.178659 -46.222509)
			(xy 186.161654 -46.167674) (xy 186.153054 -46.11091) (xy 186.152536 -46.082204) (xy 180.813964 -46.082204)
			(xy 180.813964 -48.30699) (xy 192.653918 -48.30699) (xy 192.657989 -48.251368) (xy 192.670115 -48.196931)
			(xy 192.690038 -48.14484) (xy 192.717334 -48.096205) (xy 192.75142 -48.052062) (xy 192.791569 -48.013353)
			(xy 192.836927 -47.980902) (xy 192.886527 -47.955401) (xy 192.939311 -47.937394) (xy 192.994154 -47.927264)
			(xy 193.049888 -47.925227) (xy 193.105325 -47.931327) (xy 193.159282 -47.945433) (xy 193.210611 -47.967245)
			(xy 193.258217 -47.996299) (xy 193.301085 -48.031974) (xy 193.338302 -48.073511) (xy 193.369075 -48.120024)
			(xy 193.392747 -48.170521) (xy 193.408815 -48.223928) (xy 193.416935 -48.279104) (xy 193.417444 -48.30699)
			(xy 193.416935 -48.334876) (xy 193.408815 -48.390052) (xy 193.392747 -48.443459) (xy 193.369075 -48.493956)
			(xy 193.338302 -48.540469) (xy 193.301085 -48.582006) (xy 193.258217 -48.617681) (xy 193.210611 -48.646735)
			(xy 193.159282 -48.668547) (xy 193.105325 -48.682653) (xy 193.049888 -48.688753) (xy 192.994154 -48.686716)
			(xy 192.939311 -48.676586) (xy 192.886527 -48.658579) (xy 192.836927 -48.633078) (xy 192.791569 -48.600627)
			(xy 192.75142 -48.561918) (xy 192.717334 -48.517775) (xy 192.690038 -48.46914) (xy 192.670115 -48.417049)
			(xy 192.657989 -48.362612) (xy 192.653918 -48.30699) (xy 180.813964 -48.30699) (xy 180.813964 -48.753014)
			(xy 189.268352 -48.753014) (xy 189.272423 -48.697392) (xy 189.284549 -48.642955) (xy 189.304472 -48.590864)
			(xy 189.331768 -48.542229) (xy 189.365854 -48.498086) (xy 189.406003 -48.459377) (xy 189.451361 -48.426926)
			(xy 189.500961 -48.401425) (xy 189.553745 -48.383418) (xy 189.608588 -48.373288) (xy 189.664322 -48.371251)
			(xy 189.719759 -48.377351) (xy 189.773716 -48.391457) (xy 189.825045 -48.413269) (xy 189.872651 -48.442323)
			(xy 189.915519 -48.477998) (xy 189.952736 -48.519535) (xy 189.983509 -48.566048) (xy 190.007181 -48.616545)
			(xy 190.023249 -48.669952) (xy 190.031369 -48.725128) (xy 190.031878 -48.753014) (xy 190.031369 -48.7809)
			(xy 190.023249 -48.836076) (xy 190.020805 -48.8442) (xy 190.2874 -48.8442) (xy 190.291471 -48.788578)
			(xy 190.303597 -48.734141) (xy 190.32352 -48.68205) (xy 190.350816 -48.633415) (xy 190.384902 -48.589272)
			(xy 190.425051 -48.550563) (xy 190.470409 -48.518112) (xy 190.520009 -48.492611) (xy 190.572793 -48.474604)
			(xy 190.627636 -48.464474) (xy 190.68337 -48.462437) (xy 190.738807 -48.468537) (xy 190.792764 -48.482643)
			(xy 190.844093 -48.504455) (xy 190.891699 -48.533509) (xy 190.934567 -48.569184) (xy 190.971784 -48.610721)
			(xy 191.002557 -48.657234) (xy 191.026229 -48.707731) (xy 191.042297 -48.761138) (xy 191.050417 -48.816314)
			(xy 191.050926 -48.8442) (xy 191.050417 -48.872086) (xy 191.047419 -48.89246) (xy 191.314068 -48.89246)
			(xy 191.318139 -48.836838) (xy 191.330265 -48.782401) (xy 191.350188 -48.73031) (xy 191.377484 -48.681675)
			(xy 191.41157 -48.637532) (xy 191.451719 -48.598823) (xy 191.497077 -48.566372) (xy 191.546677 -48.540871)
			(xy 191.599461 -48.522864) (xy 191.654304 -48.512734) (xy 191.710038 -48.510697) (xy 191.765475 -48.516797)
			(xy 191.819432 -48.530903) (xy 191.870761 -48.552715) (xy 191.918367 -48.581769) (xy 191.961235 -48.617444)
			(xy 191.998452 -48.658981) (xy 192.029225 -48.705494) (xy 192.052897 -48.755991) (xy 192.068965 -48.809398)
			(xy 192.077085 -48.864574) (xy 192.077594 -48.89246) (xy 192.077085 -48.920346) (xy 192.074647 -48.93691)
			(xy 195.033136 -48.93691) (xy 195.037207 -48.881288) (xy 195.049333 -48.826851) (xy 195.069256 -48.77476)
			(xy 195.096552 -48.726125) (xy 195.130638 -48.681982) (xy 195.170787 -48.643273) (xy 195.216145 -48.610822)
			(xy 195.265745 -48.585321) (xy 195.318529 -48.567314) (xy 195.373372 -48.557184) (xy 195.429106 -48.555147)
			(xy 195.484543 -48.561247) (xy 195.5385 -48.575353) (xy 195.589829 -48.597165) (xy 195.637435 -48.626219)
			(xy 195.680303 -48.661894) (xy 195.71752 -48.703431) (xy 195.748293 -48.749944) (xy 195.771965 -48.800441)
			(xy 195.788033 -48.853848) (xy 195.796153 -48.909024) (xy 195.796662 -48.93691) (xy 195.796153 -48.964796)
			(xy 195.788033 -49.019972) (xy 195.771965 -49.073379) (xy 195.748293 -49.123876) (xy 195.71752 -49.170389)
			(xy 195.680303 -49.211926) (xy 195.637435 -49.247601) (xy 195.589829 -49.276655) (xy 195.5385 -49.298467)
			(xy 195.484543 -49.312573) (xy 195.429106 -49.318673) (xy 195.373372 -49.316636) (xy 195.318529 -49.306506)
			(xy 195.265745 -49.288499) (xy 195.216145 -49.262998) (xy 195.170787 -49.230547) (xy 195.130638 -49.191838)
			(xy 195.096552 -49.147695) (xy 195.069256 -49.09906) (xy 195.049333 -49.046969) (xy 195.037207 -48.992532)
			(xy 195.033136 -48.93691) (xy 192.074647 -48.93691) (xy 192.068965 -48.975522) (xy 192.052897 -49.028929)
			(xy 192.029225 -49.079426) (xy 191.998452 -49.125939) (xy 191.961235 -49.167476) (xy 191.918367 -49.203151)
			(xy 191.870761 -49.232205) (xy 191.819432 -49.254017) (xy 191.765475 -49.268123) (xy 191.710038 -49.274223)
			(xy 191.654304 -49.272186) (xy 191.599461 -49.262056) (xy 191.546677 -49.244049) (xy 191.497077 -49.218548)
			(xy 191.451719 -49.186097) (xy 191.41157 -49.147388) (xy 191.377484 -49.103245) (xy 191.350188 -49.05461)
			(xy 191.330265 -49.002519) (xy 191.318139 -48.948082) (xy 191.314068 -48.89246) (xy 191.047419 -48.89246)
			(xy 191.042297 -48.927262) (xy 191.026229 -48.980669) (xy 191.002557 -49.031166) (xy 190.971784 -49.077679)
			(xy 190.934567 -49.119216) (xy 190.891699 -49.154891) (xy 190.844093 -49.183945) (xy 190.792764 -49.205757)
			(xy 190.738807 -49.219863) (xy 190.68337 -49.225963) (xy 190.627636 -49.223926) (xy 190.572793 -49.213796)
			(xy 190.520009 -49.195789) (xy 190.470409 -49.170288) (xy 190.425051 -49.137837) (xy 190.384902 -49.099128)
			(xy 190.350816 -49.054985) (xy 190.32352 -49.00635) (xy 190.303597 -48.954259) (xy 190.291471 -48.899822)
			(xy 190.2874 -48.8442) (xy 190.020805 -48.8442) (xy 190.007181 -48.889483) (xy 189.983509 -48.93998)
			(xy 189.952736 -48.986493) (xy 189.915519 -49.02803) (xy 189.872651 -49.063705) (xy 189.825045 -49.092759)
			(xy 189.773716 -49.114571) (xy 189.719759 -49.128677) (xy 189.664322 -49.134777) (xy 189.608588 -49.13274)
			(xy 189.553745 -49.12261) (xy 189.500961 -49.104603) (xy 189.451361 -49.079102) (xy 189.406003 -49.046651)
			(xy 189.365854 -49.007942) (xy 189.331768 -48.963799) (xy 189.304472 -48.915164) (xy 189.284549 -48.863073)
			(xy 189.272423 -48.808636) (xy 189.268352 -48.753014) (xy 180.813964 -48.753014) (xy 180.813964 -49.601949)
			(xy 200.212982 -49.601949) (xy 200.212982 -49.547451) (xy 200.220737 -49.493507) (xy 200.23609 -49.441216)
			(xy 200.258728 -49.391642) (xy 200.28819 -49.345794) (xy 200.323877 -49.304605) (xy 200.365062 -49.268914)
			(xy 200.410907 -49.239447) (xy 200.460479 -49.216804) (xy 200.512768 -49.201446) (xy 200.566711 -49.193684)
			(xy 200.59396 -49.193196) (xy 200.621329 -49.193686) (xy 200.675507 -49.201499) (xy 200.72801 -49.216982)
			(xy 200.777757 -49.239818) (xy 200.823725 -49.269537) (xy 200.844658 -49.287176) (xy 200.844912 -49.28743)
			(xy 200.851988 -49.293031) (xy 200.868913 -49.299268) (xy 200.877932 -49.299622) (xy 200.944988 -49.299622)
			(xy 200.954004 -49.299254) (xy 200.97092 -49.293014) (xy 200.978008 -49.28743) (xy 200.978008 -49.287176)
			(xy 200.978262 -49.287176) (xy 200.999195 -49.269535) (xy 201.045163 -49.239811) (xy 201.094909 -49.216965)
			(xy 201.147411 -49.201469) (xy 201.201589 -49.19364) (xy 201.256331 -49.19364) (xy 201.310509 -49.201469)
			(xy 201.363011 -49.216965) (xy 201.412757 -49.239811) (xy 201.458725 -49.269535) (xy 201.479658 -49.287176)
			(xy 201.479912 -49.28743) (xy 201.486988 -49.293031) (xy 201.503913 -49.299268) (xy 201.512932 -49.299622)
			(xy 201.579988 -49.299622) (xy 201.589004 -49.299254) (xy 201.60592 -49.293014) (xy 201.613008 -49.28743)
			(xy 201.613008 -49.287176) (xy 201.613262 -49.287176) (xy 201.634195 -49.269535) (xy 201.680163 -49.239811)
			(xy 201.729909 -49.216965) (xy 201.782411 -49.201469) (xy 201.836589 -49.19364) (xy 201.891331 -49.19364)
			(xy 201.945509 -49.201469) (xy 201.998011 -49.216965) (xy 202.047757 -49.239811) (xy 202.093725 -49.269535)
			(xy 202.114658 -49.287176) (xy 202.114912 -49.28743) (xy 202.121988 -49.293031) (xy 202.138913 -49.299268)
			(xy 202.147932 -49.299622) (xy 202.214988 -49.299622) (xy 202.224004 -49.299254) (xy 202.24092 -49.293014)
			(xy 202.248008 -49.28743) (xy 202.248008 -49.287176) (xy 202.248262 -49.287176) (xy 202.269194 -49.269538)
			(xy 202.315168 -49.239826) (xy 202.364915 -49.216991) (xy 202.417415 -49.201499) (xy 202.471591 -49.193671)
			(xy 202.49896 -49.193196) (xy 202.526215 -49.193649) (xy 202.580171 -49.201401) (xy 202.632474 -49.216754)
			(xy 202.68206 -49.239394) (xy 202.727918 -49.268861) (xy 202.769116 -49.304555) (xy 202.804815 -49.34575)
			(xy 202.834287 -49.391605) (xy 202.856932 -49.441188) (xy 202.87229 -49.49349) (xy 202.880049 -49.547445)
			(xy 202.880049 -49.601955) (xy 202.87229 -49.65591) (xy 202.856932 -49.708212) (xy 202.834287 -49.757795)
			(xy 202.804815 -49.80365) (xy 202.769116 -49.844845) (xy 202.727918 -49.880539) (xy 202.68206 -49.910006)
			(xy 202.632474 -49.932646) (xy 202.580171 -49.947999) (xy 202.526215 -49.955751) (xy 202.49896 -49.956212)
			(xy 202.471591 -49.955708) (xy 202.417414 -49.947899) (xy 202.364911 -49.932418) (xy 202.315164 -49.909585)
			(xy 202.269195 -49.879869) (xy 202.248262 -49.862232) (xy 202.248008 -49.861978) (xy 202.240925 -49.856386)
			(xy 202.224005 -49.850143) (xy 202.214988 -49.849786) (xy 202.147932 -49.849786) (xy 202.138917 -49.850161)
			(xy 202.122 -49.856396) (xy 202.114912 -49.861978) (xy 202.114658 -49.862232) (xy 202.093725 -49.879873)
			(xy 202.047757 -49.909597) (xy 201.998011 -49.932443) (xy 201.945509 -49.947939) (xy 201.891331 -49.955768)
			(xy 201.836589 -49.955768) (xy 201.782411 -49.947939) (xy 201.729909 -49.932443) (xy 201.680163 -49.909597)
			(xy 201.634195 -49.879873) (xy 201.613262 -49.862232) (xy 201.613008 -49.861978) (xy 201.605925 -49.856386)
			(xy 201.589005 -49.850143) (xy 201.579988 -49.849786) (xy 201.512932 -49.849786) (xy 201.503917 -49.850161)
			(xy 201.487 -49.856396) (xy 201.479912 -49.861978) (xy 201.479912 -49.862232) (xy 201.479658 -49.862232)
			(xy 201.458725 -49.879873) (xy 201.412757 -49.909597) (xy 201.363011 -49.932443) (xy 201.310509 -49.947939)
			(xy 201.256331 -49.955768) (xy 201.201589 -49.955768) (xy 201.147411 -49.947939) (xy 201.094909 -49.932443)
			(xy 201.045163 -49.909597) (xy 200.999195 -49.879873) (xy 200.978262 -49.862232) (xy 200.978008 -49.861978)
			(xy 200.970925 -49.856386) (xy 200.954005 -49.850143) (xy 200.944988 -49.849786) (xy 200.877932 -49.849786)
			(xy 200.868917 -49.850161) (xy 200.852 -49.856396) (xy 200.844912 -49.861978) (xy 200.844912 -49.862232)
			(xy 200.844658 -49.862232) (xy 200.823719 -49.879862) (xy 200.777748 -49.909574) (xy 200.728002 -49.932412)
			(xy 200.675503 -49.947905) (xy 200.621329 -49.955736) (xy 200.59396 -49.956212) (xy 200.566711 -49.955716)
			(xy 200.512768 -49.947954) (xy 200.460479 -49.932596) (xy 200.410907 -49.909953) (xy 200.365062 -49.880486)
			(xy 200.323877 -49.844795) (xy 200.28819 -49.803606) (xy 200.258728 -49.757758) (xy 200.23609 -49.708184)
			(xy 200.220737 -49.655893) (xy 200.212982 -49.601949) (xy 180.813964 -49.601949) (xy 180.813964 -50.462434)
			(xy 190.92621 -50.462434) (xy 190.930281 -50.406812) (xy 190.942407 -50.352375) (xy 190.96233 -50.300284)
			(xy 190.989626 -50.251649) (xy 191.023712 -50.207506) (xy 191.063861 -50.168797) (xy 191.109219 -50.136346)
			(xy 191.158819 -50.110845) (xy 191.211603 -50.092838) (xy 191.266446 -50.082708) (xy 191.32218 -50.080671)
			(xy 191.377617 -50.086771) (xy 191.431574 -50.100877) (xy 191.482903 -50.122689) (xy 191.530509 -50.151743)
			(xy 191.573377 -50.187418) (xy 191.610594 -50.228955) (xy 191.641367 -50.275468) (xy 191.665039 -50.325965)
			(xy 191.681107 -50.379372) (xy 191.689227 -50.434548) (xy 191.689736 -50.462434) (xy 191.689227 -50.49032)
			(xy 191.681107 -50.545496) (xy 191.665039 -50.598903) (xy 191.641367 -50.6494) (xy 191.610594 -50.695913)
			(xy 191.573377 -50.73745) (xy 191.530509 -50.773125) (xy 191.482903 -50.802179) (xy 191.431574 -50.823991)
			(xy 191.377617 -50.838097) (xy 191.32218 -50.844197) (xy 191.266446 -50.84216) (xy 191.211603 -50.83203)
			(xy 191.158819 -50.814023) (xy 191.109219 -50.788522) (xy 191.063861 -50.756071) (xy 191.023712 -50.717362)
			(xy 190.989626 -50.673219) (xy 190.96233 -50.624584) (xy 190.942407 -50.572493) (xy 190.930281 -50.518056)
			(xy 190.92621 -50.462434) (xy 180.813964 -50.462434) (xy 180.813964 -51.019456) (xy 192.849498 -51.019456)
			(xy 192.853569 -50.963834) (xy 192.865695 -50.909397) (xy 192.885618 -50.857306) (xy 192.912914 -50.808671)
			(xy 192.947 -50.764528) (xy 192.987149 -50.725819) (xy 193.032507 -50.693368) (xy 193.082107 -50.667867)
			(xy 193.134891 -50.64986) (xy 193.189734 -50.63973) (xy 193.245468 -50.637693) (xy 193.300905 -50.643793)
			(xy 193.354862 -50.657899) (xy 193.406191 -50.679711) (xy 193.453797 -50.708765) (xy 193.496665 -50.74444)
			(xy 193.533882 -50.785977) (xy 193.564655 -50.83249) (xy 193.588327 -50.882987) (xy 193.604395 -50.936394)
			(xy 193.612515 -50.99157) (xy 193.613024 -51.019456) (xy 193.612515 -51.047342) (xy 193.604395 -51.102518)
			(xy 193.588327 -51.155925) (xy 193.564655 -51.206422) (xy 193.539799 -51.243992) (xy 201.233024 -51.243992)
			(xy 201.23348 -51.216621) (xy 201.241299 -51.162442) (xy 201.25679 -51.109938) (xy 201.279634 -51.060191)
			(xy 201.309362 -51.014225) (xy 201.327004 -50.993294) (xy 201.327258 -50.99304) (xy 201.332841 -50.985951)
			(xy 201.339088 -50.969036) (xy 201.33945 -50.96002) (xy 201.33945 -50.892964) (xy 201.339121 -50.883944)
			(xy 201.332855 -50.867027) (xy 201.327258 -50.859944) (xy 201.327004 -50.859944) (xy 201.327004 -50.85969)
			(xy 201.309347 -50.838772) (xy 201.279638 -50.792795) (xy 201.256805 -50.743044) (xy 201.241318 -50.690541)
			(xy 201.233495 -50.636362) (xy 201.233024 -50.608992) (xy 201.233448 -50.581737) (xy 201.241207 -50.527784)
			(xy 201.256566 -50.475483) (xy 201.279211 -50.425901) (xy 201.308683 -50.380046) (xy 201.344381 -50.338853)
			(xy 201.385578 -50.303159) (xy 201.431436 -50.273692) (xy 201.481021 -50.251052) (xy 201.533323 -50.235698)
			(xy 201.587277 -50.227945) (xy 201.614532 -50.227484) (xy 201.643449 -50.228019) (xy 201.70062 -50.23674)
			(xy 201.75582 -50.253993) (xy 201.807783 -50.279381) (xy 201.855317 -50.312323) (xy 201.897333 -50.352064)
			(xy 201.915522 -50.37455) (xy 201.923121 -50.383366) (xy 201.944028 -50.393543) (xy 201.955654 -50.394108)
			(xy 202.03541 -50.394108) (xy 202.04704 -50.393557) (xy 202.06795 -50.383376) (xy 202.075542 -50.37455)
			(xy 202.093697 -50.352036) (xy 202.135725 -50.312305) (xy 202.183268 -50.279371) (xy 202.235237 -50.253988)
			(xy 202.29044 -50.236738) (xy 202.347614 -50.228016) (xy 202.376532 -50.227484) (xy 202.403784 -50.227948)
			(xy 202.457732 -50.235709) (xy 202.510026 -50.251067) (xy 202.559603 -50.273712) (xy 202.605453 -50.303181)
			(xy 202.646643 -50.338874) (xy 202.682334 -50.380066) (xy 202.7118 -50.425918) (xy 202.734441 -50.475496)
			(xy 202.749796 -50.527792) (xy 202.757554 -50.58174) (xy 202.75804 -50.608992) (xy 202.757586 -50.635307)
			(xy 202.750351 -50.687437) (xy 202.736031 -50.73808) (xy 202.714896 -50.78628) (xy 202.687347 -50.831123)
			(xy 202.653904 -50.871761) (xy 202.63485 -50.889916) (xy 202.627447 -50.897436) (xy 202.618922 -50.916717)
			(xy 202.61834 -50.927254) (xy 202.61834 -51.00193) (xy 202.618882 -51.012479) (xy 202.627407 -51.031775)
			(xy 202.63485 -51.039268) (xy 202.653941 -51.057388) (xy 202.687393 -51.098026) (xy 202.714946 -51.142874)
			(xy 202.736078 -51.191082) (xy 202.750388 -51.241735) (xy 202.757605 -51.293874) (xy 202.75804 -51.320192)
			(xy 202.757515 -51.347442) (xy 202.74976 -51.401386) (xy 202.734408 -51.453678) (xy 202.71177 -51.503253)
			(xy 202.682307 -51.549102) (xy 202.64662 -51.590292) (xy 202.605434 -51.625983) (xy 202.559589 -51.655451)
			(xy 202.510016 -51.678094) (xy 202.457725 -51.693452) (xy 202.403782 -51.701212) (xy 202.376532 -51.7017)
			(xy 202.348868 -51.701163) (xy 202.29412 -51.693168) (xy 202.241099 -51.677356) (xy 202.190915 -51.654057)
			(xy 202.144619 -51.623759) (xy 202.10318 -51.587098) (xy 202.067466 -51.544839) (xy 202.052428 -51.521614)
			(xy 202.045788 -51.511941) (xy 202.025929 -51.499496) (xy 202.014328 -51.497738) (xy 201.934318 -51.489864)
			(xy 201.92268 -51.489247) (xy 201.900843 -51.497316) (xy 201.892408 -51.505358) (xy 201.892154 -51.505612)
			(xy 201.87408 -51.5242) (xy 201.833746 -51.556777) (xy 201.78937 -51.583589) (xy 201.741771 -51.604141)
			(xy 201.691825 -51.618053) (xy 201.640455 -51.625069) (xy 201.614532 -51.6255) (xy 201.58728 -51.625015)
			(xy 201.533329 -51.617262) (xy 201.481031 -51.60191) (xy 201.431451 -51.57927) (xy 201.385597 -51.549805)
			(xy 201.344404 -51.514113) (xy 201.308709 -51.472922) (xy 201.279241 -51.427071) (xy 201.256599 -51.377491)
			(xy 201.241243 -51.325194) (xy 201.233487 -51.271244) (xy 201.233024 -51.243992) (xy 193.539799 -51.243992)
			(xy 193.533882 -51.252935) (xy 193.496665 -51.294472) (xy 193.453797 -51.330147) (xy 193.406191 -51.359201)
			(xy 193.354862 -51.381013) (xy 193.300905 -51.395119) (xy 193.245468 -51.401219) (xy 193.189734 -51.399182)
			(xy 193.134891 -51.389052) (xy 193.082107 -51.371045) (xy 193.032507 -51.345544) (xy 192.987149 -51.313093)
			(xy 192.947 -51.274384) (xy 192.912914 -51.230241) (xy 192.885618 -51.181606) (xy 192.865695 -51.129515)
			(xy 192.853569 -51.075078) (xy 192.849498 -51.019456) (xy 180.813964 -51.019456) (xy 180.813964 -52.035456)
			(xy 195.041264 -52.035456) (xy 195.045335 -51.979834) (xy 195.057461 -51.925397) (xy 195.077384 -51.873306)
			(xy 195.10468 -51.824671) (xy 195.138766 -51.780528) (xy 195.178915 -51.741819) (xy 195.224273 -51.709368)
			(xy 195.273873 -51.683867) (xy 195.326657 -51.66586) (xy 195.3815 -51.65573) (xy 195.437234 -51.653693)
			(xy 195.492671 -51.659793) (xy 195.546628 -51.673899) (xy 195.597957 -51.695711) (xy 195.645563 -51.724765)
			(xy 195.688431 -51.76044) (xy 195.725648 -51.801977) (xy 195.756421 -51.84849) (xy 195.780093 -51.898987)
			(xy 195.796161 -51.952394) (xy 195.804281 -52.00757) (xy 195.80479 -52.035456) (xy 195.804281 -52.063342)
			(xy 195.796161 -52.118518) (xy 195.780093 -52.171925) (xy 195.756421 -52.222422) (xy 195.725648 -52.268935)
			(xy 195.688431 -52.310472) (xy 195.645563 -52.346147) (xy 195.597957 -52.375201) (xy 195.546628 -52.397013)
			(xy 195.492671 -52.411119) (xy 195.437234 -52.417219) (xy 195.3815 -52.415182) (xy 195.326657 -52.405052)
			(xy 195.273873 -52.387045) (xy 195.224273 -52.361544) (xy 195.178915 -52.329093) (xy 195.138766 -52.290384)
			(xy 195.10468 -52.246241) (xy 195.077384 -52.197606) (xy 195.057461 -52.145515) (xy 195.045335 -52.091078)
			(xy 195.041264 -52.035456) (xy 180.813964 -52.035456) (xy 180.813964 -54.731412) (xy 181.620668 -54.731412)
			(xy 181.621125 -54.704041) (xy 181.628942 -54.649861) (xy 181.644432 -54.597357) (xy 181.667277 -54.54761)
			(xy 181.697005 -54.501645) (xy 181.714648 -54.480714) (xy 181.714902 -54.48046) (xy 181.72047 -54.473361)
			(xy 181.726728 -54.456454) (xy 181.727094 -54.44744) (xy 181.727094 -54.380384) (xy 181.726746 -54.371366)
			(xy 181.720492 -54.354449) (xy 181.714902 -54.347364) (xy 181.714648 -54.347364) (xy 181.714648 -54.34711)
			(xy 181.697018 -54.326168) (xy 181.667291 -54.280202) (xy 181.644444 -54.230458) (xy 181.628946 -54.177957)
			(xy 181.621116 -54.123779) (xy 181.621114 -54.069039) (xy 181.628942 -54.014861) (xy 181.644438 -53.962359)
			(xy 181.667283 -53.912613) (xy 181.697007 -53.866646) (xy 181.714648 -53.845714) (xy 181.714902 -53.84546)
			(xy 181.72047 -53.838361) (xy 181.726728 -53.821454) (xy 181.727094 -53.81244) (xy 181.727094 -53.745384)
			(xy 181.726746 -53.736366) (xy 181.720492 -53.719449) (xy 181.714902 -53.712364) (xy 181.714648 -53.712364)
			(xy 181.714648 -53.71211) (xy 181.697018 -53.691168) (xy 181.667291 -53.645202) (xy 181.644444 -53.595458)
			(xy 181.628946 -53.542957) (xy 181.621116 -53.488779) (xy 181.621114 -53.434039) (xy 181.628942 -53.379861)
			(xy 181.644438 -53.327359) (xy 181.667283 -53.277613) (xy 181.697007 -53.231646) (xy 181.714648 -53.210714)
			(xy 181.714902 -53.21046) (xy 181.72047 -53.203361) (xy 181.726728 -53.186454) (xy 181.727094 -53.17744)
			(xy 181.727094 -53.110384) (xy 181.726746 -53.101366) (xy 181.720492 -53.084449) (xy 181.714902 -53.077364)
			(xy 181.714648 -53.077364) (xy 181.714648 -53.07711) (xy 181.697008 -53.056179) (xy 181.667294 -53.010207)
			(xy 181.644458 -52.960459) (xy 181.628967 -52.907958) (xy 181.621141 -52.853781) (xy 181.620668 -52.826412)
			(xy 181.621154 -52.799161) (xy 181.62891 -52.745213) (xy 181.644265 -52.692918) (xy 181.666907 -52.643341)
			(xy 181.696373 -52.597491) (xy 181.732064 -52.5563) (xy 181.773255 -52.520609) (xy 181.819105 -52.491143)
			(xy 181.868682 -52.468501) (xy 181.920977 -52.453146) (xy 181.974925 -52.44539) (xy 182.029427 -52.44539)
			(xy 182.083375 -52.453146) (xy 182.13567 -52.468501) (xy 182.185247 -52.491143) (xy 182.231097 -52.520609)
			(xy 182.272288 -52.5563) (xy 182.307979 -52.597491) (xy 182.337445 -52.643341) (xy 182.360087 -52.692918)
			(xy 182.375442 -52.745213) (xy 182.383198 -52.799161) (xy 182.383684 -52.826412) (xy 182.383229 -52.853783)
			(xy 182.375409 -52.907962) (xy 182.359918 -52.960466) (xy 182.337073 -53.010212) (xy 182.307346 -53.056179)
			(xy 182.289704 -53.07711) (xy 182.28945 -53.077364) (xy 182.283866 -53.084452) (xy 182.277619 -53.101368)
			(xy 182.277258 -53.110384) (xy 182.277258 -53.17744) (xy 182.277583 -53.18646) (xy 182.283851 -53.203378)
			(xy 182.28945 -53.21046) (xy 182.289704 -53.21046) (xy 182.289704 -53.210714) (xy 182.307355 -53.231638)
			(xy 182.337077 -53.277608) (xy 182.35992 -53.327356) (xy 182.375414 -53.379859) (xy 182.383241 -53.434038)
			(xy 182.383239 -53.48878) (xy 182.37541 -53.542959) (xy 182.359914 -53.595461) (xy 182.337068 -53.645208)
			(xy 182.307344 -53.691177) (xy 182.289704 -53.71211) (xy 182.28945 -53.712364) (xy 182.283866 -53.719452)
			(xy 182.277619 -53.736368) (xy 182.277258 -53.745384) (xy 182.277258 -53.81244) (xy 182.277583 -53.82146)
			(xy 182.283851 -53.838378) (xy 182.28945 -53.84546) (xy 182.289704 -53.84546) (xy 182.289704 -53.845714)
			(xy 182.307355 -53.866638) (xy 182.337077 -53.912608) (xy 182.35992 -53.962356) (xy 182.375414 -54.014859)
			(xy 182.383241 -54.069038) (xy 182.383239 -54.12378) (xy 182.37541 -54.177959) (xy 182.359914 -54.230461)
			(xy 182.337068 -54.280208) (xy 182.307344 -54.326177) (xy 182.289704 -54.34711) (xy 182.28945 -54.347364)
			(xy 182.283866 -54.354452) (xy 182.277619 -54.371368) (xy 182.277258 -54.380384) (xy 182.277258 -54.44744)
			(xy 182.277583 -54.45646) (xy 182.283851 -54.473378) (xy 182.28945 -54.48046) (xy 182.289704 -54.48046)
			(xy 182.289704 -54.480714) (xy 182.307317 -54.501667) (xy 182.337033 -54.547634) (xy 182.359873 -54.597376)
			(xy 182.375371 -54.649872) (xy 182.383206 -54.704044) (xy 182.383684 -54.731412) (xy 182.383198 -54.758663)
			(xy 182.378534 -54.791102) (xy 184.276492 -54.791102) (xy 184.276961 -54.763732) (xy 184.284779 -54.709553)
			(xy 184.300267 -54.65705) (xy 184.323108 -54.607303) (xy 184.352831 -54.561336) (xy 184.370472 -54.540404)
			(xy 184.370726 -54.54015) (xy 184.376301 -54.533055) (xy 184.382554 -54.516145) (xy 184.382918 -54.50713)
			(xy 184.382918 -54.440074) (xy 184.38257 -54.431056) (xy 184.376316 -54.41414) (xy 184.370726 -54.407054)
			(xy 184.370472 -54.407054) (xy 184.370472 -54.4068) (xy 184.352831 -54.385867) (xy 184.323103 -54.3399)
			(xy 184.300255 -54.290154) (xy 184.284757 -54.237652) (xy 184.276927 -54.183473) (xy 184.276927 -54.12873)
			(xy 184.284756 -54.074551) (xy 184.300254 -54.022049) (xy 184.323102 -53.972303) (xy 184.35283 -53.926336)
			(xy 184.370472 -53.905404) (xy 184.370726 -53.90515) (xy 184.376301 -53.898055) (xy 184.382554 -53.881145)
			(xy 184.382918 -53.87213) (xy 184.382918 -53.805074) (xy 184.38257 -53.796056) (xy 184.376316 -53.77914)
			(xy 184.370726 -53.772054) (xy 184.370472 -53.772054) (xy 184.370472 -53.7718) (xy 184.352831 -53.750867)
			(xy 184.323103 -53.7049) (xy 184.300255 -53.655154) (xy 184.284757 -53.602652) (xy 184.276927 -53.548473)
			(xy 184.276927 -53.49373) (xy 184.284756 -53.439551) (xy 184.300254 -53.387049) (xy 184.323102 -53.337303)
			(xy 184.35283 -53.291336) (xy 184.370472 -53.270404) (xy 184.370726 -53.27015) (xy 184.376301 -53.263055)
			(xy 184.382554 -53.246145) (xy 184.382918 -53.23713) (xy 184.382918 -53.170074) (xy 184.38257 -53.161056)
			(xy 184.376316 -53.14414) (xy 184.370726 -53.137054) (xy 184.370472 -53.137054) (xy 184.370472 -53.1368)
			(xy 184.352815 -53.115882) (xy 184.323107 -53.069905) (xy 184.300275 -53.020154) (xy 184.284788 -52.96765)
			(xy 184.276964 -52.913472) (xy 184.276492 -52.886102) (xy 184.276978 -52.858851) (xy 184.284734 -52.804903)
			(xy 184.300089 -52.752608) (xy 184.322731 -52.703031) (xy 184.352197 -52.657181) (xy 184.387888 -52.61599)
			(xy 184.429079 -52.580299) (xy 184.474929 -52.550833) (xy 184.524506 -52.528191) (xy 184.576801 -52.512836)
			(xy 184.630749 -52.50508) (xy 184.685251 -52.50508) (xy 184.739199 -52.512836) (xy 184.791494 -52.528191)
			(xy 184.830594 -52.546048) (xy 189.779696 -52.546048) (xy 189.779696 -52.491552) (xy 189.787451 -52.437611)
			(xy 189.802803 -52.385322) (xy 189.82544 -52.33575) (xy 189.854901 -52.289904) (xy 189.890586 -52.248717)
			(xy 189.931769 -52.213027) (xy 189.977612 -52.183561) (xy 190.027181 -52.160919) (xy 190.079468 -52.14556)
			(xy 190.133408 -52.137799) (xy 190.160656 -52.13731) (xy 190.188025 -52.137799) (xy 190.242204 -52.145611)
			(xy 190.294707 -52.161095) (xy 190.344454 -52.183931) (xy 190.390422 -52.213651) (xy 190.411354 -52.23129)
			(xy 190.411608 -52.231544) (xy 190.418684 -52.237145) (xy 190.435609 -52.243382) (xy 190.444628 -52.243736)
			(xy 190.511684 -52.243736) (xy 190.520699 -52.243363) (xy 190.537616 -52.237126) (xy 190.544704 -52.231544)
			(xy 190.544704 -52.23129) (xy 190.544958 -52.23129) (xy 190.565891 -52.213649) (xy 190.611859 -52.183925)
			(xy 190.661605 -52.161079) (xy 190.714107 -52.145583) (xy 190.768285 -52.137754) (xy 190.823027 -52.137754)
			(xy 190.877205 -52.145583) (xy 190.929707 -52.161079) (xy 190.979453 -52.183925) (xy 191.025421 -52.213649)
			(xy 191.046354 -52.23129) (xy 191.046608 -52.231544) (xy 191.053684 -52.237145) (xy 191.070609 -52.243382)
			(xy 191.079628 -52.243736) (xy 191.146684 -52.243736) (xy 191.155699 -52.243363) (xy 191.172616 -52.237126)
			(xy 191.179704 -52.231544) (xy 191.179704 -52.23129) (xy 191.179958 -52.23129) (xy 191.200894 -52.213656)
			(xy 191.246866 -52.183943) (xy 191.296612 -52.161107) (xy 191.349112 -52.145615) (xy 191.403287 -52.137785)
			(xy 191.430656 -52.13731) (xy 191.457912 -52.137734) (xy 191.511871 -52.145486) (xy 191.564176 -52.160839)
			(xy 191.613764 -52.18348) (xy 191.659625 -52.212948) (xy 191.700825 -52.248644) (xy 191.736525 -52.28984)
			(xy 191.765999 -52.335697) (xy 191.788645 -52.385283) (xy 191.804004 -52.437586) (xy 191.811763 -52.491544)
			(xy 191.811763 -52.546056) (xy 191.805818 -52.587398) (xy 192.85534 -52.587398) (xy 192.859411 -52.531776)
			(xy 192.871537 -52.477339) (xy 192.89146 -52.425248) (xy 192.918756 -52.376613) (xy 192.952842 -52.33247)
			(xy 192.992991 -52.293761) (xy 193.038349 -52.26131) (xy 193.087949 -52.235809) (xy 193.140733 -52.217802)
			(xy 193.195576 -52.207672) (xy 193.25131 -52.205635) (xy 193.306747 -52.211735) (xy 193.360704 -52.225841)
			(xy 193.412033 -52.247653) (xy 193.459639 -52.276707) (xy 193.502507 -52.312382) (xy 193.539724 -52.353919)
			(xy 193.570497 -52.400432) (xy 193.594169 -52.450929) (xy 193.610237 -52.504336) (xy 193.617833 -52.555948)
			(xy 200.683902 -52.555948) (xy 200.683902 -52.501452) (xy 200.691658 -52.447509) (xy 200.70701 -52.39522)
			(xy 200.729648 -52.345647) (xy 200.759111 -52.299801) (xy 200.794797 -52.258614) (xy 200.835982 -52.222925)
			(xy 200.881826 -52.19346) (xy 200.931397 -52.170819) (xy 200.983686 -52.155463) (xy 201.037628 -52.147704)
			(xy 201.064876 -52.147216) (xy 201.092246 -52.147692) (xy 201.146425 -52.155507) (xy 201.198928 -52.170994)
			(xy 201.248675 -52.193833) (xy 201.294642 -52.223556) (xy 201.315574 -52.241196) (xy 201.315828 -52.24145)
			(xy 201.322927 -52.247019) (xy 201.339834 -52.253275) (xy 201.348848 -52.253642) (xy 201.415904 -52.253642)
			(xy 201.424923 -52.253299) (xy 201.44184 -52.247043) (xy 201.448924 -52.24145) (xy 201.448924 -52.241196)
			(xy 201.449178 -52.241196) (xy 201.470107 -52.223553) (xy 201.516081 -52.193842) (xy 201.565829 -52.171007)
			(xy 201.61833 -52.155517) (xy 201.672507 -52.147689) (xy 201.699876 -52.147216) (xy 201.727132 -52.147629)
			(xy 201.781089 -52.155384) (xy 201.833393 -52.170739) (xy 201.882979 -52.193381) (xy 201.928838 -52.222851)
			(xy 201.970036 -52.258547) (xy 202.005735 -52.299743) (xy 202.035207 -52.3456) (xy 202.057853 -52.395185)
			(xy 202.073211 -52.447488) (xy 202.080969 -52.501444) (xy 202.080969 -52.555956) (xy 202.073211 -52.609912)
			(xy 202.057853 -52.662215) (xy 202.035207 -52.7118) (xy 202.005735 -52.757657) (xy 201.970036 -52.798853)
			(xy 201.928838 -52.834549) (xy 201.882979 -52.864019) (xy 201.833393 -52.886661) (xy 201.781089 -52.902016)
			(xy 201.727132 -52.909771) (xy 201.699876 -52.910232) (xy 201.672504 -52.909797) (xy 201.618323 -52.901974)
			(xy 201.565819 -52.886479) (xy 201.516073 -52.86363) (xy 201.470108 -52.833897) (xy 201.449178 -52.816252)
			(xy 201.448924 -52.815998) (xy 201.441835 -52.810415) (xy 201.42492 -52.804166) (xy 201.415904 -52.803806)
			(xy 201.348848 -52.803806) (xy 201.339833 -52.804185) (xy 201.322916 -52.810417) (xy 201.315828 -52.815998)
			(xy 201.315828 -52.816252) (xy 201.315574 -52.816252) (xy 201.294619 -52.833862) (xy 201.248653 -52.86358)
			(xy 201.198912 -52.886422) (xy 201.146416 -52.90192) (xy 201.092244 -52.909755) (xy 201.064876 -52.910232)
			(xy 201.037628 -52.909696) (xy 200.983686 -52.901937) (xy 200.931397 -52.886581) (xy 200.881826 -52.86394)
			(xy 200.835982 -52.834475) (xy 200.794797 -52.798786) (xy 200.759111 -52.757599) (xy 200.729648 -52.711753)
			(xy 200.70701 -52.66218) (xy 200.691658 -52.609891) (xy 200.683902 -52.555948) (xy 193.617833 -52.555948)
			(xy 193.618357 -52.559512) (xy 193.618866 -52.587398) (xy 193.618357 -52.615284) (xy 193.610237 -52.67046)
			(xy 193.594169 -52.723867) (xy 193.570497 -52.774364) (xy 193.539724 -52.820877) (xy 193.502507 -52.862414)
			(xy 193.459639 -52.898089) (xy 193.412033 -52.927143) (xy 193.360704 -52.948955) (xy 193.306747 -52.963061)
			(xy 193.25131 -52.969161) (xy 193.195576 -52.967124) (xy 193.140733 -52.956994) (xy 193.087949 -52.938987)
			(xy 193.038349 -52.913486) (xy 192.992991 -52.881035) (xy 192.952842 -52.842326) (xy 192.918756 -52.798183)
			(xy 192.89146 -52.749548) (xy 192.871537 -52.697457) (xy 192.859411 -52.64302) (xy 192.85534 -52.587398)
			(xy 191.805818 -52.587398) (xy 191.804004 -52.600014) (xy 191.788645 -52.652317) (xy 191.765999 -52.701903)
			(xy 191.736525 -52.74776) (xy 191.700825 -52.788956) (xy 191.659625 -52.824652) (xy 191.613764 -52.85412)
			(xy 191.564176 -52.876761) (xy 191.511871 -52.892114) (xy 191.457912 -52.899866) (xy 191.430656 -52.900326)
			(xy 191.403286 -52.899845) (xy 191.349107 -52.892034) (xy 191.296603 -52.876549) (xy 191.246856 -52.85371)
			(xy 191.200889 -52.823987) (xy 191.179958 -52.806346) (xy 191.179704 -52.806092) (xy 191.172621 -52.8005)
			(xy 191.155701 -52.794257) (xy 191.146684 -52.7939) (xy 191.079628 -52.7939) (xy 191.070612 -52.79427)
			(xy 191.053695 -52.800509) (xy 191.046608 -52.806092) (xy 191.046354 -52.806346) (xy 191.025421 -52.823987)
			(xy 190.979453 -52.853711) (xy 190.929707 -52.876557) (xy 190.877205 -52.892053) (xy 190.823027 -52.899882)
			(xy 190.768285 -52.899882) (xy 190.714107 -52.892053) (xy 190.661605 -52.876557) (xy 190.611859 -52.853711)
			(xy 190.565891 -52.823987) (xy 190.544958 -52.806346) (xy 190.544704 -52.806092) (xy 190.537621 -52.8005)
			(xy 190.520701 -52.794257) (xy 190.511684 -52.7939) (xy 190.444628 -52.7939) (xy 190.435612 -52.79427)
			(xy 190.418695 -52.800509) (xy 190.411608 -52.806092) (xy 190.411608 -52.806346) (xy 190.411354 -52.806346)
			(xy 190.390405 -52.823965) (xy 190.344438 -52.853682) (xy 190.294695 -52.876522) (xy 190.242197 -52.892018)
			(xy 190.188024 -52.89985) (xy 190.160656 -52.900326) (xy 190.133408 -52.899801) (xy 190.079468 -52.89204)
			(xy 190.027181 -52.876681) (xy 189.977612 -52.854039) (xy 189.931769 -52.824573) (xy 189.890586 -52.788883)
			(xy 189.854901 -52.747696) (xy 189.82544 -52.70185) (xy 189.802803 -52.652278) (xy 189.787451 -52.599989)
			(xy 189.779696 -52.546048) (xy 184.830594 -52.546048) (xy 184.841071 -52.550833) (xy 184.886921 -52.580299)
			(xy 184.928112 -52.61599) (xy 184.963803 -52.657181) (xy 184.993269 -52.703031) (xy 185.015911 -52.752608)
			(xy 185.031266 -52.804903) (xy 185.039022 -52.858851) (xy 185.039508 -52.886102) (xy 185.039041 -52.913472)
			(xy 185.031223 -52.967651) (xy 185.015734 -53.020154) (xy 184.992893 -53.069901) (xy 184.963169 -53.115868)
			(xy 184.945528 -53.1368) (xy 184.945274 -53.137054) (xy 184.939698 -53.144147) (xy 184.933446 -53.161059)
			(xy 184.933082 -53.170074) (xy 184.933082 -53.23713) (xy 184.933428 -53.246148) (xy 184.939684 -53.263065)
			(xy 184.945274 -53.27015) (xy 184.945528 -53.27015) (xy 184.945528 -53.270404) (xy 184.963173 -53.291334)
			(xy 184.992901 -53.337301) (xy 185.015749 -53.387048) (xy 185.031247 -53.439551) (xy 185.039076 -53.49373)
			(xy 185.039076 -53.548473) (xy 185.031246 -53.602652) (xy 185.015748 -53.655155) (xy 184.992899 -53.704901)
			(xy 184.963171 -53.750868) (xy 184.946598 -53.77053) (xy 185.31078 -53.77053) (xy 185.311289 -53.741612)
			(xy 185.320016 -53.684439) (xy 185.337274 -53.629239) (xy 185.362667 -53.577277) (xy 185.395613 -53.529743)
			(xy 185.435358 -53.487728) (xy 185.457846 -53.46954) (xy 185.466633 -53.461913) (xy 185.476826 -53.441027)
			(xy 185.477404 -53.429408) (xy 185.477404 -53.349652) (xy 185.476877 -53.338019) (xy 185.466679 -53.317109)
			(xy 185.457846 -53.30952) (xy 185.435361 -53.291331) (xy 185.395628 -53.249309) (xy 185.362691 -53.201774)
			(xy 185.337303 -53.149812) (xy 185.320047 -53.094615) (xy 185.311316 -53.037446) (xy 185.31078 -53.00853)
			(xy 185.311283 -52.981278) (xy 185.319036 -52.92733) (xy 185.334387 -52.875033) (xy 185.357026 -52.825454)
			(xy 185.386489 -52.779601) (xy 185.422179 -52.738409) (xy 185.463368 -52.702714) (xy 185.509217 -52.673246)
			(xy 185.558794 -52.650602) (xy 185.611088 -52.635245) (xy 185.665036 -52.627486) (xy 185.692288 -52.627022)
			(xy 185.718602 -52.62749) (xy 185.770731 -52.634724) (xy 185.821374 -52.649042) (xy 185.869573 -52.670175)
			(xy 185.914416 -52.697721) (xy 185.955056 -52.73116) (xy 185.973212 -52.750212) (xy 185.980726 -52.757623)
			(xy 186.000012 -52.766142) (xy 186.01055 -52.766722) (xy 186.085226 -52.766722) (xy 186.095772 -52.76616)
			(xy 186.115067 -52.757647) (xy 186.122564 -52.750212) (xy 186.140698 -52.731135) (xy 186.181332 -52.697679)
			(xy 186.226177 -52.670123) (xy 186.274382 -52.648988) (xy 186.325033 -52.634676) (xy 186.377171 -52.627457)
			(xy 186.403488 -52.627022) (xy 186.430742 -52.627467) (xy 186.484695 -52.635223) (xy 186.536995 -52.650579)
			(xy 186.586577 -52.673222) (xy 186.632432 -52.702692) (xy 186.673625 -52.738387) (xy 186.709319 -52.779583)
			(xy 186.738787 -52.825439) (xy 186.761428 -52.875022) (xy 186.776781 -52.927323) (xy 186.784535 -52.981276)
			(xy 186.784996 -53.00853) (xy 186.784509 -53.036196) (xy 186.776505 -53.090946) (xy 186.760684 -53.143969)
			(xy 186.737377 -53.194153) (xy 186.707072 -53.240448) (xy 186.670403 -53.281886) (xy 186.628139 -53.317598)
			(xy 186.60491 -53.332634) (xy 186.595211 -53.339244) (xy 186.58278 -53.359125) (xy 186.581034 -53.370734)
			(xy 186.57316 -53.450744) (xy 186.572506 -53.462383) (xy 186.580601 -53.484222) (xy 186.588654 -53.492654)
			(xy 186.588908 -53.492908) (xy 186.607477 -53.511001) (xy 186.640056 -53.551331) (xy 186.666871 -53.595702)
			(xy 186.687425 -53.643298) (xy 186.701342 -53.69324) (xy 186.708362 -53.744608) (xy 186.708796 -53.77053)
			(xy 186.70835 -53.797783) (xy 186.700589 -53.851732) (xy 186.68523 -53.904029) (xy 186.662584 -53.953607)
			(xy 186.633114 -53.999457) (xy 186.597418 -54.040648) (xy 186.556224 -54.076339) (xy 186.51037 -54.105804)
			(xy 186.460789 -54.128444) (xy 186.408491 -54.143798) (xy 186.354541 -54.151553) (xy 186.327288 -54.152038)
			(xy 186.299917 -54.151594) (xy 186.245736 -54.143773) (xy 186.193232 -54.12828) (xy 186.143486 -54.105433)
			(xy 186.09752 -54.075702) (xy 186.07659 -54.058058) (xy 186.076336 -54.057804) (xy 186.069243 -54.052227)
			(xy 186.052331 -54.045974) (xy 186.043316 -54.045612) (xy 185.97626 -54.045612) (xy 185.967241 -54.045947)
			(xy 185.950324 -54.05221) (xy 185.94324 -54.057804) (xy 185.94324 -54.058058) (xy 185.942986 -54.058058)
			(xy 185.922027 -54.075664) (xy 185.876062 -54.105382) (xy 185.826322 -54.128225) (xy 185.773827 -54.143724)
			(xy 185.719655 -54.15156) (xy 185.692288 -54.152038) (xy 185.665038 -54.151533) (xy 185.611092 -54.143776)
			(xy 185.5588 -54.128421) (xy 185.509224 -54.105781) (xy 185.463376 -54.076316) (xy 185.422186 -54.040626)
			(xy 185.386495 -53.999439) (xy 185.357028 -53.953591) (xy 185.334385 -53.904017) (xy 185.319028 -53.851725)
			(xy 185.311268 -53.79778) (xy 185.31078 -53.77053) (xy 184.946598 -53.77053) (xy 184.945528 -53.7718)
			(xy 184.945274 -53.772054) (xy 184.939698 -53.779147) (xy 184.933446 -53.796059) (xy 184.933082 -53.805074)
			(xy 184.933082 -53.87213) (xy 184.933428 -53.881148) (xy 184.939684 -53.898065) (xy 184.945274 -53.90515)
			(xy 184.945528 -53.90515) (xy 184.945528 -53.905404) (xy 184.963173 -53.926334) (xy 184.992901 -53.972301)
			(xy 185.015749 -54.022048) (xy 185.031247 -54.074551) (xy 185.039076 -54.12873) (xy 185.039076 -54.183473)
			(xy 185.031246 -54.237652) (xy 185.015748 -54.290155) (xy 185.001954 -54.320186) (xy 187.230512 -54.320186)
			(xy 187.230967 -54.292815) (xy 187.238787 -54.238636) (xy 187.254279 -54.186132) (xy 187.277123 -54.136386)
			(xy 187.30685 -54.090419) (xy 187.324492 -54.069488) (xy 187.324746 -54.069234) (xy 187.33033 -54.062146)
			(xy 187.336577 -54.04523) (xy 187.336938 -54.036214) (xy 187.336938 -53.969158) (xy 187.336545 -53.960145)
			(xy 187.330322 -53.943228) (xy 187.324746 -53.936138) (xy 187.324492 -53.936138) (xy 187.324492 -53.935884)
			(xy 187.306878 -53.914932) (xy 187.277162 -53.868965) (xy 187.254322 -53.819222) (xy 187.238825 -53.766726)
			(xy 187.23099 -53.712554) (xy 187.230512 -53.685186) (xy 187.230998 -53.657935) (xy 187.238754 -53.603987)
			(xy 187.254109 -53.551692) (xy 187.276751 -53.502115) (xy 187.306217 -53.456265) (xy 187.341908 -53.415074)
			(xy 187.383099 -53.379383) (xy 187.428949 -53.349917) (xy 187.478526 -53.327275) (xy 187.530821 -53.31192)
			(xy 187.584769 -53.304164) (xy 187.639271 -53.304164) (xy 187.693219 -53.31192) (xy 187.745514 -53.327275)
			(xy 187.795091 -53.349917) (xy 187.840941 -53.379383) (xy 187.882132 -53.415074) (xy 187.917823 -53.456265)
			(xy 187.947289 -53.502115) (xy 187.969931 -53.551692) (xy 187.985286 -53.603987) (xy 187.993042 -53.657935)
			(xy 187.993528 -53.685186) (xy 187.993071 -53.712557) (xy 187.985254 -53.766737) (xy 187.969764 -53.819241)
			(xy 187.946919 -53.868988) (xy 187.917191 -53.914953) (xy 187.899548 -53.935884) (xy 187.899294 -53.936138)
			(xy 187.893727 -53.943238) (xy 187.887469 -53.960144) (xy 187.887102 -53.969158) (xy 187.887102 -54.036214)
			(xy 187.887452 -54.045232) (xy 187.893704 -54.062148) (xy 187.899294 -54.069234) (xy 187.899548 -54.069234)
			(xy 187.899548 -54.069488) (xy 187.917187 -54.09042) (xy 187.946901 -54.136392) (xy 187.969737 -54.18614)
			(xy 187.985228 -54.238641) (xy 187.993055 -54.292817) (xy 187.993528 -54.320186) (xy 187.993042 -54.347437)
			(xy 187.985286 -54.401385) (xy 187.969931 -54.45368) (xy 187.947289 -54.503257) (xy 187.917823 -54.549107)
			(xy 187.882132 -54.590298) (xy 187.840941 -54.625989) (xy 187.795091 -54.655455) (xy 187.745514 -54.678097)
			(xy 187.693219 -54.693452) (xy 187.639271 -54.701208) (xy 187.584769 -54.701208) (xy 187.530821 -54.693452)
			(xy 187.478526 -54.678097) (xy 187.428949 -54.655455) (xy 187.383099 -54.625989) (xy 187.341908 -54.590298)
			(xy 187.306217 -54.549107) (xy 187.276751 -54.503257) (xy 187.254109 -54.45368) (xy 187.238754 -54.401385)
			(xy 187.230998 -54.347437) (xy 187.230512 -54.320186) (xy 185.001954 -54.320186) (xy 184.992899 -54.339901)
			(xy 184.963171 -54.385868) (xy 184.945528 -54.4068) (xy 184.945274 -54.407054) (xy 184.939698 -54.414147)
			(xy 184.933446 -54.431059) (xy 184.933082 -54.440074) (xy 184.933082 -54.50713) (xy 184.933428 -54.516148)
			(xy 184.939684 -54.533065) (xy 184.945274 -54.54015) (xy 184.945528 -54.54015) (xy 184.945528 -54.540404)
			(xy 184.963187 -54.56132) (xy 184.992895 -54.607298) (xy 185.015726 -54.657049) (xy 185.031213 -54.709553)
			(xy 185.039036 -54.763732) (xy 185.039153 -54.770528) (xy 188.171074 -54.770528) (xy 188.171538 -54.743158)
			(xy 188.179354 -54.688978) (xy 188.194842 -54.636474) (xy 188.217685 -54.586727) (xy 188.247411 -54.540761)
			(xy 188.265054 -54.51983) (xy 188.265308 -54.519576) (xy 188.270912 -54.512501) (xy 188.277148 -54.495575)
			(xy 188.2775 -54.486556) (xy 188.2775 -54.4195) (xy 188.277143 -54.410483) (xy 188.270895 -54.393566)
			(xy 188.265308 -54.38648) (xy 188.265054 -54.38648) (xy 188.265054 -54.386226) (xy 188.247422 -54.365288)
			(xy 188.217707 -54.319318) (xy 188.194869 -54.269572) (xy 188.179377 -54.217072) (xy 188.171548 -54.162897)
			(xy 188.171074 -54.135528) (xy 188.17156 -54.108277) (xy 188.179316 -54.054329) (xy 188.194671 -54.002034)
			(xy 188.217313 -53.952457) (xy 188.246779 -53.906607) (xy 188.28247 -53.865416) (xy 188.323661 -53.829725)
			(xy 188.369511 -53.800259) (xy 188.419088 -53.777617) (xy 188.471383 -53.762262) (xy 188.525331 -53.754506)
			(xy 188.579833 -53.754506) (xy 188.633781 -53.762262) (xy 188.686076 -53.777617) (xy 188.735653 -53.800259)
			(xy 188.781503 -53.829725) (xy 188.822694 -53.865416) (xy 188.858385 -53.906607) (xy 188.887851 -53.952457)
			(xy 188.892926 -53.96357) (xy 192.872104 -53.96357) (xy 192.876175 -53.907948) (xy 192.888301 -53.853511)
			(xy 192.908224 -53.80142) (xy 192.93552 -53.752785) (xy 192.969606 -53.708642) (xy 193.009755 -53.669933)
			(xy 193.055113 -53.637482) (xy 193.104713 -53.611981) (xy 193.157497 -53.593974) (xy 193.21234 -53.583844)
			(xy 193.268074 -53.581807) (xy 193.323511 -53.587907) (xy 193.377468 -53.602013) (xy 193.428797 -53.623825)
			(xy 193.476403 -53.652879) (xy 193.519271 -53.688554) (xy 193.556488 -53.730091) (xy 193.587261 -53.776604)
			(xy 193.610933 -53.827101) (xy 193.627001 -53.880508) (xy 193.635121 -53.935684) (xy 193.63563 -53.96357)
			(xy 193.635121 -53.991456) (xy 193.627001 -54.046632) (xy 193.610933 -54.100039) (xy 193.587261 -54.150536)
			(xy 193.556488 -54.197049) (xy 193.519271 -54.238586) (xy 193.476403 -54.274261) (xy 193.428797 -54.303315)
			(xy 193.377468 -54.325127) (xy 193.323511 -54.339233) (xy 193.268074 -54.345333) (xy 193.21234 -54.343296)
			(xy 193.157497 -54.333166) (xy 193.104713 -54.315159) (xy 193.055113 -54.289658) (xy 193.009755 -54.257207)
			(xy 192.969606 -54.218498) (xy 192.93552 -54.174355) (xy 192.908224 -54.12572) (xy 192.888301 -54.073629)
			(xy 192.876175 -54.019192) (xy 192.872104 -53.96357) (xy 188.892926 -53.96357) (xy 188.910493 -54.002034)
			(xy 188.925848 -54.054329) (xy 188.933604 -54.108277) (xy 188.93409 -54.135528) (xy 188.933643 -54.162899)
			(xy 188.925821 -54.217079) (xy 188.910327 -54.269582) (xy 188.887481 -54.319329) (xy 188.857753 -54.365295)
			(xy 188.84011 -54.386226) (xy 188.839856 -54.38648) (xy 188.834266 -54.393564) (xy 188.828023 -54.410483)
			(xy 188.827664 -54.4195) (xy 188.827664 -54.486556) (xy 188.82805 -54.49557) (xy 188.834278 -54.512487)
			(xy 188.839856 -54.519576) (xy 188.84011 -54.519576) (xy 188.84011 -54.51983) (xy 188.857731 -54.540776)
			(xy 188.887445 -54.586745) (xy 188.910285 -54.636489) (xy 188.92578 -54.688987) (xy 188.933613 -54.74316)
			(xy 188.93409 -54.770528) (xy 188.933604 -54.797779) (xy 188.925848 -54.851727) (xy 188.910493 -54.904022)
			(xy 188.887851 -54.953599) (xy 188.858385 -54.999449) (xy 188.822694 -55.04064) (xy 188.781503 -55.076331)
			(xy 188.735653 -55.105797) (xy 188.686076 -55.128439) (xy 188.633781 -55.143794) (xy 188.579833 -55.15155)
			(xy 188.525331 -55.15155) (xy 188.471383 -55.143794) (xy 188.419088 -55.128439) (xy 188.369511 -55.105797)
			(xy 188.323661 -55.076331) (xy 188.28247 -55.04064) (xy 188.246779 -54.999449) (xy 188.217313 -54.953599)
			(xy 188.194671 -54.904022) (xy 188.179316 -54.851727) (xy 188.17156 -54.797779) (xy 188.171074 -54.770528)
			(xy 185.039153 -54.770528) (xy 185.039508 -54.791102) (xy 185.039022 -54.818353) (xy 185.031266 -54.872301)
			(xy 185.015911 -54.924596) (xy 184.993269 -54.974173) (xy 184.963803 -55.020023) (xy 184.928112 -55.061214)
			(xy 184.886921 -55.096905) (xy 184.841071 -55.126371) (xy 184.791494 -55.149013) (xy 184.739199 -55.164368)
			(xy 184.685251 -55.172124) (xy 184.630749 -55.172124) (xy 184.576801 -55.164368) (xy 184.524506 -55.149013)
			(xy 184.474929 -55.126371) (xy 184.429079 -55.096905) (xy 184.387888 -55.061214) (xy 184.352197 -55.020023)
			(xy 184.322731 -54.974173) (xy 184.300089 -54.924596) (xy 184.284734 -54.872301) (xy 184.276978 -54.818353)
			(xy 184.276492 -54.791102) (xy 182.378534 -54.791102) (xy 182.375442 -54.812611) (xy 182.360087 -54.864906)
			(xy 182.337445 -54.914483) (xy 182.307979 -54.960333) (xy 182.272288 -55.001524) (xy 182.231097 -55.037215)
			(xy 182.185247 -55.066681) (xy 182.13567 -55.089323) (xy 182.083375 -55.104678) (xy 182.029427 -55.112434)
			(xy 181.974925 -55.112434) (xy 181.920977 -55.104678) (xy 181.868682 -55.089323) (xy 181.819105 -55.066681)
			(xy 181.773255 -55.037215) (xy 181.732064 -55.001524) (xy 181.696373 -54.960333) (xy 181.666907 -54.914483)
			(xy 181.644265 -54.864906) (xy 181.62891 -54.812611) (xy 181.621154 -54.758663) (xy 181.620668 -54.731412)
			(xy 180.813964 -54.731412) (xy 180.813964 -57.002934) (xy 189.663578 -57.002934) (xy 189.664102 -56.974843)
			(xy 189.672324 -56.919268) (xy 189.68861 -56.8655) (xy 189.712608 -56.814702) (xy 189.743798 -56.767975)
			(xy 189.781506 -56.726329) (xy 189.824915 -56.690665) (xy 189.848744 -56.675782) (xy 189.857634 -56.670448)
			(xy 189.869826 -56.65343) (xy 189.890146 -56.560212) (xy 189.885828 -56.539638) (xy 189.879986 -56.531002)
			(xy 189.863983 -56.50694) (xy 189.838641 -56.455008) (xy 189.821417 -56.399849) (xy 189.812702 -56.342725)
			(xy 189.812168 -56.313832) (xy 189.812685 -56.286581) (xy 189.820437 -56.232633) (xy 189.835788 -56.180338)
			(xy 189.858425 -56.130759) (xy 189.887887 -56.084907) (xy 189.923575 -56.043715) (xy 189.964762 -56.008021)
			(xy 190.01061 -55.978552) (xy 190.060185 -55.955907) (xy 190.112478 -55.940549) (xy 190.166425 -55.932789)
			(xy 190.193676 -55.932324) (xy 190.221046 -55.932798) (xy 190.275225 -55.940613) (xy 190.327728 -55.9561)
			(xy 190.377475 -55.97894) (xy 190.423442 -56.008663) (xy 190.444374 -56.026304) (xy 190.444628 -56.026558)
			(xy 190.451726 -56.032127) (xy 190.468634 -56.038383) (xy 190.477648 -56.03875) (xy 190.544704 -56.03875)
			(xy 190.553722 -56.038406) (xy 190.57064 -56.03215) (xy 190.577724 -56.026558) (xy 190.577724 -56.026304)
			(xy 190.577978 -56.026304) (xy 190.598911 -56.008663) (xy 190.644879 -55.978939) (xy 190.694625 -55.956093)
			(xy 190.747127 -55.940597) (xy 190.801305 -55.932768) (xy 190.856047 -55.932768) (xy 190.910225 -55.940597)
			(xy 190.962727 -55.956093) (xy 191.012473 -55.978939) (xy 191.058441 -56.008663) (xy 191.079374 -56.026304)
			(xy 191.079628 -56.026558) (xy 191.086726 -56.032127) (xy 191.103634 -56.038383) (xy 191.112648 -56.03875)
			(xy 191.179704 -56.03875) (xy 191.188722 -56.038406) (xy 191.20564 -56.03215) (xy 191.212724 -56.026558)
			(xy 191.212724 -56.026304) (xy 191.212978 -56.026304) (xy 191.233908 -56.008662) (xy 191.279881 -55.978951)
			(xy 191.329629 -55.956115) (xy 191.382131 -55.940625) (xy 191.436307 -55.932797) (xy 191.463676 -55.932324)
			(xy 191.490932 -55.932721) (xy 191.54489 -55.940476) (xy 191.597196 -55.955831) (xy 191.646783 -55.978474)
			(xy 191.692643 -56.007944) (xy 191.733842 -56.043641) (xy 191.769541 -56.084838) (xy 191.799014 -56.130696)
			(xy 191.82166 -56.180282) (xy 191.837019 -56.232586) (xy 191.844777 -56.286544) (xy 191.844777 -56.341056)
			(xy 191.837019 -56.395014) (xy 191.82166 -56.447318) (xy 191.799014 -56.496904) (xy 191.769541 -56.542762)
			(xy 191.733842 -56.583959) (xy 191.692643 -56.619656) (xy 191.646783 -56.649126) (xy 191.597196 -56.671769)
			(xy 191.54489 -56.687124) (xy 191.490932 -56.694879) (xy 191.463676 -56.69534) (xy 191.436305 -56.694903)
			(xy 191.382124 -56.68708) (xy 191.32962 -56.671585) (xy 191.279873 -56.648737) (xy 191.233908 -56.619005)
			(xy 191.212978 -56.60136) (xy 191.212724 -56.601106) (xy 191.205634 -56.595524) (xy 191.18872 -56.589274)
			(xy 191.179704 -56.588914) (xy 191.112648 -56.588914) (xy 191.103633 -56.589291) (xy 191.086716 -56.595524)
			(xy 191.079628 -56.601106) (xy 191.079628 -56.60136) (xy 191.079374 -56.60136) (xy 191.058441 -56.619001)
			(xy 191.012473 -56.648725) (xy 190.962727 -56.671571) (xy 190.910225 -56.687067) (xy 190.856047 -56.694896)
			(xy 190.801305 -56.694896) (xy 190.747127 -56.687067) (xy 190.694625 -56.671571) (xy 190.644879 -56.648725)
			(xy 190.598911 -56.619001) (xy 190.577978 -56.60136) (xy 190.577724 -56.601106) (xy 190.570634 -56.595524)
			(xy 190.55372 -56.589274) (xy 190.544704 -56.588914) (xy 190.477648 -56.588914) (xy 190.468633 -56.589291)
			(xy 190.451716 -56.595524) (xy 190.444628 -56.601106) (xy 190.44412 -56.60136) (xy 190.431388 -56.612307)
			(xy 190.404295 -56.632146) (xy 190.390018 -56.640984) (xy 190.381128 -56.646318) (xy 190.368936 -56.663336)
			(xy 190.348616 -56.756554) (xy 190.352934 -56.777128) (xy 190.358776 -56.785764) (xy 190.37476 -56.809838)
			(xy 190.400107 -56.861766) (xy 190.417337 -56.91692) (xy 190.426057 -56.974042) (xy 190.426594 -57.002934)
			(xy 190.426108 -57.030185) (xy 190.418352 -57.084133) (xy 190.402997 -57.136428) (xy 190.380355 -57.186005)
			(xy 190.350889 -57.231855) (xy 190.315198 -57.273046) (xy 190.274007 -57.308737) (xy 190.228157 -57.338203)
			(xy 190.17858 -57.360845) (xy 190.126285 -57.3762) (xy 190.072337 -57.383956) (xy 190.017835 -57.383956)
			(xy 189.963887 -57.3762) (xy 189.911592 -57.360845) (xy 189.862015 -57.338203) (xy 189.816165 -57.308737)
			(xy 189.774974 -57.273046) (xy 189.739283 -57.231855) (xy 189.709817 -57.186005) (xy 189.687175 -57.136428)
			(xy 189.67182 -57.084133) (xy 189.664064 -57.030185) (xy 189.663578 -57.002934) (xy 180.813964 -57.002934)
			(xy 180.813964 -58.679334) (xy 190.095378 -58.679334) (xy 190.095808 -58.653019) (xy 190.103052 -58.600889)
			(xy 190.117379 -58.550246) (xy 190.138518 -58.502047) (xy 190.16607 -58.457205) (xy 190.199514 -58.416566)
			(xy 190.218568 -58.39841) (xy 190.225963 -58.390882) (xy 190.234492 -58.371607) (xy 190.235078 -58.361072)
			(xy 190.235078 -58.286396) (xy 190.234571 -58.275844) (xy 190.226021 -58.256548) (xy 190.218568 -58.249058)
			(xy 190.199493 -58.230922) (xy 190.166039 -58.190287) (xy 190.138483 -58.145443) (xy 190.117348 -58.097238)
			(xy 190.103035 -58.046588) (xy 190.095814 -57.994451) (xy 190.095378 -57.968134) (xy 190.095864 -57.940883)
			(xy 190.10362 -57.886935) (xy 190.118975 -57.83464) (xy 190.141617 -57.785063) (xy 190.171083 -57.739213)
			(xy 190.206774 -57.698022) (xy 190.247965 -57.662331) (xy 190.293815 -57.632865) (xy 190.343392 -57.610223)
			(xy 190.395687 -57.594868) (xy 190.449635 -57.587112) (xy 190.504137 -57.587112) (xy 190.558085 -57.594868)
			(xy 190.61038 -57.610223) (xy 190.659957 -57.632865) (xy 190.705807 -57.662331) (xy 190.746998 -57.698022)
			(xy 190.782689 -57.739213) (xy 190.812155 -57.785063) (xy 190.834797 -57.83464) (xy 190.850152 -57.886935)
			(xy 190.857908 -57.940883) (xy 190.858394 -57.968134) (xy 190.857951 -57.994449) (xy 190.850712 -58.046578)
			(xy 190.836388 -58.097222) (xy 190.815251 -58.145421) (xy 190.7877 -58.190264) (xy 190.754257 -58.230902)
			(xy 190.735204 -58.249058) (xy 190.72782 -58.256594) (xy 190.719285 -58.275863) (xy 190.718694 -58.286396)
			(xy 190.718694 -58.361072) (xy 190.719227 -58.371621) (xy 190.72776 -58.390916) (xy 190.735204 -58.39841)
			(xy 190.754258 -58.416567) (xy 190.787715 -58.457196) (xy 190.815274 -58.502036) (xy 190.836413 -58.550237)
			(xy 190.850731 -58.600884) (xy 190.857955 -58.653018) (xy 190.858394 -58.679334) (xy 190.857908 -58.706585)
			(xy 190.850152 -58.760533) (xy 190.834797 -58.812828) (xy 190.812155 -58.862405) (xy 190.782689 -58.908255)
			(xy 190.746998 -58.949446) (xy 190.705807 -58.985137) (xy 190.659957 -59.014603) (xy 190.61038 -59.037245)
			(xy 190.558085 -59.0526) (xy 190.504137 -59.060356) (xy 190.449635 -59.060356) (xy 190.395687 -59.0526)
			(xy 190.343392 -59.037245) (xy 190.293815 -59.014603) (xy 190.247965 -58.985137) (xy 190.206774 -58.949446)
			(xy 190.171083 -58.908255) (xy 190.141617 -58.862405) (xy 190.118975 -58.812828) (xy 190.10362 -58.760533)
			(xy 190.095864 -58.706585) (xy 190.095378 -58.679334) (xy 180.813964 -58.679334) (xy 180.813964 -60.019254)
			(xy 190.235761 -60.019254) (xy 190.235761 -59.964746) (xy 190.243519 -59.910792) (xy 190.258877 -59.858492)
			(xy 190.281522 -59.80891) (xy 190.310993 -59.763056) (xy 190.346691 -59.721863) (xy 190.387888 -59.686169)
			(xy 190.433745 -59.656703) (xy 190.483329 -59.634063) (xy 190.535631 -59.618711) (xy 190.589586 -59.610959)
			(xy 190.61684 -59.610498) (xy 190.644209 -59.611) (xy 190.698386 -59.618809) (xy 190.750889 -59.63429)
			(xy 190.800637 -59.657124) (xy 190.846605 -59.68684) (xy 190.867538 -59.704478) (xy 190.867792 -59.704732)
			(xy 190.874874 -59.710325) (xy 190.891794 -59.716567) (xy 190.900812 -59.716924) (xy 190.967868 -59.716924)
			(xy 190.976883 -59.716546) (xy 190.9938 -59.710313) (xy 191.000888 -59.704732) (xy 191.000888 -59.704478)
			(xy 191.001142 -59.704478) (xy 191.022075 -59.686837) (xy 191.068043 -59.657113) (xy 191.117789 -59.634267)
			(xy 191.170291 -59.618771) (xy 191.224469 -59.610942) (xy 191.279211 -59.610942) (xy 191.333389 -59.618771)
			(xy 191.385891 -59.634267) (xy 191.435637 -59.657113) (xy 191.481605 -59.686837) (xy 191.502538 -59.704478)
			(xy 191.502792 -59.704732) (xy 191.509874 -59.710325) (xy 191.526794 -59.716567) (xy 191.535812 -59.716924)
			(xy 191.602868 -59.716924) (xy 191.611883 -59.716546) (xy 191.6288 -59.710313) (xy 191.635888 -59.704732)
			(xy 191.635888 -59.704478) (xy 191.636142 -59.704478) (xy 191.657082 -59.686849) (xy 191.703053 -59.657137)
			(xy 191.752799 -59.634299) (xy 191.805297 -59.618805) (xy 191.859471 -59.610974) (xy 191.88684 -59.610498)
			(xy 191.91409 -59.610975) (xy 191.968034 -59.618736) (xy 192.020325 -59.634095) (xy 192.069898 -59.656738)
			(xy 192.115744 -59.686206) (xy 192.15693 -59.721898) (xy 192.192618 -59.763088) (xy 192.222081 -59.808937)
			(xy 192.244719 -59.858513) (xy 192.260073 -59.910805) (xy 192.267828 -59.96475) (xy 192.267828 -60.01925)
			(xy 192.260073 -60.073195) (xy 192.244719 -60.125487) (xy 192.222081 -60.175063) (xy 192.192618 -60.220912)
			(xy 192.15693 -60.262102) (xy 192.115744 -60.297794) (xy 192.069898 -60.327262) (xy 192.020325 -60.349905)
			(xy 191.968034 -60.365264) (xy 191.91409 -60.373025) (xy 191.88684 -60.373514) (xy 191.859471 -60.373021)
			(xy 191.805293 -60.365209) (xy 191.75279 -60.349726) (xy 191.703043 -60.326891) (xy 191.657075 -60.297172)
			(xy 191.636142 -60.279534) (xy 191.635888 -60.27928) (xy 191.628811 -60.27368) (xy 191.611887 -60.267442)
			(xy 191.602868 -60.267088) (xy 191.535812 -60.267088) (xy 191.526796 -60.267453) (xy 191.509879 -60.273695)
			(xy 191.502792 -60.27928) (xy 191.502538 -60.279534) (xy 191.481605 -60.297175) (xy 191.435637 -60.326899)
			(xy 191.385891 -60.349745) (xy 191.333389 -60.365241) (xy 191.279211 -60.37307) (xy 191.224469 -60.37307)
			(xy 191.170291 -60.365241) (xy 191.117789 -60.349745) (xy 191.068043 -60.326899) (xy 191.022075 -60.297175)
			(xy 191.001142 -60.279534) (xy 191.000888 -60.27928) (xy 190.993811 -60.27368) (xy 190.976887 -60.267442)
			(xy 190.967868 -60.267088) (xy 190.900812 -60.267088) (xy 190.891796 -60.267453) (xy 190.874879 -60.273695)
			(xy 190.867792 -60.27928) (xy 190.867792 -60.279534) (xy 190.867538 -60.279534) (xy 190.846607 -60.297174)
			(xy 190.800633 -60.326885) (xy 190.750885 -60.34972) (xy 190.698385 -60.365211) (xy 190.644209 -60.373039)
			(xy 190.61684 -60.373514) (xy 190.589586 -60.373041) (xy 190.535631 -60.365289) (xy 190.483329 -60.349937)
			(xy 190.433745 -60.327297) (xy 190.387888 -60.297831) (xy 190.346691 -60.262137) (xy 190.310993 -60.220944)
			(xy 190.281522 -60.17509) (xy 190.258877 -60.125508) (xy 190.243519 -60.073208) (xy 190.235761 -60.019254)
			(xy 180.813964 -60.019254) (xy 180.813964 -67.128953) (xy 182.466675 -67.128953) (xy 182.466675 -67.074447)
			(xy 182.474433 -67.020495) (xy 182.48979 -66.968196) (xy 182.512435 -66.918616) (xy 182.541905 -66.872763)
			(xy 182.577601 -66.831572) (xy 182.618797 -66.79588) (xy 182.664653 -66.766415) (xy 182.714236 -66.743776)
			(xy 182.766536 -66.728424) (xy 182.820489 -66.720672) (xy 182.847742 -66.720212) (xy 182.875111 -66.720709)
			(xy 182.929289 -66.728519) (xy 182.981792 -66.744001) (xy 183.031539 -66.766836) (xy 183.077507 -66.796554)
			(xy 183.09844 -66.814192) (xy 183.098694 -66.814446) (xy 183.105774 -66.820042) (xy 183.122696 -66.826282)
			(xy 183.131714 -66.826638) (xy 183.19877 -66.826638) (xy 183.207784 -66.826258) (xy 183.224701 -66.820026)
			(xy 183.23179 -66.814446) (xy 183.23179 -66.814192) (xy 183.232044 -66.814192) (xy 183.252985 -66.796564)
			(xy 183.298956 -66.766851) (xy 183.348701 -66.744013) (xy 183.401199 -66.728519) (xy 183.455373 -66.720688)
			(xy 183.482742 -66.720212) (xy 183.509993 -66.720661) (xy 183.563939 -66.728422) (xy 183.616231 -66.743782)
			(xy 183.665806 -66.766427) (xy 183.711653 -66.795896) (xy 183.752841 -66.831589) (xy 183.788529 -66.87278)
			(xy 183.817993 -66.918631) (xy 183.840633 -66.968208) (xy 183.855986 -67.020502) (xy 183.863742 -67.074449)
			(xy 183.863742 -67.128951) (xy 183.855986 -67.182898) (xy 183.840633 -67.235192) (xy 183.817993 -67.284769)
			(xy 183.788529 -67.33062) (xy 183.752841 -67.371811) (xy 183.711653 -67.407504) (xy 183.665806 -67.436973)
			(xy 183.616231 -67.459618) (xy 183.563939 -67.474978) (xy 183.509993 -67.482739) (xy 183.482742 -67.483228)
			(xy 183.455372 -67.482755) (xy 183.401192 -67.474941) (xy 183.348689 -67.459455) (xy 183.298942 -67.436614)
			(xy 183.252975 -67.40689) (xy 183.232044 -67.389248) (xy 183.23179 -67.388994) (xy 183.224711 -67.383396)
			(xy 183.207788 -67.377157) (xy 183.19877 -67.376802) (xy 183.131714 -67.376802) (xy 183.122698 -67.377165)
			(xy 183.105781 -67.383408) (xy 183.098694 -67.388994) (xy 183.098694 -67.389248) (xy 183.09844 -67.389248)
			(xy 183.077497 -67.406874) (xy 183.031528 -67.436589) (xy 182.981783 -67.459429) (xy 182.929285 -67.474923)
			(xy 182.875111 -67.482753) (xy 182.847742 -67.483228) (xy 182.820489 -67.482728) (xy 182.766536 -67.474976)
			(xy 182.714236 -67.459624) (xy 182.664653 -67.436985) (xy 182.618797 -67.40752) (xy 182.577601 -67.371828)
			(xy 182.541905 -67.330637) (xy 182.512435 -67.284784) (xy 182.48979 -67.235204) (xy 182.474433 -67.182905)
			(xy 182.466675 -67.128953) (xy 180.813964 -67.128953) (xy 180.813964 -67.488054) (xy 186.879228 -67.488054)
			(xy 186.883299 -67.432432) (xy 186.895425 -67.377995) (xy 186.915348 -67.325904) (xy 186.942644 -67.277269)
			(xy 186.97673 -67.233126) (xy 187.016879 -67.194417) (xy 187.062237 -67.161966) (xy 187.111837 -67.136465)
			(xy 187.164621 -67.118458) (xy 187.219464 -67.108328) (xy 187.275198 -67.106291) (xy 187.330635 -67.112391)
			(xy 187.384592 -67.126497) (xy 187.435921 -67.148309) (xy 187.483527 -67.177363) (xy 187.526395 -67.213038)
			(xy 187.563612 -67.254575) (xy 187.594385 -67.301088) (xy 187.618057 -67.351585) (xy 187.634125 -67.404992)
			(xy 187.642245 -67.460168) (xy 187.642754 -67.488054) (xy 187.642245 -67.51594) (xy 187.63906 -67.537584)
			(xy 188.171326 -67.537584) (xy 188.175397 -67.481962) (xy 188.187523 -67.427525) (xy 188.207446 -67.375434)
			(xy 188.234742 -67.326799) (xy 188.268828 -67.282656) (xy 188.308977 -67.243947) (xy 188.354335 -67.211496)
			(xy 188.403935 -67.185995) (xy 188.456719 -67.167988) (xy 188.511562 -67.157858) (xy 188.567296 -67.155821)
			(xy 188.622733 -67.161921) (xy 188.67669 -67.176027) (xy 188.728019 -67.197839) (xy 188.775625 -67.226893)
			(xy 188.818493 -67.262568) (xy 188.85571 -67.304105) (xy 188.886483 -67.350618) (xy 188.910155 -67.401115)
			(xy 188.926223 -67.454522) (xy 188.934343 -67.509698) (xy 188.934852 -67.537584) (xy 188.934343 -67.56547)
			(xy 188.930298 -67.592956) (xy 189.44539 -67.592956) (xy 189.449461 -67.537334) (xy 189.461587 -67.482897)
			(xy 189.48151 -67.430806) (xy 189.508806 -67.382171) (xy 189.542892 -67.338028) (xy 189.583041 -67.299319)
			(xy 189.628399 -67.266868) (xy 189.677999 -67.241367) (xy 189.730783 -67.22336) (xy 189.785626 -67.21323)
			(xy 189.84136 -67.211193) (xy 189.896797 -67.217293) (xy 189.950754 -67.231399) (xy 190.002083 -67.253211)
			(xy 190.049689 -67.282265) (xy 190.092557 -67.31794) (xy 190.129774 -67.359477) (xy 190.160547 -67.40599)
			(xy 190.184219 -67.456487) (xy 190.200287 -67.509894) (xy 190.208407 -67.56507) (xy 190.208916 -67.592956)
			(xy 190.208407 -67.620842) (xy 190.200287 -67.676018) (xy 190.184219 -67.729425) (xy 190.160547 -67.779922)
			(xy 190.129774 -67.826435) (xy 190.092557 -67.867972) (xy 190.049689 -67.903647) (xy 190.002083 -67.932701)
			(xy 189.950754 -67.954513) (xy 189.896797 -67.968619) (xy 189.84136 -67.974719) (xy 189.785626 -67.972682)
			(xy 189.730783 -67.962552) (xy 189.677999 -67.944545) (xy 189.628399 -67.919044) (xy 189.583041 -67.886593)
			(xy 189.542892 -67.847884) (xy 189.508806 -67.803741) (xy 189.48151 -67.755106) (xy 189.461587 -67.703015)
			(xy 189.449461 -67.648578) (xy 189.44539 -67.592956) (xy 188.930298 -67.592956) (xy 188.926223 -67.620646)
			(xy 188.910155 -67.674053) (xy 188.886483 -67.72455) (xy 188.85571 -67.771063) (xy 188.818493 -67.8126)
			(xy 188.775625 -67.848275) (xy 188.728019 -67.877329) (xy 188.67669 -67.899141) (xy 188.622733 -67.913247)
			(xy 188.567296 -67.919347) (xy 188.511562 -67.91731) (xy 188.456719 -67.90718) (xy 188.403935 -67.889173)
			(xy 188.354335 -67.863672) (xy 188.308977 -67.831221) (xy 188.268828 -67.792512) (xy 188.234742 -67.748369)
			(xy 188.207446 -67.699734) (xy 188.187523 -67.647643) (xy 188.175397 -67.593206) (xy 188.171326 -67.537584)
			(xy 187.63906 -67.537584) (xy 187.634125 -67.571116) (xy 187.618057 -67.624523) (xy 187.594385 -67.67502)
			(xy 187.563612 -67.721533) (xy 187.526395 -67.76307) (xy 187.483527 -67.798745) (xy 187.435921 -67.827799)
			(xy 187.384592 -67.849611) (xy 187.330635 -67.863717) (xy 187.275198 -67.869817) (xy 187.219464 -67.86778)
			(xy 187.164621 -67.85765) (xy 187.111837 -67.839643) (xy 187.062237 -67.814142) (xy 187.016879 -67.781691)
			(xy 186.97673 -67.742982) (xy 186.942644 -67.698839) (xy 186.915348 -67.650204) (xy 186.895425 -67.598113)
			(xy 186.883299 -67.543676) (xy 186.879228 -67.488054) (xy 180.813964 -67.488054) (xy 180.813964 -68.586604)
			(xy 184.72531 -68.586604) (xy 184.725776 -68.559234) (xy 184.733593 -68.505055) (xy 184.749082 -68.452551)
			(xy 184.771924 -68.402804) (xy 184.801649 -68.356838) (xy 184.81929 -68.335906) (xy 184.819544 -68.335652)
			(xy 184.82512 -68.328559) (xy 184.831372 -68.311647) (xy 184.831736 -68.302632) (xy 184.831736 -68.235576)
			(xy 184.831383 -68.226559) (xy 184.825132 -68.209642) (xy 184.819544 -68.202556) (xy 184.81929 -68.202556)
			(xy 184.81929 -68.202302) (xy 184.801637 -68.181381) (xy 184.771927 -68.135405) (xy 184.749094 -68.085655)
			(xy 184.733607 -68.033152) (xy 184.725782 -67.978974) (xy 184.72531 -67.951604) (xy 184.725759 -67.92435)
			(xy 184.733516 -67.870398) (xy 184.748872 -67.818099) (xy 184.771516 -67.768518) (xy 184.800985 -67.722664)
			(xy 184.83668 -67.68147) (xy 184.877875 -67.645777) (xy 184.92373 -67.616309) (xy 184.973312 -67.593668)
			(xy 185.025612 -67.578313) (xy 185.079564 -67.570558) (xy 185.106818 -67.570096) (xy 185.133132 -67.570553)
			(xy 185.185261 -67.57779) (xy 185.235904 -67.592111) (xy 185.284103 -67.613246) (xy 185.328946 -67.640794)
			(xy 185.369586 -67.674234) (xy 185.387742 -67.693286) (xy 185.395248 -67.700706) (xy 185.41454 -67.70922)
			(xy 185.42508 -67.709796) (xy 185.499756 -67.709796) (xy 185.510305 -67.709258) (xy 185.5296 -67.700729)
			(xy 185.537094 -67.693286) (xy 185.555257 -67.674238) (xy 185.595885 -67.64078) (xy 185.640724 -67.613221)
			(xy 185.688923 -67.592081) (xy 185.739569 -67.577762) (xy 185.791702 -67.570536) (xy 185.818018 -67.570096)
			(xy 185.845389 -67.570552) (xy 185.899568 -67.578373) (xy 185.952071 -67.593864) (xy 186.001818 -67.616708)
			(xy 186.047784 -67.646434) (xy 186.068716 -67.664076) (xy 186.06897 -67.66433) (xy 186.076059 -67.669913)
			(xy 186.092974 -67.676161) (xy 186.10199 -67.676522) (xy 186.169046 -67.676522) (xy 186.17806 -67.676135)
			(xy 186.194977 -67.669908) (xy 186.202066 -67.66433) (xy 186.202066 -67.664076) (xy 186.20232 -67.664076)
			(xy 186.223268 -67.646457) (xy 186.269237 -67.616743) (xy 186.31898 -67.593904) (xy 186.371477 -67.578408)
			(xy 186.42565 -67.570573) (xy 186.453018 -67.570096) (xy 186.48027 -67.570561) (xy 186.534219 -67.57832)
			(xy 186.586514 -67.593678) (xy 186.636091 -67.616321) (xy 186.681942 -67.64579) (xy 186.723132 -67.681483)
			(xy 186.758823 -67.722676) (xy 186.788289 -67.768528) (xy 186.81093 -67.818107) (xy 186.826285 -67.870403)
			(xy 186.834041 -67.924352) (xy 186.834526 -67.951604) (xy 186.83408 -67.978975) (xy 186.82626 -68.033156)
			(xy 186.810767 -68.08566) (xy 186.787921 -68.135406) (xy 186.75819 -68.181372) (xy 186.740546 -68.202302)
			(xy 186.740292 -68.202556) (xy 186.734717 -68.20965) (xy 186.728464 -68.226561) (xy 186.7281 -68.235576)
			(xy 186.7281 -68.302632) (xy 186.728442 -68.31165) (xy 186.7347 -68.328567) (xy 186.740292 -68.335652)
			(xy 186.740546 -68.335652) (xy 186.740546 -68.335906) (xy 186.758193 -68.356832) (xy 186.787905 -68.402806)
			(xy 186.810741 -68.452555) (xy 186.82623 -68.505057) (xy 186.834054 -68.559234) (xy 186.834526 -68.586604)
			(xy 186.834026 -68.613855) (xy 186.826269 -68.667801) (xy 186.810915 -68.720094) (xy 186.794275 -68.75653)
			(xy 190.270384 -68.75653) (xy 190.270847 -68.729159) (xy 190.278663 -68.674979) (xy 190.294151 -68.622475)
			(xy 190.316994 -68.572729) (xy 190.346721 -68.526763) (xy 190.364364 -68.505832) (xy 190.364618 -68.505578)
			(xy 190.370222 -68.498503) (xy 190.376458 -68.481577) (xy 190.37681 -68.472558) (xy 190.37681 -68.405502)
			(xy 190.37645 -68.396486) (xy 190.370204 -68.379569) (xy 190.364618 -68.372482) (xy 190.364364 -68.372482)
			(xy 190.364364 -68.372228) (xy 190.346719 -68.351301) (xy 190.317009 -68.305326) (xy 190.294175 -68.255577)
			(xy 190.278685 -68.203076) (xy 190.270858 -68.148899) (xy 190.270384 -68.12153) (xy 190.270883 -68.094278)
			(xy 190.278636 -68.040329) (xy 190.293988 -67.988032) (xy 190.316626 -67.938453) (xy 190.34609 -67.8926)
			(xy 190.38178 -67.851407) (xy 190.422969 -67.815713) (xy 190.468819 -67.786244) (xy 190.518397 -67.763601)
			(xy 190.570692 -67.748244) (xy 190.62464 -67.740486) (xy 190.651892 -67.740022) (xy 190.679262 -67.740487)
			(xy 190.733442 -67.748305) (xy 190.785945 -67.763794) (xy 190.835692 -67.786636) (xy 190.881658 -67.81636)
			(xy 190.90259 -67.834002) (xy 190.902844 -67.834256) (xy 190.909938 -67.839832) (xy 190.926849 -67.846084)
			(xy 190.935864 -67.846448) (xy 191.00292 -67.846448) (xy 191.011939 -67.846112) (xy 191.028857 -67.839851)
			(xy 191.03594 -67.834256) (xy 191.03594 -67.834002) (xy 191.036194 -67.834002) (xy 191.057118 -67.816353)
			(xy 191.103093 -67.786642) (xy 191.152842 -67.763808) (xy 191.205345 -67.74832) (xy 191.259522 -67.740494)
			(xy 191.286892 -67.740022) (xy 191.313206 -67.740488) (xy 191.365335 -67.747722) (xy 191.415978 -67.762041)
			(xy 191.464177 -67.783174) (xy 191.509021 -67.81072) (xy 191.54966 -67.84416) (xy 191.567816 -67.863212)
			(xy 191.575328 -67.870625) (xy 191.594615 -67.879142) (xy 191.605154 -67.879722) (xy 191.67983 -67.879722)
			(xy 191.690376 -67.879162) (xy 191.709671 -67.870648) (xy 191.717168 -67.863212) (xy 191.7353 -67.844133)
			(xy 191.775934 -67.810677) (xy 191.82078 -67.783121) (xy 191.868985 -67.761987) (xy 191.919637 -67.747675)
			(xy 191.971774 -67.740457) (xy 191.998092 -67.740022) (xy 192.025346 -67.740463) (xy 192.079299 -67.74822)
			(xy 192.131599 -67.763576) (xy 192.181182 -67.78622) (xy 192.227036 -67.81569) (xy 192.26823 -67.851386)
			(xy 192.303923 -67.892582) (xy 192.333391 -67.938438) (xy 192.356032 -67.988021) (xy 192.371385 -68.040322)
			(xy 192.379139 -68.094276) (xy 192.3796 -68.12153) (xy 192.379152 -68.148901) (xy 192.371329 -68.203081)
			(xy 192.355836 -68.255584) (xy 192.332991 -68.305331) (xy 192.303263 -68.351297) (xy 192.28562 -68.372228)
			(xy 192.285366 -68.372482) (xy 192.279777 -68.379567) (xy 192.273533 -68.396485) (xy 192.273174 -68.405502)
			(xy 192.273174 -68.472558) (xy 192.273557 -68.481572) (xy 192.279787 -68.498489) (xy 192.285366 -68.505578)
			(xy 192.28562 -68.505578) (xy 192.28562 -68.505832) (xy 192.303244 -68.526776) (xy 192.332957 -68.572746)
			(xy 192.355796 -68.622491) (xy 192.371291 -68.674988) (xy 192.379123 -68.729162) (xy 192.3796 -68.75653)
			(xy 192.37915 -68.783782) (xy 192.371389 -68.837732) (xy 192.35603 -68.890028) (xy 192.333385 -68.939606)
			(xy 192.303915 -68.985456) (xy 192.268219 -69.026646) (xy 192.227026 -69.062337) (xy 192.181172 -69.091803)
			(xy 192.131592 -69.114443) (xy 192.079295 -69.129797) (xy 192.025344 -69.137553) (xy 191.998092 -69.138038)
			(xy 191.971777 -69.137596) (xy 191.919647 -69.130358) (xy 191.869003 -69.116036) (xy 191.820803 -69.094899)
			(xy 191.77596 -69.067347) (xy 191.735323 -69.033903) (xy 191.717168 -69.014848) (xy 191.709654 -69.007437)
			(xy 191.690368 -68.998917) (xy 191.67983 -68.998338) (xy 191.605154 -68.998338) (xy 191.594605 -68.998872)
			(xy 191.575308 -69.007402) (xy 191.567816 -69.014848) (xy 191.549655 -69.033898) (xy 191.509025 -69.067354)
			(xy 191.464186 -69.094912) (xy 191.415986 -69.116051) (xy 191.36534 -69.13037) (xy 191.313208 -69.137598)
			(xy 191.286892 -69.138038) (xy 191.259521 -69.137592) (xy 191.20534 -69.129771) (xy 191.152836 -69.114279)
			(xy 191.10309 -69.091432) (xy 191.057124 -69.061702) (xy 191.036194 -69.044058) (xy 191.03594 -69.043804)
			(xy 191.028846 -69.038228) (xy 191.011935 -69.031975) (xy 191.00292 -69.031612) (xy 190.935864 -69.031612)
			(xy 190.926845 -69.031949) (xy 190.909928 -69.03821) (xy 190.902844 -69.043804) (xy 190.902844 -69.044058)
			(xy 190.90259 -69.044058) (xy 190.881667 -69.061709) (xy 190.835692 -69.09142) (xy 190.785943 -69.114255)
			(xy 190.73344 -69.129743) (xy 190.679262 -69.137567) (xy 190.651892 -69.138038) (xy 190.624642 -69.13753)
			(xy 190.570697 -69.129773) (xy 190.518404 -69.114418) (xy 190.468829 -69.091778) (xy 190.42298 -69.062314)
			(xy 190.381791 -69.026625) (xy 190.346099 -68.985438) (xy 190.316632 -68.939591) (xy 190.293989 -68.890017)
			(xy 190.278632 -68.837725) (xy 190.270872 -68.78378) (xy 190.270384 -68.75653) (xy 186.794275 -68.75653)
			(xy 186.788274 -68.76967) (xy 186.758809 -68.81552) (xy 186.723119 -68.856709) (xy 186.681931 -68.892401)
			(xy 186.636083 -68.921868) (xy 186.586507 -68.94451) (xy 186.534215 -68.959866) (xy 186.480269 -68.967625)
			(xy 186.453018 -68.968112) (xy 186.425648 -68.967632) (xy 186.37147 -68.959817) (xy 186.318967 -68.944331)
			(xy 186.26922 -68.921493) (xy 186.223252 -68.891772) (xy 186.20232 -68.874132) (xy 186.202066 -68.873878)
			(xy 186.194966 -68.86831) (xy 186.17806 -68.862053) (xy 186.169046 -68.861686) (xy 186.10199 -68.861686)
			(xy 186.092973 -68.862041) (xy 186.076056 -68.868291) (xy 186.06897 -68.873878) (xy 186.06897 -68.874132)
			(xy 186.068716 -68.874132) (xy 186.047793 -68.891782) (xy 186.001817 -68.921491) (xy 185.952067 -68.944324)
			(xy 185.899565 -68.959813) (xy 185.845388 -68.967639) (xy 185.818018 -68.968112) (xy 185.791705 -68.967629)
			(xy 185.739577 -68.960397) (xy 185.688935 -68.94608) (xy 185.640736 -68.924951) (xy 185.595892 -68.897408)
			(xy 185.555251 -68.863972) (xy 185.537094 -68.844922) (xy 185.529574 -68.837519) (xy 185.510293 -68.828995)
			(xy 185.499756 -68.828412) (xy 185.42508 -68.828412) (xy 185.414533 -68.828967) (xy 185.395237 -68.837484)
			(xy 185.387742 -68.844922) (xy 185.369612 -68.864003) (xy 185.328976 -68.897457) (xy 185.28413 -68.925012)
			(xy 185.235925 -68.946146) (xy 185.185273 -68.960458) (xy 185.133136 -68.967677) (xy 185.106818 -68.968112)
			(xy 185.079566 -68.967628) (xy 185.025616 -68.959874) (xy 184.973319 -68.94452) (xy 184.923739 -68.92188)
			(xy 184.877886 -68.892414) (xy 184.836693 -68.856723) (xy 184.800999 -68.815532) (xy 184.771531 -68.769681)
			(xy 184.748888 -68.720102) (xy 184.733531 -68.667806) (xy 184.725774 -68.613856) (xy 184.72531 -68.586604)
			(xy 180.813964 -68.586604) (xy 180.813964 -71.555864) (xy 187.294518 -71.555864) (xy 187.298589 -71.500242)
			(xy 187.310715 -71.445805) (xy 187.330638 -71.393714) (xy 187.357934 -71.345079) (xy 187.39202 -71.300936)
			(xy 187.432169 -71.262227) (xy 187.477527 -71.229776) (xy 187.527127 -71.204275) (xy 187.579911 -71.186268)
			(xy 187.634754 -71.176138) (xy 187.690488 -71.174101) (xy 187.745925 -71.180201) (xy 187.799882 -71.194307)
			(xy 187.851211 -71.216119) (xy 187.898817 -71.245173) (xy 187.941685 -71.280848) (xy 187.978902 -71.322385)
			(xy 188.009675 -71.368898) (xy 188.033347 -71.419395) (xy 188.049415 -71.472802) (xy 188.057535 -71.527978)
			(xy 188.058044 -71.555864) (xy 188.057535 -71.58375) (xy 188.051696 -71.623428) (xy 188.803532 -71.623428)
			(xy 188.807603 -71.567806) (xy 188.819729 -71.513369) (xy 188.839652 -71.461278) (xy 188.866948 -71.412643)
			(xy 188.901034 -71.3685) (xy 188.941183 -71.329791) (xy 188.986541 -71.29734) (xy 189.036141 -71.271839)
			(xy 189.088925 -71.253832) (xy 189.143768 -71.243702) (xy 189.199502 -71.241665) (xy 189.254939 -71.247765)
			(xy 189.308896 -71.261871) (xy 189.360225 -71.283683) (xy 189.407831 -71.312737) (xy 189.450699 -71.348412)
			(xy 189.487916 -71.389949) (xy 189.518689 -71.436462) (xy 189.542361 -71.486959) (xy 189.558429 -71.540366)
			(xy 189.566549 -71.595542) (xy 189.567058 -71.623428) (xy 189.566549 -71.651314) (xy 189.558429 -71.70649)
			(xy 189.542361 -71.759897) (xy 189.518689 -71.810394) (xy 189.487916 -71.856907) (xy 189.450699 -71.898444)
			(xy 189.407831 -71.934119) (xy 189.360225 -71.963173) (xy 189.308896 -71.984985) (xy 189.254939 -71.999091)
			(xy 189.199502 -72.005191) (xy 189.143768 -72.003154) (xy 189.088925 -71.993024) (xy 189.036141 -71.975017)
			(xy 188.986541 -71.949516) (xy 188.941183 -71.917065) (xy 188.901034 -71.878356) (xy 188.866948 -71.834213)
			(xy 188.839652 -71.785578) (xy 188.819729 -71.733487) (xy 188.807603 -71.67905) (xy 188.803532 -71.623428)
			(xy 188.051696 -71.623428) (xy 188.049415 -71.638926) (xy 188.033347 -71.692333) (xy 188.009675 -71.74283)
			(xy 187.978902 -71.789343) (xy 187.941685 -71.83088) (xy 187.898817 -71.866555) (xy 187.851211 -71.895609)
			(xy 187.799882 -71.917421) (xy 187.745925 -71.931527) (xy 187.690488 -71.937627) (xy 187.634754 -71.93559)
			(xy 187.579911 -71.92546) (xy 187.527127 -71.907453) (xy 187.477527 -71.881952) (xy 187.432169 -71.849501)
			(xy 187.39202 -71.810792) (xy 187.357934 -71.766649) (xy 187.330638 -71.718014) (xy 187.310715 -71.665923)
			(xy 187.298589 -71.611486) (xy 187.294518 -71.555864) (xy 180.813964 -71.555864) (xy 180.813964 -74.353166)
			(xy 180.815488 -74.365612) (xy 180.817369 -74.372151) (xy 180.824073 -74.383986) (xy 180.828696 -74.38898)
			(xy 183.176418 -76.736448) (xy 183.19453 -76.755229) (xy 183.225212 -76.797427) (xy 183.24891 -76.843908)
			(xy 183.265038 -76.893526) (xy 183.2732 -76.945057) (xy 183.2737 -76.971144) (xy 183.2737 -80.362806)
			(xy 187.844936 -80.362806) (xy 187.849007 -80.307184) (xy 187.861133 -80.252747) (xy 187.881056 -80.200656)
			(xy 187.908352 -80.152021) (xy 187.942438 -80.107878) (xy 187.982587 -80.069169) (xy 188.027945 -80.036718)
			(xy 188.077545 -80.011217) (xy 188.130329 -79.99321) (xy 188.185172 -79.98308) (xy 188.240906 -79.981043)
			(xy 188.296343 -79.987143) (xy 188.3503 -80.001249) (xy 188.401629 -80.023061) (xy 188.449235 -80.052115)
			(xy 188.492103 -80.08779) (xy 188.52932 -80.129327) (xy 188.560093 -80.17584) (xy 188.583765 -80.226337)
			(xy 188.599833 -80.279744) (xy 188.607953 -80.33492) (xy 188.608462 -80.362806) (xy 188.607953 -80.390692)
			(xy 188.599833 -80.445868) (xy 188.583765 -80.499275) (xy 188.560093 -80.549772) (xy 188.52932 -80.596285)
			(xy 188.492103 -80.637822) (xy 188.449235 -80.673497) (xy 188.401629 -80.702551) (xy 188.3503 -80.724363)
			(xy 188.296343 -80.738469) (xy 188.240906 -80.744569) (xy 188.185172 -80.742532) (xy 188.130329 -80.732402)
			(xy 188.077545 -80.714395) (xy 188.027945 -80.688894) (xy 187.982587 -80.656443) (xy 187.942438 -80.617734)
			(xy 187.908352 -80.573591) (xy 187.881056 -80.524956) (xy 187.861133 -80.472865) (xy 187.849007 -80.418428)
			(xy 187.844936 -80.362806) (xy 183.2737 -80.362806) (xy 183.2737 -80.49006) (xy 183.273217 -80.516149)
			(xy 183.265057 -80.567684) (xy 183.248931 -80.617307) (xy 183.225237 -80.663795) (xy 183.194558 -80.706001)
			(xy 183.176418 -80.724756) (xy 183.11368 -80.78724) (xy 183.107443 -80.794681) (xy 183.10058 -80.812828)
			(xy 183.100936 -80.832226) (xy 183.104282 -80.841342) (xy 183.115204 -80.867504) (xy 183.119947 -80.869682)
			(xy 183.130063 -80.872238) (xy 183.13527 -80.872584) (xy 188.462412 -80.872584) (xy 188.472045 -80.872118)
			(xy 188.489927 -80.864936) (xy 188.49721 -80.858614) (xy 193.597784 -75.75804) (xy 193.600491 -75.75519)
			(xy 193.605087 -75.748813) (xy 193.606928 -75.74534) (xy 193.609508 -75.739912) (xy 193.612326 -75.728233)
			(xy 193.612516 -75.722226) (xy 193.612516 -71.061072) (xy 193.612262 -68.59016) (xy 193.612753 -68.564888)
			(xy 193.620448 -68.514933) (xy 193.635622 -68.46672) (xy 193.657926 -68.421364) (xy 193.686845 -68.37991)
			(xy 193.703956 -68.361306) (xy 193.708555 -68.354929) (xy 193.713988 -68.340186) (xy 193.714624 -68.33235)
			(xy 193.714624 -68.03898) (xy 193.71456 -68.035374) (xy 193.713538 -68.028236) (xy 193.712592 -68.024756)
			(xy 193.711068 -68.020184) (xy 193.707258 -68.01104) (xy 193.686938 -67.99072) (xy 193.686684 -67.990466)
			(xy 193.682162 -67.985766) (xy 193.67547 -67.974577) (xy 193.673476 -67.968368) (xy 193.672714 -67.964558)
			(xy 193.672714 -67.964304) (xy 193.672206 -67.962018) (xy 193.671952 -67.961002) (xy 193.671952 -67.959732)
			(xy 193.670171 -67.949666) (xy 193.659824 -67.932056) (xy 193.643421 -67.919886) (xy 193.633598 -67.91706)
			(xy 193.616045 -67.920149) (xy 193.580554 -67.923455) (xy 193.562732 -67.923664) (xy 193.548584 -67.923553)
			(xy 193.520362 -67.921516) (xy 193.506344 -67.9196) (xy 193.476372 -67.92341) (xy 193.449448 -67.907916)
			(xy 193.44005 -67.903598) (xy 193.415877 -67.895068) (xy 193.36985 -67.872501) (xy 193.327224 -67.844028)
			(xy 193.307716 -67.827398) (xy 193.293746 -67.825366) (xy 193.276728 -67.825366) (xy 193.269238 -67.825059)
			(xy 193.254911 -67.820671) (xy 193.248534 -67.81673) (xy 193.239898 -67.811396) (xy 193.226436 -67.809872)
			(xy 193.221472 -67.809665) (xy 193.211621 -67.810936) (xy 193.206878 -67.812412) (xy 193.184018 -67.82054)
			(xy 193.176906 -67.826636) (xy 193.156028 -67.844027) (xy 193.110277 -67.873338) (xy 193.060829 -67.895859)
			(xy 193.008684 -67.911132) (xy 192.9549 -67.918849) (xy 192.927732 -67.919346) (xy 192.900475 -67.918885)
			(xy 192.846515 -67.911131) (xy 192.794208 -67.895776) (xy 192.744619 -67.873133) (xy 192.698757 -67.843663)
			(xy 192.657557 -67.807966) (xy 192.621856 -67.766768) (xy 192.592382 -67.720909) (xy 192.569735 -67.671322)
			(xy 192.554376 -67.619016) (xy 192.546617 -67.565057) (xy 192.546617 -67.510543) (xy 192.554376 -67.456584)
			(xy 192.569735 -67.404278) (xy 192.592382 -67.354691) (xy 192.621856 -67.308832) (xy 192.657557 -67.267634)
			(xy 192.698757 -67.231937) (xy 192.744619 -67.202467) (xy 192.794208 -67.179824) (xy 192.846515 -67.164469)
			(xy 192.900475 -67.156715) (xy 192.927732 -67.15633) (xy 192.928494 -67.15633) (xy 192.95885 -67.156956)
			(xy 193.018784 -67.166648) (xy 193.076427 -67.185708) (xy 193.130325 -67.213656) (xy 193.155062 -67.23126)
			(xy 193.167508 -67.240912) (xy 193.168016 -67.24142) (xy 193.172842 -67.244214) (xy 193.178411 -67.247018)
			(xy 193.190487 -67.250107) (xy 193.196718 -67.25031) (xy 193.213736 -67.25031) (xy 193.221227 -67.250613)
			(xy 193.235557 -67.254998) (xy 193.24193 -67.258946) (xy 193.250566 -67.26428) (xy 193.264028 -67.265804)
			(xy 193.268715 -67.266045) (xy 193.278043 -67.265015) (xy 193.28257 -67.263772) (xy 193.286888 -67.262248)
			(xy 193.291348 -67.260402) (xy 193.299536 -67.255294) (xy 193.303144 -67.252088) (xy 193.32458 -67.233337)
			(xy 193.37193 -67.201693) (xy 193.423415 -67.177348) (xy 193.477918 -67.16083) (xy 193.534256 -67.152498)
			(xy 193.562732 -67.152012) (xy 193.587624 -67.152774) (xy 193.592328 -67.150817) (xy 193.6009 -67.14531)
			(xy 193.604642 -67.141852) (xy 193.656458 -67.091052) (xy 193.663417 -67.083631) (xy 193.671301 -67.064894)
			(xy 193.671698 -67.05473) (xy 193.671698 -66.057272) (xy 193.671633 -66.053667) (xy 193.670609 -66.046529)
			(xy 193.669666 -66.043048) (xy 193.668142 -66.038476) (xy 193.664332 -66.029332) (xy 192.949576 -65.314576)
			(xy 192.944242 -65.310004) (xy 190.655448 -65.310004) (xy 190.64859 -65.310512) (xy 190.640487 -65.311945)
			(xy 190.625729 -65.319206) (xy 190.619634 -65.324736) (xy 190.066168 -65.878456) (xy 190.047397 -65.896486)
			(xy 190.005279 -65.927062) (xy 189.958902 -65.950683) (xy 189.909405 -65.96677) (xy 189.858003 -65.974928)
			(xy 189.83198 -65.975484) (xy 189.156848 -65.975484) (xy 189.130824 -65.974957) (xy 189.07942 -65.96679)
			(xy 189.029922 -65.950697) (xy 188.983544 -65.927072) (xy 188.941424 -65.896495) (xy 188.92266 -65.878456)
			(xy 188.522356 -65.478152) (xy 188.517879 -65.473908) (xy 188.507353 -65.467483) (xy 188.501528 -65.465452)
			(xy 188.501274 -65.465452) (xy 188.47599 -65.457119) (xy 188.427836 -65.434419) (xy 188.383309 -65.405241)
			(xy 188.343273 -65.370152) (xy 188.308508 -65.329835) (xy 188.27969 -65.285074) (xy 188.257378 -65.236739)
			(xy 188.242008 -65.18577) (xy 188.233877 -65.133159) (xy 188.23305 -65.10655) (xy 188.23305 -65.09639)
			(xy 188.233967 -65.066168) (xy 188.244173 -65.006575) (xy 188.25337 -64.977772) (xy 188.25337 -64.977518)
			(xy 188.255217 -64.97174) (xy 188.256364 -64.959667) (xy 188.255656 -64.953642) (xy 188.253878 -64.942212)
			(xy 188.196728 -64.862456) (xy 188.187838 -64.85382) (xy 187.710826 -64.85382) (xy 187.704817 -64.85399)
			(xy 187.693138 -64.85682) (xy 187.687712 -64.859408) (xy 187.684237 -64.861246) (xy 187.677856 -64.865837)
			(xy 187.675012 -64.868552) (xy 186.56046 -65.983104) (xy 186.546998 -65.995804) (xy 186.545982 -65.99682)
			(xy 186.527383 -66.013707) (xy 186.486047 -66.042253) (xy 186.440884 -66.064249) (xy 186.392925 -66.079196)
			(xy 186.343261 -66.086751) (xy 186.318144 -66.087244) (xy 183.017922 -66.087244) (xy 183.013604 -66.08953)
			(xy 182.985178 -66.104445) (xy 182.924577 -66.125604) (xy 182.861294 -66.136351) (xy 182.8292 -66.137028)
			(xy 182.828692 -66.137028) (xy 182.80144 -66.136542) (xy 182.74749 -66.128784) (xy 182.695193 -66.113427)
			(xy 182.645615 -66.090784) (xy 182.599763 -66.061316) (xy 182.558571 -66.025623) (xy 182.522879 -65.984431)
			(xy 182.493412 -65.938578) (xy 182.47077 -65.888999) (xy 182.455415 -65.836702) (xy 182.447658 -65.782752)
			(xy 182.447658 -65.728248) (xy 182.455415 -65.674298) (xy 182.47077 -65.622001) (xy 182.493412 -65.572422)
			(xy 182.522879 -65.526569) (xy 182.558571 -65.485377) (xy 182.599763 -65.449684) (xy 182.645615 -65.420216)
			(xy 182.695193 -65.397573) (xy 182.74749 -65.382216) (xy 182.80144 -65.374458) (xy 182.828692 -65.374012)
			(xy 182.828946 -65.374012) (xy 182.853193 -65.374408) (xy 182.901294 -65.38058) (xy 182.948229 -65.392781)
			(xy 182.993246 -65.410815) (xy 183.01462 -65.422272) (xy 183.017414 -65.423796) (xy 186.159648 -65.423796)
			(xy 186.169046 -65.423034) (xy 186.176478 -65.421394) (xy 186.18993 -65.41429) (xy 186.195462 -65.409064)
			(xy 187.317126 -64.287146) (xy 187.31738 -64.286892) (xy 187.337096 -64.26804) (xy 187.381517 -64.236384)
			(xy 187.405772 -64.2239) (xy 187.413392 -64.22009) (xy 187.896754 -63.736474) (xy 187.897516 -63.735458)
			(xy 187.917677 -63.715282) (xy 187.963753 -63.681671) (xy 188.015027 -63.656699) (xy 188.042296 -63.648336)
			(xy 188.04509 -63.647828) (xy 188.047884 -63.647066) (xy 188.067962 -63.642053) (xy 188.108982 -63.636575)
			(xy 188.129672 -63.636144) (xy 190.268352 -63.636144) (xy 190.275504 -63.635763) (xy 190.289174 -63.631511)
			(xy 190.295276 -63.627762) (xy 190.302134 -63.622936) (xy 190.306706 -63.618872) (xy 190.311222 -63.614054)
			(xy 190.31778 -63.602597) (xy 190.31966 -63.596266) (xy 190.323216 -63.583312) (xy 190.327534 -63.572898)
			(xy 190.332106 -63.56096) (xy 190.333869 -63.556818) (xy 190.338595 -63.549156) (xy 190.341504 -63.54572)
			(xy 190.34252 -63.54445) (xy 190.346825 -63.538998) (xy 190.35261 -63.526375) (xy 190.35395 -63.519558)
			(xy 190.354966 -63.5127) (xy 190.354204 -63.505842) (xy 190.353655 -63.502169) (xy 190.35161 -63.495029)
			(xy 190.35014 -63.491618) (xy 190.341504 -63.472314) (xy 190.341504 -63.471806) (xy 190.336932 -63.461392)
			(xy 190.330328 -63.454534) (xy 190.330074 -63.45428) (xy 190.329566 -63.453772) (xy 190.309332 -63.432376)
			(xy 190.275032 -63.384511) (xy 190.248493 -63.331944) (xy 190.230344 -63.275925) (xy 190.221017 -63.217782)
			(xy 190.220346 -63.188342) (xy 190.220346 -63.180214) (xy 190.221346 -63.151261) (xy 190.231017 -63.094144)
			(xy 190.249212 -63.039146) (xy 190.275512 -62.987531) (xy 190.309314 -62.940485) (xy 190.349841 -62.89909)
			(xy 190.396159 -62.864299) (xy 190.447206 -62.83691) (xy 190.501806 -62.817553) (xy 190.558705 -62.806674)
			(xy 190.58763 -62.805056) (xy 190.587884 -62.805056) (xy 190.601854 -62.804802) (xy 190.602362 -62.804802)
			(xy 190.627989 -62.80523) (xy 190.678777 -62.812125) (xy 190.728181 -62.825768) (xy 190.77531 -62.845913)
			(xy 190.819312 -62.872196) (xy 190.839598 -62.88786) (xy 190.846202 -62.89294) (xy 190.857378 -62.89675)
			(xy 190.87084 -62.898782) (xy 190.892684 -62.898782) (xy 190.89629 -62.898844) (xy 190.90343 -62.899861)
			(xy 190.906908 -62.900814) (xy 190.910464 -62.901576) (xy 190.964312 -62.901576) (xy 190.972918 -62.901249)
			(xy 190.989159 -62.895548) (xy 190.996062 -62.8904) (xy 190.996316 -62.890146) (xy 190.997078 -62.889638)
			(xy 191.00165 -62.886082) (xy 191.00419 -62.88405) (xy 191.004952 -62.883288) (xy 191.02705 -62.86754)
			(xy 191.028066 -62.867032) (xy 191.03594 -62.861698) (xy 191.039496 -62.859666) (xy 191.056134 -62.849892)
			(xy 191.090998 -62.833351) (xy 191.109092 -62.826646) (xy 191.109854 -62.826392) (xy 191.113664 -62.825122)
			(xy 191.138688 -62.817066) (xy 191.190308 -62.80712) (xy 191.216534 -62.80531) (xy 191.236092 -62.804802)
			(xy 191.236854 -62.804802) (xy 191.252856 -62.805056) (xy 191.257174 -62.80531) (xy 191.286583 -62.80745)
			(xy 191.344273 -62.819646) (xy 191.399404 -62.840558) (xy 191.45067 -62.869691) (xy 191.47409 -62.887606)
			(xy 191.474344 -62.88786) (xy 191.477392 -62.8904) (xy 191.483503 -62.89413) (xy 191.497168 -62.898379)
			(xy 191.504316 -62.898782) (xy 191.527684 -62.898782) (xy 191.533125 -62.89892) (xy 191.543761 -62.901217)
			(xy 191.548766 -62.903354) (xy 191.562482 -62.909704) (xy 191.567187 -62.911769) (xy 191.577167 -62.9142)
			(xy 191.582294 -62.91453) (xy 191.59093 -62.914022) (xy 191.598219 -62.912746) (xy 191.611654 -62.906558)
			(xy 191.617346 -62.90183) (xy 191.6176 -62.901576) (xy 191.63867 -62.883469) (xy 191.685064 -62.85291)
			(xy 191.735397 -62.829398) (xy 191.788607 -62.813429) (xy 191.843569 -62.80534) (xy 191.871346 -62.804802)
			(xy 191.871854 -62.804802) (xy 191.899109 -62.805262) (xy 191.953064 -62.813014) (xy 192.005367 -62.828366)
			(xy 192.054952 -62.851006) (xy 192.10081 -62.880473) (xy 192.142008 -62.916167) (xy 192.177705 -62.957361)
			(xy 192.207177 -63.003216) (xy 192.229821 -63.052799) (xy 192.245178 -63.105101) (xy 192.252935 -63.159055)
			(xy 192.253362 -63.18631) (xy 192.252792 -63.216037) (xy 192.243564 -63.274769) (xy 192.225334 -63.331358)
			(xy 192.198543 -63.384433) (xy 192.16384 -63.432707) (xy 192.14338 -63.45428) (xy 192.143126 -63.454534)
			(xy 192.13703 -63.460884) (xy 192.132966 -63.46952) (xy 192.129156 -63.477648) (xy 192.127124 -63.483744)
			(xy 192.124076 -63.497968) (xy 192.12321 -63.504155) (xy 192.124096 -63.516612) (xy 192.125854 -63.522606)
			(xy 192.144904 -63.569342) (xy 192.144904 -63.56985) (xy 192.160398 -63.606934) (xy 192.167256 -63.617856)
			(xy 192.174861 -63.62611) (xy 192.195162 -63.635614) (xy 192.206372 -63.636144) (xy 193.094864 -63.636144)
			(xy 193.106716 -63.635534) (xy 193.127926 -63.624953) (xy 193.135504 -63.615824) (xy 193.135504 -57.775602)
			(xy 193.132964 -57.771792) (xy 193.126664 -57.761874) (xy 193.115351 -57.74128) (xy 193.110358 -57.730644)
			(xy 193.102738 -57.71261) (xy 193.09588 -57.700418) (xy 193.080241 -57.678708) (xy 193.05538 -57.631334)
			(xy 193.038438 -57.580587) (xy 193.029853 -57.527779) (xy 193.029332 -57.501028) (xy 193.029332 -56.577992)
			(xy 193.025261 -56.572851) (xy 193.01497 -56.564728) (xy 193.009012 -56.56199) (xy 192.916556 -56.528208)
			(xy 192.909182 -56.525734) (xy 192.893656 -56.524945) (xy 192.886076 -56.526684) (xy 192.87871 -56.528716)
			(xy 192.865502 -56.537098) (xy 192.860422 -56.543194) (xy 192.842166 -56.564011) (xy 192.800681 -56.600678)
			(xy 192.754339 -56.630977) (xy 192.704111 -56.654272) (xy 192.651048 -56.670078) (xy 192.59626 -56.678062)
			(xy 192.568576 -56.678576) (xy 192.541328 -56.678088) (xy 192.487388 -56.67033) (xy 192.4351 -56.654974)
			(xy 192.38553 -56.632333) (xy 192.339687 -56.602869) (xy 192.298503 -56.56718) (xy 192.262817 -56.525994)
			(xy 192.233355 -56.480149) (xy 192.210718 -56.430577) (xy 192.195365 -56.378289) (xy 192.18761 -56.324348)
			(xy 192.18761 -56.269852) (xy 192.195365 -56.215911) (xy 192.210718 -56.163623) (xy 192.233355 -56.114051)
			(xy 192.262817 -56.068206) (xy 192.298503 -56.02702) (xy 192.339687 -55.991331) (xy 192.38553 -55.961867)
			(xy 192.4351 -55.939226) (xy 192.487388 -55.92387) (xy 192.541328 -55.916112) (xy 192.568576 -55.91556)
			(xy 192.595433 -55.916015) (xy 192.648616 -55.923539) (xy 192.700221 -55.938443) (xy 192.749227 -55.960431)
			(xy 192.794668 -55.98907) (xy 192.835648 -56.023795) (xy 192.853818 -56.043576) (xy 192.854072 -56.04383)
			(xy 192.855342 -56.045354) (xy 192.85585 -56.045862) (xy 192.860676 -56.051196) (xy 192.876424 -56.06161)
			(xy 192.885665 -56.066309) (xy 192.906242 -56.068682) (xy 192.916302 -56.066182) (xy 192.972944 -56.045608)
			(xy 193.006218 -56.033416) (xy 193.013021 -56.030668) (xy 193.02477 -56.02189) (xy 193.029332 -56.016144)
			(xy 193.029332 -55.113428) (xy 193.029816 -55.08734) (xy 193.037979 -55.035806) (xy 193.054107 -54.986185)
			(xy 193.077804 -54.9397) (xy 193.108485 -54.897497) (xy 193.126614 -54.878732) (xy 195.050664 -52.954682)
			(xy 195.057014 -52.944014) (xy 195.058792 -52.938172) (xy 195.067227 -52.912592) (xy 195.090285 -52.863915)
			(xy 195.119957 -52.818964) (xy 195.155654 -52.77863) (xy 195.196667 -52.743716) (xy 195.242181 -52.714913)
			(xy 195.291292 -52.692796) (xy 195.343024 -52.677802) (xy 195.396351 -52.67023) (xy 195.450213 -52.67023)
			(xy 195.50354 -52.677802) (xy 195.555272 -52.692796) (xy 195.604383 -52.714913) (xy 195.649897 -52.743716)
			(xy 195.69091 -52.77863) (xy 195.726607 -52.818964) (xy 195.756279 -52.863915) (xy 195.779337 -52.912592)
			(xy 195.787772 -52.938172) (xy 195.78955 -52.944014) (xy 195.7959 -52.954682) (xy 196.337773 -53.496555)
			(xy 200.233441 -53.496555) (xy 200.233441 -53.442045) (xy 200.241199 -53.388089) (xy 200.256557 -53.335786)
			(xy 200.279203 -53.286202) (xy 200.308676 -53.240345) (xy 200.344374 -53.19915) (xy 200.385573 -53.163455)
			(xy 200.431432 -53.133987) (xy 200.481018 -53.111346) (xy 200.533322 -53.095992) (xy 200.587279 -53.088239)
			(xy 200.614534 -53.087778) (xy 200.641906 -53.088205) (xy 200.696087 -53.096029) (xy 200.748592 -53.111527)
			(xy 200.798338 -53.134377) (xy 200.844302 -53.164112) (xy 200.865232 -53.181758) (xy 200.865486 -53.182012)
			(xy 200.872571 -53.1876) (xy 200.889489 -53.193846) (xy 200.898506 -53.194204) (xy 200.965562 -53.194204)
			(xy 200.974577 -53.193828) (xy 200.991494 -53.187594) (xy 200.998582 -53.182012) (xy 200.998582 -53.181758)
			(xy 200.998836 -53.181758) (xy 201.019776 -53.164129) (xy 201.065747 -53.134417) (xy 201.115493 -53.111579)
			(xy 201.167991 -53.096086) (xy 201.222165 -53.088254) (xy 201.249534 -53.087778) (xy 201.276783 -53.088295)
			(xy 201.330725 -53.096055) (xy 201.383013 -53.111412) (xy 201.432584 -53.134054) (xy 201.478429 -53.163521)
			(xy 201.519613 -53.199211) (xy 201.5553 -53.240398) (xy 201.584762 -53.286245) (xy 201.6074 -53.335819)
			(xy 201.622753 -53.388109) (xy 201.630508 -53.442051) (xy 201.630508 -53.496549) (xy 201.622753 -53.550491)
			(xy 201.6074 -53.602781) (xy 201.584762 -53.652355) (xy 201.5553 -53.698202) (xy 201.519613 -53.739389)
			(xy 201.478429 -53.775079) (xy 201.432584 -53.804546) (xy 201.383013 -53.827188) (xy 201.330725 -53.842545)
			(xy 201.276783 -53.850305) (xy 201.249534 -53.850794) (xy 201.222164 -53.850309) (xy 201.167986 -53.842496)
			(xy 201.115483 -53.827012) (xy 201.065736 -53.804174) (xy 201.019768 -53.774453) (xy 200.998836 -53.756814)
			(xy 200.998582 -53.75656) (xy 200.991508 -53.750955) (xy 200.974581 -53.74472) (xy 200.965562 -53.744368)
			(xy 200.898506 -53.744368) (xy 200.88949 -53.744735) (xy 200.872574 -53.750976) (xy 200.865486 -53.75656)
			(xy 200.865486 -53.756814) (xy 200.865232 -53.756814) (xy 200.8443 -53.774454) (xy 200.798327 -53.804165)
			(xy 200.74858 -53.827001) (xy 200.696079 -53.842492) (xy 200.641903 -53.85032) (xy 200.614534 -53.850794)
			(xy 200.587279 -53.850361) (xy 200.533322 -53.842608) (xy 200.481018 -53.827254) (xy 200.431432 -53.804613)
			(xy 200.385573 -53.775145) (xy 200.344374 -53.73945) (xy 200.308676 -53.698255) (xy 200.279203 -53.652398)
			(xy 200.256557 -53.602814) (xy 200.241199 -53.550511) (xy 200.233441 -53.496555) (xy 196.337773 -53.496555)
			(xy 196.456554 -53.615336) (xy 196.474669 -53.634115) (xy 196.505359 -53.676311) (xy 196.529063 -53.722792)
			(xy 196.545197 -53.772411) (xy 196.553362 -53.823944) (xy 196.553836 -53.850032) (xy 196.553836 -54.912768)
			(xy 196.554295 -54.922404) (xy 196.561468 -54.940295) (xy 196.567806 -54.947566) (xy 196.570092 -54.949852)
			(xy 196.613391 -54.989055) (xy 198.001045 -54.989055) (xy 198.001045 -54.934545) (xy 198.008803 -54.88059)
			(xy 198.024161 -54.828289) (xy 198.046806 -54.778705) (xy 198.076277 -54.73285) (xy 198.111975 -54.691655)
			(xy 198.153172 -54.655961) (xy 198.19903 -54.626492) (xy 198.248615 -54.603851) (xy 198.300918 -54.588497)
			(xy 198.354873 -54.580743) (xy 198.382128 -54.580282) (xy 198.41022 -54.580755) (xy 198.465799 -54.588986)
			(xy 198.519568 -54.605281) (xy 198.570366 -54.629287) (xy 198.617092 -54.660485) (xy 198.658737 -54.6982)
			(xy 198.694398 -54.741616) (xy 198.70928 -54.765448) (xy 198.714614 -54.774338) (xy 198.731632 -54.78653)
			(xy 198.82485 -54.80685) (xy 198.845424 -54.802532) (xy 198.85406 -54.79669) (xy 198.878132 -54.780704)
			(xy 198.930061 -54.755358) (xy 198.985216 -54.738129) (xy 199.042338 -54.729409) (xy 199.07123 -54.728872)
			(xy 199.098481 -54.72935) (xy 199.152428 -54.73711) (xy 199.204722 -54.752468) (xy 199.254298 -54.775111)
			(xy 199.300147 -54.804579) (xy 199.341336 -54.840271) (xy 199.377027 -54.881461) (xy 199.406494 -54.927311)
			(xy 199.429136 -54.976888) (xy 199.444492 -55.029182) (xy 199.452251 -55.083129) (xy 199.452738 -55.11038)
			(xy 199.452275 -55.137751) (xy 199.444459 -55.19193) (xy 199.42897 -55.244434) (xy 199.406127 -55.294181)
			(xy 199.3764 -55.340147) (xy 199.358758 -55.361078) (xy 199.358504 -55.361332) (xy 199.35294 -55.368434)
			(xy 199.34668 -55.385339) (xy 199.346312 -55.394352) (xy 199.346312 -55.461408) (xy 199.346663 -55.470426)
			(xy 199.352914 -55.487343) (xy 199.358504 -55.494428) (xy 199.358758 -55.494428) (xy 199.358758 -55.494682)
			(xy 199.37638 -55.51563) (xy 199.406106 -55.561595) (xy 199.428954 -55.611339) (xy 199.444452 -55.663838)
			(xy 199.452283 -55.718015) (xy 199.452285 -55.772755) (xy 199.444459 -55.826932) (xy 199.428965 -55.879433)
			(xy 199.406121 -55.929179) (xy 199.376398 -55.975146) (xy 199.358758 -55.996078) (xy 199.358504 -55.996332)
			(xy 199.35294 -56.003434) (xy 199.34668 -56.020339) (xy 199.346312 -56.029352) (xy 199.346312 -56.096408)
			(xy 199.346663 -56.105426) (xy 199.352914 -56.122343) (xy 199.358504 -56.129428) (xy 199.358758 -56.129428)
			(xy 199.358758 -56.129682) (xy 199.376396 -56.150615) (xy 199.406109 -56.196587) (xy 199.428946 -56.246334)
			(xy 199.444437 -56.298835) (xy 199.452265 -56.353011) (xy 199.452738 -56.38038) (xy 199.452252 -56.407631)
			(xy 199.444496 -56.461579) (xy 199.429141 -56.513874) (xy 199.406499 -56.563451) (xy 199.377033 -56.609301)
			(xy 199.341342 -56.650492) (xy 199.300151 -56.686183) (xy 199.254301 -56.715649) (xy 199.204724 -56.738291)
			(xy 199.152429 -56.753646) (xy 199.098481 -56.761402) (xy 199.043979 -56.761402) (xy 198.990031 -56.753646)
			(xy 198.937736 -56.738291) (xy 198.888159 -56.715649) (xy 198.842309 -56.686183) (xy 198.801118 -56.650492)
			(xy 198.765427 -56.609301) (xy 198.735961 -56.563451) (xy 198.713319 -56.513874) (xy 198.697964 -56.461579)
			(xy 198.690208 -56.407631) (xy 198.689722 -56.38038) (xy 198.690171 -56.353009) (xy 198.697992 -56.298829)
			(xy 198.713485 -56.246326) (xy 198.736331 -56.196579) (xy 198.766059 -56.150613) (xy 198.783702 -56.129682)
			(xy 198.783956 -56.129428) (xy 198.789544 -56.122342) (xy 198.795788 -56.105425) (xy 198.796148 -56.096408)
			(xy 198.796148 -56.029352) (xy 198.795777 -56.020336) (xy 198.789541 -56.003419) (xy 198.783956 -55.996332)
			(xy 198.783702 -55.996332) (xy 198.783702 -55.996078) (xy 198.766043 -55.975161) (xy 198.736321 -55.92919)
			(xy 198.713478 -55.879441) (xy 198.697984 -55.826936) (xy 198.690158 -55.772756) (xy 198.69016 -55.718014)
			(xy 198.697991 -55.663834) (xy 198.713489 -55.611331) (xy 198.736335 -55.561584) (xy 198.766061 -55.515615)
			(xy 198.783702 -55.494682) (xy 198.783956 -55.494428) (xy 198.789544 -55.487342) (xy 198.795788 -55.470425)
			(xy 198.796148 -55.461408) (xy 198.796148 -55.394352) (xy 198.795777 -55.385336) (xy 198.789541 -55.368419)
			(xy 198.783956 -55.361332) (xy 198.783702 -55.360824) (xy 198.772759 -55.348089) (xy 198.752917 -55.320998)
			(xy 198.744078 -55.306722) (xy 198.738744 -55.297832) (xy 198.721726 -55.28564) (xy 198.628508 -55.26532)
			(xy 198.607934 -55.269638) (xy 198.599298 -55.27548) (xy 198.575235 -55.291481) (xy 198.523303 -55.316824)
			(xy 198.468145 -55.334049) (xy 198.411021 -55.342764) (xy 198.382128 -55.343298) (xy 198.354873 -55.342857)
			(xy 198.300918 -55.335103) (xy 198.248615 -55.319749) (xy 198.19903 -55.297108) (xy 198.153172 -55.267639)
			(xy 198.111975 -55.231945) (xy 198.076277 -55.19075) (xy 198.046806 -55.144895) (xy 198.024161 -55.095311)
			(xy 198.008803 -55.04301) (xy 198.001045 -54.989055) (xy 196.613391 -54.989055) (xy 196.62648 -55.000906)
			(xy 196.633846 -55.006494) (xy 196.639961 -55.009976) (xy 196.653484 -55.013845) (xy 196.660516 -55.014114)
			(xy 196.665342 -55.014114) (xy 196.667628 -55.01386) (xy 196.704712 -55.012082) (xy 196.70522 -55.012082)
			(xy 196.712332 -55.012082) (xy 196.742252 -55.01318) (xy 196.801216 -55.023546) (xy 196.857837 -55.042999)
			(xy 196.910722 -55.07106) (xy 196.958573 -55.10704) (xy 196.979794 -55.12816) (xy 196.986906 -55.135526)
			(xy 197.016116 -55.148226) (xy 197.02027 -55.149783) (xy 197.028957 -55.151572) (xy 197.033388 -55.151782)
			(xy 197.08876 -55.151782) (xy 197.101206 -55.149242) (xy 197.107048 -55.148226) (xy 197.13575 -55.135526)
			(xy 197.142608 -55.128414) (xy 197.160637 -55.110347) (xy 197.200686 -55.078704) (xy 197.244599 -55.052687)
			(xy 197.29159 -55.03276) (xy 197.34082 -55.01928) (xy 197.391407 -55.012488) (xy 197.416928 -55.012082)
			(xy 197.444179 -55.01257) (xy 197.498125 -55.02033) (xy 197.550418 -55.035688) (xy 197.599993 -55.058331)
			(xy 197.645841 -55.087799) (xy 197.687029 -55.123491) (xy 197.722718 -55.164682) (xy 197.752182 -55.210532)
			(xy 197.774822 -55.260109) (xy 197.790176 -55.312403) (xy 197.797932 -55.366349) (xy 197.797932 -55.420851)
			(xy 197.790176 -55.474797) (xy 197.774822 -55.527091) (xy 197.752182 -55.576668) (xy 197.722718 -55.622518)
			(xy 197.687029 -55.663709) (xy 197.645841 -55.699401) (xy 197.599993 -55.728869) (xy 197.550418 -55.751512)
			(xy 197.498125 -55.76687) (xy 197.444179 -55.77463) (xy 197.416928 -55.775098) (xy 197.391441 -55.774669)
			(xy 197.340922 -55.767873) (xy 197.291758 -55.754412) (xy 197.244824 -55.734526) (xy 197.200955 -55.708567)
			(xy 197.160932 -55.677) (xy 197.142862 -55.65902) (xy 197.13575 -55.651654) (xy 197.10654 -55.638954)
			(xy 197.102386 -55.637401) (xy 197.093698 -55.63562) (xy 197.089268 -55.635398) (xy 197.040246 -55.635398)
			(xy 197.030086 -55.636414) (xy 197.019164 -55.6387) (xy 197.013576 -55.639716) (xy 196.986906 -55.651654)
			(xy 196.980048 -55.65902) (xy 196.960355 -55.678639) (xy 196.916303 -55.71254) (xy 196.867798 -55.739688)
			(xy 196.815866 -55.759509) (xy 196.761606 -55.771581) (xy 196.733922 -55.774082) (xy 196.73189 -55.774082)
			(xy 196.723056 -55.775412) (xy 196.70707 -55.783363) (xy 196.700648 -55.789576) (xy 196.69379 -55.796688)
			(xy 196.693282 -55.797196) (xy 196.679566 -55.811166) (xy 196.672984 -55.818547) (xy 196.665535 -55.836846)
			(xy 196.665088 -55.846726) (xy 196.665088 -56.612282) (xy 196.66465 -56.622345) (xy 196.656913 -56.640927)
			(xy 196.650102 -56.64835) (xy 195.813172 -57.48528) (xy 198.705976 -57.48528) (xy 198.710047 -57.429658)
			(xy 198.722173 -57.375221) (xy 198.742096 -57.32313) (xy 198.769392 -57.274495) (xy 198.803478 -57.230352)
			(xy 198.843627 -57.191643) (xy 198.888985 -57.159192) (xy 198.938585 -57.133691) (xy 198.991369 -57.115684)
			(xy 199.046212 -57.105554) (xy 199.101946 -57.103517) (xy 199.157383 -57.109617) (xy 199.21134 -57.123723)
			(xy 199.262669 -57.145535) (xy 199.310275 -57.174589) (xy 199.353143 -57.210264) (xy 199.39036 -57.251801)
			(xy 199.421133 -57.298314) (xy 199.444805 -57.348811) (xy 199.460873 -57.402218) (xy 199.468993 -57.457394)
			(xy 199.469502 -57.48528) (xy 199.468993 -57.513166) (xy 199.460873 -57.568342) (xy 199.444805 -57.621749)
			(xy 199.421133 -57.672246) (xy 199.39036 -57.718759) (xy 199.353143 -57.760296) (xy 199.310275 -57.795971)
			(xy 199.262669 -57.825025) (xy 199.21134 -57.846837) (xy 199.157383 -57.860943) (xy 199.101946 -57.867043)
			(xy 199.046212 -57.865006) (xy 198.991369 -57.854876) (xy 198.938585 -57.836869) (xy 198.888985 -57.811368)
			(xy 198.843627 -57.778917) (xy 198.803478 -57.740208) (xy 198.769392 -57.696065) (xy 198.742096 -57.64743)
			(xy 198.722173 -57.595339) (xy 198.710047 -57.540902) (xy 198.705976 -57.48528) (xy 195.813172 -57.48528)
			(xy 195.403216 -57.895236) (xy 195.400513 -57.898089) (xy 195.395925 -57.90447) (xy 195.394072 -57.907936)
			(xy 195.391489 -57.913363) (xy 195.388666 -57.925043) (xy 195.388484 -57.93105) (xy 195.388484 -58.561224)
			(xy 200.662284 -58.561224) (xy 200.666355 -58.505602) (xy 200.678481 -58.451165) (xy 200.698404 -58.399074)
			(xy 200.7257 -58.350439) (xy 200.759786 -58.306296) (xy 200.799935 -58.267587) (xy 200.845293 -58.235136)
			(xy 200.894893 -58.209635) (xy 200.947677 -58.191628) (xy 201.00252 -58.181498) (xy 201.058254 -58.179461)
			(xy 201.113691 -58.185561) (xy 201.167648 -58.199667) (xy 201.218977 -58.221479) (xy 201.266583 -58.250533)
			(xy 201.309451 -58.286208) (xy 201.346668 -58.327745) (xy 201.377441 -58.374258) (xy 201.401113 -58.424755)
			(xy 201.417181 -58.478162) (xy 201.425301 -58.533338) (xy 201.42581 -58.561224) (xy 201.425301 -58.58911)
			(xy 201.417181 -58.644286) (xy 201.401113 -58.697693) (xy 201.377441 -58.74819) (xy 201.346668 -58.794703)
			(xy 201.309451 -58.83624) (xy 201.266583 -58.871915) (xy 201.218977 -58.900969) (xy 201.167648 -58.922781)
			(xy 201.113691 -58.936887) (xy 201.058254 -58.942987) (xy 201.00252 -58.94095) (xy 200.947677 -58.93082)
			(xy 200.894893 -58.912813) (xy 200.845293 -58.887312) (xy 200.799935 -58.854861) (xy 200.759786 -58.816152)
			(xy 200.7257 -58.772009) (xy 200.698404 -58.723374) (xy 200.678481 -58.671283) (xy 200.666355 -58.616846)
			(xy 200.662284 -58.561224) (xy 195.388484 -58.561224) (xy 195.388484 -59.174634) (xy 199.193148 -59.174634)
			(xy 199.197219 -59.119012) (xy 199.209345 -59.064575) (xy 199.229268 -59.012484) (xy 199.256564 -58.963849)
			(xy 199.29065 -58.919706) (xy 199.330799 -58.880997) (xy 199.376157 -58.848546) (xy 199.425757 -58.823045)
			(xy 199.478541 -58.805038) (xy 199.533384 -58.794908) (xy 199.589118 -58.792871) (xy 199.644555 -58.798971)
			(xy 199.698512 -58.813077) (xy 199.749841 -58.834889) (xy 199.797447 -58.863943) (xy 199.840315 -58.899618)
			(xy 199.877532 -58.941155) (xy 199.908305 -58.987668) (xy 199.931977 -59.038165) (xy 199.948045 -59.091572)
			(xy 199.956165 -59.146748) (xy 199.956674 -59.174634) (xy 199.956165 -59.20252) (xy 199.948045 -59.257696)
			(xy 199.931977 -59.311103) (xy 199.908305 -59.3616) (xy 199.877532 -59.408113) (xy 199.840315 -59.44965)
			(xy 199.797447 -59.485325) (xy 199.749841 -59.514379) (xy 199.698512 -59.536191) (xy 199.644555 -59.550297)
			(xy 199.589118 -59.556397) (xy 199.533384 -59.55436) (xy 199.478541 -59.54423) (xy 199.425757 -59.526223)
			(xy 199.376157 -59.500722) (xy 199.330799 -59.468271) (xy 199.29065 -59.429562) (xy 199.256564 -59.385419)
			(xy 199.229268 -59.336784) (xy 199.209345 -59.284693) (xy 199.197219 -59.230256) (xy 199.193148 -59.174634)
			(xy 195.388484 -59.174634) (xy 195.388484 -60.633356) (xy 201.896978 -60.633356) (xy 201.901049 -60.577734)
			(xy 201.913175 -60.523297) (xy 201.933098 -60.471206) (xy 201.960394 -60.422571) (xy 201.99448 -60.378428)
			(xy 202.034629 -60.339719) (xy 202.079987 -60.307268) (xy 202.129587 -60.281767) (xy 202.182371 -60.26376)
			(xy 202.237214 -60.25363) (xy 202.292948 -60.251593) (xy 202.348385 -60.257693) (xy 202.402342 -60.271799)
			(xy 202.453671 -60.293611) (xy 202.501277 -60.322665) (xy 202.544145 -60.35834) (xy 202.581362 -60.399877)
			(xy 202.612135 -60.44639) (xy 202.635807 -60.496887) (xy 202.651875 -60.550294) (xy 202.659995 -60.60547)
			(xy 202.660504 -60.633356) (xy 202.659995 -60.661242) (xy 202.651875 -60.716418) (xy 202.635807 -60.769825)
			(xy 202.612135 -60.820322) (xy 202.581362 -60.866835) (xy 202.544145 -60.908372) (xy 202.501277 -60.944047)
			(xy 202.453671 -60.973101) (xy 202.402342 -60.994913) (xy 202.348385 -61.009019) (xy 202.292948 -61.015119)
			(xy 202.237214 -61.013082) (xy 202.182371 -61.002952) (xy 202.129587 -60.984945) (xy 202.079987 -60.959444)
			(xy 202.034629 -60.926993) (xy 201.99448 -60.888284) (xy 201.960394 -60.844141) (xy 201.933098 -60.795506)
			(xy 201.913175 -60.743415) (xy 201.901049 -60.688978) (xy 201.896978 -60.633356) (xy 195.388484 -60.633356)
			(xy 195.388484 -61.487812) (xy 200.404474 -61.487812) (xy 200.408545 -61.43219) (xy 200.420671 -61.377753)
			(xy 200.440594 -61.325662) (xy 200.46789 -61.277027) (xy 200.501976 -61.232884) (xy 200.542125 -61.194175)
			(xy 200.587483 -61.161724) (xy 200.637083 -61.136223) (xy 200.689867 -61.118216) (xy 200.74471 -61.108086)
			(xy 200.800444 -61.106049) (xy 200.855881 -61.112149) (xy 200.909838 -61.126255) (xy 200.961167 -61.148067)
			(xy 201.008773 -61.177121) (xy 201.051641 -61.212796) (xy 201.088858 -61.254333) (xy 201.119631 -61.300846)
			(xy 201.143303 -61.351343) (xy 201.159371 -61.40475) (xy 201.167491 -61.459926) (xy 201.168 -61.487812)
			(xy 201.167491 -61.515698) (xy 201.159371 -61.570874) (xy 201.143303 -61.624281) (xy 201.119631 -61.674778)
			(xy 201.088858 -61.721291) (xy 201.051641 -61.762828) (xy 201.008773 -61.798503) (xy 200.961167 -61.827557)
			(xy 200.909838 -61.849369) (xy 200.855881 -61.863475) (xy 200.800444 -61.869575) (xy 200.74471 -61.867538)
			(xy 200.689867 -61.857408) (xy 200.637083 -61.839401) (xy 200.587483 -61.8139) (xy 200.542125 -61.781449)
			(xy 200.501976 -61.74274) (xy 200.46789 -61.698597) (xy 200.440594 -61.649962) (xy 200.420671 -61.597871)
			(xy 200.408545 -61.543434) (xy 200.404474 -61.487812) (xy 195.388484 -61.487812) (xy 195.388484 -62.121034)
			(xy 198.342248 -62.121034) (xy 198.346319 -62.065412) (xy 198.358445 -62.010975) (xy 198.378368 -61.958884)
			(xy 198.405664 -61.910249) (xy 198.43975 -61.866106) (xy 198.479899 -61.827397) (xy 198.525257 -61.794946)
			(xy 198.574857 -61.769445) (xy 198.627641 -61.751438) (xy 198.682484 -61.741308) (xy 198.738218 -61.739271)
			(xy 198.793655 -61.745371) (xy 198.847612 -61.759477) (xy 198.898941 -61.781289) (xy 198.946547 -61.810343)
			(xy 198.989415 -61.846018) (xy 199.026632 -61.887555) (xy 199.057405 -61.934068) (xy 199.081077 -61.984565)
			(xy 199.097145 -62.037972) (xy 199.105265 -62.093148) (xy 199.105774 -62.121034) (xy 199.105265 -62.14892)
			(xy 199.097145 -62.204096) (xy 199.081077 -62.257503) (xy 199.057405 -62.308) (xy 199.026632 -62.354513)
			(xy 198.989415 -62.39605) (xy 198.946547 -62.431725) (xy 198.898941 -62.460779) (xy 198.847612 -62.482591)
			(xy 198.793655 -62.496697) (xy 198.738218 -62.502797) (xy 198.682484 -62.50076) (xy 198.627641 -62.49063)
			(xy 198.574857 -62.472623) (xy 198.525257 -62.447122) (xy 198.479899 -62.414671) (xy 198.43975 -62.375962)
			(xy 198.405664 -62.331819) (xy 198.378368 -62.283184) (xy 198.358445 -62.231093) (xy 198.346319 -62.176656)
			(xy 198.342248 -62.121034) (xy 195.388484 -62.121034) (xy 195.388484 -62.787276) (xy 195.388484 -62.788038)
			(xy 195.38905 -62.797419) (xy 195.396078 -62.814831) (xy 195.408915 -62.828534) (xy 195.417186 -62.832996)
			(xy 195.422774 -62.835282) (xy 195.467986 -62.85103) (xy 195.515738 -62.86754) (xy 195.524836 -62.869757)
			(xy 195.543483 -62.868218) (xy 195.560344 -62.860109) (xy 195.567046 -62.85357) (xy 195.56984 -62.850268)
			(xy 195.588035 -62.828005) (xy 195.629979 -62.78868) (xy 195.677347 -62.756091) (xy 195.729068 -62.730976)
			(xy 195.78397 -62.713903) (xy 195.840812 -62.705259) (xy 195.86956 -62.704726) (xy 195.896812 -62.705187)
			(xy 195.950763 -62.712938) (xy 196.003061 -62.728289) (xy 196.052641 -62.750928) (xy 196.098496 -62.780392)
			(xy 196.139689 -62.816082) (xy 196.175384 -62.857272) (xy 196.204853 -62.903123) (xy 196.227497 -62.952702)
			(xy 196.242853 -63.004998) (xy 196.250611 -63.058948) (xy 196.250611 -63.113452) (xy 196.242853 -63.167402)
			(xy 196.227497 -63.219698) (xy 196.204853 -63.269277) (xy 196.202183 -63.273432) (xy 197.676768 -63.273432)
			(xy 197.680839 -63.21781) (xy 197.692965 -63.163373) (xy 197.712888 -63.111282) (xy 197.740184 -63.062647)
			(xy 197.77427 -63.018504) (xy 197.814419 -62.979795) (xy 197.859777 -62.947344) (xy 197.909377 -62.921843)
			(xy 197.962161 -62.903836) (xy 198.017004 -62.893706) (xy 198.072738 -62.891669) (xy 198.128175 -62.897769)
			(xy 198.182132 -62.911875) (xy 198.233461 -62.933687) (xy 198.281067 -62.962741) (xy 198.323935 -62.998416)
			(xy 198.361152 -63.039953) (xy 198.391925 -63.086466) (xy 198.415597 -63.136963) (xy 198.431665 -63.19037)
			(xy 198.439785 -63.245546) (xy 198.440294 -63.273432) (xy 198.439785 -63.301318) (xy 198.431665 -63.356494)
			(xy 198.415597 -63.409901) (xy 198.391925 -63.460398) (xy 198.361152 -63.506911) (xy 198.323935 -63.548448)
			(xy 198.281067 -63.584123) (xy 198.233461 -63.613177) (xy 198.182132 -63.634989) (xy 198.128175 -63.649095)
			(xy 198.072738 -63.655195) (xy 198.017004 -63.653158) (xy 197.962161 -63.643028) (xy 197.909377 -63.625021)
			(xy 197.859777 -63.59952) (xy 197.814419 -63.567069) (xy 197.77427 -63.52836) (xy 197.740184 -63.484217)
			(xy 197.712888 -63.435582) (xy 197.692965 -63.383491) (xy 197.680839 -63.329054) (xy 197.676768 -63.273432)
			(xy 196.202183 -63.273432) (xy 196.175384 -63.315128) (xy 196.139689 -63.356318) (xy 196.098496 -63.392008)
			(xy 196.052641 -63.421472) (xy 196.003061 -63.444111) (xy 195.950763 -63.459462) (xy 195.896812 -63.467213)
			(xy 195.86956 -63.467742) (xy 195.84081 -63.467224) (xy 195.783961 -63.458598) (xy 195.729052 -63.441532)
			(xy 195.677328 -63.416414) (xy 195.629963 -63.383814) (xy 195.588031 -63.34447) (xy 195.56984 -63.3222)
			(xy 195.567046 -63.318898) (xy 195.56034 -63.312361) (xy 195.543489 -63.304229) (xy 195.524839 -63.302714)
			(xy 195.515738 -63.304928) (xy 195.467986 -63.321438) (xy 195.422774 -63.337186) (xy 195.417186 -63.339472)
			(xy 195.408913 -63.343937) (xy 195.396066 -63.357639) (xy 195.38901 -63.375046) (xy 195.388484 -63.38443)
			(xy 195.388484 -65.124076) (xy 200.20737 -65.124076) (xy 200.211441 -65.068454) (xy 200.223567 -65.014017)
			(xy 200.24349 -64.961926) (xy 200.270786 -64.913291) (xy 200.304872 -64.869148) (xy 200.345021 -64.830439)
			(xy 200.390379 -64.797988) (xy 200.439979 -64.772487) (xy 200.492763 -64.75448) (xy 200.547606 -64.74435)
			(xy 200.60334 -64.742313) (xy 200.658777 -64.748413) (xy 200.712734 -64.762519) (xy 200.764063 -64.784331)
			(xy 200.811669 -64.813385) (xy 200.854537 -64.84906) (xy 200.891754 -64.890597) (xy 200.922527 -64.93711)
			(xy 200.946199 -64.987607) (xy 200.962267 -65.041014) (xy 200.970387 -65.09619) (xy 200.970896 -65.124076)
			(xy 200.970387 -65.151962) (xy 200.962267 -65.207138) (xy 200.946199 -65.260545) (xy 200.922527 -65.311042)
			(xy 200.891754 -65.357555) (xy 200.854537 -65.399092) (xy 200.811669 -65.434767) (xy 200.764063 -65.463821)
			(xy 200.712734 -65.485633) (xy 200.658777 -65.499739) (xy 200.60334 -65.505839) (xy 200.547606 -65.503802)
			(xy 200.492763 -65.493672) (xy 200.439979 -65.475665) (xy 200.390379 -65.450164) (xy 200.345021 -65.417713)
			(xy 200.304872 -65.379004) (xy 200.270786 -65.334861) (xy 200.24349 -65.286226) (xy 200.223567 -65.234135)
			(xy 200.211441 -65.179698) (xy 200.20737 -65.124076) (xy 195.388484 -65.124076) (xy 195.388484 -66.942716)
			(xy 195.388795 -66.950909) (xy 195.39398 -66.966453) (xy 195.398644 -66.973196) (xy 195.40347 -66.978784)
			(xy 195.572126 -67.14744) (xy 195.577556 -67.15242) (xy 195.590596 -67.159266) (xy 195.59778 -67.160902)
			(xy 195.598288 -67.160902) (xy 195.607686 -67.161918) (xy 199.756268 -67.161918) (xy 199.76338 -67.16141)
			(xy 202.364594 -64.560196) (xy 202.369584 -64.554698) (xy 202.376435 -64.541533) (xy 202.378056 -64.534288)
			(xy 202.379072 -64.524636) (xy 202.379072 -63.136272) (xy 202.378564 -63.135002) (xy 202.321922 -63.092584)
			(xy 202.321414 -63.092584) (xy 202.300586 -63.07709) (xy 202.291579 -63.071769) (xy 202.270981 -63.068246)
			(xy 202.260708 -63.070232) (xy 202.258168 -63.070994) (xy 202.23107 -63.078713) (xy 202.175341 -63.087006)
			(xy 202.14717 -63.087504) (xy 202.11992 -63.087016) (xy 202.065976 -63.079256) (xy 202.013685 -63.063898)
			(xy 201.964112 -63.041255) (xy 201.918266 -63.011788) (xy 201.877079 -62.976097) (xy 201.841391 -62.934907)
			(xy 201.811928 -62.889058) (xy 201.78929 -62.839483) (xy 201.773937 -62.787191) (xy 201.766181 -62.733246)
			(xy 201.765662 -62.705996) (xy 201.766142 -62.678825) (xy 201.773853 -62.625033) (xy 201.789119 -62.572878)
			(xy 201.81163 -62.523418) (xy 201.840931 -62.477652) (xy 201.876429 -62.436507) (xy 201.917406 -62.400814)
			(xy 201.963033 -62.371297) (xy 202.012387 -62.348552) (xy 202.064468 -62.33304) (xy 202.118223 -62.325075)
			(xy 202.145392 -62.324488) (xy 202.147678 -62.324488) (xy 202.172062 -62.32525) (xy 202.172824 -62.32525)
			(xy 202.174602 -62.325504) (xy 202.176126 -62.325504) (xy 202.207114 -62.32906) (xy 202.232488 -62.333538)
			(xy 202.281808 -62.348446) (xy 202.305412 -62.358778) (xy 202.305666 -62.359032) (xy 202.30592 -62.359032)
			(xy 202.30719 -62.35954) (xy 202.31735 -62.364366) (xy 202.328018 -62.364366) (xy 202.335199 -62.364118)
			(xy 202.348993 -62.360119) (xy 202.355196 -62.356492) (xy 202.35545 -62.356238) (xy 202.362501 -62.351393)
			(xy 202.373138 -62.338005) (xy 202.378773 -62.321861) (xy 202.379072 -62.313312) (xy 202.379072 -62.254384)
			(xy 202.378897 -62.248232) (xy 202.375934 -62.236291) (xy 202.37323 -62.230762) (xy 202.359766 -62.203868)
			(xy 202.340527 -62.146887) (xy 202.330442 -62.087597) (xy 202.329542 -62.057534) (xy 202.329542 -62.048136)
			(xy 202.33025 -62.021038) (xy 202.338382 -61.967446) (xy 202.354018 -61.915545) (xy 202.376844 -61.86638)
			(xy 202.4064 -61.820941) (xy 202.44209 -61.780144) (xy 202.483196 -61.744809) (xy 202.52889 -61.715649)
			(xy 202.578251 -61.693251) (xy 202.630287 -61.678066) (xy 202.683947 -61.6704) (xy 202.71105 -61.66993)
			(xy 202.712828 -61.66993) (xy 202.743838 -61.670641) (xy 202.805014 -61.680867) (xy 202.863737 -61.700835)
			(xy 202.89139 -61.714888) (xy 202.894692 -61.716412) (xy 202.900534 -61.71946) (xy 203.411582 -61.71946)
			(xy 203.421234 -61.718444) (xy 203.428479 -61.716818) (xy 203.441649 -61.709977) (xy 203.447142 -61.704982)
			(xy 203.628752 -61.523372) (xy 203.62926 -61.51626) (xy 203.62926 -58.87085) (xy 203.629006 -58.865516)
			(xy 203.627216 -58.85447) (xy 203.615641 -58.835349) (xy 203.606654 -58.828686) (xy 203.573634 -58.809382)
			(xy 203.529184 -58.783474) (xy 203.521028 -58.779496) (xy 203.503064 -58.77704) (xy 203.494132 -58.778648)
			(xy 203.47813 -58.782458) (xy 203.472542 -58.785506) (xy 203.444539 -58.799875) (xy 203.384992 -58.82025)
			(xy 203.322908 -58.830572) (xy 203.29144 -58.831226) (xy 203.290932 -58.831226) (xy 203.263676 -58.830765)
			(xy 203.209719 -58.823012) (xy 203.157415 -58.807658) (xy 203.107829 -58.785016) (xy 203.061969 -58.755547)
			(xy 203.020771 -58.719852) (xy 202.985072 -58.678656) (xy 202.955599 -58.6328) (xy 202.932954 -58.583215)
			(xy 202.917595 -58.530912) (xy 202.909837 -58.476956) (xy 202.909837 -58.422444) (xy 202.917595 -58.368488)
			(xy 202.932954 -58.316185) (xy 202.955599 -58.2666) (xy 202.985072 -58.220744) (xy 203.020771 -58.179548)
			(xy 203.061969 -58.143853) (xy 203.107829 -58.114384) (xy 203.157415 -58.091742) (xy 203.209719 -58.076388)
			(xy 203.263676 -58.068635) (xy 203.290932 -58.06821) (xy 203.291694 -58.06821) (xy 203.316016 -58.068586)
			(xy 203.364267 -58.07476) (xy 203.41134 -58.08702) (xy 203.456472 -58.105168) (xy 203.477876 -58.116724)
			(xy 203.47813 -58.116978) (xy 203.480924 -58.118502) (xy 203.486262 -58.120904) (xy 203.497678 -58.123479)
			(xy 203.50353 -58.123582) (xy 203.516738 -58.123328) (xy 203.605384 -58.071512) (xy 203.610742 -58.067985)
			(xy 203.619612 -58.058726) (xy 203.62291 -58.053224) (xy 203.625894 -58.047441) (xy 203.629114 -58.034837)
			(xy 203.62926 -58.028332) (xy 203.62926 -54.863238) (xy 203.629001 -54.857977) (xy 203.626576 -54.84773)
			(xy 203.624434 -54.842918) (xy 203.618846 -54.840632) (xy 203.598018 -54.831996) (xy 203.58863 -54.828455)
			(xy 203.568584 -54.828292) (xy 203.550021 -54.835865) (xy 203.542646 -54.842664) (xy 200.518245 -57.867296)
			(xy 201.743054 -57.867296) (xy 201.747125 -57.811674) (xy 201.759251 -57.757237) (xy 201.779174 -57.705146)
			(xy 201.80647 -57.656511) (xy 201.840556 -57.612368) (xy 201.880705 -57.573659) (xy 201.926063 -57.541208)
			(xy 201.975663 -57.515707) (xy 202.028447 -57.4977) (xy 202.08329 -57.48757) (xy 202.139024 -57.485533)
			(xy 202.194461 -57.491633) (xy 202.248418 -57.505739) (xy 202.299747 -57.527551) (xy 202.347353 -57.556605)
			(xy 202.390221 -57.59228) (xy 202.427438 -57.633817) (xy 202.458211 -57.68033) (xy 202.481883 -57.730827)
			(xy 202.497951 -57.784234) (xy 202.506071 -57.83941) (xy 202.50658 -57.867296) (xy 202.506071 -57.895182)
			(xy 202.497951 -57.950358) (xy 202.481883 -58.003765) (xy 202.458211 -58.054262) (xy 202.427438 -58.100775)
			(xy 202.390221 -58.142312) (xy 202.347353 -58.177987) (xy 202.299747 -58.207041) (xy 202.248418 -58.228853)
			(xy 202.194461 -58.242959) (xy 202.139024 -58.249059) (xy 202.08329 -58.247022) (xy 202.028447 -58.236892)
			(xy 201.975663 -58.218885) (xy 201.926063 -58.193384) (xy 201.880705 -58.160933) (xy 201.840556 -58.122224)
			(xy 201.80647 -58.078081) (xy 201.779174 -58.029446) (xy 201.759251 -57.977355) (xy 201.747125 -57.922918)
			(xy 201.743054 -57.867296) (xy 200.518245 -57.867296) (xy 200.212706 -58.172858) (xy 200.206356 -58.183526)
			(xy 200.204578 -58.189368) (xy 200.196129 -58.214933) (xy 200.173047 -58.263578) (xy 200.14336 -58.308497)
			(xy 200.107656 -58.348799) (xy 200.066643 -58.383684) (xy 200.021135 -58.412461) (xy 199.972036 -58.434558)
			(xy 199.920318 -58.449537) (xy 199.867009 -58.457101) (xy 199.840088 -58.457592) (xy 199.812836 -58.457128)
			(xy 199.758887 -58.449369) (xy 199.706592 -58.434012) (xy 199.657014 -58.411369) (xy 199.611164 -58.3819)
			(xy 199.569974 -58.346206) (xy 199.534283 -58.305014) (xy 199.504818 -58.259161) (xy 199.482178 -58.209582)
			(xy 199.466825 -58.157285) (xy 199.45907 -58.103336) (xy 199.45858 -58.076084) (xy 199.458326 -58.076084)
			(xy 199.458783 -58.049148) (xy 199.466349 -57.99581) (xy 199.481341 -57.944066) (xy 199.503462 -57.894945)
			(xy 199.532273 -57.849424) (xy 199.567199 -57.808408) (xy 199.607548 -57.772712) (xy 199.652516 -57.743046)
			(xy 199.701209 -57.72) (xy 199.726804 -57.711594) (xy 199.727058 -57.711594) (xy 199.732894 -57.709586)
			(xy 199.743434 -57.703169) (xy 199.747886 -57.698894) (xy 203.290932 -54.155848) (xy 203.29144 -54.14899)
			(xy 203.29144 -46.159674) (xy 203.291368 -46.155667) (xy 203.290084 -46.147755) (xy 203.2889 -46.143926)
			(xy 203.287884 -46.140878) (xy 203.284328 -46.132242) (xy 203.277216 -46.124876) (xy 203.2762 -46.123606)
			(xy 203.274676 -46.121828) (xy 197.461124 -40.308276) (xy 197.45579 -40.303704) (xy 194.567048 -40.303704)
			(xy 194.56273 -40.30599) (xy 194.534304 -40.320905) (xy 194.473703 -40.342065) (xy 194.41042 -40.352814)
			(xy 194.378326 -40.353488) (xy 194.377818 -40.353488) (xy 194.350566 -40.353026) (xy 194.296616 -40.345271)
			(xy 194.244318 -40.329918) (xy 194.194739 -40.307278) (xy 194.148886 -40.277812) (xy 194.107693 -40.24212)
			(xy 194.071999 -40.200929) (xy 194.042531 -40.155077) (xy 194.019889 -40.105498) (xy 194.004532 -40.053202)
			(xy 193.996775 -39.999252) (xy 193.996775 -39.944748) (xy 194.004532 -39.890798) (xy 194.019889 -39.838502)
			(xy 194.042531 -39.788923) (xy 194.071999 -39.743071) (xy 194.107693 -39.70188) (xy 194.148886 -39.666188)
			(xy 194.194739 -39.636722) (xy 194.244318 -39.614082) (xy 194.296616 -39.598729) (xy 194.350566 -39.590974)
			(xy 194.377818 -39.590472) (xy 194.378072 -39.590472) (xy 194.40232 -39.590864) (xy 194.450424 -39.597028)
			(xy 194.497363 -39.609223) (xy 194.542384 -39.627252) (xy 194.563746 -39.638732) (xy 194.56654 -39.640256)
			(xy 197.14845 -39.640256) (xy 197.158488 -39.639822) (xy 197.177022 -39.632101) (xy 197.191175 -39.617861)
			(xy 197.19544 -39.60876) (xy 197.20687 -39.581074) (xy 197.2056 -39.574724) (xy 197.042532 -39.41191)
			(xy 193.840862 -36.210494) (xy 193.838576 -36.208716) (xy 192.838578 -36.208716) (xy 192.829688 -36.216844)
			(xy 192.797176 -36.261802) (xy 192.780666 -36.284916) (xy 192.776928 -36.291025) (xy 192.772662 -36.304689)
			(xy 192.772284 -36.31184) (xy 192.772284 -36.331906) (xy 192.77457 -36.339526) (xy 192.782733 -36.367329)
			(xy 192.791527 -36.424601) (xy 192.792096 -36.453572) (xy 192.791635 -36.480826) (xy 192.783881 -36.534779)
			(xy 192.768527 -36.58708) (xy 192.745886 -36.636663) (xy 192.716419 -36.682518) (xy 192.680725 -36.723713)
			(xy 192.639531 -36.759409) (xy 192.593677 -36.788878) (xy 192.544095 -36.811521) (xy 192.491795 -36.826877)
			(xy 192.437842 -36.834633) (xy 192.410588 -36.83508) (xy 192.383465 -36.834602) (xy 192.329766 -36.826916)
			(xy 192.277697 -36.8117) (xy 192.228309 -36.789262) (xy 192.182598 -36.760054) (xy 192.141485 -36.724665)
			(xy 192.1058 -36.683808) (xy 192.076263 -36.638309) (xy 192.053469 -36.589084) (xy 192.037877 -36.537127)
			(xy 192.029804 -36.483485) (xy 192.02908 -36.456366) (xy 192.02908 -36.45281) (xy 192.029641 -36.423839)
			(xy 192.038449 -36.366569) (xy 192.046606 -36.338764) (xy 192.047368 -36.336224) (xy 192.048892 -36.331398)
			(xy 192.050416 -36.318444) (xy 192.050686 -36.310291) (xy 192.046682 -36.294485) (xy 192.042542 -36.287456)
			(xy 192.023492 -36.260786) (xy 191.992504 -36.21786) (xy 191.983106 -36.208716) (xy 191.460374 -36.208716)
			(xy 191.454532 -36.211764) (xy 191.45123 -36.213288) (xy 191.423428 -36.227423) (xy 191.364366 -36.247451)
			(xy 191.302834 -36.257613) (xy 191.271652 -36.258246) (xy 191.27089 -36.258246) (xy 191.243637 -36.257759)
			(xy 191.189684 -36.250001) (xy 191.137386 -36.234643) (xy 191.087805 -36.212) (xy 191.041951 -36.18253)
			(xy 191.000758 -36.146835) (xy 190.965064 -36.105641) (xy 190.935596 -36.059786) (xy 190.912953 -36.010205)
			(xy 190.897597 -35.957906) (xy 190.88984 -35.903954) (xy 190.88984 -35.849446) (xy 190.897597 -35.795494)
			(xy 190.912953 -35.743195) (xy 190.935596 -35.693614) (xy 190.965064 -35.647759) (xy 191.000758 -35.606565)
			(xy 191.041951 -35.57087) (xy 191.087805 -35.5414) (xy 191.137386 -35.518757) (xy 191.189684 -35.503399)
			(xy 191.243637 -35.495641) (xy 191.27089 -35.49523) (xy 191.271652 -35.49523) (xy 191.302834 -35.495867)
			(xy 191.364366 -35.506031) (xy 191.423431 -35.526048) (xy 191.45123 -35.540188) (xy 191.454532 -35.541712)
			(xy 191.460374 -35.54476) (xy 193.653918 -35.54476) (xy 193.663015 -35.544346) (xy 193.680035 -35.537908)
			(xy 193.693728 -35.525925) (xy 193.698368 -35.51809) (xy 193.7004 -35.51301) (xy 193.703126 -35.505978)
			(xy 193.704689 -35.490984) (xy 193.703448 -35.483546) (xy 193.702178 -35.476942) (xy 193.695066 -35.463734)
			(xy 191.841882 -33.61055) (xy 191.82377 -33.591769) (xy 191.793088 -33.549571) (xy 191.769391 -33.50309)
			(xy 191.753263 -33.453472) (xy 191.745101 -33.401941) (xy 191.7446 -33.375854) (xy 191.7446 -28.954476)
			(xy 191.744741 -28.942557) (xy 191.746519 -28.918785) (xy 191.748156 -28.906978) (xy 191.74968 -28.896056)
			(xy 191.746632 -28.885642) (xy 191.744966 -28.880424) (xy 191.739702 -28.87082) (xy 191.736218 -28.866592)
			(xy 191.684656 -28.806902) (xy 191.677534 -28.799985) (xy 191.659496 -28.791737) (xy 191.649604 -28.7909)
			(xy 189.173358 -28.7909) (xy 189.148069 -28.790402) (xy 189.098115 -28.782487) (xy 189.050012 -28.76686)
			(xy 189.004944 -28.743904) (xy 188.964019 -28.714185) (xy 188.945774 -28.696666) (xy 188.028072 -27.77871)
			(xy 188.022366 -27.773377) (xy 188.008526 -27.766154) (xy 188.000894 -27.764486) (xy 187.992004 -27.763724)
			(xy 187.810648 -27.763724) (xy 187.80098 -27.764195) (xy 187.783052 -27.771448) (xy 187.769085 -27.784826)
			(xy 187.764674 -27.793442) (xy 187.752736 -27.821128) (xy 187.727336 -27.88031) (xy 187.725428 -27.885171)
			(xy 187.723382 -27.895409) (xy 187.723272 -27.90063) (xy 187.736988 -27.934666) (xy 187.743084 -27.941524)
			(xy 187.76188 -27.962672) (xy 187.794659 -28.008792) (xy 187.821501 -28.0586) (xy 187.841999 -28.111338)
			(xy 187.855838 -28.166201) (xy 187.862809 -28.222351) (xy 187.863226 -28.250642) (xy 187.862972 -28.734512)
			(xy 187.862972 -29.114242) (xy 187.862482 -29.14421) (xy 187.854659 -29.203632) (xy 187.839146 -29.261525)
			(xy 187.81621 -29.316898) (xy 187.786243 -29.368804) (xy 187.749756 -29.416354) (xy 187.707376 -29.458734)
			(xy 187.659826 -29.495221) (xy 187.60792 -29.525188) (xy 187.552547 -29.548124) (xy 187.494654 -29.563637)
			(xy 187.435232 -29.57146) (xy 187.375296 -29.57146) (xy 187.315874 -29.563637) (xy 187.257981 -29.548124)
			(xy 187.202608 -29.525188) (xy 187.150702 -29.495221) (xy 187.103152 -29.458734) (xy 187.060772 -29.416354)
			(xy 187.024285 -29.368804) (xy 186.994318 -29.316898) (xy 186.971382 -29.261525) (xy 186.955869 -29.203632)
			(xy 186.948046 -29.14421) (xy 186.947556 -29.114242) (xy 186.947556 -28.734512) (xy 186.947302 -28.250642)
			(xy 186.947727 -28.222353) (xy 186.954706 -28.166206) (xy 186.968552 -28.111348) (xy 186.989051 -28.058614)
			(xy 187.015894 -28.008808) (xy 187.048669 -27.962689) (xy 187.067444 -27.941524) (xy 187.07354 -27.934666)
			(xy 187.087256 -27.90063) (xy 187.087186 -27.895404) (xy 187.085144 -27.885158) (xy 187.083192 -27.88031)
			(xy 187.057792 -27.821128) (xy 187.045854 -27.793442) (xy 187.04146 -27.784811) (xy 187.02749 -27.77142)
			(xy 187.009554 -27.764155) (xy 186.99988 -27.763724) (xy 186.934094 -27.763724) (xy 186.908072 -27.763192)
			(xy 186.856674 -27.755017) (xy 186.807183 -27.738916) (xy 186.760814 -27.715283) (xy 186.718704 -27.684699)
			(xy 186.699906 -27.666696) (xy 185.6486 -26.615136) (xy 185.644684 -26.611386) (xy 185.63559 -26.60549)
			(xy 185.630566 -26.603452) (xy 185.620055 -26.600102) (xy 185.598072 -26.601682) (xy 185.588148 -26.6065)
			(xy 185.584084 -26.608786) (xy 185.570684 -26.618609) (xy 185.550572 -26.645027) (xy 185.540024 -26.67651)
			(xy 185.53938 -26.693114) (xy 185.53938 -27.342846) (xy 185.53889 -27.37283) (xy 185.531062 -27.432286)
			(xy 185.515541 -27.490211) (xy 185.492592 -27.545615) (xy 185.462608 -27.597549) (xy 185.426102 -27.645125)
			(xy 185.383697 -27.68753) (xy 185.336121 -27.724036) (xy 185.284187 -27.75402) (xy 185.228783 -27.776969)
			(xy 185.170858 -27.79249) (xy 185.111402 -27.800318) (xy 185.051434 -27.800318) (xy 184.991978 -27.79249)
			(xy 184.934053 -27.776969) (xy 184.878649 -27.75402) (xy 184.826715 -27.724036) (xy 184.779139 -27.68753)
			(xy 184.736734 -27.645125) (xy 184.700228 -27.597549) (xy 184.670244 -27.545615) (xy 184.647295 -27.490211)
			(xy 184.631774 -27.432286) (xy 184.623946 -27.37283) (xy 184.623456 -27.342846) (xy 184.623456 -26.479246)
			(xy 184.623987 -26.448026) (xy 184.632471 -26.386166) (xy 184.649274 -26.32603) (xy 184.674085 -26.268732)
			(xy 184.706445 -26.215333) (xy 184.745754 -26.16682) (xy 184.791285 -26.124094) (xy 184.842195 -26.087943)
			(xy 184.897541 -26.059039) (xy 184.926732 -26.047954) (xy 184.937146 -26.044144) (xy 184.952386 -26.029412)
			(xy 184.955688 -26.025602) (xy 184.958768 -26.021652) (xy 184.96351 -26.01283) (xy 184.965086 -26.008076)
			(xy 184.96788 -25.99563) (xy 184.96788 -25.995122) (xy 184.973468 -25.970992) (xy 184.974741 -25.961252)
			(xy 184.970696 -25.942047) (xy 184.965594 -25.933654) (xy 184.963562 -25.93086) (xy 184.959498 -25.926288)
			(xy 184.770014 -25.736804) (xy 184.767163 -25.734099) (xy 184.760784 -25.729507) (xy 184.757314 -25.72766)
			(xy 184.751887 -25.725079) (xy 184.740207 -25.722262) (xy 184.7342 -25.722072) (xy 182.47995 -25.722072)
			(xy 182.474108 -25.72512) (xy 182.46852 -25.727914) (xy 182.441019 -25.741684) (xy 182.382683 -25.761153)
			(xy 182.321978 -25.771009) (xy 182.291228 -25.771602) (xy 182.263974 -25.771141) (xy 182.21002 -25.763387)
			(xy 182.15772 -25.748033) (xy 182.108136 -25.725392) (xy 182.06228 -25.695925) (xy 182.021085 -25.660231)
			(xy 181.985388 -25.619038) (xy 181.955918 -25.573183) (xy 181.933275 -25.523601) (xy 181.917918 -25.471301)
			(xy 181.910161 -25.417348) (xy 181.90972 -25.390094) (xy 181.910208 -25.362163) (xy 181.918353 -25.306898)
			(xy 181.93447 -25.253411) (xy 181.958212 -25.202845) (xy 181.989073 -25.156282) (xy 182.026394 -25.114715)
			(xy 182.069376 -25.079035) (xy 182.117101 -25.050002) (xy 182.16855 -25.028238) (xy 182.19547 -25.020778)
			(xy 182.202328 -25.019) (xy 182.209186 -25.014936) (xy 182.219092 -25.007316) (xy 182.22722 -24.999188)
			(xy 182.235133 -24.990342) (xy 182.242546 -24.967826) (xy 182.241444 -24.956008) (xy 181.889654 -24.604218)
			(xy 181.864506 -24.578277) (xy 181.820087 -24.521292) (xy 181.783003 -24.459284) (xy 181.753816 -24.39319)
			(xy 181.732968 -24.324011) (xy 181.726332 -24.288496) (xy 181.722268 -24.263858) (xy 181.718215 -24.260147)
			(xy 181.708864 -24.254377) (xy 181.703726 -24.252428) (xy 181.63667 -24.231092) (xy 181.636162 -24.231092)
			(xy 181.62397 -24.227282) (xy 181.615334 -24.225504) (xy 181.60873 -24.224996) (xy 181.603142 -24.224996)
			(xy 181.593998 -24.228806) (xy 181.589431 -24.230808) (xy 181.581108 -24.236299) (xy 181.577488 -24.239728)
			(xy 181.392576 -24.42464) (xy 181.373805 -24.442672) (xy 181.331688 -24.47325) (xy 181.285312 -24.496873)
			(xy 181.235814 -24.512962) (xy 181.184411 -24.521122) (xy 181.158388 -24.521668) (xy 179.970176 -24.521668)
			(xy 179.965858 -24.523954) (xy 179.937433 -24.538872) (xy 179.876832 -24.560039) (xy 179.813549 -24.570794)
			(xy 179.781454 -24.571452) (xy 179.780946 -24.571452) (xy 179.753688 -24.570992) (xy 179.699726 -24.56324)
			(xy 179.647416 -24.547886) (xy 179.597824 -24.525243) (xy 179.55196 -24.495773) (xy 179.510757 -24.460075)
			(xy 179.475055 -24.418877) (xy 179.445579 -24.373016) (xy 179.42293 -24.323427) (xy 179.40757 -24.271119)
			(xy 179.399811 -24.217158) (xy 179.399811 -24.162642) (xy 179.40757 -24.108681) (xy 179.42293 -24.056373)
			(xy 179.445579 -24.006784) (xy 179.475055 -23.960923) (xy 179.510757 -23.919725) (xy 179.55196 -23.884027)
			(xy 179.597825 -23.854557) (xy 179.647416 -23.831914) (xy 179.699726 -23.81656) (xy 179.753688 -23.808808)
			(xy 179.780946 -23.808436) (xy 179.7812 -23.808436) (xy 179.805448 -23.808829) (xy 179.853551 -23.814996)
			(xy 179.900488 -23.827193) (xy 179.945508 -23.845224) (xy 179.966874 -23.856696) (xy 179.969668 -23.85822)
			(xy 180.999384 -23.85822) (xy 181.002686 -23.85822) (xy 181.011704 -23.857268) (xy 181.028233 -23.849841)
			(xy 181.034944 -23.843742) (xy 181.114954 -23.763478) (xy 181.15407 -23.724362) (xy 181.154324 -23.710646)
			(xy 181.152292 -23.701756) (xy 181.142894 -23.673562) (xy 181.142894 -23.673054) (xy 181.121558 -23.603712)
			(xy 181.114192 -23.597108) (xy 181.089554 -23.59279) (xy 181.056707 -23.586392) (xy 180.992636 -23.567073)
			(xy 180.931184 -23.540575) (xy 180.873153 -23.507245) (xy 180.8193 -23.467517) (xy 180.770327 -23.421909)
			(xy 180.726872 -23.371016) (xy 180.689502 -23.315501) (xy 180.658703 -23.256088) (xy 180.646324 -23.224998)
			(xy 180.637942 -23.203154) (xy 180.633908 -23.200575) (xy 180.625082 -23.196864) (xy 180.620416 -23.195788)
			(xy 180.57114 -23.185374) (xy 180.570632 -23.185374) (xy 180.534818 -23.177754) (xy 180.520594 -23.178008)
			(xy 180.258974 -23.439628) (xy 180.235388 -23.462565) (xy 180.18395 -23.50359) (xy 180.128243 -23.538598)
			(xy 180.068966 -23.567149) (xy 180.006866 -23.588883) (xy 179.942723 -23.603529) (xy 179.877343 -23.6109)
			(xy 179.844446 -23.611332) (xy 179.809015 -23.610821) (xy 179.738668 -23.602285) (xy 179.669864 -23.585331)
			(xy 179.603605 -23.560207) (xy 179.540858 -23.527279) (xy 179.482537 -23.487027) (xy 179.429494 -23.440039)
			(xy 179.382501 -23.386999) (xy 179.342245 -23.328682) (xy 179.309312 -23.265937) (xy 179.284183 -23.19968)
			(xy 179.267224 -23.130877) (xy 179.258682 -23.060531) (xy 179.258214 -23.0251) (xy 179.258658 -22.992203)
			(xy 179.266025 -22.926823) (xy 179.280667 -22.862679) (xy 179.302398 -22.800578) (xy 179.330947 -22.741301)
			(xy 179.365954 -22.685593) (xy 179.406978 -22.634155) (xy 179.429918 -22.610572) (xy 179.922678 -22.117812)
			(xy 179.946253 -22.094863) (xy 179.997692 -22.053839) (xy 180.053401 -22.018832) (xy 180.11268 -21.990284)
			(xy 180.174782 -21.968553) (xy 180.238927 -21.953912) (xy 180.304309 -21.946545) (xy 180.337206 -21.946108)
			(xy 180.358542 -21.946616) (xy 184.16905 -21.946616) (xy 184.170574 -21.94433) (xy 184.17159 -21.942806)
			(xy 184.20207 -21.892514) (xy 184.20207 -21.892006) (xy 184.217564 -21.866098) (xy 184.22239 -21.85416)
			(xy 184.223914 -21.842476) (xy 184.224168 -21.830792) (xy 184.21858 -21.818854) (xy 184.218072 -21.817838)
			(xy 184.204173 -21.790282) (xy 184.18449 -21.731792) (xy 184.174491 -21.670894) (xy 184.173876 -21.640038)
			(xy 184.173876 -21.63572) (xy 184.174644 -21.607318) (xy 184.183557 -21.551206) (xy 184.200696 -21.497037)
			(xy 184.225682 -21.446011) (xy 184.257963 -21.399256) (xy 184.277 -21.378164) (xy 184.283858 -21.371052)
			(xy 184.287414 -21.362162) (xy 184.289954 -21.353018) (xy 184.290716 -21.344128) (xy 184.290716 -21.27377)
			(xy 184.290652 -21.269636) (xy 184.289383 -21.261468) (xy 184.288176 -21.257514) (xy 184.287414 -21.255736)
			(xy 184.284112 -21.2471) (xy 184.277 -21.23948) (xy 184.257729 -21.218153) (xy 184.225162 -21.170789)
			(xy 184.200069 -21.119076) (xy 184.183017 -21.064184) (xy 184.174392 -21.007356) (xy 184.17439 -20.949876)
			(xy 184.18301 -20.893047) (xy 184.200057 -20.838154) (xy 184.225146 -20.786439) (xy 184.257708 -20.739072)
			(xy 184.277 -20.717764) (xy 184.284112 -20.710144) (xy 184.287414 -20.701508) (xy 184.288176 -20.69973)
			(xy 184.289409 -20.695782) (xy 184.290687 -20.68761) (xy 184.290716 -20.683474) (xy 184.290716 -20.61337)
			(xy 184.290652 -20.609236) (xy 184.289383 -20.601068) (xy 184.288176 -20.597114) (xy 184.287414 -20.595336)
			(xy 184.284112 -20.5867) (xy 184.277 -20.57908) (xy 184.257729 -20.557753) (xy 184.225162 -20.510389)
			(xy 184.200069 -20.458676) (xy 184.183017 -20.403784) (xy 184.174392 -20.346956) (xy 184.17439 -20.289476)
			(xy 184.18301 -20.232647) (xy 184.200057 -20.177754) (xy 184.225146 -20.126039) (xy 184.257708 -20.078672)
			(xy 184.277 -20.057364) (xy 184.284112 -20.049744) (xy 184.287414 -20.041108) (xy 184.288176 -20.03933)
			(xy 184.289409 -20.035382) (xy 184.290687 -20.02721) (xy 184.290716 -20.023074) (xy 184.290716 -19.95297)
			(xy 184.290652 -19.948836) (xy 184.289383 -19.940668) (xy 184.288176 -19.936714) (xy 184.287414 -19.934936)
			(xy 184.284112 -19.9263) (xy 184.277 -19.91868) (xy 184.257729 -19.897353) (xy 184.225162 -19.849989)
			(xy 184.200069 -19.798276) (xy 184.183017 -19.743384) (xy 184.174392 -19.686556) (xy 184.17439 -19.629076)
			(xy 184.18301 -19.572247) (xy 184.200057 -19.517354) (xy 184.225146 -19.465639) (xy 184.257708 -19.418272)
			(xy 184.277 -19.396964) (xy 184.284112 -19.389344) (xy 184.287414 -19.380708) (xy 184.288176 -19.37893)
			(xy 184.289409 -19.374982) (xy 184.290687 -19.36681) (xy 184.290716 -19.362674) (xy 184.290716 -19.29257)
			(xy 184.290652 -19.288436) (xy 184.289383 -19.280268) (xy 184.288176 -19.276314) (xy 184.287414 -19.274536)
			(xy 184.284112 -19.2659) (xy 184.277 -19.25828) (xy 184.257729 -19.236953) (xy 184.225163 -19.189591)
			(xy 184.20007 -19.137879) (xy 184.183018 -19.082988) (xy 184.174393 -19.026161) (xy 184.173876 -18.997422)
			(xy 184.174362 -18.970171) (xy 184.182118 -18.916223) (xy 184.197473 -18.863928) (xy 184.220115 -18.814351)
			(xy 184.249581 -18.768501) (xy 184.285272 -18.72731) (xy 184.326463 -18.691619) (xy 184.372313 -18.662153)
			(xy 184.42189 -18.639511) (xy 184.474185 -18.624156) (xy 184.528133 -18.6164) (xy 184.582635 -18.6164)
			(xy 184.636583 -18.624156) (xy 184.688878 -18.639511) (xy 184.738455 -18.662153) (xy 184.784305 -18.691619)
			(xy 184.825496 -18.72731) (xy 184.861187 -18.768501) (xy 184.890653 -18.814351) (xy 184.913295 -18.863928)
			(xy 184.92865 -18.916223) (xy 184.936406 -18.970171) (xy 184.936892 -18.997422) (xy 184.936369 -19.02616)
			(xy 184.927744 -19.082986) (xy 184.910691 -19.137875) (xy 184.885597 -19.189585) (xy 184.853029 -19.236945)
			(xy 184.833768 -19.25828) (xy 184.826656 -19.2659) (xy 184.823354 -19.274536) (xy 184.822592 -19.276314)
			(xy 184.821363 -19.280263) (xy 184.820093 -19.288434) (xy 184.820052 -19.29257) (xy 184.820052 -19.362674)
			(xy 184.820119 -19.366807) (xy 184.821394 -19.374974) (xy 184.822592 -19.37893) (xy 184.823354 -19.380708)
			(xy 184.826656 -19.389344) (xy 184.833768 -19.396964) (xy 184.853038 -19.418291) (xy 184.8856 -19.465652)
			(xy 184.910689 -19.517363) (xy 184.927737 -19.572252) (xy 184.936357 -19.629078) (xy 184.936354 -19.686554)
			(xy 184.927729 -19.743379) (xy 184.910677 -19.798267) (xy 184.885584 -19.849975) (xy 184.853017 -19.897334)
			(xy 184.833768 -19.91868) (xy 184.826656 -19.9263) (xy 184.823354 -19.934936) (xy 184.822592 -19.936714)
			(xy 184.821363 -19.940663) (xy 184.820093 -19.948834) (xy 184.820052 -19.95297) (xy 184.820052 -20.023074)
			(xy 184.820119 -20.027207) (xy 184.821394 -20.035374) (xy 184.822592 -20.03933) (xy 184.823354 -20.041108)
			(xy 184.826656 -20.049744) (xy 184.833768 -20.057364) (xy 184.853038 -20.078691) (xy 184.8856 -20.126052)
			(xy 184.910689 -20.177763) (xy 184.927737 -20.232652) (xy 184.936357 -20.289478) (xy 184.936354 -20.346954)
			(xy 184.927729 -20.403779) (xy 184.910677 -20.458667) (xy 184.885584 -20.510375) (xy 184.853017 -20.557734)
			(xy 184.833768 -20.57908) (xy 184.826656 -20.5867) (xy 184.823354 -20.595336) (xy 184.822592 -20.597114)
			(xy 184.821363 -20.601063) (xy 184.820093 -20.609234) (xy 184.820052 -20.61337) (xy 184.820052 -20.683474)
			(xy 184.820119 -20.687607) (xy 184.821394 -20.695774) (xy 184.822592 -20.69973) (xy 184.823354 -20.701508)
			(xy 184.826656 -20.710144) (xy 184.833768 -20.717764) (xy 184.853038 -20.739091) (xy 184.8856 -20.786452)
			(xy 184.910689 -20.838163) (xy 184.927737 -20.893052) (xy 184.936357 -20.949878) (xy 184.936354 -21.007354)
			(xy 184.927729 -21.064179) (xy 184.910677 -21.119067) (xy 184.885584 -21.170775) (xy 184.853017 -21.218134)
			(xy 184.833768 -21.23948) (xy 184.826656 -21.2471) (xy 184.823354 -21.255736) (xy 184.822592 -21.257514)
			(xy 184.821363 -21.261463) (xy 184.820093 -21.269634) (xy 184.820052 -21.27377) (xy 184.820052 -21.344128)
			(xy 184.820814 -21.353018) (xy 184.823354 -21.362162) (xy 184.82691 -21.371052) (xy 184.834276 -21.378672)
			(xy 184.853218 -21.399719) (xy 184.885314 -21.446367) (xy 184.910163 -21.497246) (xy 184.927219 -21.55124)
			(xy 184.936106 -21.607161) (xy 184.936892 -21.635466) (xy 184.936892 -21.63953) (xy 184.936292 -21.67047)
			(xy 184.926315 -21.731541) (xy 184.906628 -21.790206) (xy 184.892696 -21.817838) (xy 184.891172 -21.820632)
			(xy 184.889049 -21.825769) (xy 184.886862 -21.836664) (xy 184.886854 -21.842222) (xy 184.887108 -21.855684)
			(xy 184.908698 -21.892006) (xy 184.908698 -21.892514) (xy 184.939178 -21.942552) (xy 184.941972 -21.946616)
			(xy 189.366906 -21.946616) (xy 189.37224 -21.946362) (xy 189.380868 -21.945095) (xy 189.396582 -21.937562)
			(xy 189.402974 -21.93163) (xy 189.714632 -21.619718) (xy 189.721316 -21.612308) (xy 189.728899 -21.593872)
			(xy 189.729364 -21.583904) (xy 189.729364 -21.567902) (xy 189.726316 -21.555964) (xy 189.723522 -21.55063)
			(xy 189.709526 -21.523008) (xy 189.689666 -21.464361) (xy 189.679512 -21.40328) (xy 189.678818 -21.372322)
			(xy 189.678818 -21.36394) (xy 189.679813 -21.337044) (xy 189.688433 -21.283919) (xy 189.704434 -21.232533)
			(xy 189.7275 -21.183906) (xy 189.757171 -21.139003) (xy 189.79286 -21.098718) (xy 189.833856 -21.063848)
			(xy 189.879347 -21.035087) (xy 189.928429 -21.013006) (xy 189.980128 -20.998044) (xy 190.033416 -20.990496)
			(xy 190.060326 -20.990052) (xy 190.06058 -20.990052) (xy 190.076582 -20.990306) (xy 190.08725 -20.990814)
			(xy 190.096394 -20.987258) (xy 190.100757 -20.985504) (xy 190.108805 -20.980642) (xy 190.112396 -20.977606)
			(xy 190.126112 -20.964652) (xy 190.12662 -20.964144) (xy 190.16853 -20.923758) (xy 190.17234 -20.919186)
			(xy 190.17234 -19.452844) (xy 190.172888 -19.417114) (xy 190.181608 -19.346187) (xy 190.198888 -19.276846)
			(xy 190.22447 -19.210121) (xy 190.257977 -19.147002) (xy 190.298909 -19.088425) (xy 190.34666 -19.03526)
			(xy 190.373254 -19.011392) (xy 190.389764 -18.997168) (xy 190.390272 -18.991326) (xy 190.39078 -18.971514)
			(xy 190.39205 -18.922238) (xy 190.39205 -18.92046) (xy 190.392558 -18.906744) (xy 190.359538 -18.873978)
			(xy 190.344044 -18.858738) (xy 190.317335 -18.831163) (xy 190.270623 -18.770238) (xy 190.232272 -18.703733)
			(xy 190.217044 -18.668492) (xy 190.203015 -18.633085) (xy 190.183196 -18.55955) (xy 190.173079 -18.484066)
			(xy 190.17234 -18.445988) (xy 190.17234 -18.44421) (xy 190.172853 -18.408796) (xy 190.181389 -18.338484)
			(xy 190.198339 -18.269714) (xy 190.223455 -18.203488) (xy 190.25637 -18.140773) (xy 190.296605 -18.082483)
			(xy 190.343573 -18.029467) (xy 190.396589 -17.9825) (xy 190.45488 -17.942266) (xy 190.517596 -17.909351)
			(xy 190.583822 -17.884237) (xy 190.652592 -17.867288) (xy 190.722904 -17.858753) (xy 190.758318 -17.858232)
			(xy 190.767716 -17.858232) (xy 190.80451 -17.859433) (xy 190.877384 -17.869883) (xy 190.94838 -17.889363)
			(xy 190.9826 -17.902936) (xy 191.017828 -17.91819) (xy 191.084326 -17.956545) (xy 191.145251 -18.003249)
			(xy 191.172846 -18.029936) (xy 191.503554 -18.360898) (xy 191.741298 -18.598642) (xy 191.764198 -18.622205)
			(xy 191.805155 -18.673587) (xy 191.840107 -18.729229) (xy 191.868613 -18.788432) (xy 191.890316 -18.850453)
			(xy 191.904943 -18.914513) (xy 191.91231 -18.979808) (xy 191.912748 -19.012662) (xy 191.912748 -21.474684)
			(xy 191.915678 -21.478429) (xy 191.922712 -21.484823) (xy 191.926718 -21.487384) (xy 191.93256 -21.49094)
			(xy 192.019936 -21.527516) (xy 192.026552 -21.530031) (xy 192.0406 -21.531708) (xy 192.047622 -21.530818)
			(xy 192.636902 -20.941538) (xy 192.637408 -20.937744) (xy 192.637411 -20.930091) (xy 192.636902 -20.926298)
			(xy 192.636902 -20.925536) (xy 192.631568 -20.892516) (xy 192.623694 -20.842986) (xy 192.62086 -20.831917)
			(xy 192.60698 -20.813794) (xy 192.597024 -20.808188) (xy 192.590166 -20.804632) (xy 192.564393 -20.790258)
			(xy 192.517222 -20.754803) (xy 192.476064 -20.712516) (xy 192.441898 -20.664403) (xy 192.415537 -20.611608)
			(xy 192.397608 -20.555388) (xy 192.388538 -20.497079) (xy 192.387982 -20.467574) (xy 192.38847 -20.440324)
			(xy 192.396229 -20.386378) (xy 192.411586 -20.334086) (xy 192.434229 -20.284511) (xy 192.463696 -20.238664)
			(xy 192.499387 -20.197476) (xy 192.540576 -20.161786) (xy 192.586426 -20.132321) (xy 192.636001 -20.109681)
			(xy 192.688294 -20.094326) (xy 192.74224 -20.086568) (xy 192.76949 -20.086066) (xy 192.796639 -20.086544)
			(xy 192.850388 -20.09424) (xy 192.902502 -20.109479) (xy 192.951931 -20.131952) (xy 192.997673 -20.161206)
			(xy 193.038807 -20.196649) (xy 193.0745 -20.237566) (xy 193.104031 -20.28313) (xy 193.126805 -20.33242)
			(xy 193.142361 -20.384442) (xy 193.150384 -20.438143) (xy 193.150998 -20.465288) (xy 193.150998 -20.467828)
			(xy 193.150401 -20.498333) (xy 193.14071 -20.558568) (xy 193.131694 -20.587716) (xy 193.13017 -20.592288)
			(xy 193.1289 -20.601432) (xy 193.1289 -20.601686) (xy 193.127376 -20.611338) (xy 193.130424 -20.623276)
			(xy 193.131534 -20.626967) (xy 193.134719 -20.633985) (xy 193.136774 -20.637246) (xy 193.14668 -20.65147)
			(xy 193.147188 -20.651978) (xy 193.166238 -20.678394) (xy 193.173315 -20.687225) (xy 193.193097 -20.698154)
			(xy 193.204338 -20.699476) (xy 194.750436 -20.699476) (xy 194.783291 -20.699933) (xy 194.848589 -20.707282)
			(xy 194.912653 -20.721897) (xy 194.921896 -20.72513) (xy 199.280538 -20.72513) (xy 199.284508 -20.594996)
			(xy 199.296404 -20.465346) (xy 199.316183 -20.336663) (xy 199.343769 -20.209424) (xy 199.379062 -20.084105)
			(xy 199.421928 -19.961169) (xy 199.47221 -19.841076) (xy 199.529719 -19.724272) (xy 199.594243 -19.61119)
			(xy 199.66554 -19.502253) (xy 199.743345 -19.397865) (xy 199.82737 -19.298414) (xy 199.917302 -19.204271)
			(xy 200.012806 -19.115786) (xy 200.113526 -19.033287) (xy 200.219088 -18.957082) (xy 200.3291 -18.887455)
			(xy 200.443152 -18.824664) (xy 200.56082 -18.768942) (xy 200.681666 -18.720498) (xy 200.805241 -18.679511)
			(xy 200.931084 -18.646134) (xy 201.058729 -18.620491) (xy 201.187699 -18.602677) (xy 201.317515 -18.592759)
			(xy 201.447694 -18.590774) (xy 201.577753 -18.596728) (xy 201.707206 -18.610601) (xy 201.835573 -18.632339)
			(xy 201.962376 -18.661863) (xy 202.087143 -18.699062) (xy 202.20941 -18.743798) (xy 202.328723 -18.795906)
			(xy 202.444636 -18.855189) (xy 202.556721 -18.92143) (xy 202.664558 -18.99438) (xy 202.767747 -19.073768)
			(xy 202.865905 -19.1593) (xy 202.958666 -19.250657) (xy 203.045685 -19.347499) (xy 203.126638 -19.449466)
			(xy 203.201224 -19.556178) (xy 203.269165 -19.667239) (xy 203.33021 -19.782235) (xy 203.384131 -19.900739)
			(xy 203.430726 -20.02231) (xy 203.469824 -20.146495) (xy 203.501278 -20.272833) (xy 203.524972 -20.400854)
			(xy 203.540816 -20.53008) (xy 203.548754 -20.660033) (xy 203.54925 -20.72513) (xy 203.548754 -20.790227)
			(xy 203.540816 -20.92018) (xy 203.524972 -21.049406) (xy 203.501278 -21.177427) (xy 203.469824 -21.303765)
			(xy 203.430726 -21.42795) (xy 203.384131 -21.549521) (xy 203.33021 -21.668025) (xy 203.269165 -21.783021)
			(xy 203.201224 -21.894082) (xy 203.126638 -22.000794) (xy 203.045685 -22.102761) (xy 202.958666 -22.199603)
			(xy 202.865905 -22.29096) (xy 202.767747 -22.376492) (xy 202.664558 -22.45588) (xy 202.556721 -22.52883)
			(xy 202.444636 -22.595071) (xy 202.328723 -22.654354) (xy 202.20941 -22.706462) (xy 202.087143 -22.751198)
			(xy 201.962376 -22.788397) (xy 201.835573 -22.817921) (xy 201.707206 -22.839659) (xy 201.577753 -22.853532)
			(xy 201.447694 -22.859486) (xy 201.317515 -22.857501) (xy 201.187699 -22.847583) (xy 201.058729 -22.829769)
			(xy 200.931084 -22.804126) (xy 200.805241 -22.770749) (xy 200.681666 -22.729762) (xy 200.56082 -22.681318)
			(xy 200.443152 -22.625596) (xy 200.3291 -22.562805) (xy 200.219088 -22.493178) (xy 200.113526 -22.416973)
			(xy 200.012806 -22.334474) (xy 199.917302 -22.245989) (xy 199.82737 -22.151846) (xy 199.743345 -22.052395)
			(xy 199.66554 -21.948007) (xy 199.594243 -21.83907) (xy 199.529719 -21.725988) (xy 199.47221 -21.609184)
			(xy 199.421928 -21.489091) (xy 199.379062 -21.366155) (xy 199.343769 -21.240836) (xy 199.316183 -21.113597)
			(xy 199.296404 -20.984914) (xy 199.284508 -20.855264) (xy 199.280538 -20.72513) (xy 194.921896 -20.72513)
			(xy 194.974679 -20.743592) (xy 195.033885 -20.772095) (xy 195.089528 -20.807047) (xy 195.140908 -20.84801)
			(xy 195.164456 -20.870926) (xy 195.568824 -21.275294) (xy 195.73494 -21.441156) (xy 195.757887 -21.46471)
			(xy 195.798911 -21.516108) (xy 195.833917 -21.571778) (xy 195.862465 -21.631021) (xy 195.884196 -21.693089)
			(xy 195.898836 -21.7572) (xy 195.906201 -21.822549) (xy 195.906531 -21.847048) (xy 196.172834 -21.847048)
			(xy 196.176905 -21.791426) (xy 196.189031 -21.736989) (xy 196.208954 -21.684898) (xy 196.23625 -21.636263)
			(xy 196.270336 -21.59212) (xy 196.310485 -21.553411) (xy 196.355843 -21.52096) (xy 196.405443 -21.495459)
			(xy 196.458227 -21.477452) (xy 196.51307 -21.467322) (xy 196.568804 -21.465285) (xy 196.624241 -21.471385)
			(xy 196.678198 -21.485491) (xy 196.729527 -21.507303) (xy 196.777133 -21.536357) (xy 196.820001 -21.572032)
			(xy 196.857218 -21.613569) (xy 196.887991 -21.660082) (xy 196.911663 -21.710579) (xy 196.927731 -21.763986)
			(xy 196.935851 -21.819162) (xy 196.93636 -21.847048) (xy 196.935851 -21.874934) (xy 196.927731 -21.93011)
			(xy 196.911663 -21.983517) (xy 196.887991 -22.034014) (xy 196.857218 -22.080527) (xy 196.820001 -22.122064)
			(xy 196.777133 -22.157739) (xy 196.729527 -22.186793) (xy 196.678198 -22.208605) (xy 196.624241 -22.222711)
			(xy 196.568804 -22.228811) (xy 196.51307 -22.226774) (xy 196.458227 -22.216644) (xy 196.405443 -22.198637)
			(xy 196.355843 -22.173136) (xy 196.310485 -22.140685) (xy 196.270336 -22.101976) (xy 196.23625 -22.057833)
			(xy 196.208954 -22.009198) (xy 196.189031 -21.957107) (xy 196.176905 -21.90267) (xy 196.172834 -21.847048)
			(xy 195.906531 -21.847048) (xy 195.906644 -21.85543) (xy 195.906644 -21.869908) (xy 195.90639 -21.87575)
			(xy 195.904701 -21.910353) (xy 195.894187 -21.978832) (xy 195.875667 -22.045591) (xy 195.8494 -22.1097)
			(xy 195.815752 -22.170261) (xy 195.775193 -22.226429) (xy 195.72829 -22.277418) (xy 195.675699 -22.322518)
			(xy 195.618153 -22.361097) (xy 195.556457 -22.392617) (xy 195.491474 -22.416637) (xy 195.42411 -22.432822)
			(xy 195.355307 -22.440946) (xy 195.320666 -22.441408) (xy 195.287793 -22.440978) (xy 195.222457 -22.433643)
			(xy 195.158355 -22.419035) (xy 195.096292 -22.397338) (xy 195.037051 -22.368826) (xy 194.981376 -22.333856)
			(xy 194.929969 -22.29287) (xy 194.906392 -22.269958) (xy 194.847718 -22.211284) (xy 194.841876 -22.210776)
			(xy 194.82943 -22.210776) (xy 194.823848 -22.21092) (xy 194.812951 -22.213354) (xy 194.80784 -22.215602)
			(xy 194.796664 -22.222714) (xy 194.79641 -22.222968) (xy 194.794886 -22.224238) (xy 194.768451 -22.24584)
			(xy 194.711444 -22.283405) (xy 194.650457 -22.314088) (xy 194.586317 -22.337474) (xy 194.519893 -22.353245)
			(xy 194.452085 -22.361187) (xy 194.41795 -22.361652) (xy 194.260978 -22.361652) (xy 194.252342 -22.369272)
			(xy 194.23253 -22.393656) (xy 194.19951 -22.43455) (xy 194.19697 -22.438614) (xy 194.19316 -22.447758)
			(xy 194.189096 -22.463506) (xy 194.191636 -22.474936) (xy 194.195483 -22.494203) (xy 194.199685 -22.533269)
			(xy 194.200018 -22.552914) (xy 194.200018 -22.553422) (xy 194.200018 -22.559264) (xy 194.199255 -22.586805)
			(xy 194.190781 -22.641245) (xy 194.174567 -22.693901) (xy 194.150949 -22.743677) (xy 194.120419 -22.78954)
			(xy 194.083611 -22.830537) (xy 194.041291 -22.865814) (xy 193.994337 -22.894639) (xy 193.943727 -22.916413)
			(xy 193.890511 -22.930683) (xy 193.863214 -22.934422) (xy 193.84899 -22.935946) (xy 193.815716 -22.937216)
			(xy 193.813684 -22.937216) (xy 193.788653 -22.936485) (xy 193.739098 -22.929267) (xy 193.690914 -22.915627)
			(xy 193.644929 -22.895799) (xy 193.601935 -22.870124) (xy 193.582036 -22.85492) (xy 193.565272 -22.84095)
			(xy 193.563748 -22.83968) (xy 193.56197 -22.838156) (xy 193.553842 -22.832822) (xy 193.543424 -22.827173)
			(xy 193.519839 -22.825171) (xy 193.50863 -22.829012) (xy 193.484754 -22.839426) (xy 193.484246 -22.839426)
			(xy 193.423286 -22.866604) (xy 193.421254 -22.86762) (xy 193.407538 -22.874478) (xy 193.402712 -22.882352)
			(xy 193.402712 -23.965154) (xy 194.17741 -23.965154) (xy 194.181481 -23.909532) (xy 194.193607 -23.855095)
			(xy 194.21353 -23.803004) (xy 194.240826 -23.754369) (xy 194.274912 -23.710226) (xy 194.315061 -23.671517)
			(xy 194.360419 -23.639066) (xy 194.410019 -23.613565) (xy 194.462803 -23.595558) (xy 194.517646 -23.585428)
			(xy 194.57338 -23.583391) (xy 194.628817 -23.589491) (xy 194.682774 -23.603597) (xy 194.734103 -23.625409)
			(xy 194.781709 -23.654463) (xy 194.824577 -23.690138) (xy 194.861794 -23.731675) (xy 194.892567 -23.778188)
			(xy 194.916239 -23.828685) (xy 194.932307 -23.882092) (xy 194.940427 -23.937268) (xy 194.940602 -23.946866)
			(xy 195.180456 -23.946866) (xy 195.184527 -23.891244) (xy 195.196653 -23.836807) (xy 195.216576 -23.784716)
			(xy 195.243872 -23.736081) (xy 195.277958 -23.691938) (xy 195.318107 -23.653229) (xy 195.363465 -23.620778)
			(xy 195.413065 -23.595277) (xy 195.465849 -23.57727) (xy 195.520692 -23.56714) (xy 195.576426 -23.565103)
			(xy 195.631863 -23.571203) (xy 195.68582 -23.585309) (xy 195.737149 -23.607121) (xy 195.784755 -23.636175)
			(xy 195.827623 -23.67185) (xy 195.86484 -23.713387) (xy 195.895613 -23.7599) (xy 195.919285 -23.810397)
			(xy 195.935353 -23.863804) (xy 195.943473 -23.91898) (xy 195.943982 -23.946866) (xy 195.943542 -23.970996)
			(xy 196.172834 -23.970996) (xy 196.176905 -23.915374) (xy 196.189031 -23.860937) (xy 196.208954 -23.808846)
			(xy 196.23625 -23.760211) (xy 196.270336 -23.716068) (xy 196.310485 -23.677359) (xy 196.355843 -23.644908)
			(xy 196.405443 -23.619407) (xy 196.458227 -23.6014) (xy 196.51307 -23.59127) (xy 196.568804 -23.589233)
			(xy 196.624241 -23.595333) (xy 196.678198 -23.609439) (xy 196.729527 -23.631251) (xy 196.777133 -23.660305)
			(xy 196.820001 -23.69598) (xy 196.857218 -23.737517) (xy 196.887991 -23.78403) (xy 196.911663 -23.834527)
			(xy 196.927731 -23.887934) (xy 196.935851 -23.94311) (xy 196.93636 -23.970996) (xy 196.935851 -23.998882)
			(xy 196.927731 -24.054058) (xy 196.911663 -24.107465) (xy 196.887991 -24.157962) (xy 196.857218 -24.204475)
			(xy 196.820001 -24.246012) (xy 196.777133 -24.281687) (xy 196.729527 -24.310741) (xy 196.678198 -24.332553)
			(xy 196.624241 -24.346659) (xy 196.568804 -24.352759) (xy 196.51307 -24.350722) (xy 196.458227 -24.340592)
			(xy 196.405443 -24.322585) (xy 196.355843 -24.297084) (xy 196.310485 -24.264633) (xy 196.270336 -24.225924)
			(xy 196.23625 -24.181781) (xy 196.208954 -24.133146) (xy 196.189031 -24.081055) (xy 196.176905 -24.026618)
			(xy 196.172834 -23.970996) (xy 195.943542 -23.970996) (xy 195.943473 -23.974752) (xy 195.935353 -24.029928)
			(xy 195.919285 -24.083335) (xy 195.895613 -24.133832) (xy 195.86484 -24.180345) (xy 195.827623 -24.221882)
			(xy 195.784755 -24.257557) (xy 195.737149 -24.286611) (xy 195.68582 -24.308423) (xy 195.631863 -24.322529)
			(xy 195.576426 -24.328629) (xy 195.520692 -24.326592) (xy 195.465849 -24.316462) (xy 195.413065 -24.298455)
			(xy 195.363465 -24.272954) (xy 195.318107 -24.240503) (xy 195.277958 -24.201794) (xy 195.243872 -24.157651)
			(xy 195.216576 -24.109016) (xy 195.196653 -24.056925) (xy 195.184527 -24.002488) (xy 195.180456 -23.946866)
			(xy 194.940602 -23.946866) (xy 194.940936 -23.965154) (xy 194.940427 -23.99304) (xy 194.932307 -24.048216)
			(xy 194.916239 -24.101623) (xy 194.892567 -24.15212) (xy 194.861794 -24.198633) (xy 194.824577 -24.24017)
			(xy 194.781709 -24.275845) (xy 194.734103 -24.304899) (xy 194.682774 -24.326711) (xy 194.628817 -24.340817)
			(xy 194.57338 -24.346917) (xy 194.517646 -24.34488) (xy 194.462803 -24.33475) (xy 194.410019 -24.316743)
			(xy 194.360419 -24.291242) (xy 194.315061 -24.258791) (xy 194.274912 -24.220082) (xy 194.240826 -24.175939)
			(xy 194.21353 -24.127304) (xy 194.193607 -24.075213) (xy 194.181481 -24.020776) (xy 194.17741 -23.965154)
			(xy 193.402712 -23.965154) (xy 193.402712 -24.807418) (xy 200.471276 -24.807418) (xy 200.475347 -24.751796)
			(xy 200.487473 -24.697359) (xy 200.507396 -24.645268) (xy 200.534692 -24.596633) (xy 200.568778 -24.55249)
			(xy 200.608927 -24.513781) (xy 200.654285 -24.48133) (xy 200.703885 -24.455829) (xy 200.756669 -24.437822)
			(xy 200.811512 -24.427692) (xy 200.867246 -24.425655) (xy 200.922683 -24.431755) (xy 200.97664 -24.445861)
			(xy 201.027969 -24.467673) (xy 201.075575 -24.496727) (xy 201.118443 -24.532402) (xy 201.15566 -24.573939)
			(xy 201.186433 -24.620452) (xy 201.210105 -24.670949) (xy 201.226173 -24.724356) (xy 201.234293 -24.779532)
			(xy 201.234802 -24.807418) (xy 201.234293 -24.835304) (xy 201.226173 -24.89048) (xy 201.210105 -24.943887)
			(xy 201.186433 -24.994384) (xy 201.15566 -25.040897) (xy 201.118443 -25.082434) (xy 201.075575 -25.118109)
			(xy 201.027969 -25.147163) (xy 200.97664 -25.168975) (xy 200.922683 -25.183081) (xy 200.867246 -25.189181)
			(xy 200.811512 -25.187144) (xy 200.756669 -25.177014) (xy 200.703885 -25.159007) (xy 200.654285 -25.133506)
			(xy 200.608927 -25.101055) (xy 200.568778 -25.062346) (xy 200.534692 -25.018203) (xy 200.507396 -24.969568)
			(xy 200.487473 -24.917477) (xy 200.475347 -24.86304) (xy 200.471276 -24.807418) (xy 193.402712 -24.807418)
			(xy 193.402712 -25.92324) (xy 193.404744 -25.92705) (xy 193.409385 -25.93487) (xy 193.423049 -25.946851)
			(xy 193.431414 -25.950418) (xy 193.434208 -25.951434) (xy 193.438526 -25.952704) (xy 193.464084 -25.961152)
			(xy 193.512729 -25.984198) (xy 193.557683 -26.013804) (xy 193.580295 -26.03373) (xy 199.3679 -26.03373)
			(xy 199.371971 -25.978108) (xy 199.384097 -25.923671) (xy 199.40402 -25.87158) (xy 199.431316 -25.822945)
			(xy 199.465402 -25.778802) (xy 199.505551 -25.740093) (xy 199.550909 -25.707642) (xy 199.600509 -25.682141)
			(xy 199.653293 -25.664134) (xy 199.708136 -25.654004) (xy 199.76387 -25.651967) (xy 199.819307 -25.658067)
			(xy 199.873264 -25.672173) (xy 199.924593 -25.693985) (xy 199.972199 -25.723039) (xy 200.015067 -25.758714)
			(xy 200.052284 -25.800251) (xy 200.083057 -25.846764) (xy 200.106729 -25.897261) (xy 200.122797 -25.950668)
			(xy 200.130917 -26.005844) (xy 200.131426 -26.03373) (xy 200.130917 -26.061616) (xy 200.122797 -26.116792)
			(xy 200.106729 -26.170199) (xy 200.083057 -26.220696) (xy 200.052284 -26.267209) (xy 200.015067 -26.308746)
			(xy 199.972199 -26.344421) (xy 199.924593 -26.373475) (xy 199.873264 -26.395287) (xy 199.819307 -26.409393)
			(xy 199.76387 -26.415493) (xy 199.708136 -26.413456) (xy 199.653293 -26.403326) (xy 199.600509 -26.385319)
			(xy 199.550909 -26.359818) (xy 199.505551 -26.327367) (xy 199.465402 -26.288658) (xy 199.431316 -26.244515)
			(xy 199.40402 -26.19588) (xy 199.384097 -26.143789) (xy 199.371971 -26.089352) (xy 199.3679 -26.03373)
			(xy 193.580295 -26.03373) (xy 193.598069 -26.049392) (xy 193.633095 -26.090265) (xy 193.662077 -26.135624)
			(xy 193.684449 -26.184583) (xy 193.692526 -26.21026) (xy 193.693796 -26.214324) (xy 193.694558 -26.216864)
			(xy 193.697352 -26.22169) (xy 193.704972 -26.231342) (xy 194.842384 -27.368754) (xy 194.860418 -27.387524)
			(xy 194.891001 -27.429641) (xy 194.914631 -27.476016) (xy 194.930728 -27.525514) (xy 194.938897 -27.576918)
			(xy 194.939412 -27.602942) (xy 194.939412 -28.139136) (xy 196.497954 -28.139136) (xy 196.502025 -28.083514)
			(xy 196.514151 -28.029077) (xy 196.534074 -27.976986) (xy 196.56137 -27.928351) (xy 196.595456 -27.884208)
			(xy 196.635605 -27.845499) (xy 196.680963 -27.813048) (xy 196.730563 -27.787547) (xy 196.783347 -27.76954)
			(xy 196.83819 -27.75941) (xy 196.893924 -27.757373) (xy 196.949361 -27.763473) (xy 197.003318 -27.777579)
			(xy 197.054647 -27.799391) (xy 197.102253 -27.828445) (xy 197.145121 -27.86412) (xy 197.182338 -27.905657)
			(xy 197.213111 -27.95217) (xy 197.236783 -28.002667) (xy 197.252851 -28.056074) (xy 197.260971 -28.11125)
			(xy 197.26148 -28.139136) (xy 197.767954 -28.139136) (xy 197.772025 -28.083514) (xy 197.784151 -28.029077)
			(xy 197.804074 -27.976986) (xy 197.83137 -27.928351) (xy 197.865456 -27.884208) (xy 197.905605 -27.845499)
			(xy 197.950963 -27.813048) (xy 198.000563 -27.787547) (xy 198.053347 -27.76954) (xy 198.10819 -27.75941)
			(xy 198.163924 -27.757373) (xy 198.219361 -27.763473) (xy 198.273318 -27.777579) (xy 198.324647 -27.799391)
			(xy 198.372253 -27.828445) (xy 198.415121 -27.86412) (xy 198.452338 -27.905657) (xy 198.483111 -27.95217)
			(xy 198.506783 -28.002667) (xy 198.522851 -28.056074) (xy 198.530971 -28.11125) (xy 198.53148 -28.139136)
			(xy 198.530971 -28.167022) (xy 198.522851 -28.222198) (xy 198.506783 -28.275605) (xy 198.483111 -28.326102)
			(xy 198.452338 -28.372615) (xy 198.415121 -28.414152) (xy 198.372253 -28.449827) (xy 198.324647 -28.478881)
			(xy 198.273318 -28.500693) (xy 198.219361 -28.514799) (xy 198.163924 -28.520899) (xy 198.10819 -28.518862)
			(xy 198.053347 -28.508732) (xy 198.000563 -28.490725) (xy 197.950963 -28.465224) (xy 197.905605 -28.432773)
			(xy 197.865456 -28.394064) (xy 197.83137 -28.349921) (xy 197.804074 -28.301286) (xy 197.784151 -28.249195)
			(xy 197.772025 -28.194758) (xy 197.767954 -28.139136) (xy 197.26148 -28.139136) (xy 197.260971 -28.167022)
			(xy 197.252851 -28.222198) (xy 197.236783 -28.275605) (xy 197.213111 -28.326102) (xy 197.182338 -28.372615)
			(xy 197.145121 -28.414152) (xy 197.102253 -28.449827) (xy 197.054647 -28.478881) (xy 197.003318 -28.500693)
			(xy 196.949361 -28.514799) (xy 196.893924 -28.520899) (xy 196.83819 -28.518862) (xy 196.783347 -28.508732)
			(xy 196.730563 -28.490725) (xy 196.680963 -28.465224) (xy 196.635605 -28.432773) (xy 196.595456 -28.394064)
			(xy 196.56137 -28.349921) (xy 196.534074 -28.301286) (xy 196.514151 -28.249195) (xy 196.502025 -28.194758)
			(xy 196.497954 -28.139136) (xy 194.939412 -28.139136) (xy 194.939412 -29.301948) (xy 194.949064 -29.3116)
			(xy 194.953382 -29.314902) (xy 195.00342 -29.335984) (xy 195.003928 -29.335984) (xy 195.043044 -29.352748)
			(xy 195.051431 -29.355581) (xy 195.06912 -29.355836) (xy 195.077588 -29.353256) (xy 195.101718 -29.343096)
			(xy 195.108068 -29.337254) (xy 195.108576 -29.336746) (xy 195.129956 -29.317397) (xy 195.177445 -29.284691)
			(xy 195.229305 -29.259483) (xy 195.284361 -29.242343) (xy 195.341365 -29.233659) (xy 195.370196 -29.233114)
			(xy 195.37045 -29.233114) (xy 195.397718 -29.233604) (xy 195.451697 -29.241371) (xy 195.504022 -29.256741)
			(xy 195.553627 -29.279399) (xy 195.599504 -29.308886) (xy 195.640717 -29.344601) (xy 195.676429 -29.385817)
			(xy 195.705913 -29.431695) (xy 195.728569 -29.481302) (xy 195.743934 -29.533628) (xy 195.751698 -29.587608)
			(xy 195.752212 -29.614876) (xy 195.75171 -29.64304) (xy 195.743435 -29.698756) (xy 195.727063 -29.752652)
			(xy 195.702948 -29.803556) (xy 195.671614 -29.850364) (xy 195.633741 -29.892059) (xy 195.612258 -29.910278)
			(xy 195.60921 -29.913326) (xy 195.606325 -29.916328) (xy 195.601471 -29.92309) (xy 195.599558 -29.926788)
			(xy 195.592954 -29.94025) (xy 195.5927 -29.941012) (xy 195.59016 -29.946092) (xy 195.58635 -29.957268)
			(xy 195.585334 -29.967174) (xy 195.585334 -30.02407) (xy 195.585449 -30.029025) (xy 195.587361 -30.03875)
			(xy 195.589144 -30.043374) (xy 195.593208 -30.052264) (xy 195.600828 -30.067504) (xy 195.603622 -30.072076)
			(xy 195.60794 -30.077156) (xy 195.613274 -30.08249) (xy 195.615052 -30.084014) (xy 195.636081 -30.102251)
			(xy 195.67315 -30.143775) (xy 195.703797 -30.190241) (xy 195.727375 -30.240663) (xy 195.743382 -30.293975)
			(xy 195.751481 -30.349045) (xy 195.751958 -30.376876) (xy 195.751496 -30.404129) (xy 195.743742 -30.45808)
			(xy 195.728387 -30.510377) (xy 195.705746 -30.559957) (xy 195.676277 -30.60581) (xy 195.640583 -30.647001)
			(xy 195.599389 -30.682693) (xy 195.553535 -30.712158) (xy 195.503953 -30.734796) (xy 195.451654 -30.750147)
			(xy 195.397703 -30.757898) (xy 195.37045 -30.758384) (xy 195.340433 -30.757826) (xy 195.281139 -30.748426)
			(xy 195.224052 -30.72985) (xy 195.17058 -30.702558) (xy 195.122047 -30.667223) (xy 195.100448 -30.64637)
			(xy 195.092187 -30.639813) (xy 195.07212 -30.633392) (xy 195.061586 -30.633924) (xy 195.053966 -30.634686)
			(xy 195.003928 -30.655768) (xy 195.00342 -30.655768) (xy 194.95897 -30.674564) (xy 194.953272 -30.677377)
			(xy 194.943376 -30.685345) (xy 194.939412 -30.690312) (xy 194.939412 -31.567882) (xy 195.098668 -31.567882)
			(xy 195.102739 -31.51226) (xy 195.114865 -31.457823) (xy 195.134788 -31.405732) (xy 195.162084 -31.357097)
			(xy 195.19617 -31.312954) (xy 195.236319 -31.274245) (xy 195.281677 -31.241794) (xy 195.331277 -31.216293)
			(xy 195.384061 -31.198286) (xy 195.438904 -31.188156) (xy 195.494638 -31.186119) (xy 195.550075 -31.192219)
			(xy 195.604032 -31.206325) (xy 195.655361 -31.228137) (xy 195.702967 -31.257191) (xy 195.745835 -31.292866)
			(xy 195.783052 -31.334403) (xy 195.813825 -31.380916) (xy 195.837497 -31.431413) (xy 195.853565 -31.48482)
			(xy 195.861685 -31.539996) (xy 195.862194 -31.567882) (xy 195.861685 -31.595768) (xy 195.853565 -31.650944)
			(xy 195.837497 -31.704351) (xy 195.830505 -31.719266) (xy 196.385432 -31.719266) (xy 196.389503 -31.663644)
			(xy 196.401629 -31.609207) (xy 196.421552 -31.557116) (xy 196.448848 -31.508481) (xy 196.482934 -31.464338)
			(xy 196.523083 -31.425629) (xy 196.568441 -31.393178) (xy 196.618041 -31.367677) (xy 196.670825 -31.34967)
			(xy 196.725668 -31.33954) (xy 196.781402 -31.337503) (xy 196.836839 -31.343603) (xy 196.890796 -31.357709)
			(xy 196.942125 -31.379521) (xy 196.989731 -31.408575) (xy 197.032599 -31.44425) (xy 197.069816 -31.485787)
			(xy 197.100589 -31.5323) (xy 197.124261 -31.582797) (xy 197.140329 -31.636204) (xy 197.144479 -31.664402)
			(xy 197.66102 -31.664402) (xy 197.665091 -31.60878) (xy 197.677217 -31.554343) (xy 197.69714 -31.502252)
			(xy 197.724436 -31.453617) (xy 197.758522 -31.409474) (xy 197.798671 -31.370765) (xy 197.844029 -31.338314)
			(xy 197.893629 -31.312813) (xy 197.946413 -31.294806) (xy 198.001256 -31.284676) (xy 198.05699 -31.282639)
			(xy 198.112427 -31.288739) (xy 198.166384 -31.302845) (xy 198.217713 -31.324657) (xy 198.265319 -31.353711)
			(xy 198.308187 -31.389386) (xy 198.345404 -31.430923) (xy 198.376177 -31.477436) (xy 198.399849 -31.527933)
			(xy 198.415917 -31.58134) (xy 198.424037 -31.636516) (xy 198.424546 -31.664402) (xy 198.424037 -31.692288)
			(xy 198.415917 -31.747464) (xy 198.399849 -31.800871) (xy 198.376177 -31.851368) (xy 198.345404 -31.897881)
			(xy 198.308187 -31.939418) (xy 198.265319 -31.975093) (xy 198.217713 -32.004147) (xy 198.166384 -32.025959)
			(xy 198.112427 -32.040065) (xy 198.05699 -32.046165) (xy 198.001256 -32.044128) (xy 197.946413 -32.033998)
			(xy 197.893629 -32.015991) (xy 197.844029 -31.99049) (xy 197.798671 -31.958039) (xy 197.758522 -31.91933)
			(xy 197.724436 -31.875187) (xy 197.69714 -31.826552) (xy 197.677217 -31.774461) (xy 197.665091 -31.720024)
			(xy 197.66102 -31.664402) (xy 197.144479 -31.664402) (xy 197.148449 -31.69138) (xy 197.148958 -31.719266)
			(xy 197.148449 -31.747152) (xy 197.140329 -31.802328) (xy 197.124261 -31.855735) (xy 197.100589 -31.906232)
			(xy 197.069816 -31.952745) (xy 197.032599 -31.994282) (xy 196.989731 -32.029957) (xy 196.942125 -32.059011)
			(xy 196.890796 -32.080823) (xy 196.836839 -32.094929) (xy 196.781402 -32.101029) (xy 196.725668 -32.098992)
			(xy 196.670825 -32.088862) (xy 196.618041 -32.070855) (xy 196.568441 -32.045354) (xy 196.523083 -32.012903)
			(xy 196.482934 -31.974194) (xy 196.448848 -31.930051) (xy 196.421552 -31.881416) (xy 196.401629 -31.829325)
			(xy 196.389503 -31.774888) (xy 196.385432 -31.719266) (xy 195.830505 -31.719266) (xy 195.813825 -31.754848)
			(xy 195.783052 -31.801361) (xy 195.745835 -31.842898) (xy 195.702967 -31.878573) (xy 195.655361 -31.907627)
			(xy 195.604032 -31.929439) (xy 195.550075 -31.943545) (xy 195.494638 -31.949645) (xy 195.438904 -31.947608)
			(xy 195.384061 -31.937478) (xy 195.331277 -31.919471) (xy 195.281677 -31.89397) (xy 195.236319 -31.861519)
			(xy 195.19617 -31.82281) (xy 195.162084 -31.778667) (xy 195.134788 -31.730032) (xy 195.114865 -31.677941)
			(xy 195.102739 -31.623504) (xy 195.098668 -31.567882) (xy 194.939412 -31.567882) (xy 194.939412 -33.146492)
			(xy 194.939584 -33.1525) (xy 194.942417 -33.164178) (xy 194.945 -33.169606) (xy 194.946839 -33.173081)
			(xy 194.951431 -33.179461) (xy 194.954144 -33.182306) (xy 197.036807 -35.264852) (xy 198.002396 -35.264852)
			(xy 198.006467 -35.20923) (xy 198.018593 -35.154793) (xy 198.038516 -35.102702) (xy 198.065812 -35.054067)
			(xy 198.099898 -35.009924) (xy 198.140047 -34.971215) (xy 198.185405 -34.938764) (xy 198.235005 -34.913263)
			(xy 198.287789 -34.895256) (xy 198.342632 -34.885126) (xy 198.398366 -34.883089) (xy 198.453803 -34.889189)
			(xy 198.50776 -34.903295) (xy 198.559089 -34.925107) (xy 198.606695 -34.954161) (xy 198.649563 -34.989836)
			(xy 198.68678 -35.031373) (xy 198.717553 -35.077886) (xy 198.741225 -35.128383) (xy 198.757293 -35.18179)
			(xy 198.765413 -35.236966) (xy 198.765922 -35.264852) (xy 198.765413 -35.292738) (xy 198.757293 -35.347914)
			(xy 198.741225 -35.401321) (xy 198.717553 -35.451818) (xy 198.68678 -35.498331) (xy 198.649563 -35.539868)
			(xy 198.606695 -35.575543) (xy 198.559089 -35.604597) (xy 198.50776 -35.626409) (xy 198.453803 -35.640515)
			(xy 198.398366 -35.646615) (xy 198.342632 -35.644578) (xy 198.287789 -35.634448) (xy 198.235005 -35.616441)
			(xy 198.185405 -35.59094) (xy 198.140047 -35.558489) (xy 198.099898 -35.51978) (xy 198.065812 -35.475637)
			(xy 198.038516 -35.427002) (xy 198.018593 -35.374911) (xy 198.006467 -35.320474) (xy 198.002396 -35.264852)
			(xy 197.036807 -35.264852) (xy 198.05896 -36.286948) (xy 199.300336 -36.286948) (xy 199.304407 -36.231326)
			(xy 199.316533 -36.176889) (xy 199.336456 -36.124798) (xy 199.363752 -36.076163) (xy 199.397838 -36.03202)
			(xy 199.437987 -35.993311) (xy 199.483345 -35.96086) (xy 199.532945 -35.935359) (xy 199.585729 -35.917352)
			(xy 199.640572 -35.907222) (xy 199.696306 -35.905185) (xy 199.751743 -35.911285) (xy 199.8057 -35.925391)
			(xy 199.857029 -35.947203) (xy 199.904635 -35.976257) (xy 199.947503 -36.011932) (xy 199.98472 -36.053469)
			(xy 200.015493 -36.099982) (xy 200.039165 -36.150479) (xy 200.055233 -36.203886) (xy 200.063353 -36.259062)
			(xy 200.063862 -36.286948) (xy 200.063353 -36.314834) (xy 200.055233 -36.37001) (xy 200.039165 -36.423417)
			(xy 200.015493 -36.473914) (xy 199.98472 -36.520427) (xy 199.947503 -36.561964) (xy 199.904635 -36.597639)
			(xy 199.857029 -36.626693) (xy 199.8057 -36.648505) (xy 199.751743 -36.662611) (xy 199.696306 -36.668711)
			(xy 199.640572 -36.666674) (xy 199.585729 -36.656544) (xy 199.532945 -36.638537) (xy 199.483345 -36.613036)
			(xy 199.437987 -36.580585) (xy 199.397838 -36.541876) (xy 199.363752 -36.497733) (xy 199.336456 -36.449098)
			(xy 199.316533 -36.397007) (xy 199.304407 -36.34257) (xy 199.300336 -36.286948) (xy 198.05896 -36.286948)
			(xy 199.490076 -37.717984) (xy 199.497294 -37.72357) (xy 199.514479 -37.729676) (xy 199.523604 -37.729922)
			(xy 199.524366 -37.729922) (xy 199.53478 -37.729668) (xy 199.553322 -37.721032) (xy 199.555354 -37.719)
			(xy 199.56399 -37.709348) (xy 199.57034 -37.69995) (xy 199.573642 -37.6936) (xy 199.574658 -37.689536)
			(xy 199.575166 -37.686996) (xy 199.582184 -37.659442) (xy 199.603265 -37.606638) (xy 199.631945 -37.557544)
			(xy 199.667589 -37.513246) (xy 199.709408 -37.474725) (xy 199.756478 -37.442831) (xy 199.807757 -37.418272)
			(xy 199.862112 -37.401589) (xy 199.918339 -37.393151) (xy 199.946768 -37.39261) (xy 199.974022 -37.393071)
			(xy 200.027975 -37.400825) (xy 200.080276 -37.416178) (xy 200.129859 -37.438819) (xy 200.175715 -37.468286)
			(xy 200.21691 -37.50398) (xy 200.252605 -37.545174) (xy 200.282074 -37.591029) (xy 200.304717 -37.640611)
			(xy 200.320072 -37.692911) (xy 200.327828 -37.746864) (xy 200.328276 -37.774118) (xy 200.327751 -37.802546)
			(xy 200.319314 -37.858773) (xy 200.30263 -37.913126) (xy 200.278067 -37.964402) (xy 200.246169 -38.011468)
			(xy 200.207643 -38.053281) (xy 200.16334 -38.088916) (xy 200.114241 -38.117585) (xy 200.061432 -38.138653)
			(xy 200.03389 -38.14572) (xy 200.033636 -38.14572) (xy 200.026524 -38.147498) (xy 200.01611 -38.152832)
			(xy 200.009252 -38.158928) (xy 200.008998 -38.159182) (xy 200.002394 -38.165024) (xy 200.001886 -38.165532)
			(xy 199.992488 -38.173914) (xy 199.991726 -38.174676) (xy 199.991218 -38.19652) (xy 199.991218 -38.197282)
			(xy 199.991518 -38.207455) (xy 199.999116 -38.226317) (xy 200.00595 -38.233858) (xy 200.675748 -38.903656)
			(xy 200.68125 -38.908637) (xy 200.694419 -38.915468) (xy 200.701656 -38.917118) (xy 200.711308 -38.918134)
			(xy 200.888346 -38.918134) (xy 200.896474 -38.917372) (xy 200.896982 -38.917372) (xy 200.904413 -38.915796)
			(xy 200.917963 -38.908946) (xy 200.923652 -38.90391) (xy 201.172318 -38.65499) (xy 201.174096 -38.652704)
			(xy 201.174096 -36.734496) (xy 201.173906 -36.728551) (xy 201.171083 -36.716998) (xy 201.168508 -36.711636)
			(xy 201.166222 -36.707318) (xy 201.158304 -36.693366) (xy 201.14457 -36.664371) (xy 201.13879 -36.649406)
			(xy 201.13752 -36.64585) (xy 201.134726 -36.637722) (xy 201.134472 -36.637214) (xy 201.13371 -36.634674)
			(xy 201.133456 -36.633912) (xy 201.132694 -36.631626) (xy 201.132186 -36.630102) (xy 201.131424 -36.62807)
			(xy 201.130408 -36.625022) (xy 201.129138 -36.621974) (xy 201.127175 -36.618144) (xy 201.122194 -36.611126)
			(xy 201.119232 -36.608004) (xy 199.62876 -35.117532) (xy 199.610725 -35.098762) (xy 199.58014 -35.056647)
			(xy 199.556509 -35.010271) (xy 199.540411 -34.960773) (xy 199.532243 -34.909368) (xy 199.531732 -34.883344)
			(xy 199.531732 -32.411162) (xy 199.522842 -32.402018) (xy 199.514968 -32.395414) (xy 199.493124 -32.377634)
			(xy 199.46112 -32.351472) (xy 199.453246 -32.345376) (xy 199.429878 -32.350202) (xy 199.429624 -32.350202)
			(xy 199.412941 -32.353666) (xy 199.379264 -32.358875) (xy 199.362314 -32.360616) (xy 199.34882 -32.361803)
			(xy 199.321758 -32.363074) (xy 199.308212 -32.363156) (xy 199.261476 -32.363156) (xy 199.261476 -32.361378)
			(xy 199.228027 -32.358238) (xy 199.162106 -32.34526) (xy 199.098104 -32.324823) (xy 199.036861 -32.297197)
			(xy 198.979181 -32.262743) (xy 198.925823 -32.221916) (xy 198.877489 -32.17525) (xy 198.834811 -32.12336)
			(xy 198.798353 -32.066926) (xy 198.768592 -32.006691) (xy 198.74592 -31.943446) (xy 198.730634 -31.878022)
			(xy 198.722936 -31.811279) (xy 198.722488 -31.777686) (xy 198.722488 -30.776164) (xy 198.719694 -30.772862)
			(xy 198.71563 -30.76829) (xy 198.63816 -30.720284) (xy 198.630587 -30.716175) (xy 198.613699 -30.712818)
			(xy 198.596662 -30.715306) (xy 198.588884 -30.719014) (xy 198.586344 -30.720284) (xy 198.577962 -30.724348)
			(xy 198.570088 -30.727904) (xy 198.544928 -30.738835) (xy 198.492293 -30.754287) (xy 198.438003 -30.762146)
			(xy 198.410576 -30.762702) (xy 198.383018 -30.762209) (xy 198.328464 -30.754361) (xy 198.275581 -30.73883)
			(xy 198.225448 -30.715931) (xy 198.179083 -30.68613) (xy 198.137432 -30.650034) (xy 198.101341 -30.608378)
			(xy 198.071546 -30.56201) (xy 198.048653 -30.511874) (xy 198.033128 -30.458989) (xy 198.025288 -30.404434)
			(xy 198.02475 -30.376876) (xy 198.02526 -30.348468) (xy 198.033615 -30.292269) (xy 198.05014 -30.237908)
			(xy 198.074476 -30.186567) (xy 198.106093 -30.13936) (xy 198.144307 -30.097314) (xy 198.165974 -30.078934)
			(xy 198.166482 -30.078426) (xy 198.17207 -30.0736) (xy 198.176134 -30.070298) (xy 198.17969 -30.066234)
			(xy 198.185532 -30.057344) (xy 198.192136 -30.04312) (xy 198.193802 -30.038667) (xy 198.195588 -30.029331)
			(xy 198.195692 -30.024578) (xy 198.195692 -29.967682) (xy 198.19555 -29.962242) (xy 198.193245 -29.951609)
			(xy 198.19112 -29.9466) (xy 198.187818 -29.939742) (xy 198.187818 -29.939234) (xy 198.18096 -29.925518)
			(xy 198.172578 -29.914088) (xy 198.167752 -29.909262) (xy 198.165974 -29.907738) (xy 198.144946 -29.8895)
			(xy 198.107881 -29.847976) (xy 198.077237 -29.80151) (xy 198.053664 -29.751087) (xy 198.037662 -29.697776)
			(xy 198.02957 -29.642706) (xy 198.029068 -29.614876) (xy 198.029555 -29.587625) (xy 198.037315 -29.533679)
			(xy 198.052672 -29.481386) (xy 198.075314 -29.43181) (xy 198.10478 -29.385961) (xy 198.140471 -29.344771)
			(xy 198.181661 -29.30908) (xy 198.22751 -29.279614) (xy 198.277086 -29.256972) (xy 198.329379 -29.241615)
			(xy 198.383325 -29.233855) (xy 198.410576 -29.233368) (xy 198.410576 -29.233114) (xy 198.439973 -29.233654)
			(xy 198.498073 -29.242666) (xy 198.554103 -29.260481) (xy 198.606739 -29.286678) (xy 198.631048 -29.303218)
			(xy 198.631556 -29.303726) (xy 198.640446 -29.309822) (xy 198.650606 -29.311854) (xy 198.656229 -29.312839)
			(xy 198.667639 -29.312585) (xy 198.673212 -29.311346) (xy 198.748142 -29.292042) (xy 198.75779 -29.289167)
			(xy 198.773894 -29.277113) (xy 198.779384 -29.268674) (xy 198.781162 -29.26461) (xy 198.795801 -29.23554)
			(xy 198.830584 -29.180525) (xy 198.871237 -29.129692) (xy 198.893938 -29.106368) (xy 201.332338 -26.667968)
			(xy 201.337322 -26.662467) (xy 201.344159 -26.6493) (xy 201.3458 -26.64206) (xy 201.346816 -26.632408)
			(xy 201.346816 -24.158194) (xy 201.347312 -24.124094) (xy 201.355229 -24.056354) (xy 201.370958 -23.989991)
			(xy 201.394284 -23.925903) (xy 201.424892 -23.864957) (xy 201.462369 -23.807976) (xy 201.506208 -23.755731)
			(xy 201.555815 -23.708928) (xy 201.610521 -23.668202) (xy 201.669585 -23.634101) (xy 201.732208 -23.607088)
			(xy 201.797544 -23.587528) (xy 201.864708 -23.575685) (xy 201.932794 -23.57172) (xy 202.00088 -23.575685)
			(xy 202.068044 -23.587528) (xy 202.13338 -23.607088) (xy 202.196003 -23.634101) (xy 202.255067 -23.668202)
			(xy 202.309773 -23.708928) (xy 202.35938 -23.755731) (xy 202.403219 -23.807976) (xy 202.440696 -23.864957)
			(xy 202.471304 -23.925903) (xy 202.49463 -23.989991) (xy 202.510359 -24.056354) (xy 202.518276 -24.124094)
			(xy 202.518772 -24.158194) (xy 202.518772 -24.807418) (xy 202.720192 -24.807418) (xy 202.724263 -24.751796)
			(xy 202.736389 -24.697359) (xy 202.756312 -24.645268) (xy 202.783608 -24.596633) (xy 202.817694 -24.55249)
			(xy 202.857843 -24.513781) (xy 202.903201 -24.48133) (xy 202.952801 -24.455829) (xy 203.005585 -24.437822)
			(xy 203.060428 -24.427692) (xy 203.116162 -24.425655) (xy 203.171599 -24.431755) (xy 203.225556 -24.445861)
			(xy 203.276885 -24.467673) (xy 203.324491 -24.496727) (xy 203.367359 -24.532402) (xy 203.404576 -24.573939)
			(xy 203.435349 -24.620452) (xy 203.459021 -24.670949) (xy 203.475089 -24.724356) (xy 203.483209 -24.779532)
			(xy 203.483718 -24.807418) (xy 203.483209 -24.835304) (xy 203.475089 -24.89048) (xy 203.459021 -24.943887)
			(xy 203.435349 -24.994384) (xy 203.404576 -25.040897) (xy 203.367359 -25.082434) (xy 203.324491 -25.118109)
			(xy 203.276885 -25.147163) (xy 203.225556 -25.168975) (xy 203.171599 -25.183081) (xy 203.116162 -25.189181)
			(xy 203.060428 -25.187144) (xy 203.005585 -25.177014) (xy 202.952801 -25.159007) (xy 202.903201 -25.133506)
			(xy 202.857843 -25.101055) (xy 202.817694 -25.062346) (xy 202.783608 -25.018203) (xy 202.756312 -24.969568)
			(xy 202.736389 -24.917477) (xy 202.724263 -24.86304) (xy 202.720192 -24.807418) (xy 202.518772 -24.807418)
			(xy 202.518772 -26.724102) (xy 202.521032 -26.727029) (xy 202.526259 -26.732257) (xy 202.529186 -26.734516)
			(xy 202.823826 -26.734516) (xy 202.826366 -26.734516) (xy 202.831725 -26.734084) (xy 202.842096 -26.731261)
			(xy 202.84694 -26.728928) (xy 202.870562 -26.716228) (xy 202.876404 -26.713434) (xy 202.876912 -26.71318)
			(xy 202.885802 -26.70556) (xy 202.889612 -26.700226) (xy 202.894996 -26.691797) (xy 202.899479 -26.672326)
			(xy 202.896231 -26.652611) (xy 202.885737 -26.635608) (xy 202.877928 -26.62936) (xy 202.872086 -26.625296)
			(xy 202.86599 -26.62301) (xy 202.839294 -26.612242) (xy 202.789224 -26.583844) (xy 202.743986 -26.548249)
			(xy 202.704606 -26.506265) (xy 202.671978 -26.458843) (xy 202.64684 -26.407059) (xy 202.629763 -26.352088)
			(xy 202.621135 -26.295175) (xy 202.620626 -26.266394) (xy 202.621112 -26.239143) (xy 202.628868 -26.185195)
			(xy 202.644223 -26.1329) (xy 202.666865 -26.083323) (xy 202.696331 -26.037473) (xy 202.732022 -25.996282)
			(xy 202.773213 -25.960591) (xy 202.819063 -25.931125) (xy 202.86864 -25.908483) (xy 202.920935 -25.893128)
			(xy 202.974883 -25.885372) (xy 203.029385 -25.885372) (xy 203.083333 -25.893128) (xy 203.135628 -25.908483)
			(xy 203.185205 -25.931125) (xy 203.231055 -25.960591) (xy 203.272246 -25.996282) (xy 203.307937 -26.037473)
			(xy 203.337403 -26.083323) (xy 203.360045 -26.1329) (xy 203.3754 -26.185195) (xy 203.383156 -26.239143)
			(xy 203.383642 -26.266394) (xy 203.383108 -26.29531) (xy 203.374381 -26.352481) (xy 203.357126 -26.407679)
			(xy 203.331738 -26.459641) (xy 203.298798 -26.507176) (xy 203.259062 -26.549196) (xy 203.236576 -26.567384)
			(xy 203.232004 -26.57094) (xy 203.222606 -26.58237) (xy 203.220313 -26.585227) (xy 203.216488 -26.591475)
			(xy 203.214986 -26.594816) (xy 203.214986 -26.595324) (xy 203.212875 -26.600591) (xy 203.210815 -26.611749)
			(xy 203.210922 -26.617422) (xy 203.212192 -26.643838) (xy 203.212192 -26.644346) (xy 203.214986 -26.690574)
			(xy 203.21778 -26.702766) (xy 203.223876 -26.713942) (xy 203.226863 -26.718654) (xy 203.234556 -26.72673)
			(xy 203.239116 -26.729944) (xy 203.240132 -26.730706) (xy 203.241656 -26.731468) (xy 203.266174 -26.746627)
			(xy 203.310864 -26.783031) (xy 203.349706 -26.825621) (xy 203.381851 -26.873468) (xy 203.406598 -26.925527)
			(xy 203.423407 -26.980663) (xy 203.431913 -27.037673) (xy 203.43241 -27.066494) (xy 203.431914 -27.094345)
			(xy 203.423988 -27.149479) (xy 203.408296 -27.202925) (xy 203.385158 -27.253593) (xy 203.355045 -27.300453)
			(xy 203.318569 -27.342551) (xy 203.276474 -27.379029) (xy 203.229616 -27.409145) (xy 203.178949 -27.432287)
			(xy 203.125505 -27.447982) (xy 203.070371 -27.455912) (xy 203.04252 -27.456384) (xy 203.042266 -27.456384)
			(xy 203.016945 -27.455981) (xy 202.966727 -27.449438) (xy 202.917774 -27.436466) (xy 202.870906 -27.417282)
			(xy 202.848718 -27.405076) (xy 202.842876 -27.401774) (xy 202.83678 -27.40025) (xy 202.823826 -27.398472)
			(xy 202.699112 -27.398472) (xy 202.689151 -27.398961) (xy 202.67073 -27.406551) (xy 202.663298 -27.413204)
			(xy 201.110088 -28.965906) (xy 200.953668 -29.12237) (xy 202.706732 -29.12237) (xy 202.706732 -28.25877)
			(xy 202.707222 -28.228786) (xy 202.71505 -28.16933) (xy 202.730571 -28.111405) (xy 202.75352 -28.056001)
			(xy 202.783504 -28.004067) (xy 202.82001 -27.956491) (xy 202.862415 -27.914086) (xy 202.909991 -27.87758)
			(xy 202.961925 -27.847596) (xy 203.017329 -27.824647) (xy 203.075254 -27.809126) (xy 203.13471 -27.801298)
			(xy 203.194678 -27.801298) (xy 203.254134 -27.809126) (xy 203.312059 -27.824647) (xy 203.367463 -27.847596)
			(xy 203.419397 -27.87758) (xy 203.466973 -27.914086) (xy 203.509378 -27.956491) (xy 203.545884 -28.004067)
			(xy 203.575868 -28.056001) (xy 203.598817 -28.111405) (xy 203.614338 -28.16933) (xy 203.622166 -28.228786)
			(xy 203.622656 -28.25877) (xy 203.622656 -29.12237) (xy 203.622166 -29.152354) (xy 203.614338 -29.21181)
			(xy 203.598817 -29.269735) (xy 203.575868 -29.325139) (xy 203.545884 -29.377073) (xy 203.509378 -29.424649)
			(xy 203.466973 -29.467054) (xy 203.419397 -29.50356) (xy 203.367463 -29.533544) (xy 203.312059 -29.556493)
			(xy 203.254134 -29.572014) (xy 203.194678 -29.579842) (xy 203.13471 -29.579842) (xy 203.075254 -29.572014)
			(xy 203.017329 -29.556493) (xy 202.961925 -29.533544) (xy 202.909991 -29.50356) (xy 202.862415 -29.467054)
			(xy 202.82001 -29.424649) (xy 202.783504 -29.377073) (xy 202.75352 -29.325139) (xy 202.730571 -29.269735)
			(xy 202.71505 -29.21181) (xy 202.707222 -29.152354) (xy 202.706732 -29.12237) (xy 200.953668 -29.12237)
			(xy 200.200006 -29.876242) (xy 200.19518 -29.88183) (xy 200.19518 -30.922468) (xy 200.852532 -30.922468)
			(xy 200.852532 -30.058868) (xy 200.853022 -30.028884) (xy 200.86085 -29.969428) (xy 200.876371 -29.911503)
			(xy 200.89932 -29.856099) (xy 200.929304 -29.804165) (xy 200.96581 -29.756589) (xy 201.008215 -29.714184)
			(xy 201.055791 -29.677678) (xy 201.107725 -29.647694) (xy 201.163129 -29.624745) (xy 201.221054 -29.609224)
			(xy 201.28051 -29.601396) (xy 201.340478 -29.601396) (xy 201.399934 -29.609224) (xy 201.457859 -29.624745)
			(xy 201.513263 -29.647694) (xy 201.565197 -29.677678) (xy 201.612773 -29.714184) (xy 201.655178 -29.756589)
			(xy 201.691684 -29.804165) (xy 201.721668 -29.856099) (xy 201.744617 -29.911503) (xy 201.760138 -29.969428)
			(xy 201.767966 -30.028884) (xy 201.768456 -30.058868) (xy 201.768456 -30.92069) (xy 215.589612 -30.92069)
			(xy 215.589612 -30.05709) (xy 215.590102 -30.027122) (xy 215.597925 -29.9677) (xy 215.613438 -29.909807)
			(xy 215.636374 -29.854434) (xy 215.666341 -29.802528) (xy 215.702828 -29.754978) (xy 215.745208 -29.712598)
			(xy 215.792758 -29.676111) (xy 215.844664 -29.646144) (xy 215.900037 -29.623208) (xy 215.95793 -29.607695)
			(xy 216.017352 -29.599872) (xy 216.077288 -29.599872) (xy 216.13671 -29.607695) (xy 216.194603 -29.623208)
			(xy 216.249976 -29.646144) (xy 216.301882 -29.676111) (xy 216.349432 -29.712598) (xy 216.391812 -29.754978)
			(xy 216.428299 -29.802528) (xy 216.458266 -29.854434) (xy 216.481202 -29.909807) (xy 216.496715 -29.9677)
			(xy 216.504538 -30.027122) (xy 216.505028 -30.05709) (xy 216.505028 -30.92069) (xy 216.504538 -30.950658)
			(xy 216.496715 -31.01008) (xy 216.481202 -31.067973) (xy 216.458266 -31.123346) (xy 216.428299 -31.175252)
			(xy 216.391812 -31.222802) (xy 216.349432 -31.265182) (xy 216.301882 -31.301669) (xy 216.249976 -31.331636)
			(xy 216.194603 -31.354572) (xy 216.13671 -31.370085) (xy 216.077288 -31.377908) (xy 216.017352 -31.377908)
			(xy 215.95793 -31.370085) (xy 215.900037 -31.354572) (xy 215.844664 -31.331636) (xy 215.792758 -31.301669)
			(xy 215.745208 -31.265182) (xy 215.702828 -31.222802) (xy 215.666341 -31.175252) (xy 215.636374 -31.123346)
			(xy 215.613438 -31.067973) (xy 215.597925 -31.01008) (xy 215.590102 -30.950658) (xy 215.589612 -30.92069)
			(xy 201.768456 -30.92069) (xy 201.768456 -30.922468) (xy 201.767966 -30.952452) (xy 201.760138 -31.011908)
			(xy 201.744617 -31.069833) (xy 201.721668 -31.125237) (xy 201.691684 -31.177171) (xy 201.655178 -31.224747)
			(xy 201.612773 -31.267152) (xy 201.565197 -31.303658) (xy 201.513263 -31.333642) (xy 201.457859 -31.356591)
			(xy 201.399934 -31.372112) (xy 201.340478 -31.37994) (xy 201.28051 -31.37994) (xy 201.221054 -31.372112)
			(xy 201.163129 -31.356591) (xy 201.107725 -31.333642) (xy 201.055791 -31.303658) (xy 201.008215 -31.267152)
			(xy 200.96581 -31.224747) (xy 200.929304 -31.177171) (xy 200.89932 -31.125237) (xy 200.876371 -31.069833)
			(xy 200.86085 -31.011908) (xy 200.853022 -30.952452) (xy 200.852532 -30.922468) (xy 200.19518 -30.922468)
			(xy 200.19518 -32.722312) (xy 202.706732 -32.722312) (xy 202.706732 -31.858712) (xy 202.707222 -31.828728)
			(xy 202.71505 -31.769272) (xy 202.730571 -31.711347) (xy 202.75352 -31.655943) (xy 202.783504 -31.604009)
			(xy 202.82001 -31.556433) (xy 202.862415 -31.514028) (xy 202.909991 -31.477522) (xy 202.961925 -31.447538)
			(xy 203.017329 -31.424589) (xy 203.075254 -31.409068) (xy 203.13471 -31.40124) (xy 203.194678 -31.40124)
			(xy 203.254134 -31.409068) (xy 203.312059 -31.424589) (xy 203.367463 -31.447538) (xy 203.419397 -31.477522)
			(xy 203.466973 -31.514028) (xy 203.509378 -31.556433) (xy 203.545884 -31.604009) (xy 203.575868 -31.655943)
			(xy 203.598817 -31.711347) (xy 203.614338 -31.769272) (xy 203.622166 -31.828728) (xy 203.622656 -31.858712)
			(xy 203.622656 -32.714184) (xy 212.947504 -32.714184) (xy 212.947504 -31.850584) (xy 212.947994 -31.820616)
			(xy 212.955817 -31.761194) (xy 212.97133 -31.703301) (xy 212.994266 -31.647928) (xy 213.024233 -31.596022)
			(xy 213.06072 -31.548472) (xy 213.1031 -31.506092) (xy 213.15065 -31.469605) (xy 213.202556 -31.439638)
			(xy 213.257929 -31.416702) (xy 213.315822 -31.401189) (xy 213.375244 -31.393366) (xy 213.43518 -31.393366)
			(xy 213.494602 -31.401189) (xy 213.552495 -31.416702) (xy 213.607868 -31.439638) (xy 213.659774 -31.469605)
			(xy 213.707324 -31.506092) (xy 213.749704 -31.548472) (xy 213.786191 -31.596022) (xy 213.816158 -31.647928)
			(xy 213.839094 -31.703301) (xy 213.854607 -31.761194) (xy 213.86243 -31.820616) (xy 213.86292 -31.850584)
			(xy 213.86292 -32.714184) (xy 213.86243 -32.744152) (xy 213.854607 -32.803574) (xy 213.839094 -32.861467)
			(xy 213.816158 -32.91684) (xy 213.786191 -32.968746) (xy 213.749704 -33.016296) (xy 213.707324 -33.058676)
			(xy 213.659774 -33.095163) (xy 213.607868 -33.12513) (xy 213.552495 -33.148066) (xy 213.494602 -33.163579)
			(xy 213.43518 -33.171402) (xy 213.375244 -33.171402) (xy 213.315822 -33.163579) (xy 213.257929 -33.148066)
			(xy 213.202556 -33.12513) (xy 213.15065 -33.095163) (xy 213.1031 -33.058676) (xy 213.06072 -33.016296)
			(xy 213.024233 -32.968746) (xy 212.994266 -32.91684) (xy 212.97133 -32.861467) (xy 212.955817 -32.803574)
			(xy 212.947994 -32.744152) (xy 212.947504 -32.714184) (xy 203.622656 -32.714184) (xy 203.622656 -32.722312)
			(xy 203.622166 -32.752296) (xy 203.614338 -32.811752) (xy 203.598817 -32.869677) (xy 203.575868 -32.925081)
			(xy 203.545884 -32.977015) (xy 203.509378 -33.024591) (xy 203.466973 -33.066996) (xy 203.419397 -33.103502)
			(xy 203.367463 -33.133486) (xy 203.312059 -33.156435) (xy 203.254134 -33.171956) (xy 203.194678 -33.179784)
			(xy 203.13471 -33.179784) (xy 203.075254 -33.171956) (xy 203.017329 -33.156435) (xy 202.961925 -33.133486)
			(xy 202.909991 -33.103502) (xy 202.862415 -33.066996) (xy 202.82001 -33.024591) (xy 202.783504 -32.977015)
			(xy 202.75352 -32.925081) (xy 202.730571 -32.869677) (xy 202.71505 -32.811752) (xy 202.707222 -32.752296)
			(xy 202.706732 -32.722312) (xy 200.19518 -32.722312) (xy 200.19518 -34.52241) (xy 200.852532 -34.52241)
			(xy 200.852532 -33.65881) (xy 200.853022 -33.628826) (xy 200.86085 -33.56937) (xy 200.876371 -33.511445)
			(xy 200.89932 -33.456041) (xy 200.929304 -33.404107) (xy 200.96581 -33.356531) (xy 201.008215 -33.314126)
			(xy 201.055791 -33.27762) (xy 201.107725 -33.247636) (xy 201.163129 -33.224687) (xy 201.221054 -33.209166)
			(xy 201.28051 -33.201338) (xy 201.340478 -33.201338) (xy 201.399934 -33.209166) (xy 201.457859 -33.224687)
			(xy 201.513263 -33.247636) (xy 201.565197 -33.27762) (xy 201.612773 -33.314126) (xy 201.655178 -33.356531)
			(xy 201.691684 -33.404107) (xy 201.721668 -33.456041) (xy 201.744617 -33.511445) (xy 201.760138 -33.56937)
			(xy 201.767966 -33.628826) (xy 201.768456 -33.65881) (xy 201.768456 -34.520886) (xy 215.589612 -34.520886)
			(xy 215.589612 -33.657286) (xy 215.590102 -33.627318) (xy 215.597925 -33.567896) (xy 215.613438 -33.510003)
			(xy 215.636374 -33.45463) (xy 215.666341 -33.402724) (xy 215.702828 -33.355174) (xy 215.745208 -33.312794)
			(xy 215.792758 -33.276307) (xy 215.844664 -33.24634) (xy 215.900037 -33.223404) (xy 215.95793 -33.207891)
			(xy 216.017352 -33.200068) (xy 216.077288 -33.200068) (xy 216.13671 -33.207891) (xy 216.194603 -33.223404)
			(xy 216.249976 -33.24634) (xy 216.301882 -33.276307) (xy 216.349432 -33.312794) (xy 216.391812 -33.355174)
			(xy 216.428299 -33.402724) (xy 216.458266 -33.45463) (xy 216.481202 -33.510003) (xy 216.496715 -33.567896)
			(xy 216.504538 -33.627318) (xy 216.505028 -33.657286) (xy 216.505028 -34.520886) (xy 216.504538 -34.550854)
			(xy 216.496715 -34.610276) (xy 216.481202 -34.668169) (xy 216.458266 -34.723542) (xy 216.428299 -34.775448)
			(xy 216.391812 -34.822998) (xy 216.349432 -34.865378) (xy 216.301882 -34.901865) (xy 216.249976 -34.931832)
			(xy 216.194603 -34.954768) (xy 216.13671 -34.970281) (xy 216.077288 -34.978104) (xy 216.017352 -34.978104)
			(xy 215.95793 -34.970281) (xy 215.900037 -34.954768) (xy 215.844664 -34.931832) (xy 215.792758 -34.901865)
			(xy 215.745208 -34.865378) (xy 215.702828 -34.822998) (xy 215.666341 -34.775448) (xy 215.636374 -34.723542)
			(xy 215.613438 -34.668169) (xy 215.597925 -34.610276) (xy 215.590102 -34.550854) (xy 215.589612 -34.520886)
			(xy 201.768456 -34.520886) (xy 201.768456 -34.52241) (xy 201.767966 -34.552394) (xy 201.760138 -34.61185)
			(xy 201.744617 -34.669775) (xy 201.721668 -34.725179) (xy 201.691684 -34.777113) (xy 201.655178 -34.824689)
			(xy 201.612773 -34.867094) (xy 201.565197 -34.9036) (xy 201.513263 -34.933584) (xy 201.457859 -34.956533)
			(xy 201.399934 -34.972054) (xy 201.340478 -34.979882) (xy 201.28051 -34.979882) (xy 201.221054 -34.972054)
			(xy 201.163129 -34.956533) (xy 201.107725 -34.933584) (xy 201.055791 -34.9036) (xy 201.008215 -34.867094)
			(xy 200.96581 -34.824689) (xy 200.929304 -34.777113) (xy 200.89932 -34.725179) (xy 200.876371 -34.669775)
			(xy 200.86085 -34.61185) (xy 200.853022 -34.552394) (xy 200.852532 -34.52241) (xy 200.19518 -34.52241)
			(xy 200.19518 -34.72434) (xy 200.195688 -34.73196) (xy 200.197141 -34.739795) (xy 200.204255 -34.754044)
			(xy 200.209658 -34.7599) (xy 201.139806 -35.689794) (xy 201.597514 -36.147502) (xy 201.604118 -36.149534)
			(xy 201.629931 -36.157633) (xy 201.679141 -36.180104) (xy 201.724684 -36.209303) (xy 201.765643 -36.244644)
			(xy 201.801198 -36.285418) (xy 201.830635 -36.330806) (xy 201.853363 -36.379899) (xy 201.868926 -36.431711)
			(xy 201.877013 -36.485201) (xy 201.877676 -36.512246) (xy 201.877676 -36.519104) (xy 201.877353 -36.536937)
			(xy 201.873796 -36.572429) (xy 201.870564 -36.58997) (xy 201.86904 -36.597336) (xy 201.868389 -36.60013)
			(xy 206.098655 -36.60013) (xy 206.102659 -36.512245) (xy 206.114639 -36.425088) (xy 206.134494 -36.339381)
			(xy 206.162061 -36.255836) (xy 206.197111 -36.175143) (xy 206.239353 -36.097971) (xy 206.288438 -36.024961)
			(xy 206.343959 -35.956717) (xy 206.405456 -35.893804) (xy 206.472418 -35.836744) (xy 206.544292 -35.78601)
			(xy 206.620482 -35.742022) (xy 206.700356 -35.705144) (xy 206.783253 -35.675683) (xy 206.868485 -35.653881)
			(xy 206.955347 -35.639921) (xy 207.043118 -35.633917) (xy 207.131072 -35.63592) (xy 207.218479 -35.645912)
			(xy 207.304615 -35.663812) (xy 207.388767 -35.68947) (xy 207.470237 -35.722674) (xy 207.54835 -35.763148)
			(xy 207.622458 -35.810559) (xy 207.691949 -35.864512) (xy 207.756245 -35.92456) (xy 207.814814 -35.990207)
			(xy 207.867171 -36.060907) (xy 207.912883 -36.136076) (xy 207.951569 -36.21509) (xy 207.98291 -36.297295)
			(xy 208.006645 -36.382009) (xy 208.022579 -36.46853) (xy 208.030579 -36.556142) (xy 208.03108 -36.60013)
			(xy 208.030579 -36.644118) (xy 208.022579 -36.73173) (xy 208.006645 -36.818251) (xy 207.98291 -36.902965)
			(xy 207.951569 -36.98517) (xy 207.912883 -37.064184) (xy 207.867171 -37.139353) (xy 207.814814 -37.210053)
			(xy 207.756245 -37.2757) (xy 207.691949 -37.335748) (xy 207.622458 -37.389701) (xy 207.54835 -37.437112)
			(xy 207.470237 -37.477586) (xy 207.388767 -37.51079) (xy 207.304615 -37.536448) (xy 207.218479 -37.554348)
			(xy 207.131072 -37.56434) (xy 207.043118 -37.566343) (xy 206.955347 -37.560339) (xy 206.868485 -37.546379)
			(xy 206.783253 -37.524577) (xy 206.700356 -37.495116) (xy 206.620482 -37.458238) (xy 206.544292 -37.41425)
			(xy 206.472418 -37.363516) (xy 206.405456 -37.306456) (xy 206.343959 -37.243543) (xy 206.288438 -37.175299)
			(xy 206.239353 -37.102289) (xy 206.197111 -37.025117) (xy 206.162061 -36.944424) (xy 206.134494 -36.860879)
			(xy 206.114639 -36.775172) (xy 206.102659 -36.688015) (xy 206.098655 -36.60013) (xy 201.868389 -36.60013)
			(xy 201.86487 -36.615244) (xy 201.853545 -36.650229) (xy 201.846434 -36.667186) (xy 201.846434 -36.667694)
			(xy 201.842624 -36.675822) (xy 201.838052 -36.685982) (xy 201.838052 -39.452296) (xy 201.83983 -39.454582)
			(xy 203.653906 -41.268751) (xy 209.94395 -41.268751) (xy 209.94395 -41.214249) (xy 209.951706 -41.160301)
			(xy 209.96706 -41.108006) (xy 209.989699 -41.058428) (xy 210.019163 -41.012577) (xy 210.054852 -40.971385)
			(xy 210.09604 -40.935691) (xy 210.141888 -40.906221) (xy 210.191463 -40.883576) (xy 210.243756 -40.868215)
			(xy 210.297703 -40.860453) (xy 210.324954 -40.859964) (xy 210.353694 -40.860465) (xy 210.410522 -40.869094)
			(xy 210.465412 -40.88615) (xy 210.517124 -40.911247) (xy 210.564485 -40.943816) (xy 210.585812 -40.963088)
			(xy 210.59267 -40.969692) (xy 210.610704 -40.976804) (xy 210.699604 -40.976804) (xy 210.717638 -40.969692)
			(xy 210.724496 -40.963088) (xy 210.745808 -40.9438) (xy 210.793173 -40.911234) (xy 210.844889 -40.886144)
			(xy 210.899783 -40.869098) (xy 210.956614 -40.860481) (xy 210.985354 -40.859964) (xy 211.012607 -40.86048)
			(xy 211.066559 -40.868231) (xy 211.118858 -40.883582) (xy 211.168441 -40.90622) (xy 211.214296 -40.935685)
			(xy 211.255491 -40.971376) (xy 211.291187 -41.012567) (xy 211.320658 -41.058419) (xy 211.343302 -41.107998)
			(xy 211.358659 -41.160296) (xy 211.366417 -41.214247) (xy 211.366417 -41.268753) (xy 211.358659 -41.322704)
			(xy 211.343302 -41.375002) (xy 211.320658 -41.424581) (xy 211.291187 -41.470433) (xy 211.255491 -41.511624)
			(xy 211.214296 -41.547315) (xy 211.168441 -41.57678) (xy 211.118858 -41.599418) (xy 211.066559 -41.614769)
			(xy 211.012607 -41.62252) (xy 210.985354 -41.62298) (xy 210.956615 -41.622463) (xy 210.899788 -41.613835)
			(xy 210.844898 -41.596783) (xy 210.793187 -41.57169) (xy 210.745824 -41.539126) (xy 210.724496 -41.519856)
			(xy 210.717638 -41.513252) (xy 210.699604 -41.50614) (xy 210.610704 -41.50614) (xy 210.59267 -41.513252)
			(xy 210.585812 -41.519856) (xy 210.564503 -41.539148) (xy 210.517136 -41.571711) (xy 210.46542 -41.5968)
			(xy 210.410525 -41.613845) (xy 210.353694 -41.622462) (xy 210.324954 -41.62298) (xy 210.297703 -41.622547)
			(xy 210.243756 -41.614785) (xy 210.191463 -41.599424) (xy 210.141888 -41.576779) (xy 210.09604 -41.547309)
			(xy 210.054852 -41.511615) (xy 210.019163 -41.470423) (xy 209.989699 -41.424572) (xy 209.96706 -41.374994)
			(xy 209.951706 -41.322699) (xy 209.94395 -41.268751) (xy 203.653906 -41.268751) (xy 205.690273 -43.305222)
			(xy 212.407246 -43.305222) (xy 212.407714 -43.277852) (xy 212.415529 -43.223672) (xy 212.431018 -43.171169)
			(xy 212.453859 -43.121422) (xy 212.483584 -43.075455) (xy 212.501226 -43.054524) (xy 212.50148 -43.05427)
			(xy 212.507053 -43.047174) (xy 212.513306 -43.030264) (xy 212.513672 -43.02125) (xy 212.513672 -42.954194)
			(xy 212.513324 -42.945176) (xy 212.507071 -42.928259) (xy 212.50148 -42.921174) (xy 212.501226 -42.921174)
			(xy 212.501226 -42.92092) (xy 212.483587 -42.899988) (xy 212.453874 -42.854015) (xy 212.431038 -42.804268)
			(xy 212.415547 -42.751767) (xy 212.407719 -42.697591) (xy 212.407246 -42.670222) (xy 212.407798 -42.641484)
			(xy 212.416416 -42.584659) (xy 212.43346 -42.529769) (xy 212.458545 -42.478057) (xy 212.491103 -42.430692)
			(xy 212.51037 -42.409364) (xy 212.516974 -42.402506) (xy 212.524086 -42.384472) (xy 212.524086 -42.295572)
			(xy 212.516974 -42.277538) (xy 212.51037 -42.27068) (xy 212.491123 -42.249333) (xy 212.458562 -42.201973)
			(xy 212.433473 -42.150264) (xy 212.416424 -42.095377) (xy 212.4078 -42.038553) (xy 212.407798 -41.981079)
			(xy 212.416417 -41.924255) (xy 212.433461 -41.869366) (xy 212.458546 -41.817655) (xy 212.491103 -41.770292)
			(xy 212.51037 -41.748964) (xy 212.516974 -41.742106) (xy 212.524086 -41.724072) (xy 212.524086 -41.635172)
			(xy 212.516974 -41.617138) (xy 212.51037 -41.61028) (xy 212.491115 -41.588939) (xy 212.458545 -41.541582)
			(xy 212.433449 -41.489873) (xy 212.416395 -41.434986) (xy 212.407769 -41.37816) (xy 212.407246 -41.349422)
			(xy 212.407732 -41.322171) (xy 212.415488 -41.268223) (xy 212.430843 -41.215928) (xy 212.453485 -41.166351)
			(xy 212.482951 -41.120501) (xy 212.518642 -41.07931) (xy 212.559833 -41.043619) (xy 212.605683 -41.014153)
			(xy 212.65526 -40.991511) (xy 212.707555 -40.976156) (xy 212.761503 -40.9684) (xy 212.816005 -40.9684)
			(xy 212.869953 -40.976156) (xy 212.922248 -40.991511) (xy 212.971825 -41.014153) (xy 213.017675 -41.043619)
			(xy 213.058866 -41.07931) (xy 213.094557 -41.120501) (xy 213.124023 -41.166351) (xy 213.146665 -41.215928)
			(xy 213.16202 -41.268223) (xy 213.169776 -41.322171) (xy 213.170262 -41.349422) (xy 213.169735 -41.378161)
			(xy 213.161111 -41.434987) (xy 213.14406 -41.489877) (xy 213.11897 -41.541589) (xy 213.086407 -41.588952)
			(xy 213.067138 -41.61028) (xy 213.060534 -41.617138) (xy 213.053422 -41.635172) (xy 213.053422 -41.724072)
			(xy 213.060534 -41.742106) (xy 213.067138 -41.748964) (xy 213.086432 -41.770271) (xy 213.119 -41.817636)
			(xy 213.144093 -41.869351) (xy 213.161143 -41.924245) (xy 213.169765 -41.981075) (xy 213.169762 -42.038557)
			(xy 213.161136 -42.095387) (xy 213.144081 -42.150279) (xy 213.118984 -42.201992) (xy 213.086412 -42.249354)
			(xy 213.067138 -42.27068) (xy 213.060534 -42.277538) (xy 213.053422 -42.295572) (xy 213.053422 -42.384472)
			(xy 213.060534 -42.402506) (xy 213.067138 -42.409364) (xy 213.086415 -42.430686) (xy 213.118981 -42.478049)
			(xy 213.144073 -42.529762) (xy 213.161122 -42.584654) (xy 213.169743 -42.641483) (xy 213.170262 -42.670222)
			(xy 213.169818 -42.697593) (xy 213.161996 -42.751774) (xy 213.146503 -42.804277) (xy 213.125946 -42.849038)
			(xy 214.991948 -42.849038) (xy 214.996019 -42.793416) (xy 215.008145 -42.738979) (xy 215.028068 -42.686888)
			(xy 215.055364 -42.638253) (xy 215.08945 -42.59411) (xy 215.129599 -42.555401) (xy 215.174957 -42.52295)
			(xy 215.224557 -42.497449) (xy 215.277341 -42.479442) (xy 215.332184 -42.469312) (xy 215.387918 -42.467275)
			(xy 215.443355 -42.473375) (xy 215.497312 -42.487481) (xy 215.548641 -42.509293) (xy 215.596247 -42.538347)
			(xy 215.639115 -42.574022) (xy 215.676332 -42.615559) (xy 215.707105 -42.662072) (xy 215.730777 -42.712569)
			(xy 215.746845 -42.765976) (xy 215.754965 -42.821152) (xy 215.755326 -42.84091) (xy 221.033084 -42.84091)
			(xy 221.037155 -42.785288) (xy 221.049281 -42.730851) (xy 221.069204 -42.67876) (xy 221.0965 -42.630125)
			(xy 221.130586 -42.585982) (xy 221.170735 -42.547273) (xy 221.216093 -42.514822) (xy 221.265693 -42.489321)
			(xy 221.318477 -42.471314) (xy 221.37332 -42.461184) (xy 221.429054 -42.459147) (xy 221.484491 -42.465247)
			(xy 221.538448 -42.479353) (xy 221.589777 -42.501165) (xy 221.637383 -42.530219) (xy 221.680251 -42.565894)
			(xy 221.717468 -42.607431) (xy 221.748241 -42.653944) (xy 221.771913 -42.704441) (xy 221.787981 -42.757848)
			(xy 221.796101 -42.813024) (xy 221.79661 -42.84091) (xy 221.796101 -42.868796) (xy 221.787981 -42.923972)
			(xy 221.771913 -42.977379) (xy 221.748241 -43.027876) (xy 221.717468 -43.074389) (xy 221.680251 -43.115926)
			(xy 221.637383 -43.151601) (xy 221.589777 -43.180655) (xy 221.538448 -43.202467) (xy 221.484491 -43.216573)
			(xy 221.429054 -43.222673) (xy 221.37332 -43.220636) (xy 221.318477 -43.210506) (xy 221.265693 -43.192499)
			(xy 221.216093 -43.166998) (xy 221.170735 -43.134547) (xy 221.130586 -43.095838) (xy 221.0965 -43.051695)
			(xy 221.069204 -43.00306) (xy 221.049281 -42.950969) (xy 221.037155 -42.896532) (xy 221.033084 -42.84091)
			(xy 215.755326 -42.84091) (xy 215.755474 -42.849038) (xy 215.754965 -42.876924) (xy 215.746845 -42.9321)
			(xy 215.730777 -42.985507) (xy 215.707105 -43.036004) (xy 215.676332 -43.082517) (xy 215.639115 -43.124054)
			(xy 215.596247 -43.159729) (xy 215.548641 -43.188783) (xy 215.497312 -43.210595) (xy 215.443355 -43.224701)
			(xy 215.387918 -43.230801) (xy 215.332184 -43.228764) (xy 215.277341 -43.218634) (xy 215.224557 -43.200627)
			(xy 215.174957 -43.175126) (xy 215.129599 -43.142675) (xy 215.08945 -43.103966) (xy 215.055364 -43.059823)
			(xy 215.028068 -43.011188) (xy 215.008145 -42.959097) (xy 214.996019 -42.90466) (xy 214.991948 -42.849038)
			(xy 213.125946 -42.849038) (xy 213.123656 -42.854024) (xy 213.093926 -42.899989) (xy 213.076282 -42.92092)
			(xy 213.076028 -42.921174) (xy 213.070438 -42.928258) (xy 213.064195 -42.945177) (xy 213.063836 -42.954194)
			(xy 213.063836 -43.02125) (xy 213.064209 -43.030265) (xy 213.070445 -43.047183) (xy 213.076028 -43.05427)
			(xy 213.076282 -43.05427) (xy 213.076282 -43.054524) (xy 213.093896 -43.075476) (xy 213.123612 -43.121443)
			(xy 213.146453 -43.171186) (xy 213.16195 -43.223682) (xy 213.169785 -43.277854) (xy 213.170262 -43.305222)
			(xy 213.169776 -43.332473) (xy 213.16202 -43.386421) (xy 213.146665 -43.438716) (xy 213.124023 -43.488293)
			(xy 213.094557 -43.534143) (xy 213.058866 -43.575334) (xy 213.017675 -43.611025) (xy 212.971825 -43.640491)
			(xy 212.922248 -43.663133) (xy 212.869953 -43.678488) (xy 212.816005 -43.686244) (xy 212.761503 -43.686244)
			(xy 212.707555 -43.678488) (xy 212.65526 -43.663133) (xy 212.605683 -43.640491) (xy 212.559833 -43.611025)
			(xy 212.518642 -43.575334) (xy 212.482951 -43.534143) (xy 212.453485 -43.488293) (xy 212.430843 -43.438716)
			(xy 212.415488 -43.386421) (xy 212.407732 -43.332473) (xy 212.407246 -43.305222) (xy 205.690273 -43.305222)
			(xy 206.121289 -43.73626) (xy 214.313006 -43.73626) (xy 214.317077 -43.680638) (xy 214.329203 -43.626201)
			(xy 214.349126 -43.57411) (xy 214.376422 -43.525475) (xy 214.410508 -43.481332) (xy 214.450657 -43.442623)
			(xy 214.496015 -43.410172) (xy 214.545615 -43.384671) (xy 214.598399 -43.366664) (xy 214.653242 -43.356534)
			(xy 214.708976 -43.354497) (xy 214.764413 -43.360597) (xy 214.81837 -43.374703) (xy 214.869699 -43.396515)
			(xy 214.917305 -43.425569) (xy 214.960173 -43.461244) (xy 214.99739 -43.502781) (xy 215.028163 -43.549294)
			(xy 215.051835 -43.599791) (xy 215.067903 -43.653198) (xy 215.076023 -43.708374) (xy 215.076532 -43.73626)
			(xy 215.076023 -43.764146) (xy 215.067903 -43.819322) (xy 215.056594 -43.85691) (xy 218.819728 -43.85691)
			(xy 218.823799 -43.801288) (xy 218.835925 -43.746851) (xy 218.855848 -43.69476) (xy 218.883144 -43.646125)
			(xy 218.91723 -43.601982) (xy 218.957379 -43.563273) (xy 219.002737 -43.530822) (xy 219.052337 -43.505321)
			(xy 219.105121 -43.487314) (xy 219.159964 -43.477184) (xy 219.215698 -43.475147) (xy 219.271135 -43.481247)
			(xy 219.325092 -43.495353) (xy 219.376421 -43.517165) (xy 219.424027 -43.546219) (xy 219.466895 -43.581894)
			(xy 219.504112 -43.623431) (xy 219.534885 -43.669944) (xy 219.558557 -43.720441) (xy 219.574625 -43.773848)
			(xy 219.582745 -43.829024) (xy 219.583254 -43.85691) (xy 219.582745 -43.884796) (xy 219.574625 -43.939972)
			(xy 219.558557 -43.993379) (xy 219.534885 -44.043876) (xy 219.504112 -44.090389) (xy 219.466895 -44.131926)
			(xy 219.424027 -44.167601) (xy 219.376421 -44.196655) (xy 219.325092 -44.218467) (xy 219.271135 -44.232573)
			(xy 219.215698 -44.238673) (xy 219.159964 -44.236636) (xy 219.105121 -44.226506) (xy 219.052337 -44.208499)
			(xy 219.002737 -44.182998) (xy 218.957379 -44.150547) (xy 218.91723 -44.111838) (xy 218.883144 -44.067695)
			(xy 218.855848 -44.01906) (xy 218.835925 -43.966969) (xy 218.823799 -43.912532) (xy 218.819728 -43.85691)
			(xy 215.056594 -43.85691) (xy 215.051835 -43.872729) (xy 215.028163 -43.923226) (xy 214.99739 -43.969739)
			(xy 214.960173 -44.011276) (xy 214.917305 -44.046951) (xy 214.869699 -44.076005) (xy 214.81837 -44.097817)
			(xy 214.764413 -44.111923) (xy 214.708976 -44.118023) (xy 214.653242 -44.115986) (xy 214.598399 -44.105856)
			(xy 214.545615 -44.087849) (xy 214.496015 -44.062348) (xy 214.450657 -44.029897) (xy 214.410508 -43.991188)
			(xy 214.376422 -43.947045) (xy 214.349126 -43.89841) (xy 214.329203 -43.846319) (xy 214.317077 -43.791882)
			(xy 214.313006 -43.73626) (xy 206.121289 -43.73626) (xy 206.79283 -44.407836) (xy 206.799678 -44.415233)
			(xy 206.807411 -44.433832) (xy 206.807816 -44.443904) (xy 206.807816 -44.520358) (xy 206.809594 -44.533566)
			(xy 206.810356 -44.535852) (xy 206.815944 -44.547536) (xy 206.815944 -44.54779) (xy 206.828306 -44.567879)
			(xy 206.847846 -44.610812) (xy 206.861107 -44.656079) (xy 206.867823 -44.702768) (xy 206.868268 -44.726352)
			(xy 206.868268 -45.114464) (xy 214.165432 -45.114464) (xy 214.169503 -45.058842) (xy 214.181629 -45.004405)
			(xy 214.201552 -44.952314) (xy 214.228848 -44.903679) (xy 214.262934 -44.859536) (xy 214.303083 -44.820827)
			(xy 214.348441 -44.788376) (xy 214.398041 -44.762875) (xy 214.450825 -44.744868) (xy 214.505668 -44.734738)
			(xy 214.561402 -44.732701) (xy 214.616839 -44.738801) (xy 214.670796 -44.752907) (xy 214.722125 -44.774719)
			(xy 214.769731 -44.803773) (xy 214.812599 -44.839448) (xy 214.842581 -44.87291) (xy 221.033084 -44.87291)
			(xy 221.037155 -44.817288) (xy 221.049281 -44.762851) (xy 221.069204 -44.71076) (xy 221.0965 -44.662125)
			(xy 221.130586 -44.617982) (xy 221.170735 -44.579273) (xy 221.216093 -44.546822) (xy 221.265693 -44.521321)
			(xy 221.318477 -44.503314) (xy 221.37332 -44.493184) (xy 221.429054 -44.491147) (xy 221.484491 -44.497247)
			(xy 221.538448 -44.511353) (xy 221.589777 -44.533165) (xy 221.637383 -44.562219) (xy 221.680251 -44.597894)
			(xy 221.717468 -44.639431) (xy 221.748241 -44.685944) (xy 221.771913 -44.736441) (xy 221.787981 -44.789848)
			(xy 221.796101 -44.845024) (xy 221.79661 -44.87291) (xy 221.796101 -44.900796) (xy 221.787981 -44.955972)
			(xy 221.771913 -45.009379) (xy 221.748241 -45.059876) (xy 221.717468 -45.106389) (xy 221.680251 -45.147926)
			(xy 221.637383 -45.183601) (xy 221.589777 -45.212655) (xy 221.538448 -45.234467) (xy 221.484491 -45.248573)
			(xy 221.429054 -45.254673) (xy 221.37332 -45.252636) (xy 221.318477 -45.242506) (xy 221.265693 -45.224499)
			(xy 221.216093 -45.198998) (xy 221.170735 -45.166547) (xy 221.130586 -45.127838) (xy 221.0965 -45.083695)
			(xy 221.069204 -45.03506) (xy 221.049281 -44.982969) (xy 221.037155 -44.928532) (xy 221.033084 -44.87291)
			(xy 214.842581 -44.87291) (xy 214.849816 -44.880985) (xy 214.880589 -44.927498) (xy 214.904261 -44.977995)
			(xy 214.920329 -45.031402) (xy 214.928449 -45.086578) (xy 214.928958 -45.114464) (xy 214.928449 -45.14235)
			(xy 214.920329 -45.197526) (xy 214.904261 -45.250933) (xy 214.880589 -45.30143) (xy 214.849816 -45.347943)
			(xy 214.844174 -45.35424) (xy 218.803726 -45.35424) (xy 218.807797 -45.298618) (xy 218.819923 -45.244181)
			(xy 218.839846 -45.19209) (xy 218.867142 -45.143455) (xy 218.901228 -45.099312) (xy 218.941377 -45.060603)
			(xy 218.986735 -45.028152) (xy 219.036335 -45.002651) (xy 219.089119 -44.984644) (xy 219.143962 -44.974514)
			(xy 219.199696 -44.972477) (xy 219.255133 -44.978577) (xy 219.30909 -44.992683) (xy 219.360419 -45.014495)
			(xy 219.408025 -45.043549) (xy 219.450893 -45.079224) (xy 219.48811 -45.120761) (xy 219.518883 -45.167274)
			(xy 219.542555 -45.217771) (xy 219.558623 -45.271178) (xy 219.566743 -45.326354) (xy 219.567252 -45.35424)
			(xy 219.566743 -45.382126) (xy 219.558623 -45.437302) (xy 219.542555 -45.490709) (xy 219.518883 -45.541206)
			(xy 219.48811 -45.587719) (xy 219.450893 -45.629256) (xy 219.408025 -45.664931) (xy 219.360419 -45.693985)
			(xy 219.30909 -45.715797) (xy 219.255133 -45.729903) (xy 219.199696 -45.736003) (xy 219.143962 -45.733966)
			(xy 219.089119 -45.723836) (xy 219.036335 -45.705829) (xy 218.986735 -45.680328) (xy 218.941377 -45.647877)
			(xy 218.901228 -45.609168) (xy 218.867142 -45.565025) (xy 218.839846 -45.51639) (xy 218.819923 -45.464299)
			(xy 218.807797 -45.409862) (xy 218.803726 -45.35424) (xy 214.844174 -45.35424) (xy 214.812599 -45.38948)
			(xy 214.769731 -45.425155) (xy 214.722125 -45.454209) (xy 214.670796 -45.476021) (xy 214.616839 -45.490127)
			(xy 214.561402 -45.496227) (xy 214.505668 -45.49419) (xy 214.450825 -45.48406) (xy 214.398041 -45.466053)
			(xy 214.348441 -45.440552) (xy 214.303083 -45.408101) (xy 214.262934 -45.369392) (xy 214.228848 -45.325249)
			(xy 214.201552 -45.276614) (xy 214.181629 -45.224523) (xy 214.169503 -45.170086) (xy 214.165432 -45.114464)
			(xy 206.868268 -45.114464) (xy 206.868268 -46.082204) (xy 212.152484 -46.082204) (xy 212.152981 -46.054953)
			(xy 212.160737 -46.001006) (xy 212.176091 -45.948712) (xy 212.198732 -45.899136) (xy 212.228197 -45.853286)
			(xy 212.263887 -45.812095) (xy 212.305076 -45.776404) (xy 212.350925 -45.746937) (xy 212.400501 -45.724296)
			(xy 212.452795 -45.70894) (xy 212.506741 -45.701182) (xy 212.533992 -45.700696) (xy 212.560894 -45.701164)
			(xy 212.614164 -45.708735) (xy 212.665842 -45.723713) (xy 212.714904 -45.745802) (xy 212.760376 -45.774564)
			(xy 212.801358 -45.809428) (xy 212.837036 -45.849703) (xy 212.852254 -45.871892) (xy 212.859366 -45.882814)
			(xy 212.882226 -45.894752) (xy 212.994494 -45.89272) (xy 213.016846 -45.879766) (xy 213.023704 -45.86859)
			(xy 213.038636 -45.844996) (xy 213.074314 -45.802044) (xy 213.11587 -45.764751) (xy 213.162418 -45.733912)
			(xy 213.212964 -45.710188) (xy 213.266428 -45.694083) (xy 213.321668 -45.685943) (xy 213.349586 -45.685456)
			(xy 213.376579 -45.685925) (xy 213.430027 -45.693529) (xy 213.48187 -45.708588) (xy 213.531075 -45.7308)
			(xy 213.576659 -45.759723) (xy 213.59749 -45.776896) (xy 213.605618 -45.784008) (xy 213.626192 -45.790104)
			(xy 213.711536 -45.779182) (xy 213.722087 -45.777435) (xy 213.740367 -45.766361) (xy 213.746842 -45.757846)
			(xy 213.762176 -45.736601) (xy 213.797766 -45.698148) (xy 213.838287 -45.664931) (xy 213.882973 -45.637574)
			(xy 213.930984 -45.616593) (xy 213.981416 -45.602383) (xy 214.033318 -45.595211) (xy 214.059516 -45.594778)
			(xy 214.086765 -45.595293) (xy 214.140709 -45.603051) (xy 214.193 -45.618407) (xy 214.242574 -45.641049)
			(xy 214.28842 -45.670514) (xy 214.329607 -45.706204) (xy 214.365295 -45.747393) (xy 214.394759 -45.79324)
			(xy 214.417398 -45.842815) (xy 214.432752 -45.895106) (xy 214.440508 -45.949051) (xy 214.440508 -46.003549)
			(xy 214.432752 -46.057494) (xy 214.417398 -46.109785) (xy 214.394759 -46.15936) (xy 214.365295 -46.205207)
			(xy 214.329607 -46.246396) (xy 214.28842 -46.282086) (xy 214.242574 -46.311551) (xy 214.193 -46.334193)
			(xy 214.140709 -46.349549) (xy 214.086765 -46.357307) (xy 214.059516 -46.357794) (xy 214.032524 -46.357312)
			(xy 213.979077 -46.349709) (xy 213.927234 -46.334653) (xy 213.878029 -46.312444) (xy 213.832444 -46.283525)
			(xy 213.811612 -46.266354) (xy 213.803484 -46.259242) (xy 213.78291 -46.253146) (xy 213.697566 -46.264068)
			(xy 213.68702 -46.265833) (xy 213.668739 -46.276896) (xy 213.66226 -46.285404) (xy 213.644649 -46.309706)
			(xy 213.603052 -46.352965) (xy 213.579456 -46.37151) (xy 213.571582 -46.377352) (xy 213.561168 -46.394878)
			(xy 213.54796 -46.485302) (xy 213.552786 -46.504606) (xy 213.558628 -46.51248) (xy 213.558628 -46.512734)
			(xy 213.576125 -46.537482) (xy 213.603931 -46.591333) (xy 213.622869 -46.648904) (xy 213.630072 -46.693836)
			(xy 218.776296 -46.693836) (xy 218.776782 -46.666585) (xy 218.784538 -46.612637) (xy 218.799893 -46.560342)
			(xy 218.822535 -46.510765) (xy 218.852001 -46.464915) (xy 218.887692 -46.423724) (xy 218.928883 -46.388033)
			(xy 218.974733 -46.358567) (xy 219.02431 -46.335925) (xy 219.076605 -46.32057) (xy 219.130553 -46.312814)
			(xy 219.185055 -46.312814) (xy 219.239003 -46.32057) (xy 219.291298 -46.335925) (xy 219.340875 -46.358567)
			(xy 219.386725 -46.388033) (xy 219.427916 -46.423724) (xy 219.463607 -46.464915) (xy 219.493073 -46.510765)
			(xy 219.515715 -46.560342) (xy 219.53107 -46.612637) (xy 219.538826 -46.666585) (xy 219.539312 -46.693836)
			(xy 219.538838 -46.720263) (xy 219.531528 -46.772611) (xy 219.517056 -46.823446) (xy 219.495696 -46.871793)
			(xy 219.482162 -46.894496) (xy 219.481908 -46.89475) (xy 219.476571 -46.904768) (xy 219.474316 -46.927318)
			(xy 219.47759 -46.938184) (xy 219.503752 -47.01286) (xy 219.508136 -47.023375) (xy 219.524225 -47.039464)
			(xy 219.53474 -47.043848) (xy 219.534994 -47.043848) (xy 219.559513 -47.052891) (xy 219.605964 -47.076839)
			(xy 219.648715 -47.106899) (xy 219.686965 -47.142511) (xy 219.72 -47.183007) (xy 219.747202 -47.227631)
			(xy 219.768063 -47.275548) (xy 219.782192 -47.325863) (xy 219.789325 -47.377635) (xy 219.789756 -47.403766)
			(xy 219.78927 -47.431017) (xy 219.781514 -47.484965) (xy 219.766159 -47.53726) (xy 219.743517 -47.586837)
			(xy 219.714051 -47.632687) (xy 219.67836 -47.673878) (xy 219.637169 -47.709569) (xy 219.591319 -47.739035)
			(xy 219.541742 -47.761677) (xy 219.489447 -47.777032) (xy 219.435499 -47.784788) (xy 219.380997 -47.784788)
			(xy 219.327049 -47.777032) (xy 219.274754 -47.761677) (xy 219.225177 -47.739035) (xy 219.179327 -47.709569)
			(xy 219.138136 -47.673878) (xy 219.102445 -47.632687) (xy 219.072979 -47.586837) (xy 219.050337 -47.53726)
			(xy 219.034982 -47.484965) (xy 219.027226 -47.431017) (xy 219.02674 -47.403766) (xy 219.027208 -47.377338)
			(xy 219.034518 -47.324991) (xy 219.048993 -47.274155) (xy 219.070354 -47.225809) (xy 219.08389 -47.203106)
			(xy 219.084144 -47.202852) (xy 219.089479 -47.192833) (xy 219.091738 -47.170284) (xy 219.088462 -47.159418)
			(xy 219.0623 -47.084742) (xy 219.057937 -47.074216) (xy 219.041834 -47.058131) (xy 219.031312 -47.053754)
			(xy 219.031058 -47.053754) (xy 219.006551 -47.04468) (xy 218.960098 -47.020739) (xy 218.917346 -46.990683)
			(xy 218.879094 -46.955077) (xy 218.846057 -46.914584) (xy 218.818854 -46.869964) (xy 218.797991 -46.822049)
			(xy 218.783861 -46.771736) (xy 218.776727 -46.719966) (xy 218.776296 -46.693836) (xy 213.630072 -46.693836)
			(xy 213.632462 -46.708745) (xy 213.63305 -46.739048) (xy 213.632567 -46.766299) (xy 213.624805 -46.820244)
			(xy 213.609446 -46.872536) (xy 213.586802 -46.922111) (xy 213.557335 -46.967959) (xy 213.521643 -47.009148)
			(xy 213.480454 -47.044838) (xy 213.434606 -47.074305) (xy 213.385031 -47.096948) (xy 213.332738 -47.112306)
			(xy 213.278793 -47.120067) (xy 213.251542 -47.120556) (xy 213.225508 -47.120134) (xy 213.173924 -47.11304)
			(xy 213.123782 -47.099005) (xy 213.076011 -47.078288) (xy 213.031498 -47.051275) (xy 213.011004 -47.035212)
			(xy 213.003253 -47.029461) (xy 212.984838 -47.023726) (xy 212.97519 -47.024036) (xy 212.895434 -47.030386)
			(xy 212.877654 -47.039022) (xy 212.871304 -47.046388) (xy 212.853144 -47.066054) (xy 212.812232 -47.100574)
			(xy 212.766898 -47.129041) (xy 212.718033 -47.150895) (xy 212.666593 -47.165708) (xy 212.613589 -47.17319)
			(xy 212.586824 -47.173642) (xy 212.559575 -47.1731) (xy 212.505631 -47.165347) (xy 212.453339 -47.149997)
			(xy 212.403765 -47.127361) (xy 212.357916 -47.0979) (xy 212.316726 -47.062215) (xy 212.281034 -47.021031)
			(xy 212.251567 -46.975186) (xy 212.228923 -46.925615) (xy 212.213565 -46.873326) (xy 212.205805 -46.819383)
			(xy 212.205316 -46.792134) (xy 212.205836 -46.76336) (xy 212.214488 -46.706465) (xy 212.231585 -46.651515)
			(xy 212.256739 -46.599754) (xy 212.289381 -46.552359) (xy 212.308694 -46.531022) (xy 212.31606 -46.523148)
			(xy 212.323172 -46.503336) (xy 212.315806 -46.40707) (xy 212.3059 -46.388274) (xy 212.297518 -46.38167)
			(xy 212.275333 -46.363446) (xy 212.236123 -46.32151) (xy 212.203638 -46.274174) (xy 212.178609 -46.222506)
			(xy 212.161603 -46.167672) (xy 212.153002 -46.110909) (xy 212.152484 -46.082204) (xy 206.868268 -46.082204)
			(xy 206.868268 -48.30699) (xy 218.653866 -48.30699) (xy 218.657937 -48.251368) (xy 218.670063 -48.196931)
			(xy 218.689986 -48.14484) (xy 218.717282 -48.096205) (xy 218.751368 -48.052062) (xy 218.791517 -48.013353)
			(xy 218.836875 -47.980902) (xy 218.886475 -47.955401) (xy 218.939259 -47.937394) (xy 218.994102 -47.927264)
			(xy 219.049836 -47.925227) (xy 219.105273 -47.931327) (xy 219.15923 -47.945433) (xy 219.210559 -47.967245)
			(xy 219.258165 -47.996299) (xy 219.301033 -48.031974) (xy 219.33825 -48.073511) (xy 219.369023 -48.120024)
			(xy 219.392695 -48.170521) (xy 219.408763 -48.223928) (xy 219.416883 -48.279104) (xy 219.417392 -48.30699)
			(xy 219.416883 -48.334876) (xy 219.408763 -48.390052) (xy 219.392695 -48.443459) (xy 219.369023 -48.493956)
			(xy 219.33825 -48.540469) (xy 219.301033 -48.582006) (xy 219.258165 -48.617681) (xy 219.210559 -48.646735)
			(xy 219.15923 -48.668547) (xy 219.105273 -48.682653) (xy 219.049836 -48.688753) (xy 218.994102 -48.686716)
			(xy 218.939259 -48.676586) (xy 218.886475 -48.658579) (xy 218.836875 -48.633078) (xy 218.791517 -48.600627)
			(xy 218.751368 -48.561918) (xy 218.717282 -48.517775) (xy 218.689986 -48.46914) (xy 218.670063 -48.417049)
			(xy 218.657937 -48.362612) (xy 218.653866 -48.30699) (xy 206.868268 -48.30699) (xy 206.868268 -48.753014)
			(xy 215.2683 -48.753014) (xy 215.272371 -48.697392) (xy 215.284497 -48.642955) (xy 215.30442 -48.590864)
			(xy 215.331716 -48.542229) (xy 215.365802 -48.498086) (xy 215.405951 -48.459377) (xy 215.451309 -48.426926)
			(xy 215.500909 -48.401425) (xy 215.553693 -48.383418) (xy 215.608536 -48.373288) (xy 215.66427 -48.371251)
			(xy 215.719707 -48.377351) (xy 215.773664 -48.391457) (xy 215.824993 -48.413269) (xy 215.872599 -48.442323)
			(xy 215.915467 -48.477998) (xy 215.952684 -48.519535) (xy 215.983457 -48.566048) (xy 216.007129 -48.616545)
			(xy 216.023197 -48.669952) (xy 216.031317 -48.725128) (xy 216.031826 -48.753014) (xy 216.031317 -48.7809)
			(xy 216.023197 -48.836076) (xy 216.020753 -48.8442) (xy 216.287348 -48.8442) (xy 216.291419 -48.788578)
			(xy 216.303545 -48.734141) (xy 216.323468 -48.68205) (xy 216.350764 -48.633415) (xy 216.38485 -48.589272)
			(xy 216.424999 -48.550563) (xy 216.470357 -48.518112) (xy 216.519957 -48.492611) (xy 216.572741 -48.474604)
			(xy 216.627584 -48.464474) (xy 216.683318 -48.462437) (xy 216.738755 -48.468537) (xy 216.792712 -48.482643)
			(xy 216.844041 -48.504455) (xy 216.891647 -48.533509) (xy 216.934515 -48.569184) (xy 216.971732 -48.610721)
			(xy 217.002505 -48.657234) (xy 217.026177 -48.707731) (xy 217.042245 -48.761138) (xy 217.050365 -48.816314)
			(xy 217.050874 -48.8442) (xy 217.050365 -48.872086) (xy 217.047367 -48.89246) (xy 217.314016 -48.89246)
			(xy 217.318087 -48.836838) (xy 217.330213 -48.782401) (xy 217.350136 -48.73031) (xy 217.377432 -48.681675)
			(xy 217.411518 -48.637532) (xy 217.451667 -48.598823) (xy 217.497025 -48.566372) (xy 217.546625 -48.540871)
			(xy 217.599409 -48.522864) (xy 217.654252 -48.512734) (xy 217.709986 -48.510697) (xy 217.765423 -48.516797)
			(xy 217.81938 -48.530903) (xy 217.870709 -48.552715) (xy 217.918315 -48.581769) (xy 217.961183 -48.617444)
			(xy 217.9984 -48.658981) (xy 218.029173 -48.705494) (xy 218.052845 -48.755991) (xy 218.068913 -48.809398)
			(xy 218.077033 -48.864574) (xy 218.077542 -48.89246) (xy 218.077033 -48.920346) (xy 218.074595 -48.93691)
			(xy 221.033084 -48.93691) (xy 221.037155 -48.881288) (xy 221.049281 -48.826851) (xy 221.069204 -48.77476)
			(xy 221.0965 -48.726125) (xy 221.130586 -48.681982) (xy 221.170735 -48.643273) (xy 221.216093 -48.610822)
			(xy 221.265693 -48.585321) (xy 221.318477 -48.567314) (xy 221.37332 -48.557184) (xy 221.429054 -48.555147)
			(xy 221.484491 -48.561247) (xy 221.538448 -48.575353) (xy 221.589777 -48.597165) (xy 221.637383 -48.626219)
			(xy 221.680251 -48.661894) (xy 221.717468 -48.703431) (xy 221.748241 -48.749944) (xy 221.771913 -48.800441)
			(xy 221.787981 -48.853848) (xy 221.796101 -48.909024) (xy 221.79661 -48.93691) (xy 221.796101 -48.964796)
			(xy 221.787981 -49.019972) (xy 221.771913 -49.073379) (xy 221.748241 -49.123876) (xy 221.717468 -49.170389)
			(xy 221.680251 -49.211926) (xy 221.637383 -49.247601) (xy 221.589777 -49.276655) (xy 221.538448 -49.298467)
			(xy 221.484491 -49.312573) (xy 221.429054 -49.318673) (xy 221.37332 -49.316636) (xy 221.318477 -49.306506)
			(xy 221.265693 -49.288499) (xy 221.216093 -49.262998) (xy 221.170735 -49.230547) (xy 221.130586 -49.191838)
			(xy 221.0965 -49.147695) (xy 221.069204 -49.09906) (xy 221.049281 -49.046969) (xy 221.037155 -48.992532)
			(xy 221.033084 -48.93691) (xy 218.074595 -48.93691) (xy 218.068913 -48.975522) (xy 218.052845 -49.028929)
			(xy 218.029173 -49.079426) (xy 217.9984 -49.125939) (xy 217.961183 -49.167476) (xy 217.918315 -49.203151)
			(xy 217.870709 -49.232205) (xy 217.81938 -49.254017) (xy 217.765423 -49.268123) (xy 217.709986 -49.274223)
			(xy 217.654252 -49.272186) (xy 217.599409 -49.262056) (xy 217.546625 -49.244049) (xy 217.497025 -49.218548)
			(xy 217.451667 -49.186097) (xy 217.411518 -49.147388) (xy 217.377432 -49.103245) (xy 217.350136 -49.05461)
			(xy 217.330213 -49.002519) (xy 217.318087 -48.948082) (xy 217.314016 -48.89246) (xy 217.047367 -48.89246)
			(xy 217.042245 -48.927262) (xy 217.026177 -48.980669) (xy 217.002505 -49.031166) (xy 216.971732 -49.077679)
			(xy 216.934515 -49.119216) (xy 216.891647 -49.154891) (xy 216.844041 -49.183945) (xy 216.792712 -49.205757)
			(xy 216.738755 -49.219863) (xy 216.683318 -49.225963) (xy 216.627584 -49.223926) (xy 216.572741 -49.213796)
			(xy 216.519957 -49.195789) (xy 216.470357 -49.170288) (xy 216.424999 -49.137837) (xy 216.38485 -49.099128)
			(xy 216.350764 -49.054985) (xy 216.323468 -49.00635) (xy 216.303545 -48.954259) (xy 216.291419 -48.899822)
			(xy 216.287348 -48.8442) (xy 216.020753 -48.8442) (xy 216.007129 -48.889483) (xy 215.983457 -48.93998)
			(xy 215.952684 -48.986493) (xy 215.915467 -49.02803) (xy 215.872599 -49.063705) (xy 215.824993 -49.092759)
			(xy 215.773664 -49.114571) (xy 215.719707 -49.128677) (xy 215.66427 -49.134777) (xy 215.608536 -49.13274)
			(xy 215.553693 -49.12261) (xy 215.500909 -49.104603) (xy 215.451309 -49.079102) (xy 215.405951 -49.046651)
			(xy 215.365802 -49.007942) (xy 215.331716 -48.963799) (xy 215.30442 -48.915164) (xy 215.284497 -48.863073)
			(xy 215.272371 -48.808636) (xy 215.2683 -48.753014) (xy 206.868268 -48.753014) (xy 206.868268 -49.95291)
			(xy 221.033084 -49.95291) (xy 221.037155 -49.897288) (xy 221.049281 -49.842851) (xy 221.069204 -49.79076)
			(xy 221.0965 -49.742125) (xy 221.130586 -49.697982) (xy 221.170735 -49.659273) (xy 221.216093 -49.626822)
			(xy 221.265693 -49.601321) (xy 221.318477 -49.583314) (xy 221.37332 -49.573184) (xy 221.429054 -49.571147)
			(xy 221.484491 -49.577247) (xy 221.538448 -49.591353) (xy 221.589777 -49.613165) (xy 221.637383 -49.642219)
			(xy 221.680251 -49.677894) (xy 221.717468 -49.719431) (xy 221.748241 -49.765944) (xy 221.771913 -49.816441)
			(xy 221.787981 -49.869848) (xy 221.796101 -49.925024) (xy 221.79661 -49.95291) (xy 221.796101 -49.980796)
			(xy 221.787981 -50.035972) (xy 221.771913 -50.089379) (xy 221.748241 -50.139876) (xy 221.717468 -50.186389)
			(xy 221.680251 -50.227926) (xy 221.637383 -50.263601) (xy 221.589777 -50.292655) (xy 221.538448 -50.314467)
			(xy 221.484491 -50.328573) (xy 221.429054 -50.334673) (xy 221.37332 -50.332636) (xy 221.318477 -50.322506)
			(xy 221.265693 -50.304499) (xy 221.216093 -50.278998) (xy 221.170735 -50.246547) (xy 221.130586 -50.207838)
			(xy 221.0965 -50.163695) (xy 221.069204 -50.11506) (xy 221.049281 -50.062969) (xy 221.037155 -50.008532)
			(xy 221.033084 -49.95291) (xy 206.868268 -49.95291) (xy 206.868268 -51.019456) (xy 218.849446 -51.019456)
			(xy 218.853517 -50.963834) (xy 218.865643 -50.909397) (xy 218.885566 -50.857306) (xy 218.912862 -50.808671)
			(xy 218.946948 -50.764528) (xy 218.987097 -50.725819) (xy 219.032455 -50.693368) (xy 219.082055 -50.667867)
			(xy 219.134839 -50.64986) (xy 219.189682 -50.63973) (xy 219.245416 -50.637693) (xy 219.300853 -50.643793)
			(xy 219.35481 -50.657899) (xy 219.406139 -50.679711) (xy 219.453745 -50.708765) (xy 219.496613 -50.74444)
			(xy 219.53383 -50.785977) (xy 219.564603 -50.83249) (xy 219.588275 -50.882987) (xy 219.604343 -50.936394)
			(xy 219.612463 -50.99157) (xy 219.612972 -51.019456) (xy 219.612463 -51.047342) (xy 219.604343 -51.102518)
			(xy 219.588275 -51.155925) (xy 219.564603 -51.206422) (xy 219.53383 -51.252935) (xy 219.496613 -51.294472)
			(xy 219.453745 -51.330147) (xy 219.406139 -51.359201) (xy 219.35481 -51.381013) (xy 219.300853 -51.395119)
			(xy 219.245416 -51.401219) (xy 219.189682 -51.399182) (xy 219.134839 -51.389052) (xy 219.082055 -51.371045)
			(xy 219.032455 -51.345544) (xy 218.987097 -51.313093) (xy 218.946948 -51.274384) (xy 218.912862 -51.230241)
			(xy 218.885566 -51.181606) (xy 218.865643 -51.129515) (xy 218.853517 -51.075078) (xy 218.849446 -51.019456)
			(xy 206.868268 -51.019456) (xy 206.868268 -52.035456) (xy 221.041212 -52.035456) (xy 221.045283 -51.979834)
			(xy 221.057409 -51.925397) (xy 221.077332 -51.873306) (xy 221.104628 -51.824671) (xy 221.138714 -51.780528)
			(xy 221.178863 -51.741819) (xy 221.224221 -51.709368) (xy 221.273821 -51.683867) (xy 221.326605 -51.66586)
			(xy 221.381448 -51.65573) (xy 221.437182 -51.653693) (xy 221.492619 -51.659793) (xy 221.546576 -51.673899)
			(xy 221.597905 -51.695711) (xy 221.645511 -51.724765) (xy 221.688379 -51.76044) (xy 221.725596 -51.801977)
			(xy 221.756369 -51.84849) (xy 221.780041 -51.898987) (xy 221.796109 -51.952394) (xy 221.804229 -52.00757)
			(xy 221.804738 -52.035456) (xy 221.804229 -52.063342) (xy 221.796109 -52.118518) (xy 221.780041 -52.171925)
			(xy 221.756369 -52.222422) (xy 221.725596 -52.268935) (xy 221.688379 -52.310472) (xy 221.645511 -52.346147)
			(xy 221.597905 -52.375201) (xy 221.546576 -52.397013) (xy 221.492619 -52.411119) (xy 221.437182 -52.417219)
			(xy 221.381448 -52.415182) (xy 221.326605 -52.405052) (xy 221.273821 -52.387045) (xy 221.224221 -52.361544)
			(xy 221.178863 -52.329093) (xy 221.138714 -52.290384) (xy 221.104628 -52.246241) (xy 221.077332 -52.197606)
			(xy 221.057409 -52.145515) (xy 221.045283 -52.091078) (xy 221.041212 -52.035456) (xy 206.868268 -52.035456)
			(xy 206.868268 -54.731412) (xy 207.620616 -54.731412) (xy 207.621085 -54.704042) (xy 207.628902 -54.649863)
			(xy 207.64439 -54.597359) (xy 207.667231 -54.547613) (xy 207.696955 -54.501646) (xy 207.714596 -54.480714)
			(xy 207.71485 -54.48046) (xy 207.720424 -54.473365) (xy 207.726677 -54.456454) (xy 207.727042 -54.44744)
			(xy 207.727042 -54.380384) (xy 207.726705 -54.371365) (xy 207.720445 -54.354447) (xy 207.71485 -54.347364)
			(xy 207.714596 -54.347364) (xy 207.714596 -54.34711) (xy 207.696968 -54.326167) (xy 207.667245 -54.2802)
			(xy 207.644401 -54.230456) (xy 207.628905 -54.177955) (xy 207.621076 -54.123779) (xy 207.621075 -54.069039)
			(xy 207.628902 -54.014862) (xy 207.644395 -53.962361) (xy 207.667237 -53.912616) (xy 207.696957 -53.866647)
			(xy 207.714596 -53.845714) (xy 207.71485 -53.84546) (xy 207.720424 -53.838365) (xy 207.726677 -53.821454)
			(xy 207.727042 -53.81244) (xy 207.727042 -53.745384) (xy 207.726705 -53.736365) (xy 207.720445 -53.719447)
			(xy 207.71485 -53.712364) (xy 207.714596 -53.712364) (xy 207.714596 -53.71211) (xy 207.696968 -53.691167)
			(xy 207.667245 -53.6452) (xy 207.644401 -53.595456) (xy 207.628905 -53.542955) (xy 207.621076 -53.488779)
			(xy 207.621075 -53.434039) (xy 207.628902 -53.379862) (xy 207.644395 -53.327361) (xy 207.667237 -53.277616)
			(xy 207.696957 -53.231647) (xy 207.714596 -53.210714) (xy 207.71485 -53.21046) (xy 207.720424 -53.203365)
			(xy 207.726677 -53.186454) (xy 207.727042 -53.17744) (xy 207.727042 -53.110384) (xy 207.726705 -53.101365)
			(xy 207.720445 -53.084447) (xy 207.71485 -53.077364) (xy 207.714596 -53.077364) (xy 207.714596 -53.07711)
			(xy 207.696948 -53.056186) (xy 207.667237 -53.010211) (xy 207.644403 -52.960461) (xy 207.628914 -52.907959)
			(xy 207.621089 -52.853782) (xy 207.620616 -52.826412) (xy 207.621102 -52.799161) (xy 207.628858 -52.745213)
			(xy 207.644213 -52.692918) (xy 207.666855 -52.643341) (xy 207.696321 -52.597491) (xy 207.732012 -52.5563)
			(xy 207.773203 -52.520609) (xy 207.819053 -52.491143) (xy 207.86863 -52.468501) (xy 207.920925 -52.453146)
			(xy 207.974873 -52.44539) (xy 208.029375 -52.44539) (xy 208.083323 -52.453146) (xy 208.135618 -52.468501)
			(xy 208.185195 -52.491143) (xy 208.231045 -52.520609) (xy 208.272236 -52.5563) (xy 208.307927 -52.597491)
			(xy 208.337393 -52.643341) (xy 208.360035 -52.692918) (xy 208.37539 -52.745213) (xy 208.383146 -52.799161)
			(xy 208.383632 -52.826412) (xy 208.38319 -52.853783) (xy 208.375369 -52.907964) (xy 208.359875 -52.960468)
			(xy 208.337027 -53.010215) (xy 208.307297 -53.05618) (xy 208.289652 -53.07711) (xy 208.289398 -53.077364)
			(xy 208.28382 -53.084457) (xy 208.277568 -53.101369) (xy 208.277206 -53.110384) (xy 208.277206 -53.17744)
			(xy 208.277543 -53.186459) (xy 208.283804 -53.203376) (xy 208.289398 -53.21046) (xy 208.289652 -53.21046)
			(xy 208.289652 -53.210714) (xy 208.307305 -53.231637) (xy 208.337031 -53.277606) (xy 208.359877 -53.327354)
			(xy 208.375373 -53.379857) (xy 208.383201 -53.434038) (xy 208.3832 -53.48878) (xy 208.37537 -53.54296)
			(xy 208.359871 -53.595463) (xy 208.337023 -53.64521) (xy 208.307294 -53.691178) (xy 208.289652 -53.71211)
			(xy 208.289398 -53.712364) (xy 208.28382 -53.719457) (xy 208.277568 -53.736369) (xy 208.277206 -53.745384)
			(xy 208.277206 -53.81244) (xy 208.277543 -53.821459) (xy 208.283804 -53.838376) (xy 208.289398 -53.84546)
			(xy 208.289652 -53.84546) (xy 208.289652 -53.845714) (xy 208.307305 -53.866637) (xy 208.337031 -53.912606)
			(xy 208.359877 -53.962354) (xy 208.375373 -54.014857) (xy 208.383201 -54.069038) (xy 208.3832 -54.12378)
			(xy 208.37537 -54.17796) (xy 208.359871 -54.230463) (xy 208.337023 -54.28021) (xy 208.307294 -54.326178)
			(xy 208.289652 -54.34711) (xy 208.289398 -54.347364) (xy 208.28382 -54.354457) (xy 208.277568 -54.371369)
			(xy 208.277206 -54.380384) (xy 208.277206 -54.44744) (xy 208.277543 -54.456459) (xy 208.283804 -54.473376)
			(xy 208.289398 -54.48046) (xy 208.289652 -54.48046) (xy 208.289652 -54.480714) (xy 208.307257 -54.501674)
			(xy 208.336975 -54.547638) (xy 208.359819 -54.597379) (xy 208.375318 -54.649873) (xy 208.383154 -54.704045)
			(xy 208.383632 -54.731412) (xy 208.383146 -54.758663) (xy 208.378482 -54.791102) (xy 210.27644 -54.791102)
			(xy 210.276897 -54.763731) (xy 210.284716 -54.709552) (xy 210.300206 -54.657048) (xy 210.32305 -54.607301)
			(xy 210.352777 -54.561335) (xy 210.37042 -54.540404) (xy 210.370674 -54.54015) (xy 210.376254 -54.53306)
			(xy 210.382503 -54.516145) (xy 210.382866 -54.50713) (xy 210.382866 -54.440074) (xy 210.382529 -54.431055)
			(xy 210.376268 -54.414138) (xy 210.370674 -54.407054) (xy 210.37042 -54.407054) (xy 210.37042 -54.4068)
			(xy 210.352782 -54.385866) (xy 210.323057 -54.339898) (xy 210.300212 -54.290152) (xy 210.284716 -54.23765)
			(xy 210.276887 -54.183472) (xy 210.276887 -54.128731) (xy 210.284715 -54.074553) (xy 210.300211 -54.022051)
			(xy 210.323056 -53.972305) (xy 210.35278 -53.926337) (xy 210.37042 -53.905404) (xy 210.370674 -53.90515)
			(xy 210.376254 -53.89806) (xy 210.382503 -53.881145) (xy 210.382866 -53.87213) (xy 210.382866 -53.805074)
			(xy 210.382529 -53.796055) (xy 210.376268 -53.779138) (xy 210.370674 -53.772054) (xy 210.37042 -53.772054)
			(xy 210.37042 -53.7718) (xy 210.352782 -53.750866) (xy 210.323057 -53.704898) (xy 210.300212 -53.655152)
			(xy 210.284716 -53.60265) (xy 210.276887 -53.548472) (xy 210.276887 -53.493731) (xy 210.284715 -53.439553)
			(xy 210.300211 -53.387051) (xy 210.323056 -53.337305) (xy 210.35278 -53.291337) (xy 210.37042 -53.270404)
			(xy 210.370674 -53.27015) (xy 210.376254 -53.26306) (xy 210.382503 -53.246145) (xy 210.382866 -53.23713)
			(xy 210.382866 -53.170074) (xy 210.382529 -53.161055) (xy 210.376268 -53.144138) (xy 210.370674 -53.137054)
			(xy 210.37042 -53.137054) (xy 210.37042 -53.1368) (xy 210.352771 -53.115876) (xy 210.32306 -53.069901)
			(xy 210.300225 -53.020152) (xy 210.284737 -52.967649) (xy 210.276912 -52.913472) (xy 210.27644 -52.886102)
			(xy 210.276926 -52.858851) (xy 210.284682 -52.804903) (xy 210.300037 -52.752608) (xy 210.322679 -52.703031)
			(xy 210.352145 -52.657181) (xy 210.387836 -52.61599) (xy 210.429027 -52.580299) (xy 210.474877 -52.550833)
			(xy 210.524454 -52.528191) (xy 210.576749 -52.512836) (xy 210.630697 -52.50508) (xy 210.685199 -52.50508)
			(xy 210.739147 -52.512836) (xy 210.791442 -52.528191) (xy 210.830551 -52.546052) (xy 215.779573 -52.546052)
			(xy 215.779573 -52.491548) (xy 215.78733 -52.4376) (xy 215.802686 -52.385304) (xy 215.825327 -52.335726)
			(xy 215.854794 -52.289875) (xy 215.890487 -52.248684) (xy 215.931678 -52.212992) (xy 215.977529 -52.183525)
			(xy 216.027108 -52.160884) (xy 216.079403 -52.145529) (xy 216.133352 -52.137773) (xy 216.160604 -52.13731)
			(xy 216.187974 -52.137771) (xy 216.242154 -52.14559) (xy 216.294657 -52.16108) (xy 216.344404 -52.183923)
			(xy 216.39037 -52.213648) (xy 216.411302 -52.23129) (xy 216.411556 -52.231544) (xy 216.418647 -52.237124)
			(xy 216.435561 -52.243373) (xy 216.444576 -52.243736) (xy 216.511632 -52.243736) (xy 216.520649 -52.243387)
			(xy 216.537566 -52.237133) (xy 216.544652 -52.231544) (xy 216.544652 -52.23129) (xy 216.544906 -52.23129)
			(xy 216.565839 -52.213649) (xy 216.611807 -52.183925) (xy 216.661553 -52.161079) (xy 216.714055 -52.145583)
			(xy 216.768233 -52.137754) (xy 216.822975 -52.137754) (xy 216.877153 -52.145583) (xy 216.929655 -52.161079)
			(xy 216.979401 -52.183925) (xy 217.025369 -52.213649) (xy 217.046302 -52.23129) (xy 217.046556 -52.231544)
			(xy 217.053647 -52.237124) (xy 217.070561 -52.243373) (xy 217.079576 -52.243736) (xy 217.146632 -52.243736)
			(xy 217.155649 -52.243387) (xy 217.172566 -52.237133) (xy 217.179652 -52.231544) (xy 217.179652 -52.23129)
			(xy 217.179906 -52.23129) (xy 217.200824 -52.213633) (xy 217.246801 -52.183924) (xy 217.296552 -52.161092)
			(xy 217.349056 -52.145605) (xy 217.403234 -52.137782) (xy 217.430604 -52.13731) (xy 217.457856 -52.13776)
			(xy 217.511806 -52.145517) (xy 217.564103 -52.160874) (xy 217.613682 -52.183516) (xy 217.659534 -52.212984)
			(xy 217.700726 -52.248677) (xy 217.736419 -52.289869) (xy 217.765886 -52.335722) (xy 217.788528 -52.385301)
			(xy 217.803883 -52.437598) (xy 217.81164 -52.491548) (xy 217.81164 -52.546052) (xy 217.805695 -52.587398)
			(xy 218.855288 -52.587398) (xy 218.859359 -52.531776) (xy 218.871485 -52.477339) (xy 218.891408 -52.425248)
			(xy 218.918704 -52.376613) (xy 218.95279 -52.33247) (xy 218.992939 -52.293761) (xy 219.038297 -52.26131)
			(xy 219.087897 -52.235809) (xy 219.140681 -52.217802) (xy 219.195524 -52.207672) (xy 219.251258 -52.205635)
			(xy 219.306695 -52.211735) (xy 219.360652 -52.225841) (xy 219.411981 -52.247653) (xy 219.459587 -52.276707)
			(xy 219.502455 -52.312382) (xy 219.539672 -52.353919) (xy 219.570445 -52.400432) (xy 219.594117 -52.450929)
			(xy 219.610185 -52.504336) (xy 219.618305 -52.559512) (xy 219.618814 -52.587398) (xy 219.618305 -52.615284)
			(xy 219.610185 -52.67046) (xy 219.594117 -52.723867) (xy 219.570445 -52.774364) (xy 219.539672 -52.820877)
			(xy 219.502455 -52.862414) (xy 219.459587 -52.898089) (xy 219.411981 -52.927143) (xy 219.360652 -52.948955)
			(xy 219.306695 -52.963061) (xy 219.251258 -52.969161) (xy 219.195524 -52.967124) (xy 219.140681 -52.956994)
			(xy 219.087897 -52.938987) (xy 219.038297 -52.913486) (xy 218.992939 -52.881035) (xy 218.95279 -52.842326)
			(xy 218.918704 -52.798183) (xy 218.891408 -52.749548) (xy 218.871485 -52.697457) (xy 218.859359 -52.64302)
			(xy 218.855288 -52.587398) (xy 217.805695 -52.587398) (xy 217.803883 -52.600002) (xy 217.788528 -52.652299)
			(xy 217.765886 -52.701878) (xy 217.736419 -52.747731) (xy 217.700726 -52.788923) (xy 217.659534 -52.824616)
			(xy 217.613682 -52.854084) (xy 217.564103 -52.876726) (xy 217.511806 -52.892083) (xy 217.457856 -52.89984)
			(xy 217.430604 -52.900326) (xy 217.403233 -52.899876) (xy 217.349053 -52.892057) (xy 217.296549 -52.876565)
			(xy 217.246802 -52.853719) (xy 217.200836 -52.82399) (xy 217.179906 -52.806346) (xy 217.179652 -52.806092)
			(xy 217.172555 -52.80052) (xy 217.155646 -52.794265) (xy 217.146632 -52.7939) (xy 217.079576 -52.7939)
			(xy 217.070558 -52.794246) (xy 217.053641 -52.800501) (xy 217.046556 -52.806092) (xy 217.046302 -52.806346)
			(xy 217.025369 -52.823987) (xy 216.979401 -52.853711) (xy 216.929655 -52.876557) (xy 216.877153 -52.892053)
			(xy 216.822975 -52.899882) (xy 216.768233 -52.899882) (xy 216.714055 -52.892053) (xy 216.661553 -52.876557)
			(xy 216.611807 -52.853711) (xy 216.565839 -52.823987) (xy 216.544906 -52.806346) (xy 216.544652 -52.806092)
			(xy 216.537555 -52.80052) (xy 216.520646 -52.794265) (xy 216.511632 -52.7939) (xy 216.444576 -52.7939)
			(xy 216.435558 -52.794246) (xy 216.418641 -52.800501) (xy 216.411556 -52.806092) (xy 216.411556 -52.806346)
			(xy 216.411302 -52.806346) (xy 216.390373 -52.823989) (xy 216.3444 -52.853702) (xy 216.294652 -52.876538)
			(xy 216.24215 -52.892028) (xy 216.187974 -52.899854) (xy 216.160604 -52.900326) (xy 216.133352 -52.899827)
			(xy 216.079403 -52.892071) (xy 216.027108 -52.876716) (xy 215.977529 -52.854075) (xy 215.931678 -52.824608)
			(xy 215.890487 -52.788916) (xy 215.854794 -52.747725) (xy 215.825327 -52.701874) (xy 215.802686 -52.652296)
			(xy 215.78733 -52.6) (xy 215.779573 -52.546052) (xy 210.830551 -52.546052) (xy 210.841019 -52.550833)
			(xy 210.886869 -52.580299) (xy 210.92806 -52.61599) (xy 210.963751 -52.657181) (xy 210.993217 -52.703031)
			(xy 211.015859 -52.752608) (xy 211.031214 -52.804903) (xy 211.03897 -52.858851) (xy 211.039456 -52.886102)
			(xy 211.039002 -52.913473) (xy 211.031183 -52.967653) (xy 211.015692 -53.020156) (xy 210.992847 -53.069903)
			(xy 210.963119 -53.115869) (xy 210.945476 -53.1368) (xy 210.945222 -53.137054) (xy 210.939639 -53.144143)
			(xy 210.933392 -53.161058) (xy 210.93303 -53.170074) (xy 210.93303 -53.23713) (xy 210.933366 -53.246149)
			(xy 210.939627 -53.263066) (xy 210.945222 -53.27015) (xy 210.945476 -53.27015) (xy 210.945476 -53.270404)
			(xy 210.963119 -53.291335) (xy 210.992843 -53.337303) (xy 211.015688 -53.38705) (xy 211.031184 -53.439552)
			(xy 211.039012 -53.493731) (xy 211.039012 -53.548472) (xy 211.031183 -53.602651) (xy 211.015687 -53.655153)
			(xy 210.992842 -53.704899) (xy 210.963117 -53.750867) (xy 210.946546 -53.77053) (xy 211.310728 -53.77053)
			(xy 211.311257 -53.741613) (xy 211.319983 -53.684442) (xy 211.337238 -53.629243) (xy 211.362627 -53.577281)
			(xy 211.395569 -53.529747) (xy 211.435309 -53.48773) (xy 211.457794 -53.46954) (xy 211.466572 -53.461905)
			(xy 211.476772 -53.441025) (xy 211.477352 -53.429408) (xy 211.477352 -53.349652) (xy 211.476843 -53.338016)
			(xy 211.466635 -53.317106) (xy 211.457794 -53.30952) (xy 211.435319 -53.291319) (xy 211.395583 -53.249301)
			(xy 211.362644 -53.201768) (xy 211.337254 -53.149809) (xy 211.319996 -53.094613) (xy 211.311264 -53.037445)
			(xy 211.310728 -53.00853) (xy 211.311183 -52.981276) (xy 211.318937 -52.927323) (xy 211.334291 -52.875023)
			(xy 211.356933 -52.825441) (xy 211.386401 -52.779586) (xy 211.422096 -52.738392) (xy 211.46329 -52.702697)
			(xy 211.509146 -52.67323) (xy 211.558729 -52.650589) (xy 211.611029 -52.635236) (xy 211.664982 -52.627483)
			(xy 211.692236 -52.627022) (xy 211.718551 -52.627458) (xy 211.770681 -52.634699) (xy 211.821325 -52.649023)
			(xy 211.869524 -52.670162) (xy 211.914367 -52.697713) (xy 211.955005 -52.731158) (xy 211.97316 -52.750212)
			(xy 211.980693 -52.7576) (xy 211.999964 -52.766132) (xy 212.010498 -52.766722) (xy 212.085174 -52.766722)
			(xy 212.095723 -52.766186) (xy 212.115018 -52.757655) (xy 212.122512 -52.750212) (xy 212.140671 -52.73116)
			(xy 212.1813 -52.697702) (xy 212.226139 -52.670142) (xy 212.274339 -52.649003) (xy 212.324986 -52.634685)
			(xy 212.37712 -52.62746) (xy 212.403436 -52.627022) (xy 212.43069 -52.627444) (xy 212.484641 -52.635207)
			(xy 212.536939 -52.650568) (xy 212.586518 -52.673215) (xy 212.63237 -52.702688) (xy 212.67356 -52.738386)
			(xy 212.709251 -52.779583) (xy 212.738716 -52.82544) (xy 212.761355 -52.875023) (xy 212.776707 -52.927324)
			(xy 212.78446 -52.981276) (xy 212.784944 -53.00853) (xy 212.784481 -53.036197) (xy 212.776476 -53.09095)
			(xy 212.760653 -53.143974) (xy 212.737342 -53.194159) (xy 212.707033 -53.240454) (xy 212.670359 -53.28189)
			(xy 212.628089 -53.317599) (xy 212.604858 -53.332634) (xy 212.595169 -53.339256) (xy 212.58273 -53.359128)
			(xy 212.580982 -53.370734) (xy 212.573108 -53.450744) (xy 212.572469 -53.462382) (xy 212.580556 -53.484219)
			(xy 212.588602 -53.492654) (xy 212.588856 -53.492908) (xy 212.607415 -53.511011) (xy 212.639997 -53.551337)
			(xy 212.666814 -53.595707) (xy 212.687371 -53.643301) (xy 212.701289 -53.693242) (xy 212.70831 -53.744608)
			(xy 212.708744 -53.77053) (xy 212.70825 -53.79778) (xy 212.700491 -53.851726) (xy 212.685133 -53.904018)
			(xy 212.662491 -53.953593) (xy 212.633025 -53.999442) (xy 212.597335 -54.040631) (xy 212.556147 -54.076322)
			(xy 212.510299 -54.105789) (xy 212.460724 -54.128431) (xy 212.408432 -54.143789) (xy 212.354486 -54.15155)
			(xy 212.327236 -54.152038) (xy 212.299866 -54.151566) (xy 212.245686 -54.143752) (xy 212.193183 -54.128265)
			(xy 212.143436 -54.105424) (xy 212.097469 -54.0757) (xy 212.076538 -54.058058) (xy 212.076284 -54.057804)
			(xy 212.069206 -54.052205) (xy 212.052283 -54.045966) (xy 212.043264 -54.045612) (xy 211.976208 -54.045612)
			(xy 211.967191 -54.04597) (xy 211.950274 -54.052217) (xy 211.943188 -54.057804) (xy 211.943188 -54.058058)
			(xy 211.942934 -54.058058) (xy 211.921995 -54.075688) (xy 211.876024 -54.105403) (xy 211.826279 -54.128241)
			(xy 211.77378 -54.143734) (xy 211.719605 -54.151564) (xy 211.692236 -54.152038) (xy 211.664985 -54.151511)
			(xy 211.611038 -54.14376) (xy 211.558743 -54.12841) (xy 211.509165 -54.105774) (xy 211.463314 -54.076312)
			(xy 211.422121 -54.040625) (xy 211.386427 -53.999439) (xy 211.356958 -53.953593) (xy 211.334313 -53.904018)
			(xy 211.318954 -53.851726) (xy 211.311193 -53.797781) (xy 211.310728 -53.77053) (xy 210.946546 -53.77053)
			(xy 210.945476 -53.7718) (xy 210.945222 -53.772054) (xy 210.939639 -53.779143) (xy 210.933392 -53.796058)
			(xy 210.93303 -53.805074) (xy 210.93303 -53.87213) (xy 210.933366 -53.881149) (xy 210.939627 -53.898066)
			(xy 210.945222 -53.90515) (xy 210.945476 -53.90515) (xy 210.945476 -53.905404) (xy 210.963119 -53.926335)
			(xy 210.992843 -53.972303) (xy 211.015688 -54.02205) (xy 211.031184 -54.074552) (xy 211.039012 -54.128731)
			(xy 211.039012 -54.183472) (xy 211.031183 -54.237651) (xy 211.015687 -54.290153) (xy 211.001895 -54.320186)
			(xy 213.23046 -54.320186) (xy 213.230903 -54.292815) (xy 213.238724 -54.238634) (xy 213.254218 -54.18613)
			(xy 213.277065 -54.136384) (xy 213.306796 -54.090418) (xy 213.32444 -54.069488) (xy 213.324694 -54.069234)
			(xy 213.330272 -54.062141) (xy 213.336524 -54.045229) (xy 213.336886 -54.036214) (xy 213.336886 -53.969158)
			(xy 213.336504 -53.960144) (xy 213.330274 -53.943226) (xy 213.324694 -53.936138) (xy 213.32444 -53.936138)
			(xy 213.32444 -53.935884) (xy 213.306833 -53.914926) (xy 213.277115 -53.868961) (xy 213.254272 -53.81922)
			(xy 213.238774 -53.766725) (xy 213.230938 -53.712553) (xy 213.23046 -53.685186) (xy 213.230946 -53.657935)
			(xy 213.238702 -53.603987) (xy 213.254057 -53.551692) (xy 213.276699 -53.502115) (xy 213.306165 -53.456265)
			(xy 213.341856 -53.415074) (xy 213.383047 -53.379383) (xy 213.428897 -53.349917) (xy 213.478474 -53.327275)
			(xy 213.530769 -53.31192) (xy 213.584717 -53.304164) (xy 213.639219 -53.304164) (xy 213.693167 -53.31192)
			(xy 213.745462 -53.327275) (xy 213.795039 -53.349917) (xy 213.840889 -53.379383) (xy 213.88208 -53.415074)
			(xy 213.917771 -53.456265) (xy 213.947237 -53.502115) (xy 213.969879 -53.551692) (xy 213.985234 -53.603987)
			(xy 213.99299 -53.657935) (xy 213.993476 -53.685186) (xy 213.993008 -53.712556) (xy 213.985191 -53.766735)
			(xy 213.969703 -53.819239) (xy 213.946862 -53.868986) (xy 213.917137 -53.914952) (xy 213.899496 -53.935884)
			(xy 213.899242 -53.936138) (xy 213.893668 -53.943233) (xy 213.887415 -53.960144) (xy 213.88705 -53.969158)
			(xy 213.88705 -54.036214) (xy 213.88739 -54.045233) (xy 213.893648 -54.06215) (xy 213.899242 -54.069234)
			(xy 213.899496 -54.069234) (xy 213.899496 -54.069488) (xy 213.917142 -54.090414) (xy 213.946853 -54.136389)
			(xy 213.969688 -54.186138) (xy 213.985177 -54.23864) (xy 213.993003 -54.292816) (xy 213.993476 -54.320186)
			(xy 213.99299 -54.347437) (xy 213.985234 -54.401385) (xy 213.969879 -54.45368) (xy 213.947237 -54.503257)
			(xy 213.917771 -54.549107) (xy 213.88208 -54.590298) (xy 213.840889 -54.625989) (xy 213.795039 -54.655455)
			(xy 213.745462 -54.678097) (xy 213.693167 -54.693452) (xy 213.639219 -54.701208) (xy 213.584717 -54.701208)
			(xy 213.530769 -54.693452) (xy 213.478474 -54.678097) (xy 213.428897 -54.655455) (xy 213.383047 -54.625989)
			(xy 213.341856 -54.590298) (xy 213.306165 -54.549107) (xy 213.276699 -54.503257) (xy 213.254057 -54.45368)
			(xy 213.238702 -54.401385) (xy 213.230946 -54.347437) (xy 213.23046 -54.320186) (xy 211.001895 -54.320186)
			(xy 210.992842 -54.339899) (xy 210.963117 -54.385867) (xy 210.945476 -54.4068) (xy 210.945222 -54.407054)
			(xy 210.939639 -54.414143) (xy 210.933392 -54.431058) (xy 210.93303 -54.440074) (xy 210.93303 -54.50713)
			(xy 210.933366 -54.516149) (xy 210.939627 -54.533066) (xy 210.945222 -54.54015) (xy 210.945476 -54.54015)
			(xy 210.945476 -54.540404) (xy 210.963127 -54.561327) (xy 210.992838 -54.607302) (xy 211.015672 -54.657052)
			(xy 211.03116 -54.709554) (xy 211.038984 -54.763732) (xy 211.039101 -54.770528) (xy 214.171022 -54.770528)
			(xy 214.171499 -54.743158) (xy 214.179313 -54.688979) (xy 214.1948 -54.636476) (xy 214.217639 -54.586729)
			(xy 214.247362 -54.540762) (xy 214.265002 -54.51983) (xy 214.265256 -54.519576) (xy 214.270865 -54.512505)
			(xy 214.277097 -54.495576) (xy 214.277448 -54.486556) (xy 214.277448 -54.4195) (xy 214.277102 -54.410482)
			(xy 214.270848 -54.393564) (xy 214.265256 -54.38648) (xy 214.265002 -54.38648) (xy 214.265002 -54.386226)
			(xy 214.247362 -54.365295) (xy 214.21765 -54.319322) (xy 214.194814 -54.269574) (xy 214.179324 -54.217073)
			(xy 214.171496 -54.162897) (xy 214.171022 -54.135528) (xy 214.171508 -54.108277) (xy 214.179264 -54.054329)
			(xy 214.194619 -54.002034) (xy 214.217261 -53.952457) (xy 214.246727 -53.906607) (xy 214.282418 -53.865416)
			(xy 214.323609 -53.829725) (xy 214.369459 -53.800259) (xy 214.419036 -53.777617) (xy 214.471331 -53.762262)
			(xy 214.525279 -53.754506) (xy 214.579781 -53.754506) (xy 214.633729 -53.762262) (xy 214.686024 -53.777617)
			(xy 214.735601 -53.800259) (xy 214.781451 -53.829725) (xy 214.822642 -53.865416) (xy 214.858333 -53.906607)
			(xy 214.887799 -53.952457) (xy 214.892874 -53.96357) (xy 218.872052 -53.96357) (xy 218.876123 -53.907948)
			(xy 218.888249 -53.853511) (xy 218.908172 -53.80142) (xy 218.935468 -53.752785) (xy 218.969554 -53.708642)
			(xy 219.009703 -53.669933) (xy 219.055061 -53.637482) (xy 219.104661 -53.611981) (xy 219.157445 -53.593974)
			(xy 219.212288 -53.583844) (xy 219.268022 -53.581807) (xy 219.323459 -53.587907) (xy 219.377416 -53.602013)
			(xy 219.428745 -53.623825) (xy 219.476351 -53.652879) (xy 219.519219 -53.688554) (xy 219.556436 -53.730091)
			(xy 219.587209 -53.776604) (xy 219.610881 -53.827101) (xy 219.626949 -53.880508) (xy 219.635069 -53.935684)
			(xy 219.635578 -53.96357) (xy 219.635069 -53.991456) (xy 219.626949 -54.046632) (xy 219.610881 -54.100039)
			(xy 219.587209 -54.150536) (xy 219.556436 -54.197049) (xy 219.519219 -54.238586) (xy 219.476351 -54.274261)
			(xy 219.428745 -54.303315) (xy 219.377416 -54.325127) (xy 219.323459 -54.339233) (xy 219.268022 -54.345333)
			(xy 219.212288 -54.343296) (xy 219.157445 -54.333166) (xy 219.104661 -54.315159) (xy 219.055061 -54.289658)
			(xy 219.009703 -54.257207) (xy 218.969554 -54.218498) (xy 218.935468 -54.174355) (xy 218.908172 -54.12572)
			(xy 218.888249 -54.073629) (xy 218.876123 -54.019192) (xy 218.872052 -53.96357) (xy 214.892874 -53.96357)
			(xy 214.910441 -54.002034) (xy 214.925796 -54.054329) (xy 214.933552 -54.108277) (xy 214.934038 -54.135528)
			(xy 214.933603 -54.1629) (xy 214.92578 -54.217081) (xy 214.910285 -54.269585) (xy 214.887436 -54.319331)
			(xy 214.857703 -54.365296) (xy 214.840058 -54.386226) (xy 214.839804 -54.38648) (xy 214.83422 -54.393568)
			(xy 214.827972 -54.410484) (xy 214.827612 -54.4195) (xy 214.827612 -54.486556) (xy 214.827988 -54.495571)
			(xy 214.834222 -54.512488) (xy 214.839804 -54.519576) (xy 214.840058 -54.519576) (xy 214.840058 -54.51983)
			(xy 214.857671 -54.540783) (xy 214.887388 -54.586749) (xy 214.91023 -54.636492) (xy 214.925727 -54.688988)
			(xy 214.933561 -54.74316) (xy 214.934038 -54.770528) (xy 214.933552 -54.797779) (xy 214.925796 -54.851727)
			(xy 214.910441 -54.904022) (xy 214.887799 -54.953599) (xy 214.858333 -54.999449) (xy 214.822642 -55.04064)
			(xy 214.781451 -55.076331) (xy 214.735601 -55.105797) (xy 214.686024 -55.128439) (xy 214.633729 -55.143794)
			(xy 214.579781 -55.15155) (xy 214.525279 -55.15155) (xy 214.471331 -55.143794) (xy 214.419036 -55.128439)
			(xy 214.369459 -55.105797) (xy 214.323609 -55.076331) (xy 214.282418 -55.04064) (xy 214.246727 -54.999449)
			(xy 214.217261 -54.953599) (xy 214.194619 -54.904022) (xy 214.179264 -54.851727) (xy 214.171508 -54.797779)
			(xy 214.171022 -54.770528) (xy 211.039101 -54.770528) (xy 211.039456 -54.791102) (xy 211.03897 -54.818353)
			(xy 211.031214 -54.872301) (xy 211.015859 -54.924596) (xy 210.993217 -54.974173) (xy 210.963751 -55.020023)
			(xy 210.92806 -55.061214) (xy 210.886869 -55.096905) (xy 210.841019 -55.126371) (xy 210.791442 -55.149013)
			(xy 210.739147 -55.164368) (xy 210.685199 -55.172124) (xy 210.630697 -55.172124) (xy 210.576749 -55.164368)
			(xy 210.524454 -55.149013) (xy 210.474877 -55.126371) (xy 210.429027 -55.096905) (xy 210.387836 -55.061214)
			(xy 210.352145 -55.020023) (xy 210.322679 -54.974173) (xy 210.300037 -54.924596) (xy 210.284682 -54.872301)
			(xy 210.276926 -54.818353) (xy 210.27644 -54.791102) (xy 208.378482 -54.791102) (xy 208.37539 -54.812611)
			(xy 208.360035 -54.864906) (xy 208.337393 -54.914483) (xy 208.307927 -54.960333) (xy 208.272236 -55.001524)
			(xy 208.231045 -55.037215) (xy 208.185195 -55.066681) (xy 208.135618 -55.089323) (xy 208.083323 -55.104678)
			(xy 208.029375 -55.112434) (xy 207.974873 -55.112434) (xy 207.920925 -55.104678) (xy 207.86863 -55.089323)
			(xy 207.819053 -55.066681) (xy 207.773203 -55.037215) (xy 207.732012 -55.001524) (xy 207.696321 -54.960333)
			(xy 207.666855 -54.914483) (xy 207.644213 -54.864906) (xy 207.628858 -54.812611) (xy 207.621102 -54.758663)
			(xy 207.620616 -54.731412) (xy 206.868268 -54.731412) (xy 206.868268 -57.002934) (xy 215.663526 -57.002934)
			(xy 215.664026 -56.974842) (xy 215.67225 -56.919265) (xy 215.688538 -56.865495) (xy 215.71254 -56.814696)
			(xy 215.743734 -56.767969) (xy 215.781447 -56.726325) (xy 215.824861 -56.690664) (xy 215.848692 -56.675782)
			(xy 215.857582 -56.670448) (xy 215.869774 -56.65343) (xy 215.890094 -56.560212) (xy 215.885776 -56.539638)
			(xy 215.879934 -56.531002) (xy 215.863937 -56.506936) (xy 215.838592 -56.455006) (xy 215.821366 -56.399848)
			(xy 215.81265 -56.342724) (xy 215.812116 -56.313832) (xy 215.812585 -56.286579) (xy 215.820338 -56.232627)
			(xy 215.835692 -56.180328) (xy 215.858332 -56.130746) (xy 215.887799 -56.084892) (xy 215.923492 -56.043698)
			(xy 215.964685 -56.008004) (xy 216.010539 -55.978536) (xy 216.06012 -55.955894) (xy 216.112419 -55.94054)
			(xy 216.166371 -55.932786) (xy 216.193624 -55.932324) (xy 216.220995 -55.93277) (xy 216.275175 -55.940592)
			(xy 216.327679 -55.956085) (xy 216.377425 -55.978932) (xy 216.423391 -56.008661) (xy 216.444322 -56.026304)
			(xy 216.444576 -56.026558) (xy 216.45166 -56.032148) (xy 216.468579 -56.038391) (xy 216.477596 -56.03875)
			(xy 216.544652 -56.03875) (xy 216.553668 -56.038381) (xy 216.570586 -56.032143) (xy 216.577672 -56.026558)
			(xy 216.577672 -56.026304) (xy 216.577926 -56.026304) (xy 216.598859 -56.008663) (xy 216.644827 -55.978939)
			(xy 216.694573 -55.956093) (xy 216.747075 -55.940597) (xy 216.801253 -55.932768) (xy 216.855995 -55.932768)
			(xy 216.910173 -55.940597) (xy 216.962675 -55.956093) (xy 217.012421 -55.978939) (xy 217.058389 -56.008663)
			(xy 217.079322 -56.026304) (xy 217.079576 -56.026558) (xy 217.08666 -56.032148) (xy 217.103579 -56.038391)
			(xy 217.112596 -56.03875) (xy 217.179652 -56.03875) (xy 217.188668 -56.038381) (xy 217.205586 -56.032143)
			(xy 217.212672 -56.026558) (xy 217.212672 -56.026304) (xy 217.212926 -56.026304) (xy 217.233876 -56.008687)
			(xy 217.279844 -55.978971) (xy 217.329587 -55.956131) (xy 217.382083 -55.940635) (xy 217.436256 -55.932801)
			(xy 217.463624 -55.932324) (xy 217.490876 -55.932747) (xy 217.544826 -55.940507) (xy 217.597122 -55.955866)
			(xy 217.646701 -55.97851) (xy 217.692552 -56.00798) (xy 217.733743 -56.043674) (xy 217.769435 -56.084867)
			(xy 217.798901 -56.13072) (xy 217.821542 -56.1803) (xy 217.836898 -56.232597) (xy 217.844654 -56.286548)
			(xy 217.844654 -56.341052) (xy 217.836898 -56.395003) (xy 217.821542 -56.4473) (xy 217.798901 -56.49688)
			(xy 217.769435 -56.542733) (xy 217.733743 -56.583926) (xy 217.692552 -56.61962) (xy 217.646701 -56.64909)
			(xy 217.597122 -56.671734) (xy 217.544826 -56.687093) (xy 217.490876 -56.694853) (xy 217.463624 -56.69534)
			(xy 217.436254 -56.694874) (xy 217.382074 -56.687059) (xy 217.32957 -56.67157) (xy 217.279823 -56.648728)
			(xy 217.233857 -56.619002) (xy 217.212926 -56.60136) (xy 217.212672 -56.601106) (xy 217.205568 -56.595544)
			(xy 217.188665 -56.589282) (xy 217.179652 -56.588914) (xy 217.112596 -56.588914) (xy 217.103579 -56.589266)
			(xy 217.086661 -56.595517) (xy 217.079576 -56.601106) (xy 217.079576 -56.60136) (xy 217.079322 -56.60136)
			(xy 217.058389 -56.619001) (xy 217.012421 -56.648725) (xy 216.962675 -56.671571) (xy 216.910173 -56.687067)
			(xy 216.855995 -56.694896) (xy 216.801253 -56.694896) (xy 216.747075 -56.687067) (xy 216.694573 -56.671571)
			(xy 216.644827 -56.648725) (xy 216.598859 -56.619001) (xy 216.577926 -56.60136) (xy 216.577672 -56.601106)
			(xy 216.570568 -56.595544) (xy 216.553665 -56.589282) (xy 216.544652 -56.588914) (xy 216.477596 -56.588914)
			(xy 216.468579 -56.589266) (xy 216.451661 -56.595517) (xy 216.444576 -56.601106) (xy 216.444068 -56.60136)
			(xy 216.431333 -56.612303) (xy 216.404242 -56.632145) (xy 216.389966 -56.640984) (xy 216.381076 -56.646318)
			(xy 216.368884 -56.663336) (xy 216.348564 -56.756554) (xy 216.352882 -56.777128) (xy 216.358724 -56.785764)
			(xy 216.374714 -56.809834) (xy 216.400058 -56.861764) (xy 216.417286 -56.91692) (xy 216.426005 -56.974042)
			(xy 216.426542 -57.002934) (xy 216.426056 -57.030185) (xy 216.4183 -57.084133) (xy 216.402945 -57.136428)
			(xy 216.380303 -57.186005) (xy 216.350837 -57.231855) (xy 216.315146 -57.273046) (xy 216.273955 -57.308737)
			(xy 216.228105 -57.338203) (xy 216.178528 -57.360845) (xy 216.126233 -57.3762) (xy 216.072285 -57.383956)
			(xy 216.017783 -57.383956) (xy 215.963835 -57.3762) (xy 215.91154 -57.360845) (xy 215.861963 -57.338203)
			(xy 215.816113 -57.308737) (xy 215.774922 -57.273046) (xy 215.739231 -57.231855) (xy 215.709765 -57.186005)
			(xy 215.687123 -57.136428) (xy 215.671768 -57.084133) (xy 215.664012 -57.030185) (xy 215.663526 -57.002934)
			(xy 206.868268 -57.002934) (xy 206.868268 -58.679334) (xy 216.095326 -58.679334) (xy 216.095741 -58.653018)
			(xy 216.102985 -58.600887) (xy 216.117314 -58.550243) (xy 216.138456 -58.502044) (xy 216.166012 -58.457202)
			(xy 216.19946 -58.416565) (xy 216.218516 -58.39841) (xy 216.225918 -58.390889) (xy 216.234442 -58.371608)
			(xy 216.235026 -58.361072) (xy 216.235026 -58.286396) (xy 216.234505 -58.275846) (xy 216.225963 -58.256551)
			(xy 216.218516 -58.249058) (xy 216.19945 -58.230913) (xy 216.165993 -58.190281) (xy 216.138435 -58.145439)
			(xy 216.117298 -58.097236) (xy 216.102984 -58.046587) (xy 216.095762 -57.994451) (xy 216.095326 -57.968134)
			(xy 216.095812 -57.940883) (xy 216.103568 -57.886935) (xy 216.118923 -57.83464) (xy 216.141565 -57.785063)
			(xy 216.171031 -57.739213) (xy 216.206722 -57.698022) (xy 216.247913 -57.662331) (xy 216.293763 -57.632865)
			(xy 216.34334 -57.610223) (xy 216.395635 -57.594868) (xy 216.449583 -57.587112) (xy 216.504085 -57.587112)
			(xy 216.558033 -57.594868) (xy 216.610328 -57.610223) (xy 216.659905 -57.632865) (xy 216.705755 -57.662331)
			(xy 216.746946 -57.698022) (xy 216.782637 -57.739213) (xy 216.812103 -57.785063) (xy 216.834745 -57.83464)
			(xy 216.8501 -57.886935) (xy 216.857856 -57.940883) (xy 216.858342 -57.968134) (xy 216.857916 -57.99445)
			(xy 216.850675 -58.046581) (xy 216.836349 -58.097225) (xy 216.815209 -58.145424) (xy 216.787655 -58.190266)
			(xy 216.754208 -58.230903) (xy 216.735152 -58.249058) (xy 216.727775 -58.2566) (xy 216.719235 -58.275864)
			(xy 216.718642 -58.286396) (xy 216.718642 -58.361072) (xy 216.719161 -58.371623) (xy 216.727702 -58.390919)
			(xy 216.735152 -58.39841) (xy 216.754215 -58.416558) (xy 216.78767 -58.45719) (xy 216.815226 -58.502032)
			(xy 216.836363 -58.550235) (xy 216.850679 -58.600883) (xy 216.857904 -58.653018) (xy 216.858342 -58.679334)
			(xy 216.857856 -58.706585) (xy 216.8501 -58.760533) (xy 216.834745 -58.812828) (xy 216.812103 -58.862405)
			(xy 216.782637 -58.908255) (xy 216.746946 -58.949446) (xy 216.705755 -58.985137) (xy 216.659905 -59.014603)
			(xy 216.610328 -59.037245) (xy 216.558033 -59.0526) (xy 216.504085 -59.060356) (xy 216.449583 -59.060356)
			(xy 216.395635 -59.0526) (xy 216.34334 -59.037245) (xy 216.293763 -59.014603) (xy 216.247913 -58.985137)
			(xy 216.206722 -58.949446) (xy 216.171031 -58.908255) (xy 216.141565 -58.862405) (xy 216.118923 -58.812828)
			(xy 216.103568 -58.760533) (xy 216.095812 -58.706585) (xy 216.095326 -58.679334) (xy 206.868268 -58.679334)
			(xy 206.868268 -60.01925) (xy 216.235784 -60.01925) (xy 216.235784 -59.96475) (xy 216.24354 -59.910804)
			(xy 216.258894 -59.858511) (xy 216.281534 -59.808935) (xy 216.310999 -59.763086) (xy 216.346688 -59.721897)
			(xy 216.387877 -59.686206) (xy 216.433725 -59.65674) (xy 216.4833 -59.634098) (xy 216.535592 -59.618742)
			(xy 216.589538 -59.610985) (xy 216.616788 -59.610498) (xy 216.644158 -59.610972) (xy 216.698337 -59.618788)
			(xy 216.75084 -59.634275) (xy 216.800587 -59.657115) (xy 216.846554 -59.686838) (xy 216.867486 -59.704478)
			(xy 216.86774 -59.704732) (xy 216.874837 -59.710303) (xy 216.891746 -59.716558) (xy 216.90076 -59.716924)
			(xy 216.967816 -59.716924) (xy 216.976833 -59.716569) (xy 216.99375 -59.710319) (xy 217.000836 -59.704732)
			(xy 217.000836 -59.704478) (xy 217.00109 -59.704478) (xy 217.022023 -59.686837) (xy 217.067991 -59.657113)
			(xy 217.117737 -59.634267) (xy 217.170239 -59.618771) (xy 217.224417 -59.610942) (xy 217.279159 -59.610942)
			(xy 217.333337 -59.618771) (xy 217.385839 -59.634267) (xy 217.435585 -59.657113) (xy 217.481553 -59.686837)
			(xy 217.502486 -59.704478) (xy 217.50274 -59.704732) (xy 217.509837 -59.710303) (xy 217.526746 -59.716558)
			(xy 217.53576 -59.716924) (xy 217.602816 -59.716924) (xy 217.611833 -59.716569) (xy 217.62875 -59.710319)
			(xy 217.635836 -59.704732) (xy 217.635836 -59.704478) (xy 217.63609 -59.704478) (xy 217.657012 -59.686827)
			(xy 217.702988 -59.657117) (xy 217.752738 -59.634284) (xy 217.805241 -59.618796) (xy 217.859418 -59.610971)
			(xy 217.886788 -59.610498) (xy 217.914042 -59.610949) (xy 217.967995 -59.618704) (xy 218.020295 -59.634059)
			(xy 218.069877 -59.656702) (xy 218.115733 -59.68617) (xy 218.156928 -59.721864) (xy 218.192623 -59.763058)
			(xy 218.222093 -59.808912) (xy 218.244736 -59.858494) (xy 218.260093 -59.910793) (xy 218.267851 -59.964746)
			(xy 218.267851 -60.019254) (xy 218.260093 -60.073207) (xy 218.244736 -60.125506) (xy 218.222093 -60.175088)
			(xy 218.192623 -60.220942) (xy 218.156928 -60.262136) (xy 218.115733 -60.29783) (xy 218.069877 -60.327298)
			(xy 218.020295 -60.349941) (xy 217.967995 -60.365296) (xy 217.914042 -60.373051) (xy 217.886788 -60.373514)
			(xy 217.859418 -60.373052) (xy 217.805239 -60.365232) (xy 217.752736 -60.349742) (xy 217.702989 -60.3269)
			(xy 217.657022 -60.297175) (xy 217.63609 -60.279534) (xy 217.635836 -60.27928) (xy 217.628745 -60.2737)
			(xy 217.611832 -60.26745) (xy 217.602816 -60.267088) (xy 217.53576 -60.267088) (xy 217.526741 -60.267428)
			(xy 217.509825 -60.273688) (xy 217.50274 -60.27928) (xy 217.502486 -60.279534) (xy 217.481553 -60.297175)
			(xy 217.435585 -60.326899) (xy 217.385839 -60.349745) (xy 217.333337 -60.365241) (xy 217.279159 -60.37307)
			(xy 217.224417 -60.37307) (xy 217.170239 -60.365241) (xy 217.117737 -60.349745) (xy 217.067991 -60.326899)
			(xy 217.022023 -60.297175) (xy 217.00109 -60.279534) (xy 217.000836 -60.27928) (xy 216.993745 -60.2737)
			(xy 216.976832 -60.26745) (xy 216.967816 -60.267088) (xy 216.90076 -60.267088) (xy 216.891741 -60.267428)
			(xy 216.874825 -60.273688) (xy 216.86774 -60.27928) (xy 216.86774 -60.279534) (xy 216.867486 -60.279534)
			(xy 216.846537 -60.297152) (xy 216.800568 -60.326865) (xy 216.750825 -60.349705) (xy 216.698328 -60.365201)
			(xy 216.644156 -60.373036) (xy 216.616788 -60.373514) (xy 216.589538 -60.373015) (xy 216.535592 -60.365258)
			(xy 216.4833 -60.349902) (xy 216.433725 -60.32726) (xy 216.387877 -60.297794) (xy 216.346688 -60.262103)
			(xy 216.310999 -60.220914) (xy 216.281534 -60.175065) (xy 216.258894 -60.125489) (xy 216.24354 -60.073196)
			(xy 216.235784 -60.01925) (xy 206.868268 -60.01925) (xy 206.868268 -67.128949) (xy 208.466698 -67.128949)
			(xy 208.466698 -67.074451) (xy 208.474454 -67.020507) (xy 208.489808 -66.968216) (xy 208.512447 -66.918642)
			(xy 208.541911 -66.872794) (xy 208.577599 -66.831606) (xy 208.618786 -66.795917) (xy 208.664633 -66.766452)
			(xy 208.714206 -66.743811) (xy 208.766497 -66.728456) (xy 208.820441 -66.720699) (xy 208.84769 -66.720212)
			(xy 208.87506 -66.720681) (xy 208.929239 -66.728498) (xy 208.981742 -66.743986) (xy 209.031489 -66.766827)
			(xy 209.077456 -66.796551) (xy 209.098388 -66.814192) (xy 209.098642 -66.814446) (xy 209.105737 -66.82002)
			(xy 209.122647 -66.826273) (xy 209.131662 -66.826638) (xy 209.198718 -66.826638) (xy 209.207735 -66.826282)
			(xy 209.224651 -66.820033) (xy 209.231738 -66.814446) (xy 209.231738 -66.814192) (xy 209.231992 -66.814192)
			(xy 209.252915 -66.796542) (xy 209.298891 -66.766832) (xy 209.34864 -66.743998) (xy 209.401143 -66.72851)
			(xy 209.45532 -66.720684) (xy 209.48269 -66.720212) (xy 209.509945 -66.720634) (xy 209.5639 -66.72839)
			(xy 209.616202 -66.743746) (xy 209.665786 -66.76639) (xy 209.711642 -66.795859) (xy 209.752838 -66.831554)
			(xy 209.788535 -66.87275) (xy 209.818006 -66.918606) (xy 209.84065 -66.968189) (xy 209.856007 -67.020491)
			(xy 209.863765 -67.074445) (xy 209.863765 -67.128955) (xy 209.856007 -67.182909) (xy 209.84065 -67.235211)
			(xy 209.818006 -67.284794) (xy 209.788535 -67.33065) (xy 209.752838 -67.371846) (xy 209.711642 -67.407541)
			(xy 209.665786 -67.43701) (xy 209.616202 -67.459654) (xy 209.5639 -67.47501) (xy 209.509945 -67.482766)
			(xy 209.48269 -67.483228) (xy 209.455319 -67.482785) (xy 209.401138 -67.474965) (xy 209.348634 -67.459471)
			(xy 209.298887 -67.436624) (xy 209.252922 -67.406893) (xy 209.231992 -67.389248) (xy 209.231738 -67.388994)
			(xy 209.224645 -67.383417) (xy 209.207733 -67.377165) (xy 209.198718 -67.376802) (xy 209.131662 -67.376802)
			(xy 209.122643 -67.377141) (xy 209.105726 -67.383401) (xy 209.098642 -67.388994) (xy 209.098642 -67.389248)
			(xy 209.098388 -67.389248) (xy 209.077427 -67.406851) (xy 209.031463 -67.43657) (xy 208.981723 -67.459414)
			(xy 208.929228 -67.474913) (xy 208.875057 -67.48275) (xy 208.84769 -67.483228) (xy 208.820441 -67.482701)
			(xy 208.766497 -67.474944) (xy 208.714206 -67.459589) (xy 208.664633 -67.436948) (xy 208.618786 -67.407483)
			(xy 208.577599 -67.371794) (xy 208.541911 -67.330606) (xy 208.512447 -67.284758) (xy 208.489808 -67.235184)
			(xy 208.474454 -67.182893) (xy 208.466698 -67.128949) (xy 206.868268 -67.128949) (xy 206.868268 -67.488054)
			(xy 212.879176 -67.488054) (xy 212.883247 -67.432432) (xy 212.895373 -67.377995) (xy 212.915296 -67.325904)
			(xy 212.942592 -67.277269) (xy 212.976678 -67.233126) (xy 213.016827 -67.194417) (xy 213.062185 -67.161966)
			(xy 213.111785 -67.136465) (xy 213.164569 -67.118458) (xy 213.219412 -67.108328) (xy 213.275146 -67.106291)
			(xy 213.330583 -67.112391) (xy 213.38454 -67.126497) (xy 213.435869 -67.148309) (xy 213.483475 -67.177363)
			(xy 213.526343 -67.213038) (xy 213.56356 -67.254575) (xy 213.594333 -67.301088) (xy 213.618005 -67.351585)
			(xy 213.634073 -67.404992) (xy 213.642193 -67.460168) (xy 213.642702 -67.488054) (xy 213.642193 -67.51594)
			(xy 213.639008 -67.537584) (xy 214.171274 -67.537584) (xy 214.175345 -67.481962) (xy 214.187471 -67.427525)
			(xy 214.207394 -67.375434) (xy 214.23469 -67.326799) (xy 214.268776 -67.282656) (xy 214.308925 -67.243947)
			(xy 214.354283 -67.211496) (xy 214.403883 -67.185995) (xy 214.456667 -67.167988) (xy 214.51151 -67.157858)
			(xy 214.567244 -67.155821) (xy 214.622681 -67.161921) (xy 214.676638 -67.176027) (xy 214.727967 -67.197839)
			(xy 214.775573 -67.226893) (xy 214.818441 -67.262568) (xy 214.855658 -67.304105) (xy 214.886431 -67.350618)
			(xy 214.910103 -67.401115) (xy 214.926171 -67.454522) (xy 214.934291 -67.509698) (xy 214.9348 -67.537584)
			(xy 214.934291 -67.56547) (xy 214.930246 -67.592956) (xy 215.445338 -67.592956) (xy 215.449409 -67.537334)
			(xy 215.461535 -67.482897) (xy 215.481458 -67.430806) (xy 215.508754 -67.382171) (xy 215.54284 -67.338028)
			(xy 215.582989 -67.299319) (xy 215.628347 -67.266868) (xy 215.677947 -67.241367) (xy 215.730731 -67.22336)
			(xy 215.785574 -67.21323) (xy 215.841308 -67.211193) (xy 215.896745 -67.217293) (xy 215.950702 -67.231399)
			(xy 216.002031 -67.253211) (xy 216.049637 -67.282265) (xy 216.092505 -67.31794) (xy 216.129722 -67.359477)
			(xy 216.160495 -67.40599) (xy 216.184167 -67.456487) (xy 216.200235 -67.509894) (xy 216.208355 -67.56507)
			(xy 216.208864 -67.592956) (xy 216.208355 -67.620842) (xy 216.200235 -67.676018) (xy 216.184167 -67.729425)
			(xy 216.160495 -67.779922) (xy 216.129722 -67.826435) (xy 216.092505 -67.867972) (xy 216.049637 -67.903647)
			(xy 216.002031 -67.932701) (xy 215.950702 -67.954513) (xy 215.896745 -67.968619) (xy 215.841308 -67.974719)
			(xy 215.785574 -67.972682) (xy 215.730731 -67.962552) (xy 215.677947 -67.944545) (xy 215.628347 -67.919044)
			(xy 215.582989 -67.886593) (xy 215.54284 -67.847884) (xy 215.508754 -67.803741) (xy 215.481458 -67.755106)
			(xy 215.461535 -67.703015) (xy 215.449409 -67.648578) (xy 215.445338 -67.592956) (xy 214.930246 -67.592956)
			(xy 214.926171 -67.620646) (xy 214.910103 -67.674053) (xy 214.886431 -67.72455) (xy 214.855658 -67.771063)
			(xy 214.818441 -67.8126) (xy 214.775573 -67.848275) (xy 214.727967 -67.877329) (xy 214.676638 -67.899141)
			(xy 214.622681 -67.913247) (xy 214.567244 -67.919347) (xy 214.51151 -67.91731) (xy 214.456667 -67.90718)
			(xy 214.403883 -67.889173) (xy 214.354283 -67.863672) (xy 214.308925 -67.831221) (xy 214.268776 -67.792512)
			(xy 214.23469 -67.748369) (xy 214.207394 -67.699734) (xy 214.187471 -67.647643) (xy 214.175345 -67.593206)
			(xy 214.171274 -67.537584) (xy 213.639008 -67.537584) (xy 213.634073 -67.571116) (xy 213.618005 -67.624523)
			(xy 213.594333 -67.67502) (xy 213.56356 -67.721533) (xy 213.526343 -67.76307) (xy 213.483475 -67.798745)
			(xy 213.435869 -67.827799) (xy 213.38454 -67.849611) (xy 213.330583 -67.863717) (xy 213.275146 -67.869817)
			(xy 213.219412 -67.86778) (xy 213.164569 -67.85765) (xy 213.111785 -67.839643) (xy 213.062185 -67.814142)
			(xy 213.016827 -67.781691) (xy 212.976678 -67.742982) (xy 212.942592 -67.698839) (xy 212.915296 -67.650204)
			(xy 212.895373 -67.598113) (xy 212.883247 -67.543676) (xy 212.879176 -67.488054) (xy 206.868268 -67.488054)
			(xy 206.868268 -68.586604) (xy 210.725258 -68.586604) (xy 210.725712 -68.559233) (xy 210.733531 -68.505053)
			(xy 210.749022 -68.452549) (xy 210.771867 -68.402803) (xy 210.801595 -68.356837) (xy 210.819238 -68.335906)
			(xy 210.819492 -68.335652) (xy 210.825062 -68.328554) (xy 210.831319 -68.311646) (xy 210.831684 -68.302632)
			(xy 210.831684 -68.235576) (xy 210.831342 -68.226558) (xy 210.825084 -68.209641) (xy 210.819492 -68.202556)
			(xy 210.819238 -68.202556) (xy 210.819238 -68.202302) (xy 210.801592 -68.181375) (xy 210.77188 -68.135401)
			(xy 210.749045 -68.085653) (xy 210.733555 -68.033151) (xy 210.72573 -67.978974) (xy 210.725258 -67.951604)
			(xy 210.725781 -67.924354) (xy 210.733536 -67.87041) (xy 210.748889 -67.818118) (xy 210.771528 -67.768543)
			(xy 210.80099 -67.722694) (xy 210.836678 -67.681505) (xy 210.877864 -67.645813) (xy 210.923709 -67.616346)
			(xy 210.973282 -67.593703) (xy 211.025573 -67.578345) (xy 211.079516 -67.570584) (xy 211.106766 -67.570096)
			(xy 211.133081 -67.570521) (xy 211.185212 -67.577764) (xy 211.235855 -67.592092) (xy 211.284054 -67.613233)
			(xy 211.328896 -67.640786) (xy 211.369534 -67.674231) (xy 211.38769 -67.693286) (xy 211.395215 -67.700683)
			(xy 211.414492 -67.709211) (xy 211.425028 -67.709796) (xy 211.499704 -67.709796) (xy 211.510256 -67.709284)
			(xy 211.529551 -67.700737) (xy 211.537042 -67.693286) (xy 211.555181 -67.674214) (xy 211.595815 -67.640759)
			(xy 211.640659 -67.613203) (xy 211.688863 -67.592067) (xy 211.739513 -67.577753) (xy 211.791649 -67.570532)
			(xy 211.817966 -67.570096) (xy 211.845335 -67.570583) (xy 211.899514 -67.578396) (xy 211.952016 -67.59388)
			(xy 212.001764 -67.616717) (xy 212.047732 -67.646437) (xy 212.068664 -67.664076) (xy 212.068918 -67.66433)
			(xy 212.075993 -67.669934) (xy 212.092919 -67.676169) (xy 212.101938 -67.676522) (xy 212.168994 -67.676522)
			(xy 212.17801 -67.676157) (xy 212.194927 -67.669914) (xy 212.202014 -67.66433) (xy 212.202014 -67.664076)
			(xy 212.202268 -67.664076) (xy 212.223198 -67.646435) (xy 212.269172 -67.616724) (xy 212.31892 -67.593889)
			(xy 212.371421 -67.578398) (xy 212.425597 -67.57057) (xy 212.452966 -67.570096) (xy 212.480218 -67.570587)
			(xy 212.534168 -67.578339) (xy 212.586466 -67.593691) (xy 212.636046 -67.61633) (xy 212.6819 -67.645795)
			(xy 212.723093 -67.681486) (xy 212.758787 -67.722676) (xy 212.788255 -67.768527) (xy 212.810898 -67.818106)
			(xy 212.826254 -67.870402) (xy 212.834011 -67.924352) (xy 212.834474 -67.951604) (xy 212.834017 -67.978975)
			(xy 212.826198 -68.033154) (xy 212.810707 -68.085658) (xy 212.787863 -68.135405) (xy 212.758136 -68.181371)
			(xy 212.740494 -68.202302) (xy 212.74024 -68.202556) (xy 212.734659 -68.209646) (xy 212.72841 -68.22656)
			(xy 212.728048 -68.235576) (xy 212.728048 -68.302632) (xy 212.728379 -68.311652) (xy 212.734643 -68.328569)
			(xy 212.74024 -68.335652) (xy 212.740494 -68.335652) (xy 212.740494 -68.335906) (xy 212.758148 -68.356826)
			(xy 212.787858 -68.402802) (xy 212.810691 -68.452552) (xy 212.826179 -68.505056) (xy 212.834002 -68.559234)
			(xy 212.834474 -68.586604) (xy 212.834048 -68.613858) (xy 212.82629 -68.667813) (xy 212.810932 -68.720113)
			(xy 212.794299 -68.75653) (xy 216.270332 -68.75653) (xy 216.270808 -68.72916) (xy 216.278622 -68.674981)
			(xy 216.294108 -68.622478) (xy 216.316948 -68.572731) (xy 216.346671 -68.526764) (xy 216.364312 -68.505832)
			(xy 216.364566 -68.505578) (xy 216.370176 -68.498508) (xy 216.376407 -68.481578) (xy 216.376758 -68.472558)
			(xy 216.376758 -68.405502) (xy 216.376409 -68.396484) (xy 216.370157 -68.379567) (xy 216.364566 -68.372482)
			(xy 216.364312 -68.372482) (xy 216.364312 -68.372228) (xy 216.346674 -68.351295) (xy 216.316962 -68.305322)
			(xy 216.294126 -68.255575) (xy 216.278634 -68.203075) (xy 216.270806 -68.148899) (xy 216.270332 -68.12153)
			(xy 216.270783 -68.094276) (xy 216.278537 -68.040323) (xy 216.293892 -67.988022) (xy 216.316533 -67.938439)
			(xy 216.346002 -67.892584) (xy 216.381697 -67.85139) (xy 216.422892 -67.815696) (xy 216.468748 -67.786229)
			(xy 216.518331 -67.763588) (xy 216.570632 -67.748235) (xy 216.624586 -67.740483) (xy 216.65184 -67.740022)
			(xy 216.679209 -67.740518) (xy 216.733387 -67.748328) (xy 216.78589 -67.76381) (xy 216.835638 -67.786645)
			(xy 216.881606 -67.816363) (xy 216.902538 -67.834002) (xy 216.902792 -67.834256) (xy 216.909872 -67.839852)
			(xy 216.926794 -67.846092) (xy 216.935812 -67.846448) (xy 217.002868 -67.846448) (xy 217.011885 -67.846087)
			(xy 217.028802 -67.839843) (xy 217.035888 -67.834256) (xy 217.035888 -67.834002) (xy 217.036142 -67.834002)
			(xy 217.057085 -67.816377) (xy 217.103055 -67.786663) (xy 217.1528 -67.763824) (xy 217.205298 -67.74833)
			(xy 217.259472 -67.740498) (xy 217.28684 -67.740022) (xy 217.313155 -67.740456) (xy 217.365285 -67.747696)
			(xy 217.415929 -67.762022) (xy 217.464128 -67.78316) (xy 217.508971 -67.810713) (xy 217.549609 -67.844158)
			(xy 217.567764 -67.863212) (xy 217.575295 -67.870602) (xy 217.594568 -67.879133) (xy 217.605102 -67.879722)
			(xy 217.679778 -67.879722) (xy 217.690327 -67.879188) (xy 217.709622 -67.870655) (xy 217.717116 -67.863212)
			(xy 217.735273 -67.844158) (xy 217.775902 -67.8107) (xy 217.820742 -67.783141) (xy 217.868943 -67.762002)
			(xy 217.91959 -67.747685) (xy 217.971724 -67.74046) (xy 217.99804 -67.740022) (xy 218.025294 -67.740441)
			(xy 218.079245 -67.748203) (xy 218.131543 -67.763565) (xy 218.181122 -67.786213) (xy 218.226974 -67.815686)
			(xy 218.268165 -67.851385) (xy 218.303856 -67.892582) (xy 218.33332 -67.938439) (xy 218.355959 -67.988023)
			(xy 218.371311 -68.040323) (xy 218.379064 -68.094276) (xy 218.379548 -68.12153) (xy 218.379112 -68.148901)
			(xy 218.371289 -68.203082) (xy 218.355794 -68.255586) (xy 218.332945 -68.305333) (xy 218.303213 -68.351298)
			(xy 218.285568 -68.372228) (xy 218.285314 -68.372482) (xy 218.27973 -68.379571) (xy 218.273481 -68.396486)
			(xy 218.273122 -68.405502) (xy 218.273122 -68.472558) (xy 218.273494 -68.481573) (xy 218.279731 -68.498491)
			(xy 218.285314 -68.505578) (xy 218.285568 -68.505578) (xy 218.285568 -68.505832) (xy 218.303184 -68.526783)
			(xy 218.3329 -68.57275) (xy 218.355741 -68.622493) (xy 218.371238 -68.674989) (xy 218.379071 -68.729162)
			(xy 218.379548 -68.75653) (xy 218.37905 -68.78378) (xy 218.371291 -68.837725) (xy 218.355934 -68.890017)
			(xy 218.333292 -68.939592) (xy 218.303826 -68.98544) (xy 218.268136 -69.026629) (xy 218.226948 -69.06232)
			(xy 218.181101 -69.091787) (xy 218.131527 -69.11443) (xy 218.079235 -69.129789) (xy 218.02529 -69.13755)
			(xy 217.99804 -69.138038) (xy 217.971724 -69.13763) (xy 217.919592 -69.130386) (xy 217.868947 -69.116057)
			(xy 217.820748 -69.094913) (xy 217.775906 -69.067355) (xy 217.73527 -69.033905) (xy 217.717116 -69.014848)
			(xy 217.709584 -69.007459) (xy 217.690312 -68.998926) (xy 217.679778 -68.998338) (xy 217.605102 -68.998338)
			(xy 217.594549 -68.998843) (xy 217.575253 -69.007394) (xy 217.567764 -69.014848) (xy 217.549628 -69.033923)
			(xy 217.508993 -69.067377) (xy 217.464148 -69.094932) (xy 217.415944 -69.116067) (xy 217.365294 -69.13038)
			(xy 217.313157 -69.137601) (xy 217.28684 -69.138038) (xy 217.25947 -69.137564) (xy 217.205291 -69.12975)
			(xy 217.152787 -69.114264) (xy 217.10304 -69.091424) (xy 217.057073 -69.061699) (xy 217.036142 -69.044058)
			(xy 217.035888 -69.043804) (xy 217.028809 -69.038207) (xy 217.011886 -69.031966) (xy 217.002868 -69.031612)
			(xy 216.935812 -69.031612) (xy 216.926795 -69.031972) (xy 216.909878 -69.038217) (xy 216.902792 -69.043804)
			(xy 216.902792 -69.044058) (xy 216.902538 -69.044058) (xy 216.881597 -69.061686) (xy 216.835627 -69.091401)
			(xy 216.785882 -69.11424) (xy 216.733383 -69.129733) (xy 216.679209 -69.137563) (xy 216.65184 -69.138038)
			(xy 216.624589 -69.137508) (xy 216.570643 -69.129757) (xy 216.518348 -69.114407) (xy 216.46877 -69.091772)
			(xy 216.422918 -69.062311) (xy 216.381726 -69.026624) (xy 216.346031 -68.985438) (xy 216.316562 -68.939592)
			(xy 216.293917 -68.890018) (xy 216.278558 -68.837726) (xy 216.270797 -68.78378) (xy 216.270332 -68.75653)
			(xy 212.794299 -68.75653) (xy 212.788286 -68.769696) (xy 212.758815 -68.81555) (xy 212.723117 -68.856744)
			(xy 212.68192 -68.892437) (xy 212.636062 -68.921904) (xy 212.586478 -68.944545) (xy 212.534175 -68.959898)
			(xy 212.480221 -68.967651) (xy 212.452966 -68.968112) (xy 212.425595 -68.967663) (xy 212.371416 -68.959841)
			(xy 212.318912 -68.944347) (xy 212.269166 -68.921502) (xy 212.223199 -68.891774) (xy 212.202268 -68.874132)
			(xy 212.202014 -68.873878) (xy 212.194929 -68.868289) (xy 212.178011 -68.862044) (xy 212.168994 -68.861686)
			(xy 212.101938 -68.861686) (xy 212.092923 -68.862064) (xy 212.076006 -68.868297) (xy 212.068918 -68.873878)
			(xy 212.068918 -68.874132) (xy 212.068664 -68.874132) (xy 212.047723 -68.89176) (xy 212.001752 -68.921472)
			(xy 211.952007 -68.94431) (xy 211.899508 -68.959804) (xy 211.845334 -68.967636) (xy 211.817966 -68.968112)
			(xy 211.791651 -68.967663) (xy 211.739522 -68.960424) (xy 211.688879 -68.946101) (xy 211.640681 -68.924965)
			(xy 211.595837 -68.897416) (xy 211.555198 -68.863975) (xy 211.537042 -68.844922) (xy 211.529504 -68.83754)
			(xy 211.510236 -68.829004) (xy 211.499704 -68.828412) (xy 211.425028 -68.828412) (xy 211.414478 -68.828939)
			(xy 211.395182 -68.837475) (xy 211.38769 -68.844922) (xy 211.369537 -68.86398) (xy 211.328906 -68.897436)
			(xy 211.284065 -68.924994) (xy 211.235864 -68.946132) (xy 211.185216 -68.960449) (xy 211.133082 -68.967673)
			(xy 211.106766 -68.968112) (xy 211.079514 -68.967654) (xy 211.025566 -68.959893) (xy 210.973271 -68.944534)
			(xy 210.923693 -68.921889) (xy 210.877843 -68.892419) (xy 210.836654 -68.856725) (xy 210.800963 -68.815532)
			(xy 210.771497 -68.76968) (xy 210.748856 -68.720101) (xy 210.733501 -68.667805) (xy 210.725744 -68.613856)
			(xy 210.725258 -68.586604) (xy 206.868268 -68.586604) (xy 206.868268 -71.555864) (xy 213.294466 -71.555864)
			(xy 213.298537 -71.500242) (xy 213.310663 -71.445805) (xy 213.330586 -71.393714) (xy 213.357882 -71.345079)
			(xy 213.391968 -71.300936) (xy 213.432117 -71.262227) (xy 213.477475 -71.229776) (xy 213.527075 -71.204275)
			(xy 213.579859 -71.186268) (xy 213.634702 -71.176138) (xy 213.690436 -71.174101) (xy 213.745873 -71.180201)
			(xy 213.79983 -71.194307) (xy 213.851159 -71.216119) (xy 213.898765 -71.245173) (xy 213.941633 -71.280848)
			(xy 213.97885 -71.322385) (xy 214.009623 -71.368898) (xy 214.033295 -71.419395) (xy 214.049363 -71.472802)
			(xy 214.057483 -71.527978) (xy 214.057992 -71.555864) (xy 214.057483 -71.58375) (xy 214.051644 -71.623428)
			(xy 214.80348 -71.623428) (xy 214.807551 -71.567806) (xy 214.819677 -71.513369) (xy 214.8396 -71.461278)
			(xy 214.866896 -71.412643) (xy 214.900982 -71.3685) (xy 214.941131 -71.329791) (xy 214.986489 -71.29734)
			(xy 215.036089 -71.271839) (xy 215.088873 -71.253832) (xy 215.143716 -71.243702) (xy 215.19945 -71.241665)
			(xy 215.254887 -71.247765) (xy 215.308844 -71.261871) (xy 215.360173 -71.283683) (xy 215.407779 -71.312737)
			(xy 215.450647 -71.348412) (xy 215.487864 -71.389949) (xy 215.518637 -71.436462) (xy 215.542309 -71.486959)
			(xy 215.558377 -71.540366) (xy 215.566497 -71.595542) (xy 215.567006 -71.623428) (xy 215.566497 -71.651314)
			(xy 215.558377 -71.70649) (xy 215.542309 -71.759897) (xy 215.518637 -71.810394) (xy 215.487864 -71.856907)
			(xy 215.450647 -71.898444) (xy 215.407779 -71.934119) (xy 215.360173 -71.963173) (xy 215.308844 -71.984985)
			(xy 215.254887 -71.999091) (xy 215.19945 -72.005191) (xy 215.143716 -72.003154) (xy 215.088873 -71.993024)
			(xy 215.036089 -71.975017) (xy 214.986489 -71.949516) (xy 214.941131 -71.917065) (xy 214.900982 -71.878356)
			(xy 214.866896 -71.834213) (xy 214.8396 -71.785578) (xy 214.819677 -71.733487) (xy 214.807551 -71.67905)
			(xy 214.80348 -71.623428) (xy 214.051644 -71.623428) (xy 214.049363 -71.638926) (xy 214.033295 -71.692333)
			(xy 214.009623 -71.74283) (xy 213.97885 -71.789343) (xy 213.941633 -71.83088) (xy 213.898765 -71.866555)
			(xy 213.851159 -71.895609) (xy 213.79983 -71.917421) (xy 213.745873 -71.931527) (xy 213.690436 -71.937627)
			(xy 213.634702 -71.93559) (xy 213.579859 -71.92546) (xy 213.527075 -71.907453) (xy 213.477475 -71.881952)
			(xy 213.432117 -71.849501) (xy 213.391968 -71.810792) (xy 213.357882 -71.766649) (xy 213.330586 -71.718014)
			(xy 213.310663 -71.665923) (xy 213.298537 -71.611486) (xy 213.294466 -71.555864) (xy 206.868268 -71.555864)
			(xy 206.868268 -77.001624) (xy 206.868432 -77.007635) (xy 206.871249 -77.01932) (xy 206.873856 -77.024738)
			(xy 206.875698 -77.02821) (xy 206.880297 -77.034584) (xy 206.883 -77.037438) (xy 207.204564 -77.359002)
			(xy 207.21574 -77.35951) (xy 207.292448 -77.353922) (xy 207.3021 -77.348588) (xy 207.302608 -77.348334)
			(xy 207.327754 -77.334618) (xy 207.334358 -77.32649) (xy 207.352566 -77.304292) (xy 207.394512 -77.265094)
			(xy 207.441853 -77.232616) (xy 207.493523 -77.207592) (xy 207.548357 -77.190585) (xy 207.605119 -77.181979)
			(xy 207.633824 -77.181456) (xy 207.661111 -77.181944) (xy 207.71513 -77.189714) (xy 207.767493 -77.205091)
			(xy 207.817135 -77.227763) (xy 207.863045 -77.257269) (xy 207.90429 -77.293008) (xy 207.940029 -77.334252)
			(xy 207.969535 -77.380162) (xy 207.992208 -77.429804) (xy 208.007585 -77.482167) (xy 208.015356 -77.536185)
			(xy 208.01584 -77.563472) (xy 208.015324 -77.592179) (xy 208.006728 -77.648945) (xy 207.989726 -77.703783)
			(xy 207.964701 -77.755455) (xy 207.932219 -77.802796) (xy 207.893011 -77.844738) (xy 207.870806 -77.862938)
			(xy 207.862424 -77.869542) (xy 207.847946 -77.896974) (xy 207.845915 -77.901368) (xy 207.843356 -77.910701)
			(xy 207.842866 -77.915516) (xy 207.838802 -77.96911) (xy 207.838294 -77.978) (xy 207.838294 -77.978254)
			(xy 207.83804 -77.981556) (xy 207.83804 -77.985366) (xy 207.838802 -77.99324) (xy 208.213706 -78.36789)
			(xy 208.398364 -78.552548) (xy 208.410048 -78.551024) (xy 208.414874 -78.550516) (xy 208.434178 -78.544674)
			(xy 208.434686 -78.544674) (xy 208.502758 -78.525624) (xy 208.5086 -78.523592) (xy 208.513408 -78.52147)
			(xy 208.52211 -78.515579) (xy 208.525872 -78.511908) (xy 208.530444 -78.507336) (xy 208.536794 -78.49616)
			(xy 208.538572 -78.488794) (xy 208.538572 -78.48854) (xy 208.545786 -78.461263) (xy 208.567152 -78.409046)
			(xy 208.595978 -78.360545) (xy 208.631633 -78.31682) (xy 208.673342 -78.278825) (xy 208.720192 -78.247388)
			(xy 208.771162 -78.223196) (xy 208.82514 -78.206777) (xy 208.880948 -78.198489) (xy 208.909158 -78.197964)
			(xy 208.936414 -78.198424) (xy 208.990371 -78.206176) (xy 209.042675 -78.221528) (xy 209.092262 -78.244168)
			(xy 209.138123 -78.273634) (xy 209.179323 -78.309328) (xy 209.215024 -78.350521) (xy 209.244499 -78.396376)
			(xy 209.267147 -78.445959) (xy 209.282509 -78.498261) (xy 209.290271 -78.552217) (xy 209.290666 -78.579472)
			(xy 209.290163 -78.607319) (xy 209.282072 -78.662422) (xy 209.266059 -78.715765) (xy 209.242462 -78.766213)
			(xy 209.211784 -78.812696) (xy 209.174676 -78.854227) (xy 209.131926 -78.889924) (xy 209.084442 -78.919028)
			(xy 209.033231 -78.940921) (xy 209.00644 -78.948534) (xy 208.999582 -78.950312) (xy 208.98612 -78.957932)
			(xy 208.9829 -78.959884) (xy 208.977033 -78.964604) (xy 208.974436 -78.96733) (xy 208.970352 -78.971898)
			(xy 208.964317 -78.98256) (xy 208.962498 -78.988412) (xy 208.943194 -79.057246) (xy 208.943194 -79.057754)
			(xy 208.938876 -79.072994) (xy 208.937858 -79.077753) (xy 208.93747 -79.087475) (xy 208.938114 -79.092298)
			(xy 210.03133 -80.185514) (xy 210.049443 -80.204295) (xy 210.080129 -80.246492) (xy 210.10383 -80.292973)
			(xy 210.119963 -80.342591) (xy 210.12813 -80.394123) (xy 210.128612 -80.42021) (xy 210.128612 -87.466678)
			(xy 210.13166 -87.47252) (xy 210.134454 -87.478108) (xy 210.148165 -87.505587) (xy 210.167607 -87.563835)
			(xy 210.177484 -87.624443) (xy 210.178142 -87.655146) (xy 210.178142 -87.655654) (xy 210.307172 -87.655654)
			(xy 210.311243 -87.600032) (xy 210.323369 -87.545595) (xy 210.343292 -87.493504) (xy 210.370588 -87.444869)
			(xy 210.404674 -87.400726) (xy 210.444823 -87.362017) (xy 210.490181 -87.329566) (xy 210.539781 -87.304065)
			(xy 210.592565 -87.286058) (xy 210.647408 -87.275928) (xy 210.703142 -87.273891) (xy 210.758579 -87.279991)
			(xy 210.812536 -87.294097) (xy 210.863865 -87.315909) (xy 210.911471 -87.344963) (xy 210.954339 -87.380638)
			(xy 210.991556 -87.422175) (xy 211.022329 -87.468688) (xy 211.046001 -87.519185) (xy 211.062069 -87.572592)
			(xy 211.070189 -87.627768) (xy 211.070698 -87.655654) (xy 211.070189 -87.68354) (xy 211.062069 -87.738716)
			(xy 211.046001 -87.792123) (xy 211.022329 -87.84262) (xy 210.991556 -87.889133) (xy 210.954339 -87.93067)
			(xy 210.911471 -87.966345) (xy 210.863865 -87.995399) (xy 210.812536 -88.017211) (xy 210.758579 -88.031317)
			(xy 210.703142 -88.037417) (xy 210.647408 -88.03538) (xy 210.592565 -88.02525) (xy 210.539781 -88.007243)
			(xy 210.490181 -87.981742) (xy 210.444823 -87.949291) (xy 210.404674 -87.910582) (xy 210.370588 -87.866439)
			(xy 210.343292 -87.817804) (xy 210.323369 -87.765713) (xy 210.311243 -87.711276) (xy 210.307172 -87.655654)
			(xy 210.178142 -87.655654) (xy 210.177656 -87.682905) (xy 210.1699 -87.736853) (xy 210.154545 -87.789148)
			(xy 210.131903 -87.838725) (xy 210.102437 -87.884575) (xy 210.066746 -87.925766) (xy 210.025555 -87.961457)
			(xy 209.979705 -87.990923) (xy 209.930128 -88.013565) (xy 209.877833 -88.02892) (xy 209.823885 -88.036676)
			(xy 209.769383 -88.036676) (xy 209.715435 -88.02892) (xy 209.66314 -88.013565) (xy 209.613563 -87.990923)
			(xy 209.567713 -87.961457) (xy 209.526522 -87.925766) (xy 209.490831 -87.884575) (xy 209.461365 -87.838725)
			(xy 209.438723 -87.789148) (xy 209.423368 -87.736853) (xy 209.415612 -87.682905) (xy 209.415126 -87.655654)
			(xy 209.415126 -87.655146) (xy 209.415762 -87.624442) (xy 209.425642 -87.563833) (xy 209.445107 -87.505591)
			(xy 209.458814 -87.478108) (xy 209.461608 -87.47252) (xy 209.464656 -87.466678) (xy 209.464656 -80.578706)
			(xy 209.464485 -80.572697) (xy 209.461654 -80.561018) (xy 209.459068 -80.555592) (xy 209.457228 -80.552118)
			(xy 209.452633 -80.54574) (xy 209.449924 -80.542892) (xy 206.763366 -77.856334) (xy 206.757353 -77.850796)
			(xy 206.742711 -77.84355) (xy 206.734664 -77.84211) (xy 206.720241 -77.840581) (xy 206.69155 -77.844741)
			(xy 206.665185 -77.856796) (xy 206.64327 -77.875773) (xy 206.62757 -77.900145) (xy 206.619353 -77.927946)
			(xy 206.61884 -77.94244) (xy 206.61884 -78.201266) (xy 206.618288 -78.227251) (xy 206.609897 -78.278539)
			(xy 206.59339 -78.327818) (xy 206.569195 -78.373813) (xy 206.537938 -78.415333) (xy 206.519526 -78.433676)
			(xy 206.51851 -78.434438) (xy 206.463392 -78.489556) (xy 206.460344 -78.494636) (xy 206.450248 -78.510341)
			(xy 206.427082 -78.539623) (xy 206.414116 -78.553056) (xy 206.412338 -78.554834) (xy 205.9813 -78.985872)
			(xy 205.973426 -78.996032) (xy 205.970632 -79.000858) (xy 205.962557 -79.026708) (xy 205.940122 -79.075999)
			(xy 205.910947 -79.121625) (xy 205.875617 -79.16267) (xy 205.834841 -79.19831) (xy 205.81239 -79.213456)
			(xy 205.804262 -79.22006) (xy 205.800452 -79.22387) (xy 205.796613 -79.227898) (xy 205.790583 -79.237247)
			(xy 205.788514 -79.242412) (xy 205.785212 -79.25181) (xy 205.785466 -79.301086) (xy 205.78572 -79.346044)
			(xy 205.786176 -79.350927) (xy 205.788737 -79.360391) (xy 205.7908 -79.36484) (xy 205.792578 -79.368142)
			(xy 205.800452 -79.378302) (xy 205.80985 -79.3877) (xy 205.814676 -79.390748) (xy 205.83756 -79.405834)
			(xy 205.879156 -79.441525) (xy 205.915218 -79.4828) (xy 205.945003 -79.52881) (xy 205.967898 -79.578609)
			(xy 205.972882 -79.595472) (xy 207.251806 -79.595472) (xy 207.255877 -79.53985) (xy 207.268003 -79.485413)
			(xy 207.287926 -79.433322) (xy 207.315222 -79.384687) (xy 207.349308 -79.340544) (xy 207.389457 -79.301835)
			(xy 207.434815 -79.269384) (xy 207.484415 -79.243883) (xy 207.537199 -79.225876) (xy 207.592042 -79.215746)
			(xy 207.647776 -79.213709) (xy 207.703213 -79.219809) (xy 207.75717 -79.233915) (xy 207.808499 -79.255727)
			(xy 207.856105 -79.284781) (xy 207.898973 -79.320456) (xy 207.93619 -79.361993) (xy 207.966963 -79.408506)
			(xy 207.990635 -79.459003) (xy 208.006703 -79.51241) (xy 208.014823 -79.567586) (xy 208.015332 -79.595472)
			(xy 208.014823 -79.623358) (xy 208.006703 -79.678534) (xy 207.990635 -79.731941) (xy 207.966963 -79.782438)
			(xy 207.93619 -79.828951) (xy 207.898973 -79.870488) (xy 207.856105 -79.906163) (xy 207.808499 -79.935217)
			(xy 207.75717 -79.957029) (xy 207.703213 -79.971135) (xy 207.647776 -79.977235) (xy 207.592042 -79.975198)
			(xy 207.537199 -79.965068) (xy 207.484415 -79.947061) (xy 207.434815 -79.92156) (xy 207.389457 -79.889109)
			(xy 207.349308 -79.8504) (xy 207.315222 -79.806257) (xy 207.287926 -79.757622) (xy 207.268003 -79.705531)
			(xy 207.255877 -79.651094) (xy 207.251806 -79.595472) (xy 205.972882 -79.595472) (xy 205.983433 -79.631171)
			(xy 205.991286 -79.685415) (xy 205.991714 -79.71282) (xy 205.991228 -79.740071) (xy 205.983472 -79.794019)
			(xy 205.968117 -79.846314) (xy 205.945475 -79.895891) (xy 205.916009 -79.941741) (xy 205.880318 -79.982932)
			(xy 205.839127 -80.018623) (xy 205.793277 -80.048089) (xy 205.7437 -80.070731) (xy 205.691405 -80.086086)
			(xy 205.637457 -80.093842) (xy 205.582955 -80.093842) (xy 205.529007 -80.086086) (xy 205.476712 -80.070731)
			(xy 205.427135 -80.048089) (xy 205.381285 -80.018623) (xy 205.340094 -79.982932) (xy 205.304403 -79.941741)
			(xy 205.274937 -79.895891) (xy 205.252295 -79.846314) (xy 205.23694 -79.794019) (xy 205.229184 -79.740071)
			(xy 205.228698 -79.71282) (xy 205.229172 -79.68572) (xy 205.236842 -79.632066) (xy 205.252031 -79.580038)
			(xy 205.274432 -79.530684) (xy 205.303595 -79.484998) (xy 205.338931 -79.443901) (xy 205.37973 -79.40822)
			(xy 205.40218 -79.393034) (xy 205.40599 -79.390494) (xy 205.421484 -79.375) (xy 205.423262 -79.371952)
			(xy 205.426172 -79.366151) (xy 205.429257 -79.353549) (xy 205.429358 -79.34706) (xy 205.42885 -79.304134)
			(xy 205.42885 -79.303626) (xy 205.428596 -79.26324) (xy 205.428383 -79.257359) (xy 205.425555 -79.245939)
			(xy 205.423008 -79.240634) (xy 205.419452 -79.233268) (xy 205.409546 -79.223362) (xy 205.40091 -79.216504)
			(xy 205.377875 -79.201432) (xy 205.335988 -79.165714) (xy 205.299669 -79.124347) (xy 205.269671 -79.078191)
			(xy 205.246617 -79.028203) (xy 205.230986 -78.975421) (xy 205.223101 -78.92094) (xy 205.222602 -78.893416)
			(xy 205.223068 -78.866095) (xy 205.230857 -78.812012) (xy 205.246279 -78.759593) (xy 205.269018 -78.709908)
			(xy 205.29861 -78.663973) (xy 205.334449 -78.622727) (xy 205.375803 -78.587014) (xy 205.421828 -78.557562)
			(xy 205.471581 -78.534974) (xy 205.497684 -78.526894) (xy 205.503272 -78.525116) (xy 205.611476 -78.416912)
			(xy 205.832202 -78.19644) (xy 205.837983 -78.190065) (xy 205.845264 -78.174486) (xy 205.846426 -78.16596)
			(xy 205.84668 -78.16088) (xy 205.84668 -78.02753) (xy 205.846067 -78.015681) (xy 205.835476 -77.994483)
			(xy 205.82636 -77.98689) (xy 205.761336 -77.938122) (xy 205.754536 -77.933433) (xy 205.738858 -77.928268)
			(xy 205.730602 -77.927962) (xy 205.716886 -77.929994) (xy 205.716632 -77.929994) (xy 205.714854 -77.930502)
			(xy 205.71333 -77.93101) (xy 205.688682 -77.937457) (xy 205.638218 -77.944469) (xy 205.612746 -77.94498)
			(xy 205.610206 -77.94498) (xy 205.59395 -77.944726) (xy 205.593442 -77.944726) (xy 205.567014 -77.943071)
			(xy 205.514957 -77.933377) (xy 205.464739 -77.916584) (xy 205.417323 -77.893012) (xy 205.373619 -77.863114)
			(xy 205.334466 -77.827464) (xy 205.300614 -77.786746) (xy 205.272714 -77.74174) (xy 205.2513 -77.693312)
			(xy 205.236784 -77.642388) (xy 205.229443 -77.589948) (xy 205.228952 -77.563472) (xy 205.22944 -77.536221)
			(xy 205.237199 -77.482274) (xy 205.252556 -77.429981) (xy 205.275199 -77.380404) (xy 205.304665 -77.334555)
			(xy 205.340356 -77.293364) (xy 205.381545 -77.257672) (xy 205.427394 -77.228204) (xy 205.476969 -77.205561)
			(xy 205.529262 -77.190202) (xy 205.583209 -77.182441) (xy 205.61046 -77.181964) (xy 205.610968 -77.181964)
			(xy 205.632167 -77.182249) (xy 205.674304 -77.186954) (xy 205.695042 -77.191362) (xy 205.70063 -77.192632)
			(xy 205.725014 -77.192632) (xy 205.734666 -77.189076) (xy 205.73873 -77.187044) (xy 205.743048 -77.18425)
			(xy 205.783688 -77.151992) (xy 205.784196 -77.151992) (xy 205.805532 -77.135228) (xy 205.809193 -77.132267)
			(xy 205.815452 -77.125232) (xy 205.817978 -77.121258) (xy 205.818994 -77.11948) (xy 205.818994 -77.119226)
			(xy 205.820264 -77.117194) (xy 205.823063 -77.111624) (xy 205.82614 -77.099548) (xy 205.82636 -77.093318)
			(xy 205.82636 -67.775074) (xy 205.826295 -67.771468) (xy 205.825273 -67.76433) (xy 205.824328 -67.76085)
			(xy 205.822804 -67.756278) (xy 205.818994 -67.747134) (xy 205.247748 -67.175888) (xy 205.244897 -67.173182)
			(xy 205.23852 -67.168587) (xy 205.235048 -67.166744) (xy 205.229621 -67.16416) (xy 205.217942 -67.161336)
			(xy 205.211934 -67.161156) (xy 203.775818 -67.161156) (xy 203.772212 -67.161218) (xy 203.765072 -67.162234)
			(xy 203.761594 -67.163188) (xy 203.757022 -67.164712) (xy 203.747878 -67.168522) (xy 202.050396 -68.866004)
			(xy 202.045824 -68.871338) (xy 202.045824 -73.46442) (xy 202.045368 -73.497275) (xy 202.03802 -73.562574)
			(xy 202.023407 -73.62664) (xy 202.001713 -73.688666) (xy 201.973212 -73.747874) (xy 201.93826 -73.803518)
			(xy 201.897298 -73.8549) (xy 201.874374 -73.87844) (xy 200.909428 -74.843386) (xy 200.885863 -74.866281)
			(xy 200.834478 -74.90723) (xy 200.778834 -74.942174) (xy 200.719631 -74.970672) (xy 200.657611 -74.992369)
			(xy 200.593553 -75.00699) (xy 200.528261 -75.014353) (xy 200.495408 -75.014836) (xy 199.761094 -75.014836)
			(xy 199.727008 -75.01434) (xy 199.659297 -75.006425) (xy 199.592962 -74.990703) (xy 199.528901 -74.967386)
			(xy 199.46798 -74.93679) (xy 199.411023 -74.899329) (xy 199.358801 -74.855508) (xy 199.312018 -74.805921)
			(xy 199.271309 -74.751238) (xy 199.237223 -74.692199) (xy 199.210221 -74.629602) (xy 199.190669 -74.564294)
			(xy 199.178831 -74.497157) (xy 199.174867 -74.4291) (xy 199.178831 -74.361043) (xy 199.190669 -74.293906)
			(xy 199.210221 -74.228598) (xy 199.237223 -74.166001) (xy 199.271309 -74.106962) (xy 199.312018 -74.052279)
			(xy 199.358801 -74.002692) (xy 199.411023 -73.958871) (xy 199.46798 -73.92141) (xy 199.528901 -73.890814)
			(xy 199.592962 -73.867497) (xy 199.659297 -73.851775) (xy 199.727008 -73.84386) (xy 199.761094 -73.843388)
			(xy 200.231502 -73.843388) (xy 200.239213 -73.843165) (xy 200.253958 -73.838652) (xy 200.260458 -73.834498)
			(xy 200.264522 -73.831196) (xy 200.467468 -73.62825) (xy 200.467976 -73.618344) (xy 200.46188 -73.56602)
			(xy 200.4568 -73.523856) (xy 200.456038 -73.522586) (xy 200.444608 -73.516236) (xy 200.4441 -73.515728)
			(xy 200.434702 -73.510394) (xy 200.405724 -73.492837) (xy 200.351623 -73.452045) (xy 200.302587 -73.405286)
			(xy 200.259272 -73.353183) (xy 200.222254 -73.296432) (xy 200.192028 -73.235791) (xy 200.168997 -73.172069)
			(xy 200.153469 -73.106116) (xy 200.145651 -73.038812) (xy 200.145142 -73.004934) (xy 200.145396 -71.41591)
			(xy 200.145396 -69.35724) (xy 200.144979 -69.34719) (xy 200.13728 -69.328624) (xy 200.123046 -69.314433)
			(xy 200.1139 -69.31025) (xy 200.110598 -69.308726) (xy 200.106788 -69.307202) (xy 200.091802 -69.305678)
			(xy 200.08469 -69.307202) (xy 200.077497 -69.308923) (xy 200.064457 -69.315887) (xy 200.059036 -69.320918)
			(xy 196.079872 -73.300082) (xy 196.077164 -73.302931) (xy 196.072566 -73.309307) (xy 196.070728 -73.312782)
			(xy 196.068148 -73.318209) (xy 196.065331 -73.329889) (xy 196.06514 -73.335896) (xy 196.06514 -76.37653)
			(xy 196.064378 -76.40828) (xy 196.064378 -76.408534) (xy 196.064124 -76.41082) (xy 196.064124 -76.62545)
			(xy 204.32979 -76.62545) (xy 204.333861 -76.569828) (xy 204.345987 -76.515391) (xy 204.36591 -76.4633)
			(xy 204.393206 -76.414665) (xy 204.427292 -76.370522) (xy 204.467441 -76.331813) (xy 204.512799 -76.299362)
			(xy 204.562399 -76.273861) (xy 204.615183 -76.255854) (xy 204.670026 -76.245724) (xy 204.72576 -76.243687)
			(xy 204.781197 -76.249787) (xy 204.835154 -76.263893) (xy 204.886483 -76.285705) (xy 204.934089 -76.314759)
			(xy 204.976957 -76.350434) (xy 205.014174 -76.391971) (xy 205.044947 -76.438484) (xy 205.068619 -76.488981)
			(xy 205.084687 -76.542388) (xy 205.092807 -76.597564) (xy 205.093316 -76.62545) (xy 205.092807 -76.653336)
			(xy 205.084687 -76.708512) (xy 205.068619 -76.761919) (xy 205.044947 -76.812416) (xy 205.014174 -76.858929)
			(xy 204.976957 -76.900466) (xy 204.934089 -76.936141) (xy 204.886483 -76.965195) (xy 204.835154 -76.987007)
			(xy 204.781197 -77.001113) (xy 204.72576 -77.007213) (xy 204.670026 -77.005176) (xy 204.615183 -76.995046)
			(xy 204.562399 -76.977039) (xy 204.512799 -76.951538) (xy 204.467441 -76.919087) (xy 204.427292 -76.880378)
			(xy 204.393206 -76.836235) (xy 204.36591 -76.7876) (xy 204.345987 -76.735509) (xy 204.333861 -76.681072)
			(xy 204.32979 -76.62545) (xy 196.064124 -76.62545) (xy 196.064124 -76.694284) (xy 196.063665 -76.727138)
			(xy 196.05631 -76.792433) (xy 196.041691 -76.856495) (xy 196.019993 -76.918517) (xy 195.991486 -76.977719)
			(xy 195.956531 -77.033358) (xy 195.915567 -77.084734) (xy 195.892674 -77.108304) (xy 195.79463 -77.206348)
			(xy 198.783954 -77.206348) (xy 198.788025 -77.150726) (xy 198.800151 -77.096289) (xy 198.820074 -77.044198)
			(xy 198.84737 -76.995563) (xy 198.881456 -76.95142) (xy 198.921605 -76.912711) (xy 198.966963 -76.88026)
			(xy 199.016563 -76.854759) (xy 199.069347 -76.836752) (xy 199.12419 -76.826622) (xy 199.179924 -76.824585)
			(xy 199.235361 -76.830685) (xy 199.289318 -76.844791) (xy 199.340647 -76.866603) (xy 199.388253 -76.895657)
			(xy 199.431121 -76.931332) (xy 199.468338 -76.972869) (xy 199.499111 -77.019382) (xy 199.522783 -77.069879)
			(xy 199.538851 -77.123286) (xy 199.546971 -77.178462) (xy 199.54748 -77.206348) (xy 199.546971 -77.234234)
			(xy 199.538851 -77.28941) (xy 199.522783 -77.342817) (xy 199.499111 -77.393314) (xy 199.468338 -77.439827)
			(xy 199.431121 -77.481364) (xy 199.388253 -77.517039) (xy 199.340647 -77.546093) (xy 199.289318 -77.567905)
			(xy 199.235361 -77.582011) (xy 199.179924 -77.588111) (xy 199.12419 -77.586074) (xy 199.069347 -77.575944)
			(xy 199.016563 -77.557937) (xy 198.966963 -77.532436) (xy 198.921605 -77.499985) (xy 198.881456 -77.461276)
			(xy 198.84737 -77.417133) (xy 198.820074 -77.368498) (xy 198.800151 -77.316407) (xy 198.788025 -77.26197)
			(xy 198.783954 -77.206348) (xy 195.79463 -77.206348) (xy 193.819018 -79.18196) (xy 195.691506 -79.18196)
			(xy 195.691992 -79.154709) (xy 195.699748 -79.100761) (xy 195.715103 -79.048466) (xy 195.737745 -78.998889)
			(xy 195.767211 -78.953039) (xy 195.802902 -78.911848) (xy 195.844093 -78.876157) (xy 195.889943 -78.846691)
			(xy 195.93952 -78.824049) (xy 195.991815 -78.808694) (xy 196.045763 -78.800938) (xy 196.100265 -78.800938)
			(xy 196.154213 -78.808694) (xy 196.206508 -78.824049) (xy 196.256085 -78.846691) (xy 196.301935 -78.876157)
			(xy 196.343126 -78.911848) (xy 196.378817 -78.953039) (xy 196.408283 -78.998889) (xy 196.430925 -79.048466)
			(xy 196.44628 -79.100761) (xy 196.454036 -79.154709) (xy 196.454522 -79.18196) (xy 196.453958 -79.210843)
			(xy 196.445242 -79.267948) (xy 196.428018 -79.323087) (xy 196.402681 -79.375) (xy 196.369808 -79.422501)
			(xy 196.33015 -79.464504) (xy 196.30771 -79.482696) (xy 196.296786 -79.491858) (xy 196.280033 -79.51491)
			(xy 196.270293 -79.541691) (xy 196.268324 -79.57012) (xy 196.274279 -79.597987) (xy 196.287695 -79.623129)
			(xy 196.307529 -79.64359) (xy 196.319648 -79.651098) (xy 196.344249 -79.665763) (xy 196.389122 -79.701351)
			(xy 196.42817 -79.743248) (xy 196.460515 -79.790512) (xy 196.48543 -79.84208) (xy 196.502355 -79.896794)
			(xy 196.510909 -79.953424) (xy 196.511418 -79.98206) (xy 196.510932 -80.009311) (xy 196.503176 -80.063259)
			(xy 196.487821 -80.115554) (xy 196.465179 -80.165131) (xy 196.435713 -80.210981) (xy 196.400022 -80.252172)
			(xy 196.358831 -80.287863) (xy 196.312981 -80.317329) (xy 196.263404 -80.339971) (xy 196.211109 -80.355326)
			(xy 196.157161 -80.363082) (xy 196.102659 -80.363082) (xy 196.048711 -80.355326) (xy 195.996416 -80.339971)
			(xy 195.946839 -80.317329) (xy 195.900989 -80.287863) (xy 195.859798 -80.252172) (xy 195.824107 -80.210981)
			(xy 195.794641 -80.165131) (xy 195.771999 -80.115554) (xy 195.756644 -80.063259) (xy 195.748888 -80.009311)
			(xy 195.748402 -79.98206) (xy 195.7489 -79.953174) (xy 195.757628 -79.896066) (xy 195.774865 -79.840925)
			(xy 195.800215 -79.789012) (xy 195.8331 -79.741513) (xy 195.872768 -79.699514) (xy 195.895214 -79.681324)
			(xy 195.906112 -79.672135) (xy 195.922862 -79.649089) (xy 195.9326 -79.622315) (xy 195.934571 -79.593893)
			(xy 195.928622 -79.566031) (xy 195.915215 -79.540893) (xy 195.89539 -79.520431) (xy 195.883276 -79.512922)
			(xy 195.858667 -79.498271) (xy 195.813797 -79.462678) (xy 195.774752 -79.420778) (xy 195.74241 -79.373511)
			(xy 195.717496 -79.321941) (xy 195.700572 -79.267226) (xy 195.692016 -79.210596) (xy 195.691506 -79.18196)
			(xy 193.819018 -79.18196) (xy 192.389506 -80.611472) (xy 205.228442 -80.611472) (xy 205.232513 -80.55585)
			(xy 205.244639 -80.501413) (xy 205.264562 -80.449322) (xy 205.291858 -80.400687) (xy 205.325944 -80.356544)
			(xy 205.366093 -80.317835) (xy 205.411451 -80.285384) (xy 205.461051 -80.259883) (xy 205.513835 -80.241876)
			(xy 205.568678 -80.231746) (xy 205.624412 -80.229709) (xy 205.679849 -80.235809) (xy 205.733806 -80.249915)
			(xy 205.785135 -80.271727) (xy 205.832741 -80.300781) (xy 205.875609 -80.336456) (xy 205.912826 -80.377993)
			(xy 205.943599 -80.424506) (xy 205.967271 -80.475003) (xy 205.983339 -80.52841) (xy 205.991459 -80.583586)
			(xy 205.991968 -80.611472) (xy 205.991459 -80.639358) (xy 205.983339 -80.694534) (xy 205.967271 -80.747941)
			(xy 205.943599 -80.798438) (xy 205.912826 -80.844951) (xy 205.875609 -80.886488) (xy 205.832741 -80.922163)
			(xy 205.785135 -80.951217) (xy 205.733806 -80.973029) (xy 205.679849 -80.987135) (xy 205.624412 -80.993235)
			(xy 205.568678 -80.991198) (xy 205.513835 -80.981068) (xy 205.461051 -80.963061) (xy 205.411451 -80.93756)
			(xy 205.366093 -80.905109) (xy 205.325944 -80.8664) (xy 205.291858 -80.822257) (xy 205.264562 -80.773622)
			(xy 205.244639 -80.721531) (xy 205.232513 -80.667094) (xy 205.228442 -80.611472) (xy 192.389506 -80.611472)
			(xy 191.822578 -81.1784) (xy 207.161382 -81.1784) (xy 207.165453 -81.122778) (xy 207.177579 -81.068341)
			(xy 207.197502 -81.01625) (xy 207.224798 -80.967615) (xy 207.258884 -80.923472) (xy 207.299033 -80.884763)
			(xy 207.344391 -80.852312) (xy 207.393991 -80.826811) (xy 207.446775 -80.808804) (xy 207.501618 -80.798674)
			(xy 207.557352 -80.796637) (xy 207.612789 -80.802737) (xy 207.666746 -80.816843) (xy 207.718075 -80.838655)
			(xy 207.765681 -80.867709) (xy 207.808549 -80.903384) (xy 207.845766 -80.944921) (xy 207.876539 -80.991434)
			(xy 207.900211 -81.041931) (xy 207.916279 -81.095338) (xy 207.924399 -81.150514) (xy 207.924908 -81.1784)
			(xy 207.924399 -81.206286) (xy 207.916279 -81.261462) (xy 207.900211 -81.314869) (xy 207.876539 -81.365366)
			(xy 207.845766 -81.411879) (xy 207.808549 -81.453416) (xy 207.765681 -81.489091) (xy 207.718075 -81.518145)
			(xy 207.666746 -81.539957) (xy 207.612789 -81.554063) (xy 207.557352 -81.560163) (xy 207.501618 -81.558126)
			(xy 207.446775 -81.547996) (xy 207.393991 -81.529989) (xy 207.344391 -81.504488) (xy 207.299033 -81.472037)
			(xy 207.258884 -81.433328) (xy 207.224798 -81.389185) (xy 207.197502 -81.34055) (xy 207.177579 -81.288459)
			(xy 207.165453 -81.234022) (xy 207.161382 -81.1784) (xy 191.822578 -81.1784) (xy 191.373506 -81.627472)
			(xy 205.228442 -81.627472) (xy 205.232513 -81.57185) (xy 205.244639 -81.517413) (xy 205.264562 -81.465322)
			(xy 205.291858 -81.416687) (xy 205.325944 -81.372544) (xy 205.366093 -81.333835) (xy 205.411451 -81.301384)
			(xy 205.461051 -81.275883) (xy 205.513835 -81.257876) (xy 205.568678 -81.247746) (xy 205.624412 -81.245709)
			(xy 205.679849 -81.251809) (xy 205.733806 -81.265915) (xy 205.785135 -81.287727) (xy 205.832741 -81.316781)
			(xy 205.875609 -81.352456) (xy 205.912826 -81.393993) (xy 205.943599 -81.440506) (xy 205.967271 -81.491003)
			(xy 205.983339 -81.54441) (xy 205.991459 -81.599586) (xy 205.991968 -81.627472) (xy 205.991459 -81.655358)
			(xy 205.983339 -81.710534) (xy 205.967271 -81.763941) (xy 205.943599 -81.814438) (xy 205.912826 -81.860951)
			(xy 205.875609 -81.902488) (xy 205.832741 -81.938163) (xy 205.785135 -81.967217) (xy 205.733806 -81.989029)
			(xy 205.679849 -82.003135) (xy 205.624412 -82.009235) (xy 205.568678 -82.007198) (xy 205.513835 -81.997068)
			(xy 205.461051 -81.979061) (xy 205.411451 -81.95356) (xy 205.366093 -81.921109) (xy 205.325944 -81.8824)
			(xy 205.291858 -81.838257) (xy 205.264562 -81.789622) (xy 205.244639 -81.737531) (xy 205.232513 -81.683094)
			(xy 205.228442 -81.627472) (xy 191.373506 -81.627472) (xy 190.573406 -82.427572) (xy 195.032628 -82.427572)
			(xy 195.036699 -82.37195) (xy 195.048825 -82.317513) (xy 195.068748 -82.265422) (xy 195.096044 -82.216787)
			(xy 195.13013 -82.172644) (xy 195.170279 -82.133935) (xy 195.215637 -82.101484) (xy 195.265237 -82.075983)
			(xy 195.318021 -82.057976) (xy 195.372864 -82.047846) (xy 195.428598 -82.045809) (xy 195.484035 -82.051909)
			(xy 195.537992 -82.066015) (xy 195.589321 -82.087827) (xy 195.636927 -82.116881) (xy 195.679795 -82.152556)
			(xy 195.717012 -82.194093) (xy 195.747785 -82.240606) (xy 195.771457 -82.291103) (xy 195.787525 -82.34451)
			(xy 195.795645 -82.399686) (xy 195.796154 -82.427572) (xy 195.795645 -82.455458) (xy 195.787525 -82.510634)
			(xy 195.771457 -82.564041) (xy 195.747785 -82.614538) (xy 195.717012 -82.661051) (xy 195.679795 -82.702588)
			(xy 195.636927 -82.738263) (xy 195.589321 -82.767317) (xy 195.587874 -82.767932) (xy 203.09662 -82.767932)
			(xy 203.100691 -82.71231) (xy 203.112817 -82.657873) (xy 203.13274 -82.605782) (xy 203.160036 -82.557147)
			(xy 203.194122 -82.513004) (xy 203.234271 -82.474295) (xy 203.279629 -82.441844) (xy 203.329229 -82.416343)
			(xy 203.382013 -82.398336) (xy 203.436856 -82.388206) (xy 203.49259 -82.386169) (xy 203.548027 -82.392269)
			(xy 203.601984 -82.406375) (xy 203.653313 -82.428187) (xy 203.700919 -82.457241) (xy 203.743787 -82.492916)
			(xy 203.781004 -82.534453) (xy 203.811777 -82.580966) (xy 203.835449 -82.631463) (xy 203.839062 -82.643472)
			(xy 205.228442 -82.643472) (xy 205.232513 -82.58785) (xy 205.244639 -82.533413) (xy 205.264562 -82.481322)
			(xy 205.291858 -82.432687) (xy 205.325944 -82.388544) (xy 205.366093 -82.349835) (xy 205.411451 -82.317384)
			(xy 205.461051 -82.291883) (xy 205.513835 -82.273876) (xy 205.568678 -82.263746) (xy 205.624412 -82.261709)
			(xy 205.679849 -82.267809) (xy 205.733806 -82.281915) (xy 205.785135 -82.303727) (xy 205.832741 -82.332781)
			(xy 205.875609 -82.368456) (xy 205.912826 -82.409993) (xy 205.943599 -82.456506) (xy 205.967271 -82.507003)
			(xy 205.983339 -82.56041) (xy 205.991459 -82.615586) (xy 205.991968 -82.643472) (xy 205.991459 -82.671358)
			(xy 205.983339 -82.726534) (xy 205.967271 -82.779941) (xy 205.943599 -82.830438) (xy 205.912826 -82.876951)
			(xy 205.875609 -82.918488) (xy 205.832741 -82.954163) (xy 205.785135 -82.983217) (xy 205.733806 -83.005029)
			(xy 205.679849 -83.019135) (xy 205.624412 -83.025235) (xy 205.568678 -83.023198) (xy 205.513835 -83.013068)
			(xy 205.461051 -82.995061) (xy 205.411451 -82.96956) (xy 205.366093 -82.937109) (xy 205.325944 -82.8984)
			(xy 205.291858 -82.854257) (xy 205.264562 -82.805622) (xy 205.244639 -82.753531) (xy 205.232513 -82.699094)
			(xy 205.228442 -82.643472) (xy 203.839062 -82.643472) (xy 203.851517 -82.68487) (xy 203.859637 -82.740046)
			(xy 203.860146 -82.767932) (xy 203.859637 -82.795818) (xy 203.851517 -82.850994) (xy 203.835449 -82.904401)
			(xy 203.811777 -82.954898) (xy 203.781004 -83.001411) (xy 203.743787 -83.042948) (xy 203.700919 -83.078623)
			(xy 203.653313 -83.107677) (xy 203.601984 -83.129489) (xy 203.548027 -83.143595) (xy 203.49259 -83.149695)
			(xy 203.436856 -83.147658) (xy 203.382013 -83.137528) (xy 203.329229 -83.119521) (xy 203.279629 -83.09402)
			(xy 203.234271 -83.061569) (xy 203.194122 -83.02286) (xy 203.160036 -82.978717) (xy 203.13274 -82.930082)
			(xy 203.112817 -82.877991) (xy 203.100691 -82.823554) (xy 203.09662 -82.767932) (xy 195.587874 -82.767932)
			(xy 195.537992 -82.789129) (xy 195.484035 -82.803235) (xy 195.428598 -82.809335) (xy 195.372864 -82.807298)
			(xy 195.318021 -82.797168) (xy 195.265237 -82.779161) (xy 195.215637 -82.75366) (xy 195.170279 -82.721209)
			(xy 195.13013 -82.6825) (xy 195.096044 -82.638357) (xy 195.068748 -82.589722) (xy 195.048825 -82.537631)
			(xy 195.036699 -82.483194) (xy 195.032628 -82.427572) (xy 190.573406 -82.427572) (xy 189.698884 -83.302094)
			(xy 189.675319 -83.324991) (xy 189.623936 -83.365945) (xy 189.568293 -83.400893) (xy 189.50909 -83.429397)
			(xy 189.447069 -83.451099) (xy 189.383011 -83.465726) (xy 189.317718 -83.473095) (xy 189.284864 -83.473544)
			(xy 189.20968 -83.473544) (xy 189.20601 -83.473588) (xy 189.198741 -83.474605) (xy 189.195202 -83.475576)
			(xy 189.188598 -83.477608) (xy 189.18174 -83.48218) (xy 189.153411 -83.500329) (xy 189.093341 -83.530631)
			(xy 189.089 -83.532218) (xy 192.411348 -83.532218) (xy 192.415419 -83.476596) (xy 192.427545 -83.422159)
			(xy 192.447468 -83.370068) (xy 192.474764 -83.321433) (xy 192.50885 -83.27729) (xy 192.548999 -83.238581)
			(xy 192.594357 -83.20613) (xy 192.643957 -83.180629) (xy 192.696741 -83.162622) (xy 192.751584 -83.152492)
			(xy 192.807318 -83.150455) (xy 192.862755 -83.156555) (xy 192.916712 -83.170661) (xy 192.968041 -83.192473)
			(xy 193.015647 -83.221527) (xy 193.058515 -83.257202) (xy 193.095732 -83.298739) (xy 193.126505 -83.345252)
			(xy 193.150177 -83.395749) (xy 193.166245 -83.449156) (xy 193.174365 -83.504332) (xy 193.174874 -83.532218)
			(xy 193.174365 -83.560104) (xy 193.166245 -83.61528) (xy 193.150177 -83.668687) (xy 193.126505 -83.719184)
			(xy 193.095732 -83.765697) (xy 193.058515 -83.807234) (xy 193.015647 -83.842909) (xy 192.968041 -83.871963)
			(xy 192.916712 -83.893775) (xy 192.862755 -83.907881) (xy 192.807318 -83.913981) (xy 192.751584 -83.911944)
			(xy 192.696741 -83.901814) (xy 192.643957 -83.883807) (xy 192.594357 -83.858306) (xy 192.548999 -83.825855)
			(xy 192.50885 -83.787146) (xy 192.474764 -83.743003) (xy 192.447468 -83.694368) (xy 192.427545 -83.642277)
			(xy 192.415419 -83.58784) (xy 192.411348 -83.532218) (xy 189.089 -83.532218) (xy 189.03015 -83.553734)
			(xy 188.9647 -83.569322) (xy 188.89788 -83.577183) (xy 188.86424 -83.577684) (xy 184.82564 -83.577684)
			(xy 184.815677 -83.578169) (xy 184.79725 -83.585753) (xy 184.789826 -83.592416) (xy 182.134256 -86.247986)
			(xy 191.338452 -86.247986) (xy 191.342523 -86.192364) (xy 191.354649 -86.137927) (xy 191.374572 -86.085836)
			(xy 191.401868 -86.037201) (xy 191.435954 -85.993058) (xy 191.476103 -85.954349) (xy 191.521461 -85.921898)
			(xy 191.571061 -85.896397) (xy 191.623845 -85.87839) (xy 191.678688 -85.86826) (xy 191.734422 -85.866223)
			(xy 191.789859 -85.872323) (xy 191.843816 -85.886429) (xy 191.895145 -85.908241) (xy 191.942751 -85.937295)
			(xy 191.985619 -85.97297) (xy 192.022836 -86.014507) (xy 192.053609 -86.06102) (xy 192.077281 -86.111517)
			(xy 192.093349 -86.164924) (xy 192.101469 -86.2201) (xy 192.101978 -86.247986) (xy 192.101469 -86.275872)
			(xy 192.093349 -86.331048) (xy 192.077281 -86.384455) (xy 192.053609 -86.434952) (xy 192.022836 -86.481465)
			(xy 191.985619 -86.523002) (xy 191.942751 -86.558677) (xy 191.895145 -86.587731) (xy 191.843816 -86.609543)
			(xy 191.789859 -86.623649) (xy 191.734422 -86.629749) (xy 191.678688 -86.627712) (xy 191.623845 -86.617582)
			(xy 191.571061 -86.599575) (xy 191.521461 -86.574074) (xy 191.476103 -86.541623) (xy 191.435954 -86.502914)
			(xy 191.401868 -86.458771) (xy 191.374572 -86.410136) (xy 191.354649 -86.358045) (xy 191.342523 -86.303608)
			(xy 191.338452 -86.247986) (xy 182.134256 -86.247986) (xy 180.006244 -88.375998) (xy 195.924168 -88.375998)
			(xy 195.928239 -88.320376) (xy 195.940365 -88.265939) (xy 195.960288 -88.213848) (xy 195.987584 -88.165213)
			(xy 196.02167 -88.12107) (xy 196.061819 -88.082361) (xy 196.107177 -88.04991) (xy 196.156777 -88.024409)
			(xy 196.209561 -88.006402) (xy 196.264404 -87.996272) (xy 196.320138 -87.994235) (xy 196.375575 -88.000335)
			(xy 196.429532 -88.014441) (xy 196.480861 -88.036253) (xy 196.528467 -88.065307) (xy 196.571335 -88.100982)
			(xy 196.608552 -88.142519) (xy 196.639325 -88.189032) (xy 196.662997 -88.239529) (xy 196.679065 -88.292936)
			(xy 196.687185 -88.348112) (xy 196.687694 -88.375998) (xy 196.687332 -88.39581) (xy 197.35749 -88.39581)
			(xy 197.361561 -88.340188) (xy 197.373687 -88.285751) (xy 197.39361 -88.23366) (xy 197.420906 -88.185025)
			(xy 197.454992 -88.140882) (xy 197.495141 -88.102173) (xy 197.540499 -88.069722) (xy 197.590099 -88.044221)
			(xy 197.642883 -88.026214) (xy 197.697726 -88.016084) (xy 197.75346 -88.014047) (xy 197.808897 -88.020147)
			(xy 197.862854 -88.034253) (xy 197.914183 -88.056065) (xy 197.961789 -88.085119) (xy 198.004657 -88.120794)
			(xy 198.041874 -88.162331) (xy 198.072647 -88.208844) (xy 198.096319 -88.259341) (xy 198.112387 -88.312748)
			(xy 198.120507 -88.367924) (xy 198.121016 -88.39581) (xy 198.120507 -88.423696) (xy 198.112387 -88.478872)
			(xy 198.096319 -88.532279) (xy 198.072647 -88.582776) (xy 198.041874 -88.629289) (xy 198.004657 -88.670826)
			(xy 197.961789 -88.706501) (xy 197.914183 -88.735555) (xy 197.862854 -88.757367) (xy 197.808897 -88.771473)
			(xy 197.75346 -88.777573) (xy 197.697726 -88.775536) (xy 197.642883 -88.765406) (xy 197.590099 -88.747399)
			(xy 197.540499 -88.721898) (xy 197.495141 -88.689447) (xy 197.454992 -88.650738) (xy 197.420906 -88.606595)
			(xy 197.39361 -88.55796) (xy 197.373687 -88.505869) (xy 197.361561 -88.451432) (xy 197.35749 -88.39581)
			(xy 196.687332 -88.39581) (xy 196.687185 -88.403884) (xy 196.679065 -88.45906) (xy 196.662997 -88.512467)
			(xy 196.639325 -88.562964) (xy 196.608552 -88.609477) (xy 196.571335 -88.651014) (xy 196.528467 -88.686689)
			(xy 196.480861 -88.715743) (xy 196.429532 -88.737555) (xy 196.375575 -88.751661) (xy 196.320138 -88.757761)
			(xy 196.264404 -88.755724) (xy 196.209561 -88.745594) (xy 196.156777 -88.727587) (xy 196.107177 -88.702086)
			(xy 196.061819 -88.669635) (xy 196.02167 -88.630926) (xy 195.987584 -88.586783) (xy 195.960288 -88.538148)
			(xy 195.940365 -88.486057) (xy 195.928239 -88.43162) (xy 195.924168 -88.375998) (xy 180.006244 -88.375998)
			(xy 178.524916 -89.857326) (xy 178.521614 -89.86139) (xy 178.517484 -89.867902) (xy 178.512966 -89.882638)
			(xy 178.512724 -89.890346) (xy 178.512724 -89.906094) (xy 192.562478 -89.906094) (xy 192.566549 -89.850472)
			(xy 192.578675 -89.796035) (xy 192.598598 -89.743944) (xy 192.625894 -89.695309) (xy 192.65998 -89.651166)
			(xy 192.700129 -89.612457) (xy 192.745487 -89.580006) (xy 192.795087 -89.554505) (xy 192.847871 -89.536498)
			(xy 192.902714 -89.526368) (xy 192.958448 -89.524331) (xy 193.013885 -89.530431) (xy 193.067842 -89.544537)
			(xy 193.119171 -89.566349) (xy 193.166777 -89.595403) (xy 193.209645 -89.631078) (xy 193.246862 -89.672615)
			(xy 193.277635 -89.719128) (xy 193.301307 -89.769625) (xy 193.304844 -89.78138) (xy 196.320408 -89.78138)
			(xy 196.324479 -89.725758) (xy 196.336605 -89.671321) (xy 196.356528 -89.61923) (xy 196.383824 -89.570595)
			(xy 196.41791 -89.526452) (xy 196.458059 -89.487743) (xy 196.503417 -89.455292) (xy 196.553017 -89.429791)
			(xy 196.605801 -89.411784) (xy 196.660644 -89.401654) (xy 196.716378 -89.399617) (xy 196.771815 -89.405717)
			(xy 196.825772 -89.419823) (xy 196.877101 -89.441635) (xy 196.924707 -89.470689) (xy 196.967575 -89.506364)
			(xy 197.004792 -89.547901) (xy 197.035565 -89.594414) (xy 197.059237 -89.644911) (xy 197.075305 -89.698318)
			(xy 197.083425 -89.753494) (xy 197.083934 -89.78138) (xy 197.083425 -89.809266) (xy 197.075305 -89.864442)
			(xy 197.059237 -89.917849) (xy 197.035565 -89.968346) (xy 197.004792 -90.014859) (xy 196.967575 -90.056396)
			(xy 196.924707 -90.092071) (xy 196.877101 -90.121125) (xy 196.825772 -90.142937) (xy 196.771815 -90.157043)
			(xy 196.716378 -90.163143) (xy 196.660644 -90.161106) (xy 196.605801 -90.150976) (xy 196.553017 -90.132969)
			(xy 196.503417 -90.107468) (xy 196.458059 -90.075017) (xy 196.41791 -90.036308) (xy 196.383824 -89.992165)
			(xy 196.356528 -89.94353) (xy 196.336605 -89.891439) (xy 196.324479 -89.837002) (xy 196.320408 -89.78138)
			(xy 193.304844 -89.78138) (xy 193.317375 -89.823032) (xy 193.325495 -89.878208) (xy 193.326004 -89.906094)
			(xy 193.325495 -89.93398) (xy 193.317375 -89.989156) (xy 193.301307 -90.042563) (xy 193.277635 -90.09306)
			(xy 193.246862 -90.139573) (xy 193.209645 -90.18111) (xy 193.166777 -90.216785) (xy 193.119171 -90.245839)
			(xy 193.067842 -90.267651) (xy 193.013885 -90.281757) (xy 192.958448 -90.287857) (xy 192.902714 -90.28582)
			(xy 192.847871 -90.27569) (xy 192.795087 -90.257683) (xy 192.745487 -90.232182) (xy 192.700129 -90.199731)
			(xy 192.65998 -90.161022) (xy 192.625894 -90.116879) (xy 192.598598 -90.068244) (xy 192.578675 -90.016153)
			(xy 192.566549 -89.961716) (xy 192.562478 -89.906094) (xy 178.512724 -89.906094) (xy 178.512724 -90.621866)
			(xy 180.64175 -90.621866) (xy 180.645821 -90.566244) (xy 180.657947 -90.511807) (xy 180.67787 -90.459716)
			(xy 180.705166 -90.411081) (xy 180.739252 -90.366938) (xy 180.779401 -90.328229) (xy 180.824759 -90.295778)
			(xy 180.874359 -90.270277) (xy 180.927143 -90.25227) (xy 180.981986 -90.24214) (xy 181.03772 -90.240103)
			(xy 181.093157 -90.246203) (xy 181.147114 -90.260309) (xy 181.198443 -90.282121) (xy 181.246049 -90.311175)
			(xy 181.288917 -90.34685) (xy 181.326134 -90.388387) (xy 181.356907 -90.4349) (xy 181.380579 -90.485397)
			(xy 181.396647 -90.538804) (xy 181.404767 -90.59398) (xy 181.405276 -90.621866) (xy 181.404767 -90.649752)
			(xy 181.396647 -90.704928) (xy 181.380579 -90.758335) (xy 181.356907 -90.808832) (xy 181.326134 -90.855345)
			(xy 181.288917 -90.896882) (xy 181.246049 -90.932557) (xy 181.198443 -90.961611) (xy 181.147114 -90.983423)
			(xy 181.093157 -90.997529) (xy 181.03772 -91.003629) (xy 180.981986 -91.001592) (xy 180.927143 -90.991462)
			(xy 180.874359 -90.973455) (xy 180.824759 -90.947954) (xy 180.779401 -90.915503) (xy 180.739252 -90.876794)
			(xy 180.705166 -90.832651) (xy 180.67787 -90.784016) (xy 180.657947 -90.731925) (xy 180.645821 -90.677488)
			(xy 180.64175 -90.621866) (xy 178.512724 -90.621866) (xy 178.512724 -95.214948) (xy 187.739796 -95.214948)
			(xy 187.743748 -95.123155) (xy 187.755578 -95.032041) (xy 187.775195 -94.942281) (xy 187.802457 -94.85454)
			(xy 187.83716 -94.769468) (xy 187.879048 -94.687693) (xy 187.927811 -94.609822) (xy 187.983087 -94.536432)
			(xy 188.044468 -94.468065) (xy 188.111499 -94.405227) (xy 188.183683 -94.348385) (xy 188.260487 -94.297958)
			(xy 188.341341 -94.25432) (xy 188.425647 -94.217794) (xy 188.512781 -94.188651) (xy 188.602098 -94.167106)
			(xy 188.692936 -94.15332) (xy 188.784623 -94.147393) (xy 188.87648 -94.14937) (xy 188.967828 -94.159236)
			(xy 189.057988 -94.176918) (xy 189.146296 -94.202285) (xy 189.232095 -94.23515) (xy 189.314752 -94.275269)
			(xy 189.393654 -94.322345) (xy 189.468217 -94.376029) (xy 189.537889 -94.435925) (xy 189.602154 -94.501588)
			(xy 189.660537 -94.572532) (xy 189.712604 -94.648233) (xy 189.757972 -94.72813) (xy 189.796303 -94.81163)
			(xy 189.827314 -94.898117) (xy 189.850775 -94.98695) (xy 189.866514 -95.07747) (xy 189.874412 -95.169009)
			(xy 189.874906 -95.214948) (xy 189.874412 -95.260887) (xy 189.866514 -95.352426) (xy 189.850775 -95.442946)
			(xy 189.827314 -95.531779) (xy 189.796303 -95.618266) (xy 189.757972 -95.701766) (xy 189.712604 -95.781663)
			(xy 189.660537 -95.857364) (xy 189.602154 -95.928308) (xy 189.54212 -95.989648) (xy 191.663826 -95.989648)
			(xy 191.667897 -95.934026) (xy 191.680023 -95.879589) (xy 191.699946 -95.827498) (xy 191.727242 -95.778863)
			(xy 191.761328 -95.73472) (xy 191.801477 -95.696011) (xy 191.846835 -95.66356) (xy 191.896435 -95.638059)
			(xy 191.949219 -95.620052) (xy 192.004062 -95.609922) (xy 192.059796 -95.607885) (xy 192.115233 -95.613985)
			(xy 192.16919 -95.628091) (xy 192.220519 -95.649903) (xy 192.268125 -95.678957) (xy 192.310993 -95.714632)
			(xy 192.34821 -95.756169) (xy 192.378983 -95.802682) (xy 192.402655 -95.853179) (xy 192.418723 -95.906586)
			(xy 192.426843 -95.961762) (xy 192.427352 -95.989648) (xy 194.269358 -95.989648) (xy 194.273429 -95.934026)
			(xy 194.285555 -95.879589) (xy 194.305478 -95.827498) (xy 194.332774 -95.778863) (xy 194.36686 -95.73472)
			(xy 194.407009 -95.696011) (xy 194.452367 -95.66356) (xy 194.501967 -95.638059) (xy 194.554751 -95.620052)
			(xy 194.609594 -95.609922) (xy 194.665328 -95.607885) (xy 194.720765 -95.613985) (xy 194.774722 -95.628091)
			(xy 194.826051 -95.649903) (xy 194.873657 -95.678957) (xy 194.916525 -95.714632) (xy 194.953742 -95.756169)
			(xy 194.984515 -95.802682) (xy 195.008187 -95.853179) (xy 195.024255 -95.906586) (xy 195.032375 -95.961762)
			(xy 195.032884 -95.989648) (xy 195.032375 -96.017534) (xy 195.024255 -96.07271) (xy 195.008187 -96.126117)
			(xy 194.984515 -96.176614) (xy 194.953742 -96.223127) (xy 194.916525 -96.264664) (xy 194.873657 -96.300339)
			(xy 194.826051 -96.329393) (xy 194.774722 -96.351205) (xy 194.720765 -96.365311) (xy 194.665328 -96.371411)
			(xy 194.609594 -96.369374) (xy 194.554751 -96.359244) (xy 194.501967 -96.341237) (xy 194.452367 -96.315736)
			(xy 194.407009 -96.283285) (xy 194.36686 -96.244576) (xy 194.332774 -96.200433) (xy 194.305478 -96.151798)
			(xy 194.285555 -96.099707) (xy 194.273429 -96.04527) (xy 194.269358 -95.989648) (xy 192.427352 -95.989648)
			(xy 192.426843 -96.017534) (xy 192.418723 -96.07271) (xy 192.402655 -96.126117) (xy 192.378983 -96.176614)
			(xy 192.34821 -96.223127) (xy 192.310993 -96.264664) (xy 192.268125 -96.300339) (xy 192.220519 -96.329393)
			(xy 192.16919 -96.351205) (xy 192.115233 -96.365311) (xy 192.059796 -96.371411) (xy 192.004062 -96.369374)
			(xy 191.949219 -96.359244) (xy 191.896435 -96.341237) (xy 191.846835 -96.315736) (xy 191.801477 -96.283285)
			(xy 191.761328 -96.244576) (xy 191.727242 -96.200433) (xy 191.699946 -96.151798) (xy 191.680023 -96.099707)
			(xy 191.667897 -96.04527) (xy 191.663826 -95.989648) (xy 189.54212 -95.989648) (xy 189.537889 -95.993971)
			(xy 189.468217 -96.053867) (xy 189.393654 -96.107551) (xy 189.314752 -96.154627) (xy 189.232095 -96.194746)
			(xy 189.146296 -96.227611) (xy 189.057988 -96.252978) (xy 188.967828 -96.27066) (xy 188.87648 -96.280526)
			(xy 188.784623 -96.282503) (xy 188.692936 -96.276576) (xy 188.602098 -96.26279) (xy 188.512781 -96.241245)
			(xy 188.425647 -96.212102) (xy 188.341341 -96.175576) (xy 188.260487 -96.131938) (xy 188.183683 -96.081511)
			(xy 188.111499 -96.024669) (xy 188.044468 -95.961831) (xy 187.983087 -95.893464) (xy 187.927811 -95.820074)
			(xy 187.879048 -95.742203) (xy 187.83716 -95.660428) (xy 187.802457 -95.575356) (xy 187.775195 -95.487615)
			(xy 187.755578 -95.397855) (xy 187.743748 -95.306741) (xy 187.739796 -95.214948) (xy 178.512724 -95.214948)
			(xy 178.512724 -96.432878) (xy 183.362598 -96.432878) (xy 183.366669 -96.377256) (xy 183.378795 -96.322819)
			(xy 183.398718 -96.270728) (xy 183.426014 -96.222093) (xy 183.4601 -96.17795) (xy 183.500249 -96.139241)
			(xy 183.545607 -96.10679) (xy 183.595207 -96.081289) (xy 183.647991 -96.063282) (xy 183.702834 -96.053152)
			(xy 183.758568 -96.051115) (xy 183.814005 -96.057215) (xy 183.867962 -96.071321) (xy 183.919291 -96.093133)
			(xy 183.966897 -96.122187) (xy 184.009765 -96.157862) (xy 184.046982 -96.199399) (xy 184.077755 -96.245912)
			(xy 184.101427 -96.296409) (xy 184.117495 -96.349816) (xy 184.125615 -96.404992) (xy 184.126124 -96.432878)
			(xy 184.125615 -96.460764) (xy 184.117495 -96.51594) (xy 184.101427 -96.569347) (xy 184.077755 -96.619844)
			(xy 184.046982 -96.666357) (xy 184.009765 -96.707894) (xy 183.966897 -96.743569) (xy 183.919291 -96.772623)
			(xy 183.867962 -96.794435) (xy 183.814005 -96.808541) (xy 183.758568 -96.814641) (xy 183.702834 -96.812604)
			(xy 183.647991 -96.802474) (xy 183.595207 -96.784467) (xy 183.545607 -96.758966) (xy 183.500249 -96.726515)
			(xy 183.4601 -96.687806) (xy 183.426014 -96.643663) (xy 183.398718 -96.595028) (xy 183.378795 -96.542937)
			(xy 183.366669 -96.4885) (xy 183.362598 -96.432878) (xy 178.512724 -96.432878) (xy 178.512724 -97.663)
			(xy 182.980582 -97.663) (xy 182.984653 -97.607378) (xy 182.996779 -97.552941) (xy 183.016702 -97.50085)
			(xy 183.043998 -97.452215) (xy 183.078084 -97.408072) (xy 183.118233 -97.369363) (xy 183.163591 -97.336912)
			(xy 183.213191 -97.311411) (xy 183.265975 -97.293404) (xy 183.320818 -97.283274) (xy 183.376552 -97.281237)
			(xy 183.431989 -97.287337) (xy 183.485946 -97.301443) (xy 183.537275 -97.323255) (xy 183.584881 -97.352309)
			(xy 183.627749 -97.387984) (xy 183.664966 -97.429521) (xy 183.695739 -97.476034) (xy 183.719411 -97.526531)
			(xy 183.735479 -97.579938) (xy 183.743599 -97.635114) (xy 183.744108 -97.663) (xy 183.743599 -97.690886)
			(xy 183.735479 -97.746062) (xy 183.719411 -97.799469) (xy 183.695739 -97.849966) (xy 183.664966 -97.896479)
			(xy 183.627749 -97.938016) (xy 183.584881 -97.973691) (xy 183.537275 -98.002745) (xy 183.485946 -98.024557)
			(xy 183.431989 -98.038663) (xy 183.376552 -98.044763) (xy 183.320818 -98.042726) (xy 183.265975 -98.032596)
			(xy 183.213191 -98.014589) (xy 183.163591 -97.989088) (xy 183.118233 -97.956637) (xy 183.078084 -97.917928)
			(xy 183.043998 -97.873785) (xy 183.016702 -97.82515) (xy 182.996779 -97.773059) (xy 182.984653 -97.718622)
			(xy 182.980582 -97.663) (xy 178.512724 -97.663) (xy 178.512724 -99.439984) (xy 183.371742 -99.439984)
			(xy 183.375813 -99.384362) (xy 183.387939 -99.329925) (xy 183.407862 -99.277834) (xy 183.435158 -99.229199)
			(xy 183.469244 -99.185056) (xy 183.509393 -99.146347) (xy 183.554751 -99.113896) (xy 183.604351 -99.088395)
			(xy 183.657135 -99.070388) (xy 183.711978 -99.060258) (xy 183.767712 -99.058221) (xy 183.823149 -99.064321)
			(xy 183.877106 -99.078427) (xy 183.928435 -99.100239) (xy 183.976041 -99.129293) (xy 184.018909 -99.164968)
			(xy 184.056126 -99.206505) (xy 184.086899 -99.253018) (xy 184.110571 -99.303515) (xy 184.126639 -99.356922)
			(xy 184.134759 -99.412098) (xy 184.135268 -99.439984) (xy 184.134759 -99.46787) (xy 184.126639 -99.523046)
			(xy 184.110571 -99.576453) (xy 184.086899 -99.62695) (xy 184.056126 -99.673463) (xy 184.018909 -99.715)
			(xy 183.976041 -99.750675) (xy 183.928435 -99.779729) (xy 183.877106 -99.801541) (xy 183.823149 -99.815647)
			(xy 183.767712 -99.821747) (xy 183.711978 -99.81971) (xy 183.657135 -99.80958) (xy 183.604351 -99.791573)
			(xy 183.554751 -99.766072) (xy 183.509393 -99.733621) (xy 183.469244 -99.694912) (xy 183.435158 -99.650769)
			(xy 183.407862 -99.602134) (xy 183.387939 -99.550043) (xy 183.375813 -99.495606) (xy 183.371742 -99.439984)
			(xy 178.512724 -99.439984) (xy 178.512724 -101.240082) (xy 183.371742 -101.240082) (xy 183.375813 -101.18446)
			(xy 183.387939 -101.130023) (xy 183.407862 -101.077932) (xy 183.435158 -101.029297) (xy 183.469244 -100.985154)
			(xy 183.509393 -100.946445) (xy 183.554751 -100.913994) (xy 183.604351 -100.888493) (xy 183.657135 -100.870486)
			(xy 183.711978 -100.860356) (xy 183.767712 -100.858319) (xy 183.823149 -100.864419) (xy 183.877106 -100.878525)
			(xy 183.928435 -100.900337) (xy 183.976041 -100.929391) (xy 184.018909 -100.965066) (xy 184.056126 -101.006603)
			(xy 184.086899 -101.053116) (xy 184.110571 -101.103613) (xy 184.126639 -101.15702) (xy 184.134759 -101.212196)
			(xy 184.135268 -101.240082) (xy 184.134759 -101.267968) (xy 184.126639 -101.323144) (xy 184.110571 -101.376551)
			(xy 184.086899 -101.427048) (xy 184.056126 -101.473561) (xy 184.018909 -101.515098) (xy 183.976041 -101.550773)
			(xy 183.928435 -101.579827) (xy 183.877106 -101.601639) (xy 183.823149 -101.615745) (xy 183.767712 -101.621845)
			(xy 183.711978 -101.619808) (xy 183.657135 -101.609678) (xy 183.604351 -101.591671) (xy 183.554751 -101.56617)
			(xy 183.509393 -101.533719) (xy 183.469244 -101.49501) (xy 183.435158 -101.450867) (xy 183.407862 -101.402232)
			(xy 183.387939 -101.350141) (xy 183.375813 -101.295704) (xy 183.371742 -101.240082) (xy 178.512724 -101.240082)
			(xy 178.512724 -102.700836) (xy 181.842662 -102.700836) (xy 181.846733 -102.645214) (xy 181.858859 -102.590777)
			(xy 181.878782 -102.538686) (xy 181.906078 -102.490051) (xy 181.940164 -102.445908) (xy 181.980313 -102.407199)
			(xy 182.025671 -102.374748) (xy 182.075271 -102.349247) (xy 182.128055 -102.33124) (xy 182.182898 -102.32111)
			(xy 182.238632 -102.319073) (xy 182.294069 -102.325173) (xy 182.348026 -102.339279) (xy 182.399355 -102.361091)
			(xy 182.446961 -102.390145) (xy 182.489829 -102.42582) (xy 182.527046 -102.467357) (xy 182.557819 -102.51387)
			(xy 182.581491 -102.564367) (xy 182.597559 -102.617774) (xy 182.605679 -102.67295) (xy 182.606188 -102.700836)
			(xy 182.605679 -102.728722) (xy 182.597559 -102.783898) (xy 182.581491 -102.837305) (xy 182.557819 -102.887802)
			(xy 182.527046 -102.934315) (xy 182.489829 -102.975852) (xy 182.446961 -103.011527) (xy 182.399355 -103.040581)
			(xy 182.348026 -103.062393) (xy 182.294069 -103.076499) (xy 182.238632 -103.082599) (xy 182.182898 -103.080562)
			(xy 182.128055 -103.070432) (xy 182.075271 -103.052425) (xy 182.025671 -103.026924) (xy 181.980313 -102.994473)
			(xy 181.940164 -102.955764) (xy 181.906078 -102.911621) (xy 181.878782 -102.862986) (xy 181.858859 -102.810895)
			(xy 181.846733 -102.756458) (xy 181.842662 -102.700836) (xy 178.512724 -102.700836) (xy 178.512724 -104.384856)
			(xy 181.762652 -104.384856) (xy 181.766723 -104.329234) (xy 181.778849 -104.274797) (xy 181.798772 -104.222706)
			(xy 181.826068 -104.174071) (xy 181.860154 -104.129928) (xy 181.900303 -104.091219) (xy 181.945661 -104.058768)
			(xy 181.995261 -104.033267) (xy 182.048045 -104.01526) (xy 182.102888 -104.00513) (xy 182.158622 -104.003093)
			(xy 182.214059 -104.009193) (xy 182.268016 -104.023299) (xy 182.319345 -104.045111) (xy 182.366951 -104.074165)
			(xy 182.409819 -104.10984) (xy 182.447036 -104.151377) (xy 182.477809 -104.19789) (xy 182.501481 -104.248387)
			(xy 182.517549 -104.301794) (xy 182.525669 -104.35697) (xy 182.526178 -104.384856) (xy 182.525669 -104.412742)
			(xy 182.517549 -104.467918) (xy 182.501481 -104.521325) (xy 182.477809 -104.571822) (xy 182.447036 -104.618335)
			(xy 182.409819 -104.659872) (xy 182.366951 -104.695547) (xy 182.319345 -104.724601) (xy 182.268016 -104.746413)
			(xy 182.214059 -104.760519) (xy 182.158622 -104.766619) (xy 182.102888 -104.764582) (xy 182.048045 -104.754452)
			(xy 181.995261 -104.736445) (xy 181.945661 -104.710944) (xy 181.900303 -104.678493) (xy 181.860154 -104.639784)
			(xy 181.826068 -104.595641) (xy 181.798772 -104.547006) (xy 181.778849 -104.494915) (xy 181.766723 -104.440478)
			(xy 181.762652 -104.384856) (xy 178.512724 -104.384856) (xy 178.512724 -111.334042) (xy 180.363874 -111.334042)
			(xy 180.367945 -111.27842) (xy 180.380071 -111.223983) (xy 180.399994 -111.171892) (xy 180.42729 -111.123257)
			(xy 180.461376 -111.079114) (xy 180.501525 -111.040405) (xy 180.546883 -111.007954) (xy 180.596483 -110.982453)
			(xy 180.649267 -110.964446) (xy 180.70411 -110.954316) (xy 180.759844 -110.952279) (xy 180.815281 -110.958379)
			(xy 180.869238 -110.972485) (xy 180.920567 -110.994297) (xy 180.968173 -111.023351) (xy 181.011041 -111.059026)
			(xy 181.048258 -111.100563) (xy 181.079031 -111.147076) (xy 181.102703 -111.197573) (xy 181.118771 -111.25098)
			(xy 181.126891 -111.306156) (xy 181.1274 -111.334042) (xy 181.126891 -111.361928) (xy 181.118771 -111.417104)
			(xy 181.102703 -111.470511) (xy 181.079031 -111.521008) (xy 181.048258 -111.567521) (xy 181.011041 -111.609058)
			(xy 180.968173 -111.644733) (xy 180.920567 -111.673787) (xy 180.869238 -111.695599) (xy 180.815281 -111.709705)
			(xy 180.759844 -111.715805) (xy 180.70411 -111.713768) (xy 180.649267 -111.703638) (xy 180.596483 -111.685631)
			(xy 180.546883 -111.66013) (xy 180.501525 -111.627679) (xy 180.461376 -111.58897) (xy 180.42729 -111.544827)
			(xy 180.399994 -111.496192) (xy 180.380071 -111.444101) (xy 180.367945 -111.389664) (xy 180.363874 -111.334042)
			(xy 178.512724 -111.334042) (xy 178.512724 -111.980726) (xy 190.001398 -111.980726) (xy 190.001938 -111.951988)
			(xy 190.010557 -111.895161) (xy 190.027603 -111.840271) (xy 190.052691 -111.788559) (xy 190.085253 -111.741195)
			(xy 190.104522 -111.719868) (xy 190.111126 -111.71301) (xy 190.118238 -111.694976) (xy 190.118238 -111.606076)
			(xy 190.111126 -111.588042) (xy 190.104522 -111.581184) (xy 190.085277 -111.559835) (xy 190.052711 -111.512476)
			(xy 190.027618 -111.460768) (xy 190.010566 -111.405881) (xy 190.001941 -111.349056) (xy 190.001939 -111.291581)
			(xy 190.010558 -111.234756) (xy 190.027604 -111.179867) (xy 190.052692 -111.128157) (xy 190.085253 -111.080795)
			(xy 190.104522 -111.059468) (xy 190.111126 -111.05261) (xy 190.118238 -111.034576) (xy 190.118238 -110.945676)
			(xy 190.111126 -110.927642) (xy 190.104522 -110.920784) (xy 190.085277 -110.899435) (xy 190.052711 -110.852076)
			(xy 190.027618 -110.800368) (xy 190.010566 -110.745481) (xy 190.001941 -110.688656) (xy 190.001939 -110.631181)
			(xy 190.010558 -110.574356) (xy 190.027604 -110.519467) (xy 190.052692 -110.467757) (xy 190.085253 -110.420395)
			(xy 190.104522 -110.399068) (xy 190.111126 -110.39221) (xy 190.118238 -110.374176) (xy 190.118238 -110.285276)
			(xy 190.111126 -110.267242) (xy 190.104522 -110.260384) (xy 190.085277 -110.239035) (xy 190.052711 -110.191676)
			(xy 190.027618 -110.139968) (xy 190.010566 -110.085081) (xy 190.001941 -110.028256) (xy 190.001939 -109.970781)
			(xy 190.010558 -109.913956) (xy 190.027604 -109.859067) (xy 190.052692 -109.807357) (xy 190.085253 -109.759995)
			(xy 190.104522 -109.738668) (xy 190.111126 -109.73181) (xy 190.118238 -109.713776) (xy 190.118238 -109.624876)
			(xy 190.111126 -109.606842) (xy 190.104522 -109.599984) (xy 190.085261 -109.578649) (xy 190.052694 -109.531289)
			(xy 190.0276 -109.479579) (xy 190.010547 -109.42469) (xy 190.001921 -109.367864) (xy 190.001398 -109.339126)
			(xy 190.00188 -109.311874) (xy 190.009633 -109.257923) (xy 190.024986 -109.205625) (xy 190.047626 -109.156045)
			(xy 190.077092 -109.110191) (xy 190.112784 -109.068998) (xy 190.153975 -109.033304) (xy 190.199827 -109.003836)
			(xy 190.249406 -108.981193) (xy 190.301703 -108.965837) (xy 190.355654 -108.958081) (xy 190.382906 -108.957618)
			(xy 190.40922 -108.958076) (xy 190.46135 -108.965312) (xy 190.511993 -108.979632) (xy 190.560192 -109.000767)
			(xy 190.605035 -109.028315) (xy 190.645674 -109.061755) (xy 190.66383 -109.080808) (xy 190.671338 -109.088226)
			(xy 190.690628 -109.09674) (xy 190.701168 -109.097318) (xy 190.775844 -109.097318) (xy 190.786391 -109.096767)
			(xy 190.805686 -109.088247) (xy 190.813182 -109.080808) (xy 190.831355 -109.06177) (xy 190.871981 -109.028311)
			(xy 190.916817 -109.000749) (xy 190.965015 -108.979608) (xy 191.015659 -108.965287) (xy 191.067791 -108.958058)
			(xy 191.094106 -108.957618) (xy 191.12136 -108.95805) (xy 191.175314 -108.965808) (xy 191.227614 -108.981166)
			(xy 191.277195 -109.003811) (xy 191.32305 -109.033283) (xy 191.364243 -109.06898) (xy 191.399937 -109.110176)
			(xy 191.429404 -109.156033) (xy 191.452045 -109.205616) (xy 191.467399 -109.257918) (xy 191.475152 -109.311872)
			(xy 191.475614 -109.339126) (xy 191.475102 -109.367865) (xy 191.466476 -109.424693) (xy 191.449423 -109.479584)
			(xy 191.424329 -109.531295) (xy 191.391762 -109.578657) (xy 191.37249 -109.599984) (xy 191.365886 -109.606842)
			(xy 191.358774 -109.624876) (xy 191.358774 -109.713776) (xy 191.365886 -109.73181) (xy 191.37249 -109.738668)
			(xy 191.391786 -109.759973) (xy 191.424349 -109.807339) (xy 191.449438 -109.859055) (xy 191.466486 -109.913949)
			(xy 191.475106 -109.970779) (xy 191.475103 -110.028259) (xy 191.466477 -110.085088) (xy 191.449424 -110.13998)
			(xy 191.42433 -110.191693) (xy 191.391762 -110.239057) (xy 191.37249 -110.260384) (xy 191.365886 -110.267242)
			(xy 191.358774 -110.285276) (xy 191.358774 -110.374176) (xy 191.365886 -110.39221) (xy 191.37249 -110.399068)
			(xy 191.391786 -110.420373) (xy 191.424349 -110.467739) (xy 191.449438 -110.519455) (xy 191.466486 -110.574349)
			(xy 191.475106 -110.631179) (xy 191.475103 -110.688659) (xy 191.466477 -110.745488) (xy 191.449424 -110.80038)
			(xy 191.42433 -110.852093) (xy 191.391762 -110.899457) (xy 191.37249 -110.920784) (xy 191.365886 -110.927642)
			(xy 191.358774 -110.945676) (xy 191.358774 -111.034576) (xy 191.365886 -111.05261) (xy 191.37249 -111.059468)
			(xy 191.391786 -111.080773) (xy 191.424349 -111.128139) (xy 191.449438 -111.179855) (xy 191.466486 -111.234749)
			(xy 191.475106 -111.291579) (xy 191.475103 -111.349059) (xy 191.466477 -111.405888) (xy 191.449424 -111.46078)
			(xy 191.42433 -111.512493) (xy 191.391762 -111.559857) (xy 191.37249 -111.581184) (xy 191.365886 -111.588042)
			(xy 191.358774 -111.606076) (xy 191.358774 -111.694976) (xy 191.365886 -111.71301) (xy 191.37249 -111.719868)
			(xy 191.391778 -111.74118) (xy 191.424341 -111.788547) (xy 191.449429 -111.840262) (xy 191.466476 -111.895156)
			(xy 191.475095 -111.951986) (xy 191.475614 -111.980726) (xy 191.475146 -112.007978) (xy 191.467387 -112.061926)
			(xy 191.452028 -112.11422) (xy 191.429385 -112.163797) (xy 191.399916 -112.209647) (xy 191.364223 -112.250837)
			(xy 191.323031 -112.286528) (xy 191.27718 -112.315994) (xy 191.227602 -112.338635) (xy 191.175306 -112.353991)
			(xy 191.121358 -112.361748) (xy 191.094106 -112.362234) (xy 191.067793 -112.361752) (xy 191.015665 -112.354518)
			(xy 190.965023 -112.340201) (xy 190.916824 -112.319072) (xy 190.87198 -112.291529) (xy 190.83134 -112.258094)
			(xy 190.813182 -112.239044) (xy 190.805663 -112.231639) (xy 190.786381 -112.223115) (xy 190.775844 -112.222534)
			(xy 190.701168 -112.222534) (xy 190.69062 -112.223076) (xy 190.671323 -112.231601) (xy 190.66383 -112.239044)
			(xy 190.645661 -112.258086) (xy 190.605034 -112.291543) (xy 190.560196 -112.319103) (xy 190.511998 -112.340243)
			(xy 190.461353 -112.354564) (xy 190.409221 -112.361793) (xy 190.382906 -112.362234) (xy 190.355656 -112.361717)
			(xy 190.301711 -112.353962) (xy 190.249418 -112.338609) (xy 190.199843 -112.31597) (xy 190.153994 -112.286507)
			(xy 190.112804 -112.250819) (xy 190.077112 -112.209632) (xy 190.047645 -112.163785) (xy 190.025003 -112.114212)
			(xy 190.009645 -112.06192) (xy 190.001886 -112.007976) (xy 190.001398 -111.980726) (xy 178.512724 -111.980726)
			(xy 178.512724 -112.510824) (xy 179.902356 -112.510824) (xy 179.906427 -112.455202) (xy 179.918553 -112.400765)
			(xy 179.938476 -112.348674) (xy 179.965772 -112.300039) (xy 179.999858 -112.255896) (xy 180.040007 -112.217187)
			(xy 180.085365 -112.184736) (xy 180.134965 -112.159235) (xy 180.187749 -112.141228) (xy 180.242592 -112.131098)
			(xy 180.298326 -112.129061) (xy 180.353763 -112.135161) (xy 180.40772 -112.149267) (xy 180.459049 -112.171079)
			(xy 180.506655 -112.200133) (xy 180.549523 -112.235808) (xy 180.58674 -112.277345) (xy 180.617513 -112.323858)
			(xy 180.641185 -112.374355) (xy 180.657253 -112.427762) (xy 180.665373 -112.482938) (xy 180.665418 -112.485424)
			(xy 182.750966 -112.485424) (xy 182.755037 -112.429802) (xy 182.767163 -112.375365) (xy 182.787086 -112.323274)
			(xy 182.814382 -112.274639) (xy 182.848468 -112.230496) (xy 182.888617 -112.191787) (xy 182.933975 -112.159336)
			(xy 182.983575 -112.133835) (xy 183.036359 -112.115828) (xy 183.091202 -112.105698) (xy 183.146936 -112.103661)
			(xy 183.202373 -112.109761) (xy 183.25633 -112.123867) (xy 183.307659 -112.145679) (xy 183.355265 -112.174733)
			(xy 183.398133 -112.210408) (xy 183.43535 -112.251945) (xy 183.466123 -112.298458) (xy 183.489795 -112.348955)
			(xy 183.505863 -112.402362) (xy 183.508742 -112.421924) (xy 185.554872 -112.421924) (xy 185.558943 -112.366302)
			(xy 185.571069 -112.311865) (xy 185.590992 -112.259774) (xy 185.618288 -112.211139) (xy 185.652374 -112.166996)
			(xy 185.692523 -112.128287) (xy 185.737881 -112.095836) (xy 185.787481 -112.070335) (xy 185.840265 -112.052328)
			(xy 185.895108 -112.042198) (xy 185.950842 -112.040161) (xy 186.006279 -112.046261) (xy 186.060236 -112.060367)
			(xy 186.111565 -112.082179) (xy 186.159171 -112.111233) (xy 186.202039 -112.146908) (xy 186.239256 -112.188445)
			(xy 186.270029 -112.234958) (xy 186.293701 -112.285455) (xy 186.309769 -112.338862) (xy 186.317889 -112.394038)
			(xy 186.318398 -112.421924) (xy 186.317889 -112.44981) (xy 186.309769 -112.504986) (xy 186.293701 -112.558393)
			(xy 186.270029 -112.60889) (xy 186.239256 -112.655403) (xy 186.202039 -112.69694) (xy 186.159171 -112.732615)
			(xy 186.111565 -112.761669) (xy 186.060236 -112.783481) (xy 186.006279 -112.797587) (xy 185.950842 -112.803687)
			(xy 185.895108 -112.80165) (xy 185.840265 -112.79152) (xy 185.787481 -112.773513) (xy 185.737881 -112.748012)
			(xy 185.692523 -112.715561) (xy 185.652374 -112.676852) (xy 185.618288 -112.632709) (xy 185.590992 -112.584074)
			(xy 185.571069 -112.531983) (xy 185.558943 -112.477546) (xy 185.554872 -112.421924) (xy 183.508742 -112.421924)
			(xy 183.513983 -112.457538) (xy 183.514492 -112.485424) (xy 183.513983 -112.51331) (xy 183.505863 -112.568486)
			(xy 183.489795 -112.621893) (xy 183.466123 -112.67239) (xy 183.43535 -112.718903) (xy 183.398133 -112.76044)
			(xy 183.355265 -112.796115) (xy 183.307659 -112.825169) (xy 183.25633 -112.846981) (xy 183.202373 -112.861087)
			(xy 183.146936 -112.867187) (xy 183.091202 -112.86515) (xy 183.036359 -112.85502) (xy 182.983575 -112.837013)
			(xy 182.933975 -112.811512) (xy 182.888617 -112.779061) (xy 182.848468 -112.740352) (xy 182.814382 -112.696209)
			(xy 182.787086 -112.647574) (xy 182.767163 -112.595483) (xy 182.755037 -112.541046) (xy 182.750966 -112.485424)
			(xy 180.665418 -112.485424) (xy 180.665882 -112.510824) (xy 180.665373 -112.53871) (xy 180.657253 -112.593886)
			(xy 180.641185 -112.647293) (xy 180.617513 -112.69779) (xy 180.58674 -112.744303) (xy 180.549523 -112.78584)
			(xy 180.506655 -112.821515) (xy 180.459049 -112.850569) (xy 180.40772 -112.872381) (xy 180.353763 -112.886487)
			(xy 180.298326 -112.892587) (xy 180.242592 -112.89055) (xy 180.187749 -112.88042) (xy 180.134965 -112.862413)
			(xy 180.085365 -112.836912) (xy 180.040007 -112.804461) (xy 179.999858 -112.765752) (xy 179.965772 -112.721609)
			(xy 179.938476 -112.672974) (xy 179.918553 -112.620883) (xy 179.906427 -112.566446) (xy 179.902356 -112.510824)
			(xy 178.512724 -112.510824) (xy 178.512724 -113.251742) (xy 180.406038 -113.251742) (xy 180.410109 -113.19612)
			(xy 180.422235 -113.141683) (xy 180.442158 -113.089592) (xy 180.469454 -113.040957) (xy 180.50354 -112.996814)
			(xy 180.543689 -112.958105) (xy 180.589047 -112.925654) (xy 180.638647 -112.900153) (xy 180.691431 -112.882146)
			(xy 180.746274 -112.872016) (xy 180.802008 -112.869979) (xy 180.857445 -112.876079) (xy 180.911402 -112.890185)
			(xy 180.962731 -112.911997) (xy 181.010337 -112.941051) (xy 181.053205 -112.976726) (xy 181.090422 -113.018263)
			(xy 181.121195 -113.064776) (xy 181.144867 -113.115273) (xy 181.160935 -113.16868) (xy 181.169055 -113.223856)
			(xy 181.169564 -113.251742) (xy 181.169055 -113.279628) (xy 181.160935 -113.334804) (xy 181.144867 -113.388211)
			(xy 181.122872 -113.43513) (xy 183.03062 -113.43513) (xy 183.034691 -113.379508) (xy 183.046817 -113.325071)
			(xy 183.06674 -113.27298) (xy 183.094036 -113.224345) (xy 183.128122 -113.180202) (xy 183.168271 -113.141493)
			(xy 183.213629 -113.109042) (xy 183.263229 -113.083541) (xy 183.316013 -113.065534) (xy 183.370856 -113.055404)
			(xy 183.42659 -113.053367) (xy 183.482027 -113.059467) (xy 183.535984 -113.073573) (xy 183.587313 -113.095385)
			(xy 183.634919 -113.124439) (xy 183.677787 -113.160114) (xy 183.715004 -113.201651) (xy 183.745777 -113.248164)
			(xy 183.769449 -113.298661) (xy 183.785517 -113.352068) (xy 183.793637 -113.407244) (xy 183.794146 -113.43513)
			(xy 183.794095 -113.437924) (xy 185.53379 -113.437924) (xy 185.537861 -113.382302) (xy 185.549987 -113.327865)
			(xy 185.56991 -113.275774) (xy 185.597206 -113.227139) (xy 185.631292 -113.182996) (xy 185.671441 -113.144287)
			(xy 185.716799 -113.111836) (xy 185.766399 -113.086335) (xy 185.819183 -113.068328) (xy 185.874026 -113.058198)
			(xy 185.92976 -113.056161) (xy 185.985197 -113.062261) (xy 186.039154 -113.076367) (xy 186.090483 -113.098179)
			(xy 186.138089 -113.127233) (xy 186.180957 -113.162908) (xy 186.218174 -113.204445) (xy 186.248947 -113.250958)
			(xy 186.272619 -113.301455) (xy 186.288687 -113.354862) (xy 186.296807 -113.410038) (xy 186.297316 -113.437924)
			(xy 186.296807 -113.46581) (xy 186.288687 -113.520986) (xy 186.272619 -113.574393) (xy 186.248947 -113.62489)
			(xy 186.218174 -113.671403) (xy 186.180957 -113.71294) (xy 186.138089 -113.748615) (xy 186.090483 -113.777669)
			(xy 186.039154 -113.799481) (xy 185.985197 -113.813587) (xy 185.92976 -113.819687) (xy 185.874026 -113.81765)
			(xy 185.819183 -113.80752) (xy 185.766399 -113.789513) (xy 185.716799 -113.764012) (xy 185.671441 -113.731561)
			(xy 185.631292 -113.692852) (xy 185.597206 -113.648709) (xy 185.56991 -113.600074) (xy 185.549987 -113.547983)
			(xy 185.537861 -113.493546) (xy 185.53379 -113.437924) (xy 183.794095 -113.437924) (xy 183.793637 -113.463016)
			(xy 183.785517 -113.518192) (xy 183.769449 -113.571599) (xy 183.745777 -113.622096) (xy 183.715004 -113.668609)
			(xy 183.677787 -113.710146) (xy 183.634919 -113.745821) (xy 183.587313 -113.774875) (xy 183.535984 -113.796687)
			(xy 183.482027 -113.810793) (xy 183.42659 -113.816893) (xy 183.370856 -113.814856) (xy 183.316013 -113.804726)
			(xy 183.263229 -113.786719) (xy 183.213629 -113.761218) (xy 183.168271 -113.728767) (xy 183.128122 -113.690058)
			(xy 183.094036 -113.645915) (xy 183.06674 -113.59728) (xy 183.046817 -113.545189) (xy 183.034691 -113.490752)
			(xy 183.03062 -113.43513) (xy 181.122872 -113.43513) (xy 181.121195 -113.438708) (xy 181.090422 -113.485221)
			(xy 181.053205 -113.526758) (xy 181.010337 -113.562433) (xy 180.962731 -113.591487) (xy 180.911402 -113.613299)
			(xy 180.857445 -113.627405) (xy 180.802008 -113.633505) (xy 180.746274 -113.631468) (xy 180.691431 -113.621338)
			(xy 180.638647 -113.603331) (xy 180.589047 -113.57783) (xy 180.543689 -113.545379) (xy 180.50354 -113.50667)
			(xy 180.469454 -113.462527) (xy 180.442158 -113.413892) (xy 180.422235 -113.361801) (xy 180.410109 -113.307364)
			(xy 180.406038 -113.251742) (xy 178.512724 -113.251742) (xy 178.512724 -114.581432) (xy 182.39943 -114.581432)
			(xy 182.403501 -114.52581) (xy 182.415627 -114.471373) (xy 182.43555 -114.419282) (xy 182.462846 -114.370647)
			(xy 182.496932 -114.326504) (xy 182.537081 -114.287795) (xy 182.582439 -114.255344) (xy 182.632039 -114.229843)
			(xy 182.684823 -114.211836) (xy 182.739666 -114.201706) (xy 182.7954 -114.199669) (xy 182.850837 -114.205769)
			(xy 182.904794 -114.219875) (xy 182.956123 -114.241687) (xy 183.003729 -114.270741) (xy 183.026984 -114.290094)
			(xy 186.460128 -114.290094) (xy 186.464199 -114.234472) (xy 186.476325 -114.180035) (xy 186.496248 -114.127944)
			(xy 186.523544 -114.079309) (xy 186.55763 -114.035166) (xy 186.597779 -113.996457) (xy 186.643137 -113.964006)
			(xy 186.692737 -113.938505) (xy 186.745521 -113.920498) (xy 186.800364 -113.910368) (xy 186.856098 -113.908331)
			(xy 186.911535 -113.914431) (xy 186.965492 -113.928537) (xy 187.016821 -113.950349) (xy 187.064427 -113.979403)
			(xy 187.107295 -114.015078) (xy 187.144512 -114.056615) (xy 187.175285 -114.103128) (xy 187.198957 -114.153625)
			(xy 187.215025 -114.207032) (xy 187.223145 -114.262208) (xy 187.223654 -114.290094) (xy 187.223145 -114.31798)
			(xy 187.215025 -114.373156) (xy 187.198957 -114.426563) (xy 187.175285 -114.47706) (xy 187.144512 -114.523573)
			(xy 187.107295 -114.56511) (xy 187.064427 -114.600785) (xy 187.016821 -114.629839) (xy 186.965492 -114.651651)
			(xy 186.911535 -114.665757) (xy 186.856098 -114.671857) (xy 186.800364 -114.66982) (xy 186.745521 -114.65969)
			(xy 186.692737 -114.641683) (xy 186.643137 -114.616182) (xy 186.597779 -114.583731) (xy 186.55763 -114.545022)
			(xy 186.523544 -114.500879) (xy 186.496248 -114.452244) (xy 186.476325 -114.400153) (xy 186.464199 -114.345716)
			(xy 186.460128 -114.290094) (xy 183.026984 -114.290094) (xy 183.046597 -114.306416) (xy 183.083814 -114.347953)
			(xy 183.114587 -114.394466) (xy 183.138259 -114.444963) (xy 183.154327 -114.49837) (xy 183.162447 -114.553546)
			(xy 183.162956 -114.581432) (xy 183.162447 -114.609318) (xy 183.154327 -114.664494) (xy 183.138259 -114.717901)
			(xy 183.114587 -114.768398) (xy 183.083814 -114.814911) (xy 183.046597 -114.856448) (xy 183.003729 -114.892123)
			(xy 182.956123 -114.921177) (xy 182.904794 -114.942989) (xy 182.850837 -114.957095) (xy 182.7954 -114.963195)
			(xy 182.739666 -114.961158) (xy 182.684823 -114.951028) (xy 182.632039 -114.933021) (xy 182.582439 -114.90752)
			(xy 182.537081 -114.875069) (xy 182.496932 -114.83636) (xy 182.462846 -114.792217) (xy 182.43555 -114.743582)
			(xy 182.415627 -114.691491) (xy 182.403501 -114.637054) (xy 182.39943 -114.581432) (xy 178.512724 -114.581432)
			(xy 178.512724 -115.285774) (xy 183.03062 -115.285774) (xy 183.034691 -115.230152) (xy 183.046817 -115.175715)
			(xy 183.06674 -115.123624) (xy 183.094036 -115.074989) (xy 183.128122 -115.030846) (xy 183.168271 -114.992137)
			(xy 183.213629 -114.959686) (xy 183.263229 -114.934185) (xy 183.316013 -114.916178) (xy 183.370856 -114.906048)
			(xy 183.42659 -114.904011) (xy 183.482027 -114.910111) (xy 183.535984 -114.924217) (xy 183.587313 -114.946029)
			(xy 183.634919 -114.975083) (xy 183.677787 -115.010758) (xy 183.715004 -115.052295) (xy 183.745777 -115.098808)
			(xy 183.769449 -115.149305) (xy 183.785517 -115.202712) (xy 183.793637 -115.257888) (xy 183.794146 -115.285774)
			(xy 183.793637 -115.31366) (xy 183.786676 -115.360958) (xy 190.218314 -115.360958) (xy 190.218811 -115.333589)
			(xy 190.226621 -115.279411) (xy 190.242102 -115.226908) (xy 190.264937 -115.177161) (xy 190.294656 -115.131193)
			(xy 190.312294 -115.11026) (xy 190.312548 -115.110006) (xy 190.318144 -115.102926) (xy 190.324384 -115.086004)
			(xy 190.32474 -115.076986) (xy 190.32474 -115.00993) (xy 190.324382 -115.000913) (xy 190.318136 -114.983995)
			(xy 190.312548 -114.97691) (xy 190.312294 -114.97691) (xy 190.312294 -114.976656) (xy 190.294667 -114.955714)
			(xy 190.264953 -114.909744) (xy 190.242115 -114.859999) (xy 190.226621 -114.807501) (xy 190.21879 -114.753326)
			(xy 190.218314 -114.725958) (xy 190.218739 -114.698705) (xy 190.226502 -114.644754) (xy 190.241863 -114.592456)
			(xy 190.264511 -114.542878) (xy 190.293984 -114.497026) (xy 190.329681 -114.455836) (xy 190.370878 -114.420145)
			(xy 190.416734 -114.39068) (xy 190.466316 -114.368041) (xy 190.518616 -114.352688) (xy 190.572569 -114.344934)
			(xy 190.599822 -114.34445) (xy 190.627193 -114.344891) (xy 190.681374 -114.352713) (xy 190.733878 -114.368207)
			(xy 190.783624 -114.391055) (xy 190.82959 -114.420786) (xy 190.85052 -114.43843) (xy 190.850774 -114.438684)
			(xy 190.857865 -114.444264) (xy 190.874778 -114.450515) (xy 190.883794 -114.450876) (xy 190.95085 -114.450876)
			(xy 190.959865 -114.4505) (xy 190.976782 -114.444266) (xy 190.98387 -114.438684) (xy 190.98387 -114.43843)
			(xy 190.984124 -114.43843) (xy 191.005078 -114.420818) (xy 191.051044 -114.391101) (xy 191.100786 -114.368259)
			(xy 191.153282 -114.352762) (xy 191.207454 -114.344927) (xy 191.234822 -114.34445) (xy 191.262072 -114.344957)
			(xy 191.316017 -114.352716) (xy 191.368308 -114.368071) (xy 191.417883 -114.390712) (xy 191.463731 -114.420177)
			(xy 191.50492 -114.455866) (xy 191.540611 -114.497053) (xy 191.570078 -114.542899) (xy 191.592722 -114.592473)
			(xy 191.60808 -114.644764) (xy 191.615841 -114.698708) (xy 191.61633 -114.725958) (xy 191.615856 -114.753328)
			(xy 191.608043 -114.807508) (xy 191.592557 -114.860011) (xy 191.569716 -114.909758) (xy 191.539992 -114.955725)
			(xy 191.52235 -114.976656) (xy 191.522096 -114.97691) (xy 191.516499 -114.983989) (xy 191.510259 -115.000912)
			(xy 191.509904 -115.00993) (xy 191.509904 -115.076986) (xy 191.510267 -115.086002) (xy 191.51651 -115.102919)
			(xy 191.522096 -115.110006) (xy 191.52235 -115.110006) (xy 191.52235 -115.11026) (xy 191.539976 -115.131203)
			(xy 191.569692 -115.177172) (xy 191.592531 -115.226917) (xy 191.608025 -115.279415) (xy 191.615855 -115.333589)
			(xy 191.61633 -115.360958) (xy 191.615806 -115.388209) (xy 191.608055 -115.442156) (xy 191.592705 -115.494452)
			(xy 191.570069 -115.54403) (xy 191.540608 -115.589883) (xy 191.50492 -115.631075) (xy 191.463734 -115.666769)
			(xy 191.417887 -115.696239) (xy 191.368312 -115.718883) (xy 191.316019 -115.734241) (xy 191.262073 -115.742001)
			(xy 191.234822 -115.742466) (xy 191.207452 -115.741995) (xy 191.153273 -115.73418) (xy 191.100769 -115.718692)
			(xy 191.051022 -115.695851) (xy 191.005056 -115.666127) (xy 190.984124 -115.648486) (xy 190.98387 -115.648232)
			(xy 190.976773 -115.642661) (xy 190.959864 -115.636407) (xy 190.95085 -115.63604) (xy 190.883794 -115.63604)
			(xy 190.874776 -115.636385) (xy 190.857858 -115.64264) (xy 190.850774 -115.648232) (xy 190.850774 -115.648486)
			(xy 190.85052 -115.648486) (xy 190.829589 -115.666127) (xy 190.783616 -115.695839) (xy 190.733869 -115.718675)
			(xy 190.681367 -115.734165) (xy 190.627191 -115.741993) (xy 190.599822 -115.742466) (xy 190.572568 -115.742024)
			(xy 190.518614 -115.734269) (xy 190.466313 -115.718914) (xy 190.41673 -115.696271) (xy 190.370875 -115.666801)
			(xy 190.329681 -115.631105) (xy 190.293987 -115.589909) (xy 190.26452 -115.544052) (xy 190.241879 -115.494468)
			(xy 190.226527 -115.442167) (xy 190.218774 -115.388212) (xy 190.218314 -115.360958) (xy 183.786676 -115.360958)
			(xy 183.785517 -115.368836) (xy 183.769449 -115.422243) (xy 183.745777 -115.47274) (xy 183.715004 -115.519253)
			(xy 183.677787 -115.56079) (xy 183.634919 -115.596465) (xy 183.587313 -115.625519) (xy 183.535984 -115.647331)
			(xy 183.482027 -115.661437) (xy 183.42659 -115.667537) (xy 183.370856 -115.6655) (xy 183.316013 -115.65537)
			(xy 183.263229 -115.637363) (xy 183.213629 -115.611862) (xy 183.168271 -115.579411) (xy 183.128122 -115.540702)
			(xy 183.094036 -115.496559) (xy 183.06674 -115.447924) (xy 183.046817 -115.395833) (xy 183.034691 -115.341396)
			(xy 183.03062 -115.285774) (xy 178.512724 -115.285774) (xy 178.512724 -115.90909) (xy 180.121304 -115.90909)
			(xy 180.125375 -115.853468) (xy 180.137501 -115.799031) (xy 180.157424 -115.74694) (xy 180.18472 -115.698305)
			(xy 180.218806 -115.654162) (xy 180.258955 -115.615453) (xy 180.304313 -115.583002) (xy 180.353913 -115.557501)
			(xy 180.406697 -115.539494) (xy 180.46154 -115.529364) (xy 180.517274 -115.527327) (xy 180.572711 -115.533427)
			(xy 180.626668 -115.547533) (xy 180.677997 -115.569345) (xy 180.725603 -115.598399) (xy 180.768471 -115.634074)
			(xy 180.805688 -115.675611) (xy 180.836461 -115.722124) (xy 180.860133 -115.772621) (xy 180.876201 -115.826028)
			(xy 180.884321 -115.881204) (xy 180.88483 -115.90909) (xy 180.884321 -115.936976) (xy 180.876201 -115.992152)
			(xy 180.860133 -116.045559) (xy 180.836461 -116.096056) (xy 180.805688 -116.142569) (xy 180.768471 -116.184106)
			(xy 180.725603 -116.219781) (xy 180.677997 -116.248835) (xy 180.626668 -116.270647) (xy 180.572711 -116.284753)
			(xy 180.517274 -116.290853) (xy 180.46154 -116.288816) (xy 180.406697 -116.278686) (xy 180.353913 -116.260679)
			(xy 180.304313 -116.235178) (xy 180.258955 -116.202727) (xy 180.218806 -116.164018) (xy 180.18472 -116.119875)
			(xy 180.157424 -116.07124) (xy 180.137501 -116.019149) (xy 180.125375 -115.964712) (xy 180.121304 -115.90909)
			(xy 178.512724 -115.90909) (xy 178.512724 -116.44757) (xy 182.256936 -116.44757) (xy 182.261007 -116.391948)
			(xy 182.273133 -116.337511) (xy 182.293056 -116.28542) (xy 182.320352 -116.236785) (xy 182.354438 -116.192642)
			(xy 182.394587 -116.153933) (xy 182.439945 -116.121482) (xy 182.489545 -116.095981) (xy 182.542329 -116.077974)
			(xy 182.597172 -116.067844) (xy 182.652906 -116.065807) (xy 182.708343 -116.071907) (xy 182.7623 -116.086013)
			(xy 182.813629 -116.107825) (xy 182.861235 -116.136879) (xy 182.904103 -116.172554) (xy 182.94132 -116.214091)
			(xy 182.972093 -116.260604) (xy 182.995765 -116.311101) (xy 183.011833 -116.364508) (xy 183.019953 -116.419684)
			(xy 183.020462 -116.44757) (xy 183.019953 -116.475456) (xy 183.019683 -116.477288) (xy 187.404246 -116.477288)
			(xy 187.408317 -116.421666) (xy 187.420443 -116.367229) (xy 187.440366 -116.315138) (xy 187.467662 -116.266503)
			(xy 187.501748 -116.22236) (xy 187.541897 -116.183651) (xy 187.587255 -116.1512) (xy 187.636855 -116.125699)
			(xy 187.689639 -116.107692) (xy 187.744482 -116.097562) (xy 187.800216 -116.095525) (xy 187.855653 -116.101625)
			(xy 187.90961 -116.115731) (xy 187.960939 -116.137543) (xy 188.008545 -116.166597) (xy 188.051413 -116.202272)
			(xy 188.08863 -116.243809) (xy 188.119403 -116.290322) (xy 188.143075 -116.340819) (xy 188.159143 -116.394226)
			(xy 188.167263 -116.449402) (xy 188.167772 -116.477288) (xy 188.167263 -116.505174) (xy 188.159143 -116.56035)
			(xy 188.143075 -116.613757) (xy 188.119403 -116.664254) (xy 188.08863 -116.710767) (xy 188.051413 -116.752304)
			(xy 188.008545 -116.787979) (xy 187.960939 -116.817033) (xy 187.90961 -116.838845) (xy 187.855653 -116.852951)
			(xy 187.800216 -116.859051) (xy 187.744482 -116.857014) (xy 187.689639 -116.846884) (xy 187.636855 -116.828877)
			(xy 187.587255 -116.803376) (xy 187.541897 -116.770925) (xy 187.501748 -116.732216) (xy 187.467662 -116.688073)
			(xy 187.440366 -116.639438) (xy 187.420443 -116.587347) (xy 187.408317 -116.53291) (xy 187.404246 -116.477288)
			(xy 183.019683 -116.477288) (xy 183.011833 -116.530632) (xy 182.995765 -116.584039) (xy 182.972093 -116.634536)
			(xy 182.94132 -116.681049) (xy 182.904103 -116.722586) (xy 182.861235 -116.758261) (xy 182.813629 -116.787315)
			(xy 182.7623 -116.809127) (xy 182.708343 -116.823233) (xy 182.652906 -116.829333) (xy 182.597172 -116.827296)
			(xy 182.542329 -116.817166) (xy 182.489545 -116.799159) (xy 182.439945 -116.773658) (xy 182.394587 -116.741207)
			(xy 182.354438 -116.702498) (xy 182.320352 -116.658355) (xy 182.293056 -116.60972) (xy 182.273133 -116.557629)
			(xy 182.261007 -116.503192) (xy 182.256936 -116.44757) (xy 178.512724 -116.44757) (xy 178.512724 -116.974874)
			(xy 178.512894 -116.980883) (xy 178.515724 -116.992562) (xy 178.518312 -116.997988) (xy 178.52015 -117.001463)
			(xy 178.524742 -117.007844) (xy 178.527456 -117.010688) (xy 179.473098 -117.95633) (xy 179.476654 -117.959378)
			(xy 179.477162 -117.959886) (xy 179.482496 -117.963696) (xy 179.487322 -117.96649) (xy 179.49037 -117.967506)
			(xy 179.493672 -117.968522) (xy 179.496212 -117.969284) (xy 179.49926 -117.9703) (xy 179.530549 -117.981541)
			(xy 179.588922 -118.013357) (xy 179.615338 -118.033546) (xy 179.638645 -118.052775) (xy 179.679479 -118.097308)
			(xy 179.696618 -118.122192) (xy 179.697126 -118.122954) (xy 179.700428 -118.12778) (xy 179.704238 -118.131336)
			(xy 179.712366 -118.137686) (xy 179.725828 -118.145814) (xy 179.731416 -118.148862) (xy 179.737512 -118.15191)
			(xy 179.742837 -118.154373) (xy 179.754253 -118.157072) (xy 179.760118 -118.157244) (xy 182.135018 -118.157244)
			(xy 182.138825 -118.157178) (xy 182.146351 -118.15603) (xy 182.150004 -118.154958) (xy 182.150766 -118.154704)
			(xy 182.161226 -118.150566) (xy 182.177435 -118.13501) (xy 182.182008 -118.124732) (xy 182.183024 -118.121938)
			(xy 182.18404 -118.118636) (xy 182.184548 -118.117112) (xy 182.18658 -118.111524) (xy 182.18658 -118.111016)
			(xy 182.195528 -118.086275) (xy 182.219266 -118.039323) (xy 182.249232 -117.996079) (xy 182.284857 -117.957364)
			(xy 182.325464 -117.923913) (xy 182.370284 -117.89636) (xy 182.418465 -117.875228) (xy 182.469094 -117.860919)
			(xy 182.521208 -117.853704) (xy 182.547514 -117.853206) (xy 182.554372 -117.85346) (xy 182.554626 -117.85346)
			(xy 182.576978 -117.854476) (xy 182.587131 -117.855338) (xy 182.607335 -117.858009) (xy 182.617364 -117.85981)
			(xy 182.623968 -117.860826) (xy 182.655947 -117.840991) (xy 182.72238 -117.805628) (xy 182.791286 -117.775364)
			(xy 182.82666 -117.762528) (xy 182.871751 -117.747252) (xy 182.964169 -117.724361) (xy 183.058348 -117.710382)
			(xy 183.15343 -117.705443) (xy 183.248551 -117.709588) (xy 183.342843 -117.722779) (xy 183.38927 -117.733318)
			(xy 183.395874 -117.735096) (xy 183.434861 -117.745118) (xy 183.511217 -117.770626) (xy 183.585271 -117.802201)
			(xy 183.656542 -117.839636) (xy 183.690768 -117.860826) (xy 183.70677 -117.858032) (xy 183.707278 -117.858032)
			(xy 183.710834 -117.857524) (xy 183.72201 -117.856) (xy 183.73598 -117.854476) (xy 183.766714 -117.853206)
			(xy 183.794563 -117.853711) (xy 183.84967 -117.861797) (xy 183.903019 -117.877797) (xy 183.953482 -117.90137)
			(xy 183.999988 -117.932019) (xy 184.041553 -117.969094) (xy 184.05983 -117.990112) (xy 184.060846 -117.991382)
			(xy 184.061608 -117.99189) (xy 184.06583 -117.995138) (xy 184.075305 -117.999999) (xy 184.080404 -118.001542)
			(xy 184.129128 -118.006938) (xy 184.225283 -118.026046) (xy 184.319105 -118.05448) (xy 184.36463 -118.072662)
			(xy 184.56529 -118.155466) (xy 184.57799 -118.157244) (xy 185.393838 -118.157244) (xy 185.400132 -118.157052)
			(xy 185.412335 -118.153962) (xy 185.417968 -118.151148) (xy 185.422794 -118.148608) (xy 185.423556 -118.1481)
			(xy 185.424318 -118.147592) (xy 185.4327 -118.143274) (xy 185.435748 -118.142004) (xy 185.438796 -118.14048)
			(xy 185.449718 -118.132098) (xy 185.450988 -118.130828) (xy 185.454036 -118.127526) (xy 185.45429 -118.127272)
			(xy 185.455052 -118.126256) (xy 185.471942 -118.106697) (xy 185.510119 -118.071866) (xy 185.552652 -118.042514)
			(xy 185.598762 -118.019179) (xy 185.647602 -118.002289) (xy 185.698276 -117.992153) (xy 185.724038 -117.990112)
			(xy 185.735745 -117.988751) (xy 185.756128 -117.976969) (xy 185.763154 -117.967506) (xy 185.787284 -117.931184)
			(xy 185.787284 -117.930676) (xy 185.80862 -117.898164) (xy 185.812654 -117.890903) (xy 185.81628 -117.874703)
			(xy 185.815732 -117.866414) (xy 185.811922 -117.855746) (xy 185.801032 -117.824014) (xy 185.789286 -117.757969)
			(xy 185.788554 -117.724428) (xy 185.788554 -117.723666) (xy 185.789042 -117.696306) (xy 185.79683 -117.642143)
			(xy 185.812246 -117.589639) (xy 185.834978 -117.539864) (xy 185.864562 -117.49383) (xy 185.900396 -117.452476)
			(xy 185.94175 -117.416642) (xy 185.987784 -117.387058) (xy 186.037559 -117.364326) (xy 186.090063 -117.34891)
			(xy 186.144226 -117.341122) (xy 186.198946 -117.341122) (xy 186.253109 -117.34891) (xy 186.305613 -117.364326)
			(xy 186.355388 -117.387058) (xy 186.401422 -117.416642) (xy 186.442776 -117.452476) (xy 186.47861 -117.49383)
			(xy 186.508194 -117.539864) (xy 186.530926 -117.589639) (xy 186.546342 -117.642143) (xy 186.55413 -117.696306)
			(xy 186.554618 -117.723666) (xy 186.554618 -117.72392) (xy 186.554135 -117.751913) (xy 186.545984 -117.807302)
			(xy 186.529844 -117.860911) (xy 186.50606 -117.911593) (xy 186.475141 -117.958266) (xy 186.456828 -117.979444)
			(xy 186.454034 -117.982492) (xy 186.444128 -117.99824) (xy 186.440572 -118.007638) (xy 186.439013 -118.012047)
			(xy 186.437356 -118.02125) (xy 186.43727 -118.025926) (xy 186.437433 -118.030893) (xy 186.439487 -118.040616)
			(xy 186.441334 -118.04523) (xy 186.450986 -118.06809) (xy 186.450986 -118.068598) (xy 186.471306 -118.115842)
			(xy 186.472322 -118.118128) (xy 186.475545 -118.124222) (xy 186.484681 -118.134537) (xy 186.490356 -118.138448)
			(xy 186.50458 -118.146576) (xy 186.51093 -118.150386) (xy 186.520836 -118.154704) (xy 186.532012 -118.15699)
			(xy 186.53252 -118.15699) (xy 186.536584 -118.157244) (xy 187.955682 -118.157244) (xy 187.965691 -118.15653)
			(xy 187.983981 -118.14831) (xy 187.997727 -118.133711) (xy 188.001656 -118.124478) (xy 188.002672 -118.12143)
			(xy 188.011487 -118.094816) (xy 188.035817 -118.044309) (xy 188.067265 -117.997898) (xy 188.105156 -117.95658)
			(xy 188.126624 -117.93855) (xy 188.147815 -117.921971) (xy 188.193958 -117.894303) (xy 188.243529 -117.873386)
			(xy 188.295545 -117.859636) (xy 188.322204 -117.856) (xy 188.333888 -117.85473) (xy 188.366908 -117.853206)
			(xy 188.393831 -117.853668) (xy 188.447142 -117.861235) (xy 188.498861 -117.876217) (xy 188.547963 -117.898317)
			(xy 188.593472 -117.927097) (xy 188.634486 -117.961985) (xy 188.670191 -118.00229) (xy 188.699879 -118.047212)
			(xy 188.722961 -118.09586) (xy 188.731398 -118.12143) (xy 188.731652 -118.1227) (xy 188.732414 -118.124224)
			(xy 188.733176 -118.126256) (xy 188.736139 -118.132613) (xy 188.744897 -118.143559) (xy 188.750448 -118.147846)
			(xy 188.756544 -118.152418) (xy 188.764418 -118.154958) (xy 188.768138 -118.156022) (xy 188.77579 -118.157164)
			(xy 188.779658 -118.157244) (xy 189.935104 -118.157244) (xy 189.944121 -118.156885) (xy 189.961039 -118.150641)
			(xy 189.968124 -118.145052) (xy 189.972737 -118.140874) (xy 189.979932 -118.130722) (xy 189.982348 -118.124986)
			(xy 189.984126 -118.12016) (xy 189.984634 -118.11889) (xy 189.993686 -118.092185) (xy 190.018549 -118.041577)
			(xy 190.050599 -117.995185) (xy 190.089134 -117.954022) (xy 190.133313 -117.918987) (xy 190.182173 -117.890843)
			(xy 190.234647 -117.870206) (xy 190.262002 -117.863366) (xy 190.279553 -117.85949) (xy 190.315173 -117.854659)
			(xy 190.333122 -117.853714) (xy 190.335154 -117.853714) (xy 190.338456 -117.85346) (xy 190.348616 -117.85346)
			(xy 190.371971 -117.853831) (xy 190.418328 -117.859567) (xy 190.441072 -117.86489) (xy 190.447168 -117.866414)
			(xy 190.471552 -117.866414) (xy 190.481712 -117.862604) (xy 190.489586 -117.859302) (xy 190.503302 -117.84838)
			(xy 190.50381 -117.847872) (xy 190.555626 -117.806724) (xy 190.556642 -117.805962) (xy 190.556896 -117.805708)
			(xy 190.565028 -117.798117) (xy 190.57437 -117.777957) (xy 190.57493 -117.766846) (xy 190.57493 -117.763544)
			(xy 190.574676 -117.761004) (xy 190.574676 -116.895118) (xy 190.575166 -116.865134) (xy 190.582994 -116.805678)
			(xy 190.598515 -116.747753) (xy 190.621464 -116.692349) (xy 190.651448 -116.640415) (xy 190.687954 -116.592839)
			(xy 190.730359 -116.550434) (xy 190.777935 -116.513928) (xy 190.829869 -116.483944) (xy 190.885273 -116.460995)
			(xy 190.943198 -116.445474) (xy 191.002654 -116.437646) (xy 191.062622 -116.437646) (xy 191.122078 -116.445474)
			(xy 191.180003 -116.460995) (xy 191.235407 -116.483944) (xy 191.287341 -116.513928) (xy 191.334917 -116.550434)
			(xy 191.377322 -116.592839) (xy 191.413828 -116.640415) (xy 191.443812 -116.692349) (xy 191.466761 -116.747753)
			(xy 191.482282 -116.805678) (xy 191.49011 -116.865134) (xy 191.4906 -116.895118) (xy 191.4906 -117.758718)
			(xy 191.490106 -117.789063) (xy 191.482084 -117.84922) (xy 191.466185 -117.90779) (xy 191.442686 -117.963746)
			(xy 191.411999 -118.016107) (xy 191.374664 -118.063953) (xy 191.331333 -118.106447) (xy 191.282768 -118.142843)
			(xy 191.22982 -118.172504) (xy 191.201802 -118.184168) (xy 191.19215 -118.187978) (xy 191.173354 -118.206774)
			(xy 191.1731 -118.206774) (xy 191.168728 -118.208899) (xy 191.160801 -118.214524) (xy 191.157352 -118.21795)
			(xy 191.156336 -118.21922) (xy 191.153176 -118.222897) (xy 191.148195 -118.231214) (xy 191.14643 -118.23573)
			(xy 191.14516 -118.239794) (xy 191.130682 -118.30177) (xy 191.130428 -118.303294) (xy 191.128396 -118.311168)
			(xy 191.126546 -118.319774) (xy 191.128166 -118.337288) (xy 191.135638 -118.353211) (xy 191.141604 -118.359682)
			(xy 192.341246 -119.559324) (xy 197.174612 -119.559324) (xy 197.174612 -118.695724) (xy 197.175102 -118.665756)
			(xy 197.182925 -118.606334) (xy 197.198438 -118.548441) (xy 197.221374 -118.493068) (xy 197.251341 -118.441162)
			(xy 197.287828 -118.393612) (xy 197.330208 -118.351232) (xy 197.377758 -118.314745) (xy 197.429664 -118.284778)
			(xy 197.485037 -118.261842) (xy 197.54293 -118.246329) (xy 197.602352 -118.238506) (xy 197.662288 -118.238506)
			(xy 197.72171 -118.246329) (xy 197.779603 -118.261842) (xy 197.834976 -118.284778) (xy 197.886882 -118.314745)
			(xy 197.934432 -118.351232) (xy 197.976812 -118.393612) (xy 198.013299 -118.441162) (xy 198.043266 -118.493068)
			(xy 198.066202 -118.548441) (xy 198.081715 -118.606334) (xy 198.089538 -118.665756) (xy 198.090028 -118.695724)
			(xy 198.090028 -119.559324) (xy 198.089538 -119.589292) (xy 198.081715 -119.648714) (xy 198.066202 -119.706607)
			(xy 198.043266 -119.76198) (xy 198.013299 -119.813886) (xy 197.976812 -119.861436) (xy 197.934432 -119.903816)
			(xy 197.886882 -119.940303) (xy 197.834976 -119.97027) (xy 197.779603 -119.993206) (xy 197.72171 -120.008719)
			(xy 197.662288 -120.016542) (xy 197.602352 -120.016542) (xy 197.54293 -120.008719) (xy 197.485037 -119.993206)
			(xy 197.429664 -119.97027) (xy 197.377758 -119.940303) (xy 197.330208 -119.903816) (xy 197.287828 -119.861436)
			(xy 197.251341 -119.813886) (xy 197.221374 -119.76198) (xy 197.198438 -119.706607) (xy 197.182925 -119.648714)
			(xy 197.175102 -119.589292) (xy 197.174612 -119.559324) (xy 192.341246 -119.559324) (xy 194.147694 -121.365772)
			(xy 199.81672 -121.365772) (xy 199.81672 -120.502172) (xy 199.81721 -120.472204) (xy 199.825033 -120.412782)
			(xy 199.840546 -120.354889) (xy 199.863482 -120.299516) (xy 199.893449 -120.24761) (xy 199.929936 -120.20006)
			(xy 199.972316 -120.15768) (xy 200.019866 -120.121193) (xy 200.071772 -120.091226) (xy 200.127145 -120.06829)
			(xy 200.185038 -120.052777) (xy 200.24446 -120.044954) (xy 200.304396 -120.044954) (xy 200.363818 -120.052777)
			(xy 200.421711 -120.06829) (xy 200.477084 -120.091226) (xy 200.52899 -120.121193) (xy 200.57654 -120.15768)
			(xy 200.61892 -120.20006) (xy 200.655407 -120.24761) (xy 200.685374 -120.299516) (xy 200.70831 -120.354889)
			(xy 200.723823 -120.412782) (xy 200.731646 -120.472204) (xy 200.732136 -120.502172) (xy 200.732136 -121.365772)
			(xy 200.731646 -121.39574) (xy 200.723823 -121.455162) (xy 200.70831 -121.513055) (xy 200.685374 -121.568428)
			(xy 200.655407 -121.620334) (xy 200.61892 -121.667884) (xy 200.57654 -121.710264) (xy 200.52899 -121.746751)
			(xy 200.477084 -121.776718) (xy 200.421711 -121.799654) (xy 200.363818 -121.815167) (xy 200.304396 -121.82299)
			(xy 200.24446 -121.82299) (xy 200.185038 -121.815167) (xy 200.127145 -121.799654) (xy 200.071772 -121.776718)
			(xy 200.019866 -121.746751) (xy 199.972316 -121.710264) (xy 199.929936 -121.667884) (xy 199.893449 -121.620334)
			(xy 199.863482 -121.568428) (xy 199.840546 -121.513055) (xy 199.825033 -121.455162) (xy 199.81721 -121.39574)
			(xy 199.81672 -121.365772) (xy 194.147694 -121.365772) (xy 195.941188 -123.159266) (xy 197.174612 -123.159266)
			(xy 197.174612 -122.295666) (xy 197.175102 -122.265698) (xy 197.182925 -122.206276) (xy 197.198438 -122.148383)
			(xy 197.221374 -122.09301) (xy 197.251341 -122.041104) (xy 197.287828 -121.993554) (xy 197.330208 -121.951174)
			(xy 197.377758 -121.914687) (xy 197.429664 -121.88472) (xy 197.485037 -121.861784) (xy 197.54293 -121.846271)
			(xy 197.602352 -121.838448) (xy 197.662288 -121.838448) (xy 197.72171 -121.846271) (xy 197.779603 -121.861784)
			(xy 197.834976 -121.88472) (xy 197.886882 -121.914687) (xy 197.934432 -121.951174) (xy 197.976812 -121.993554)
			(xy 198.013299 -122.041104) (xy 198.043266 -122.09301) (xy 198.066202 -122.148383) (xy 198.081715 -122.206276)
			(xy 198.089538 -122.265698) (xy 198.090028 -122.295666) (xy 198.090028 -123.159266) (xy 198.089538 -123.189234)
			(xy 198.081715 -123.248656) (xy 198.066202 -123.306549) (xy 198.043266 -123.361922) (xy 198.013299 -123.413828)
			(xy 197.976812 -123.461378) (xy 197.934432 -123.503758) (xy 197.886882 -123.540245) (xy 197.834976 -123.570212)
			(xy 197.779603 -123.593148) (xy 197.72171 -123.608661) (xy 197.662288 -123.616484) (xy 197.602352 -123.616484)
			(xy 197.54293 -123.608661) (xy 197.485037 -123.593148) (xy 197.429664 -123.570212) (xy 197.377758 -123.540245)
			(xy 197.330208 -123.503758) (xy 197.287828 -123.461378) (xy 197.251341 -123.413828) (xy 197.221374 -123.361922)
			(xy 197.198438 -123.306549) (xy 197.182925 -123.248656) (xy 197.175102 -123.189234) (xy 197.174612 -123.159266)
			(xy 195.941188 -123.159266) (xy 197.747636 -124.965714) (xy 199.81672 -124.965714) (xy 199.81672 -124.102114)
			(xy 199.81721 -124.072146) (xy 199.825033 -124.012724) (xy 199.840546 -123.954831) (xy 199.863482 -123.899458)
			(xy 199.893449 -123.847552) (xy 199.929936 -123.800002) (xy 199.972316 -123.757622) (xy 200.019866 -123.721135)
			(xy 200.071772 -123.691168) (xy 200.127145 -123.668232) (xy 200.185038 -123.652719) (xy 200.24446 -123.644896)
			(xy 200.304396 -123.644896) (xy 200.363818 -123.652719) (xy 200.421711 -123.668232) (xy 200.477084 -123.691168)
			(xy 200.52899 -123.721135) (xy 200.57654 -123.757622) (xy 200.61892 -123.800002) (xy 200.655407 -123.847552)
			(xy 200.685374 -123.899458) (xy 200.70831 -123.954831) (xy 200.723823 -124.012724) (xy 200.731646 -124.072146)
			(xy 200.732136 -124.102114) (xy 200.732136 -124.965714) (xy 200.731646 -124.995682) (xy 200.723823 -125.055104)
			(xy 200.70831 -125.112997) (xy 200.685374 -125.16837) (xy 200.655407 -125.220276) (xy 200.61892 -125.267826)
			(xy 200.57654 -125.310206) (xy 200.52899 -125.346693) (xy 200.477084 -125.37666) (xy 200.421711 -125.399596)
			(xy 200.363818 -125.415109) (xy 200.304396 -125.422932) (xy 200.24446 -125.422932) (xy 200.185038 -125.415109)
			(xy 200.127145 -125.399596) (xy 200.071772 -125.37666) (xy 200.019866 -125.346693) (xy 199.972316 -125.310206)
			(xy 199.929936 -125.267826) (xy 199.893449 -125.220276) (xy 199.863482 -125.16837) (xy 199.840546 -125.112997)
			(xy 199.825033 -125.055104) (xy 199.81721 -124.995682) (xy 199.81672 -124.965714) (xy 197.747636 -124.965714)
			(xy 203.731114 -130.949192) (xy 203.737789 -130.955576) (xy 203.753001 -130.966047) (xy 203.76134 -130.97002)
			(xy 203.766287 -130.972134) (xy 203.776791 -130.974448) (xy 203.782168 -130.974592) (xy 203.832714 -130.974592)
			(xy 203.833476 -130.974338) (xy 203.833476 -130.785108) (xy 203.831952 -130.772408) (xy 203.830071 -130.765924)
			(xy 203.823379 -130.754203) (xy 203.818744 -130.749294) (xy 201.288904 -128.219708) (xy 201.270873 -128.200937)
			(xy 201.240296 -128.158819) (xy 201.216672 -128.112443) (xy 201.200581 -128.062946) (xy 201.192418 -128.011543)
			(xy 201.191876 -127.98552) (xy 201.191876 -120.06834) (xy 201.191827 -120.063802) (xy 201.190289 -120.054857)
			(xy 201.188828 -120.05056) (xy 201.186774 -120.045544) (xy 201.180884 -120.036449) (xy 201.177144 -120.032526)
			(xy 193.152522 -112.008158) (xy 193.134408 -111.989378) (xy 193.103721 -111.947182) (xy 193.08002 -111.900701)
			(xy 193.063888 -111.851082) (xy 193.055725 -111.79955) (xy 193.05524 -111.773462) (xy 193.05524 -106.902758)
			(xy 193.055074 -106.896748) (xy 193.052254 -106.885064) (xy 193.049652 -106.879644) (xy 193.047809 -106.876173)
			(xy 193.043209 -106.8698) (xy 193.040508 -106.866944) (xy 192.040256 -105.866692) (xy 192.037402 -105.86399)
			(xy 192.03102 -105.859405) (xy 192.027556 -105.857548) (xy 192.02213 -105.854963) (xy 192.01045 -105.852137)
			(xy 192.004442 -105.85196) (xy 189.10173 -105.85196) (xy 189.075642 -105.851476) (xy 189.024108 -105.843314)
			(xy 188.974487 -105.827185) (xy 188.928002 -105.803488) (xy 188.8858 -105.772807) (xy 188.867034 -105.754678)
			(xy 186.369198 -103.256842) (xy 186.351086 -103.238061) (xy 186.320403 -103.195864) (xy 186.296706 -103.149382)
			(xy 186.280578 -103.099764) (xy 186.272418 -103.048233) (xy 186.271916 -103.022146) (xy 186.271916 -100.171758)
			(xy 186.268868 -100.165916) (xy 186.266074 -100.160328) (xy 186.252359 -100.13285) (xy 186.23291 -100.074602)
			(xy 186.223027 -100.013994) (xy 186.222386 -99.98329) (xy 186.222386 -99.982782) (xy 186.222872 -99.955531)
			(xy 186.230628 -99.901583) (xy 186.245983 -99.849288) (xy 186.268625 -99.799711) (xy 186.298091 -99.753861)
			(xy 186.333782 -99.71267) (xy 186.374973 -99.676979) (xy 186.420823 -99.647513) (xy 186.4704 -99.624871)
			(xy 186.522695 -99.609516) (xy 186.576643 -99.60176) (xy 186.631145 -99.60176) (xy 186.685093 -99.609516)
			(xy 186.737388 -99.624871) (xy 186.786965 -99.647513) (xy 186.832815 -99.676979) (xy 186.874006 -99.71267)
			(xy 186.909697 -99.753861) (xy 186.939163 -99.799711) (xy 186.961805 -99.849288) (xy 186.97716 -99.901583)
			(xy 186.984916 -99.955531) (xy 186.985402 -99.982782) (xy 186.985402 -99.98329) (xy 186.984771 -100.013995)
			(xy 186.974901 -100.074609) (xy 186.955446 -100.132857) (xy 186.941714 -100.160328) (xy 186.93892 -100.165916)
			(xy 186.935872 -100.171758) (xy 186.935872 -102.86365) (xy 186.936888 -102.873302) (xy 186.93852 -102.880544)
			(xy 186.945367 -102.893707) (xy 186.95035 -102.89921) (xy 189.224666 -105.173526) (xy 189.230168 -105.178507)
			(xy 189.243337 -105.185337) (xy 189.250574 -105.186988) (xy 189.260226 -105.188004) (xy 189.991238 -105.188004)
			(xy 190.000334 -105.187587) (xy 190.017353 -105.181149) (xy 190.03105 -105.169169) (xy 190.035688 -105.161334)
			(xy 190.03772 -105.156254) (xy 190.040441 -105.149222) (xy 190.04199 -105.13423) (xy 190.040768 -105.12679)
			(xy 190.039498 -105.120186) (xy 190.032386 -105.106978) (xy 187.82284 -102.897432) (xy 187.804806 -102.878662)
			(xy 187.774223 -102.836546) (xy 187.750593 -102.79017) (xy 187.734496 -102.740672) (xy 187.726329 -102.689268)
			(xy 187.725812 -102.663244) (xy 187.725812 -99.21494) (xy 187.72505 -99.206812) (xy 187.723553 -99.199145)
			(xy 187.716568 -99.18518) (xy 187.711334 -99.17938) (xy 186.365134 -97.833434) (xy 185.70702 -97.17532)
			(xy 185.696352 -97.16897) (xy 185.69051 -97.167192) (xy 185.66494 -97.158747) (xy 185.616286 -97.135672)
			(xy 185.571357 -97.105989) (xy 185.531046 -97.070287) (xy 185.496151 -97.029274) (xy 185.467366 -96.983765)
			(xy 185.445262 -96.934662) (xy 185.430278 -96.88294) (xy 185.42271 -96.829626) (xy 185.422286 -96.802702)
			(xy 185.422772 -96.775451) (xy 185.430528 -96.721502) (xy 185.445883 -96.669207) (xy 185.468524 -96.619629)
			(xy 185.49799 -96.573778) (xy 185.533681 -96.532587) (xy 185.574872 -96.496895) (xy 185.620722 -96.467428)
			(xy 185.670299 -96.444786) (xy 185.722594 -96.42943) (xy 185.776543 -96.421672) (xy 185.803794 -96.421194)
			(xy 185.830718 -96.421655) (xy 185.884031 -96.42922) (xy 185.935752 -96.444201) (xy 185.984855 -96.466299)
			(xy 186.030367 -96.495078) (xy 186.071383 -96.529966) (xy 186.107091 -96.570271) (xy 186.136782 -96.615193)
			(xy 186.159866 -96.663841) (xy 186.168284 -96.689418) (xy 186.170062 -96.69526) (xy 186.176412 -96.705928)
			(xy 186.510422 -97.039938) (xy 190.825372 -97.039938) (xy 190.829443 -96.984316) (xy 190.841569 -96.929879)
			(xy 190.861492 -96.877788) (xy 190.888788 -96.829153) (xy 190.922874 -96.78501) (xy 190.963023 -96.746301)
			(xy 191.008381 -96.71385) (xy 191.057981 -96.688349) (xy 191.110765 -96.670342) (xy 191.165608 -96.660212)
			(xy 191.221342 -96.658175) (xy 191.276779 -96.664275) (xy 191.330736 -96.678381) (xy 191.382065 -96.700193)
			(xy 191.429671 -96.729247) (xy 191.472539 -96.764922) (xy 191.509756 -96.806459) (xy 191.540529 -96.852972)
			(xy 191.564201 -96.903469) (xy 191.580269 -96.956876) (xy 191.587447 -97.005648) (xy 194.269358 -97.005648)
			(xy 194.273429 -96.950026) (xy 194.285555 -96.895589) (xy 194.305478 -96.843498) (xy 194.332774 -96.794863)
			(xy 194.36686 -96.75072) (xy 194.407009 -96.712011) (xy 194.452367 -96.67956) (xy 194.501967 -96.654059)
			(xy 194.554751 -96.636052) (xy 194.609594 -96.625922) (xy 194.665328 -96.623885) (xy 194.720765 -96.629985)
			(xy 194.774722 -96.644091) (xy 194.826051 -96.665903) (xy 194.873657 -96.694957) (xy 194.916525 -96.730632)
			(xy 194.953742 -96.772169) (xy 194.984515 -96.818682) (xy 195.008187 -96.869179) (xy 195.024255 -96.922586)
			(xy 195.032375 -96.977762) (xy 195.032884 -97.005648) (xy 195.032375 -97.033534) (xy 195.024255 -97.08871)
			(xy 195.008187 -97.142117) (xy 194.984515 -97.192614) (xy 194.953742 -97.239127) (xy 194.916525 -97.280664)
			(xy 194.873657 -97.316339) (xy 194.826051 -97.345393) (xy 194.774722 -97.367205) (xy 194.720765 -97.381311)
			(xy 194.665328 -97.387411) (xy 194.609594 -97.385374) (xy 194.554751 -97.375244) (xy 194.501967 -97.357237)
			(xy 194.452367 -97.331736) (xy 194.407009 -97.299285) (xy 194.36686 -97.260576) (xy 194.332774 -97.216433)
			(xy 194.305478 -97.167798) (xy 194.285555 -97.115707) (xy 194.273429 -97.06127) (xy 194.269358 -97.005648)
			(xy 191.587447 -97.005648) (xy 191.588389 -97.012052) (xy 191.588898 -97.039938) (xy 191.588389 -97.067824)
			(xy 191.580269 -97.123) (xy 191.564201 -97.176407) (xy 191.540529 -97.226904) (xy 191.509756 -97.273417)
			(xy 191.472539 -97.314954) (xy 191.429671 -97.350629) (xy 191.382065 -97.379683) (xy 191.330736 -97.401495)
			(xy 191.276779 -97.415601) (xy 191.221342 -97.421701) (xy 191.165608 -97.419664) (xy 191.110765 -97.409534)
			(xy 191.057981 -97.391527) (xy 191.008381 -97.366026) (xy 190.963023 -97.333575) (xy 190.922874 -97.294866)
			(xy 190.888788 -97.250723) (xy 190.861492 -97.202088) (xy 190.841569 -97.149997) (xy 190.829443 -97.09556)
			(xy 190.825372 -97.039938) (xy 186.510422 -97.039938) (xy 187.110624 -97.64014) (xy 190.017906 -97.64014)
			(xy 190.021977 -97.584518) (xy 190.034103 -97.530081) (xy 190.054026 -97.47799) (xy 190.081322 -97.429355)
			(xy 190.115408 -97.385212) (xy 190.155557 -97.346503) (xy 190.200915 -97.314052) (xy 190.250515 -97.288551)
			(xy 190.303299 -97.270544) (xy 190.358142 -97.260414) (xy 190.413876 -97.258377) (xy 190.469313 -97.264477)
			(xy 190.52327 -97.278583) (xy 190.574599 -97.300395) (xy 190.622205 -97.329449) (xy 190.665073 -97.365124)
			(xy 190.70229 -97.406661) (xy 190.733063 -97.453174) (xy 190.756735 -97.503671) (xy 190.772803 -97.557078)
			(xy 190.780923 -97.612254) (xy 190.781432 -97.64014) (xy 190.780923 -97.668026) (xy 190.772803 -97.723202)
			(xy 190.756735 -97.776609) (xy 190.733063 -97.827106) (xy 190.70229 -97.873619) (xy 190.665073 -97.915156)
			(xy 190.622205 -97.950831) (xy 190.574599 -97.979885) (xy 190.52327 -98.001697) (xy 190.469313 -98.015803)
			(xy 190.413876 -98.021903) (xy 190.358142 -98.019866) (xy 190.303299 -98.009736) (xy 190.250515 -97.991729)
			(xy 190.200915 -97.966228) (xy 190.155557 -97.933777) (xy 190.115408 -97.895068) (xy 190.081322 -97.850925)
			(xy 190.054026 -97.80229) (xy 190.034103 -97.750199) (xy 190.021977 -97.695762) (xy 190.017906 -97.64014)
			(xy 187.110624 -97.64014) (xy 187.641484 -98.171) (xy 191.663826 -98.171) (xy 191.667897 -98.115378)
			(xy 191.680023 -98.060941) (xy 191.699946 -98.00885) (xy 191.727242 -97.960215) (xy 191.761328 -97.916072)
			(xy 191.801477 -97.877363) (xy 191.846835 -97.844912) (xy 191.896435 -97.819411) (xy 191.949219 -97.801404)
			(xy 192.004062 -97.791274) (xy 192.059796 -97.789237) (xy 192.115233 -97.795337) (xy 192.16919 -97.809443)
			(xy 192.220519 -97.831255) (xy 192.268125 -97.860309) (xy 192.310993 -97.895984) (xy 192.34821 -97.937521)
			(xy 192.378983 -97.984034) (xy 192.402655 -98.034531) (xy 192.418723 -98.087938) (xy 192.426843 -98.143114)
			(xy 192.427352 -98.171) (xy 192.426843 -98.198886) (xy 192.418723 -98.254062) (xy 192.402655 -98.307469)
			(xy 192.378983 -98.357966) (xy 192.34821 -98.404479) (xy 192.310993 -98.446016) (xy 192.268125 -98.481691)
			(xy 192.220519 -98.510745) (xy 192.16919 -98.532557) (xy 192.115233 -98.546663) (xy 192.059796 -98.552763)
			(xy 192.004062 -98.550726) (xy 191.949219 -98.540596) (xy 191.896435 -98.522589) (xy 191.846835 -98.497088)
			(xy 191.801477 -98.464637) (xy 191.761328 -98.425928) (xy 191.727242 -98.381785) (xy 191.699946 -98.33315)
			(xy 191.680023 -98.281059) (xy 191.667897 -98.226622) (xy 191.663826 -98.171) (xy 187.641484 -98.171)
			(xy 188.292232 -98.821748) (xy 188.310268 -98.840517) (xy 188.340857 -98.882632) (xy 188.364492 -98.929007)
			(xy 188.380592 -98.978505) (xy 188.388764 -99.029911) (xy 188.38926 -99.055936) (xy 188.38926 -99.439984)
			(xy 191.409826 -99.439984) (xy 191.413897 -99.384362) (xy 191.426023 -99.329925) (xy 191.445946 -99.277834)
			(xy 191.473242 -99.229199) (xy 191.507328 -99.185056) (xy 191.547477 -99.146347) (xy 191.592835 -99.113896)
			(xy 191.642435 -99.088395) (xy 191.695219 -99.070388) (xy 191.750062 -99.060258) (xy 191.805796 -99.058221)
			(xy 191.861233 -99.064321) (xy 191.91519 -99.078427) (xy 191.966519 -99.100239) (xy 192.014125 -99.129293)
			(xy 192.056993 -99.164968) (xy 192.09421 -99.206505) (xy 192.124983 -99.253018) (xy 192.148655 -99.303515)
			(xy 192.164723 -99.356922) (xy 192.172843 -99.412098) (xy 192.173352 -99.439984) (xy 192.172843 -99.46787)
			(xy 192.164723 -99.523046) (xy 192.148655 -99.576453) (xy 192.124983 -99.62695) (xy 192.09421 -99.673463)
			(xy 192.056993 -99.715) (xy 192.014125 -99.750675) (xy 191.966519 -99.779729) (xy 191.91519 -99.801541)
			(xy 191.861233 -99.815647) (xy 191.805796 -99.821747) (xy 191.750062 -99.81971) (xy 191.695219 -99.80958)
			(xy 191.642435 -99.791573) (xy 191.592835 -99.766072) (xy 191.547477 -99.733621) (xy 191.507328 -99.694912)
			(xy 191.473242 -99.650769) (xy 191.445946 -99.602134) (xy 191.426023 -99.550043) (xy 191.413897 -99.495606)
			(xy 191.409826 -99.439984) (xy 188.38926 -99.439984) (xy 188.38926 -100.039932) (xy 189.976758 -100.039932)
			(xy 189.980829 -99.98431) (xy 189.992955 -99.929873) (xy 190.012878 -99.877782) (xy 190.040174 -99.829147)
			(xy 190.07426 -99.785004) (xy 190.114409 -99.746295) (xy 190.159767 -99.713844) (xy 190.209367 -99.688343)
			(xy 190.262151 -99.670336) (xy 190.316994 -99.660206) (xy 190.372728 -99.658169) (xy 190.428165 -99.664269)
			(xy 190.482122 -99.678375) (xy 190.533451 -99.700187) (xy 190.581057 -99.729241) (xy 190.623925 -99.764916)
			(xy 190.661142 -99.806453) (xy 190.691915 -99.852966) (xy 190.715587 -99.903463) (xy 190.731655 -99.95687)
			(xy 190.739775 -100.012046) (xy 190.740284 -100.039932) (xy 190.739775 -100.067818) (xy 190.731655 -100.122994)
			(xy 190.715587 -100.176401) (xy 190.691915 -100.226898) (xy 190.661142 -100.273411) (xy 190.623925 -100.314948)
			(xy 190.581057 -100.350623) (xy 190.533451 -100.379677) (xy 190.482122 -100.401489) (xy 190.428165 -100.415595)
			(xy 190.372728 -100.421695) (xy 190.316994 -100.419658) (xy 190.262151 -100.409528) (xy 190.209367 -100.391521)
			(xy 190.159767 -100.36602) (xy 190.114409 -100.333569) (xy 190.07426 -100.29486) (xy 190.040174 -100.250717)
			(xy 190.012878 -100.202082) (xy 189.992955 -100.149991) (xy 189.980829 -100.095554) (xy 189.976758 -100.039932)
			(xy 188.38926 -100.039932) (xy 188.38926 -101.240082) (xy 190.393826 -101.240082) (xy 190.397897 -101.18446)
			(xy 190.410023 -101.130023) (xy 190.429946 -101.077932) (xy 190.457242 -101.029297) (xy 190.491328 -100.985154)
			(xy 190.531477 -100.946445) (xy 190.576835 -100.913994) (xy 190.626435 -100.888493) (xy 190.679219 -100.870486)
			(xy 190.734062 -100.860356) (xy 190.789796 -100.858319) (xy 190.845233 -100.864419) (xy 190.89919 -100.878525)
			(xy 190.950519 -100.900337) (xy 190.998125 -100.929391) (xy 191.040993 -100.965066) (xy 191.07821 -101.006603)
			(xy 191.108983 -101.053116) (xy 191.116733 -101.069648) (xy 191.686178 -101.069648) (xy 191.690249 -101.014026)
			(xy 191.702375 -100.959589) (xy 191.722298 -100.907498) (xy 191.749594 -100.858863) (xy 191.78368 -100.81472)
			(xy 191.823829 -100.776011) (xy 191.869187 -100.74356) (xy 191.918787 -100.718059) (xy 191.971571 -100.700052)
			(xy 192.026414 -100.689922) (xy 192.082148 -100.687885) (xy 192.137585 -100.693985) (xy 192.191542 -100.708091)
			(xy 192.242871 -100.729903) (xy 192.290477 -100.758957) (xy 192.333345 -100.794632) (xy 192.370562 -100.836169)
			(xy 192.401335 -100.882682) (xy 192.425007 -100.933179) (xy 192.441075 -100.986586) (xy 192.449195 -101.041762)
			(xy 192.449704 -101.069648) (xy 194.269358 -101.069648) (xy 194.273429 -101.014026) (xy 194.285555 -100.959589)
			(xy 194.305478 -100.907498) (xy 194.332774 -100.858863) (xy 194.36686 -100.81472) (xy 194.407009 -100.776011)
			(xy 194.452367 -100.74356) (xy 194.501967 -100.718059) (xy 194.554751 -100.700052) (xy 194.609594 -100.689922)
			(xy 194.665328 -100.687885) (xy 194.720765 -100.693985) (xy 194.774722 -100.708091) (xy 194.826051 -100.729903)
			(xy 194.873657 -100.758957) (xy 194.916525 -100.794632) (xy 194.953742 -100.836169) (xy 194.984515 -100.882682)
			(xy 195.008187 -100.933179) (xy 195.024255 -100.986586) (xy 195.032375 -101.041762) (xy 195.032884 -101.069648)
			(xy 195.032375 -101.097534) (xy 195.024255 -101.15271) (xy 195.008187 -101.206117) (xy 194.984515 -101.256614)
			(xy 194.953742 -101.303127) (xy 194.916525 -101.344664) (xy 194.873657 -101.380339) (xy 194.826051 -101.409393)
			(xy 194.774722 -101.431205) (xy 194.720765 -101.445311) (xy 194.665328 -101.451411) (xy 194.609594 -101.449374)
			(xy 194.554751 -101.439244) (xy 194.501967 -101.421237) (xy 194.452367 -101.395736) (xy 194.407009 -101.363285)
			(xy 194.36686 -101.324576) (xy 194.332774 -101.280433) (xy 194.305478 -101.231798) (xy 194.285555 -101.179707)
			(xy 194.273429 -101.12527) (xy 194.269358 -101.069648) (xy 192.449704 -101.069648) (xy 192.449195 -101.097534)
			(xy 192.441075 -101.15271) (xy 192.425007 -101.206117) (xy 192.401335 -101.256614) (xy 192.370562 -101.303127)
			(xy 192.333345 -101.344664) (xy 192.290477 -101.380339) (xy 192.242871 -101.409393) (xy 192.191542 -101.431205)
			(xy 192.137585 -101.445311) (xy 192.082148 -101.451411) (xy 192.026414 -101.449374) (xy 191.971571 -101.439244)
			(xy 191.918787 -101.421237) (xy 191.869187 -101.395736) (xy 191.823829 -101.363285) (xy 191.78368 -101.324576)
			(xy 191.749594 -101.280433) (xy 191.722298 -101.231798) (xy 191.702375 -101.179707) (xy 191.690249 -101.12527)
			(xy 191.686178 -101.069648) (xy 191.116733 -101.069648) (xy 191.132655 -101.103613) (xy 191.148723 -101.15702)
			(xy 191.156843 -101.212196) (xy 191.157352 -101.240082) (xy 191.156843 -101.267968) (xy 191.148723 -101.323144)
			(xy 191.132655 -101.376551) (xy 191.108983 -101.427048) (xy 191.07821 -101.473561) (xy 191.040993 -101.515098)
			(xy 190.998125 -101.550773) (xy 190.950519 -101.579827) (xy 190.89919 -101.601639) (xy 190.845233 -101.615745)
			(xy 190.789796 -101.621845) (xy 190.734062 -101.619808) (xy 190.679219 -101.609678) (xy 190.626435 -101.591671)
			(xy 190.576835 -101.56617) (xy 190.531477 -101.533719) (xy 190.491328 -101.49501) (xy 190.457242 -101.450867)
			(xy 190.429946 -101.402232) (xy 190.410023 -101.350141) (xy 190.397897 -101.295704) (xy 190.393826 -101.240082)
			(xy 188.38926 -101.240082) (xy 188.38926 -102.448868) (xy 188.394086 -102.454456) (xy 188.428638 -102.489)
			(xy 190.901826 -102.489) (xy 190.905897 -102.433378) (xy 190.918023 -102.378941) (xy 190.937946 -102.32685)
			(xy 190.965242 -102.278215) (xy 190.999328 -102.234072) (xy 191.039477 -102.195363) (xy 191.084835 -102.162912)
			(xy 191.134435 -102.137411) (xy 191.187219 -102.119404) (xy 191.242062 -102.109274) (xy 191.297796 -102.107237)
			(xy 191.353233 -102.113337) (xy 191.40719 -102.127443) (xy 191.458519 -102.149255) (xy 191.506125 -102.178309)
			(xy 191.548993 -102.213984) (xy 191.58621 -102.255521) (xy 191.616983 -102.302034) (xy 191.640655 -102.352531)
			(xy 191.656723 -102.405938) (xy 191.664843 -102.461114) (xy 191.665352 -102.489) (xy 191.664843 -102.516886)
			(xy 191.656723 -102.572062) (xy 191.640655 -102.625469) (xy 191.616983 -102.675966) (xy 191.58621 -102.722479)
			(xy 191.548993 -102.764016) (xy 191.506125 -102.799691) (xy 191.458519 -102.828745) (xy 191.40719 -102.850557)
			(xy 191.353233 -102.864663) (xy 191.297796 -102.870763) (xy 191.242062 -102.868726) (xy 191.187219 -102.858596)
			(xy 191.134435 -102.840589) (xy 191.084835 -102.815088) (xy 191.039477 -102.782637) (xy 190.999328 -102.743928)
			(xy 190.965242 -102.699785) (xy 190.937946 -102.65115) (xy 190.918023 -102.599059) (xy 190.905897 -102.544622)
			(xy 190.901826 -102.489) (xy 188.428638 -102.489) (xy 189.825957 -103.886) (xy 191.409826 -103.886)
			(xy 191.413897 -103.830378) (xy 191.426023 -103.775941) (xy 191.445946 -103.72385) (xy 191.473242 -103.675215)
			(xy 191.507328 -103.631072) (xy 191.547477 -103.592363) (xy 191.592835 -103.559912) (xy 191.642435 -103.534411)
			(xy 191.695219 -103.516404) (xy 191.750062 -103.506274) (xy 191.805796 -103.504237) (xy 191.861233 -103.510337)
			(xy 191.91519 -103.524443) (xy 191.966519 -103.546255) (xy 192.014125 -103.575309) (xy 192.056993 -103.610984)
			(xy 192.09421 -103.652521) (xy 192.124983 -103.699034) (xy 192.148655 -103.749531) (xy 192.164723 -103.802938)
			(xy 192.172843 -103.858114) (xy 192.173352 -103.886) (xy 192.172843 -103.913886) (xy 192.164723 -103.969062)
			(xy 192.148655 -104.022469) (xy 192.124983 -104.072966) (xy 192.09421 -104.119479) (xy 192.056993 -104.161016)
			(xy 192.014125 -104.196691) (xy 191.966519 -104.225745) (xy 191.91519 -104.247557) (xy 191.861233 -104.261663)
			(xy 191.805796 -104.267763) (xy 191.750062 -104.265726) (xy 191.695219 -104.255596) (xy 191.642435 -104.237589)
			(xy 191.592835 -104.212088) (xy 191.547477 -104.179637) (xy 191.507328 -104.140928) (xy 191.473242 -104.096785)
			(xy 191.445946 -104.04815) (xy 191.426023 -103.996059) (xy 191.413897 -103.941622) (xy 191.409826 -103.886)
			(xy 189.825957 -103.886) (xy 190.62192 -104.681782) (xy 190.624206 -104.68356) (xy 192.280032 -104.68356)
			(xy 192.306118 -104.684049) (xy 192.357647 -104.69222) (xy 192.407261 -104.708357) (xy 192.453738 -104.73206)
			(xy 192.495932 -104.762747) (xy 192.514728 -104.780842) (xy 194.234054 -106.500168) (xy 194.252168 -106.518948)
			(xy 194.282853 -106.561144) (xy 194.306553 -106.607625) (xy 194.322682 -106.657244) (xy 194.330842 -106.708777)
			(xy 194.331336 -106.734864) (xy 194.331336 -108.044234) (xy 198.958708 -108.044234) (xy 198.959194 -108.016983)
			(xy 198.96695 -107.963035) (xy 198.982305 -107.91074) (xy 199.004947 -107.861163) (xy 199.034413 -107.815313)
			(xy 199.070104 -107.774122) (xy 199.111295 -107.738431) (xy 199.157145 -107.708965) (xy 199.206722 -107.686323)
			(xy 199.259017 -107.670968) (xy 199.312965 -107.663212) (xy 199.367467 -107.663212) (xy 199.421415 -107.670968)
			(xy 199.47371 -107.686323) (xy 199.523287 -107.708965) (xy 199.569137 -107.738431) (xy 199.610328 -107.774122)
			(xy 199.646019 -107.815313) (xy 199.675485 -107.861163) (xy 199.698127 -107.91074) (xy 199.713482 -107.963035)
			(xy 199.721238 -108.016983) (xy 199.721724 -108.044234) (xy 199.721188 -108.071805) (xy 199.713246 -108.126373)
			(xy 199.697531 -108.17923) (xy 199.674372 -108.229273) (xy 199.644251 -108.275463) (xy 199.607794 -108.316835)
			(xy 199.565762 -108.352529) (xy 199.542654 -108.367576) (xy 199.530079 -108.376034) (xy 199.510215 -108.398904)
			(xy 199.497933 -108.426595) (xy 199.494314 -108.45667) (xy 199.499675 -108.486484) (xy 199.513547 -108.513414)
			(xy 199.534707 -108.53509) (xy 199.547734 -108.542836) (xy 199.573125 -108.557309) (xy 199.619559 -108.592795)
			(xy 199.660042 -108.634944) (xy 199.693626 -108.682772) (xy 199.719528 -108.73516) (xy 199.737142 -108.790884)
			(xy 199.746056 -108.848641) (xy 199.746616 -108.877862) (xy 199.74613 -108.905113) (xy 199.738374 -108.959061)
			(xy 199.723019 -109.011356) (xy 199.700377 -109.060933) (xy 199.670911 -109.106783) (xy 199.63522 -109.147974)
			(xy 199.594029 -109.183665) (xy 199.548179 -109.213131) (xy 199.498602 -109.235773) (xy 199.446307 -109.251128)
			(xy 199.392359 -109.258884) (xy 199.337857 -109.258884) (xy 199.283909 -109.251128) (xy 199.231614 -109.235773)
			(xy 199.182037 -109.213131) (xy 199.136187 -109.183665) (xy 199.094996 -109.147974) (xy 199.059305 -109.106783)
			(xy 199.029839 -109.060933) (xy 199.007197 -109.011356) (xy 198.991842 -108.959061) (xy 198.984086 -108.905113)
			(xy 198.9836 -108.877862) (xy 198.984122 -108.85029) (xy 198.992065 -108.795721) (xy 199.007781 -108.742864)
			(xy 199.030943 -108.692819) (xy 199.061066 -108.64663) (xy 199.097525 -108.605259) (xy 199.13956 -108.569566)
			(xy 199.16267 -108.55452) (xy 199.175246 -108.546064) (xy 199.195105 -108.523192) (xy 199.207383 -108.495502)
			(xy 199.211001 -108.465428) (xy 199.20564 -108.435615) (xy 199.191772 -108.408686) (xy 199.170615 -108.387008)
			(xy 199.15759 -108.37926) (xy 199.132203 -108.36478) (xy 199.085768 -108.329297) (xy 199.045284 -108.287149)
			(xy 199.011698 -108.239323) (xy 198.985795 -108.186935) (xy 198.968181 -108.131212) (xy 198.959268 -108.073455)
			(xy 198.958708 -108.044234) (xy 194.331336 -108.044234) (xy 194.331336 -111.256826) (xy 194.332352 -111.266478)
			(xy 194.333983 -111.27372) (xy 194.340832 -111.286882) (xy 194.345814 -111.292386) (xy 201.669142 -118.615714)
			(xy 201.6762 -118.622161) (xy 201.69375 -118.629699) (xy 201.712843 -118.630235) (xy 201.721974 -118.627398)
			(xy 201.72426 -118.626382) (xy 201.731251 -118.623228) (xy 201.743135 -118.613547) (xy 201.747628 -118.607332)
			(xy 201.751438 -118.60149) (xy 201.755756 -118.58752) (xy 201.755756 -114.882168) (xy 201.755312 -114.87238)
			(xy 201.748002 -114.854219) (xy 201.741532 -114.846862) (xy 201.7268 -114.831622) (xy 201.72356 -114.82839)
			(xy 201.716151 -114.82302) (xy 201.712068 -114.820954) (xy 201.688446 -114.809778) (xy 201.688192 -114.809778)
			(xy 201.681842 -114.80927) (xy 201.67981 -114.809016) (xy 201.652038 -114.805589) (xy 201.597845 -114.791647)
			(xy 201.546269 -114.769942) (xy 201.498415 -114.740937) (xy 201.455311 -114.705255) (xy 201.417878 -114.663661)
			(xy 201.386922 -114.617046) (xy 201.363104 -114.566411) (xy 201.346935 -114.51284) (xy 201.338763 -114.457483)
			(xy 201.338763 -114.401526) (xy 201.346934 -114.346168) (xy 201.363101 -114.292597) (xy 201.386917 -114.241961)
			(xy 201.417873 -114.195346) (xy 201.455305 -114.153751) (xy 201.498409 -114.118068) (xy 201.546261 -114.089062)
			(xy 201.597837 -114.067355) (xy 201.652029 -114.053413) (xy 201.67981 -114.050064) (xy 201.681842 -114.04981)
			(xy 201.688192 -114.049302) (xy 201.688446 -114.049302) (xy 201.712068 -114.038126) (xy 201.716155 -114.036066)
			(xy 201.723567 -114.030698) (xy 201.7268 -114.027458) (xy 201.741532 -114.012218) (xy 201.748009 -114.004865)
			(xy 201.755313 -113.986702) (xy 201.755756 -113.976912) (xy 201.755756 -107.075732) (xy 201.753724 -107.061762)
			(xy 201.751817 -107.055654) (xy 201.745391 -107.044594) (xy 201.741024 -107.039918) (xy 199.098408 -104.397302)
			(xy 198.482712 -103.782114) (xy 198.459767 -103.758559) (xy 198.41875 -103.707159) (xy 198.38375 -103.651487)
			(xy 198.355207 -103.592245) (xy 198.333481 -103.530177) (xy 198.318845 -103.466067) (xy 198.311485 -103.40072)
			(xy 198.311008 -103.36784) (xy 198.311008 -86.733888) (xy 198.310532 -86.723921) (xy 198.302959 -86.705482)
			(xy 198.296276 -86.698074) (xy 198.1073 -86.509098) (xy 196.674994 -85.076538) (xy 196.669143 -85.071234)
			(xy 196.655049 -85.064129) (xy 196.647308 -85.062568) (xy 196.639434 -85.06206) (xy 196.129148 -85.06206)
			(xy 196.095057 -85.061586) (xy 196.027336 -85.053676) (xy 195.960992 -85.037957) (xy 195.896921 -85.014642)
			(xy 195.83599 -84.984045) (xy 195.779023 -84.946582) (xy 195.726791 -84.902758) (xy 195.680001 -84.853167)
			(xy 195.639284 -84.798479) (xy 195.605191 -84.739433) (xy 195.578185 -84.676828) (xy 195.558629 -84.611511)
			(xy 195.546789 -84.544366) (xy 195.542824 -84.4763) (xy 195.546789 -84.408234) (xy 195.558629 -84.341089)
			(xy 195.578185 -84.275772) (xy 195.605191 -84.213167) (xy 195.639284 -84.154121) (xy 195.680001 -84.099433)
			(xy 195.726791 -84.049842) (xy 195.779023 -84.006018) (xy 195.83599 -83.968555) (xy 195.896921 -83.937958)
			(xy 195.960992 -83.914643) (xy 196.027336 -83.898924) (xy 196.095057 -83.891014) (xy 196.129148 -83.890612)
			(xy 196.90334 -83.890612) (xy 196.936196 -83.891052) (xy 197.001495 -83.898403) (xy 197.06556 -83.913019)
			(xy 197.127586 -83.934716) (xy 197.131998 -83.93684) (xy 205.22057 -83.93684) (xy 205.22057 -83.936586)
			(xy 205.221056 -83.909335) (xy 205.228812 -83.855387) (xy 205.244167 -83.803092) (xy 205.266809 -83.753515)
			(xy 205.296275 -83.707665) (xy 205.331966 -83.666474) (xy 205.373157 -83.630783) (xy 205.419007 -83.601317)
			(xy 205.468584 -83.578675) (xy 205.520879 -83.56332) (xy 205.574827 -83.555564) (xy 205.629329 -83.555564)
			(xy 205.683277 -83.56332) (xy 205.735572 -83.578675) (xy 205.785149 -83.601317) (xy 205.830999 -83.630783)
			(xy 205.87219 -83.666474) (xy 205.907881 -83.707665) (xy 205.937347 -83.753515) (xy 205.959989 -83.803092)
			(xy 205.975344 -83.855387) (xy 205.9831 -83.909335) (xy 205.983586 -83.936586) (xy 205.98313 -83.963925)
			(xy 205.975343 -84.018044) (xy 205.95991 -84.070498) (xy 205.937149 -84.120212) (xy 205.907526 -84.166168)
			(xy 205.871646 -84.207426) (xy 205.851252 -84.225638) (xy 205.842616 -84.23275) (xy 205.833472 -84.253324)
			(xy 205.834488 -84.353654) (xy 205.84414 -84.373466) (xy 205.85303 -84.380832) (xy 205.874382 -84.399018)
			(xy 205.911993 -84.440622) (xy 205.943101 -84.487289) (xy 205.967035 -84.538011) (xy 205.983278 -84.591693)
			(xy 205.99148 -84.647175) (xy 205.991968 -84.675218) (xy 205.991968 -84.675472) (xy 205.991482 -84.702723)
			(xy 205.983726 -84.756671) (xy 205.968371 -84.808966) (xy 205.945729 -84.858543) (xy 205.916263 -84.904393)
			(xy 205.880572 -84.945584) (xy 205.839381 -84.981275) (xy 205.793531 -85.010741) (xy 205.743954 -85.033383)
			(xy 205.691659 -85.048738) (xy 205.637711 -85.056494) (xy 205.583209 -85.056494) (xy 205.529261 -85.048738)
			(xy 205.476966 -85.033383) (xy 205.427389 -85.010741) (xy 205.381539 -84.981275) (xy 205.340348 -84.945584)
			(xy 205.304657 -84.904393) (xy 205.275191 -84.858543) (xy 205.252549 -84.808966) (xy 205.237194 -84.756671)
			(xy 205.229438 -84.702723) (xy 205.228952 -84.675472) (xy 205.2294 -84.648133) (xy 205.237192 -84.594015)
			(xy 205.252628 -84.541562) (xy 205.27539 -84.491848) (xy 205.305014 -84.445892) (xy 205.340893 -84.404633)
			(xy 205.361286 -84.38642) (xy 205.369922 -84.379308) (xy 205.379066 -84.358734) (xy 205.37805 -84.258404)
			(xy 205.368398 -84.238592) (xy 205.359508 -84.231226) (xy 205.338172 -84.213024) (xy 205.300562 -84.171421)
			(xy 205.269454 -84.124757) (xy 205.245517 -84.074038) (xy 205.22927 -84.02036) (xy 205.221062 -83.964881)
			(xy 205.22057 -83.93684) (xy 197.131998 -83.93684) (xy 197.186793 -83.963221) (xy 197.242436 -83.998177)
			(xy 197.293815 -84.039142) (xy 197.31736 -84.062062) (xy 197.930848 -84.675472) (xy 202.825348 -84.675472)
			(xy 202.829419 -84.61985) (xy 202.841545 -84.565413) (xy 202.861468 -84.513322) (xy 202.888764 -84.464687)
			(xy 202.92285 -84.420544) (xy 202.962999 -84.381835) (xy 203.008357 -84.349384) (xy 203.057957 -84.323883)
			(xy 203.110741 -84.305876) (xy 203.165584 -84.295746) (xy 203.221318 -84.293709) (xy 203.276755 -84.299809)
			(xy 203.330712 -84.313915) (xy 203.382041 -84.335727) (xy 203.429647 -84.364781) (xy 203.472515 -84.400456)
			(xy 203.509732 -84.441993) (xy 203.540505 -84.488506) (xy 203.564177 -84.539003) (xy 203.580245 -84.59241)
			(xy 203.588365 -84.647586) (xy 203.588874 -84.675472) (xy 203.588365 -84.703358) (xy 203.580245 -84.758534)
			(xy 203.564177 -84.811941) (xy 203.540505 -84.862438) (xy 203.509732 -84.908951) (xy 203.472515 -84.950488)
			(xy 203.429647 -84.986163) (xy 203.382041 -85.015217) (xy 203.330712 -85.037029) (xy 203.276755 -85.051135)
			(xy 203.221318 -85.057235) (xy 203.165584 -85.055198) (xy 203.110741 -85.045068) (xy 203.057957 -85.027061)
			(xy 203.008357 -85.00156) (xy 202.962999 -84.969109) (xy 202.92285 -84.9304) (xy 202.888764 -84.886257)
			(xy 202.861468 -84.837622) (xy 202.841545 -84.785531) (xy 202.829419 -84.731094) (xy 202.825348 -84.675472)
			(xy 197.930848 -84.675472) (xy 198.946978 -85.691472) (xy 202.857352 -85.691472) (xy 202.861423 -85.63585)
			(xy 202.873549 -85.581413) (xy 202.893472 -85.529322) (xy 202.920768 -85.480687) (xy 202.954854 -85.436544)
			(xy 202.995003 -85.397835) (xy 203.040361 -85.365384) (xy 203.089961 -85.339883) (xy 203.142745 -85.321876)
			(xy 203.197588 -85.311746) (xy 203.253322 -85.309709) (xy 203.308759 -85.315809) (xy 203.362716 -85.329915)
			(xy 203.414045 -85.351727) (xy 203.461651 -85.380781) (xy 203.504519 -85.416456) (xy 203.541736 -85.457993)
			(xy 203.572509 -85.504506) (xy 203.596181 -85.555003) (xy 203.612249 -85.60841) (xy 203.620369 -85.663586)
			(xy 203.620878 -85.691472) (xy 203.620369 -85.719358) (xy 203.612249 -85.774534) (xy 203.596181 -85.827941)
			(xy 203.572509 -85.878438) (xy 203.541736 -85.924951) (xy 203.504519 -85.966488) (xy 203.461651 -86.002163)
			(xy 203.414045 -86.031217) (xy 203.362716 -86.053029) (xy 203.308759 -86.067135) (xy 203.253322 -86.073235)
			(xy 203.197588 -86.071198) (xy 203.142745 -86.061068) (xy 203.089961 -86.043061) (xy 203.040361 -86.01756)
			(xy 202.995003 -85.985109) (xy 202.954854 -85.9464) (xy 202.920768 -85.902257) (xy 202.893472 -85.853622)
			(xy 202.873549 -85.801531) (xy 202.861423 -85.747094) (xy 202.857352 -85.691472) (xy 198.946978 -85.691472)
			(xy 199.31126 -86.055708) (xy 199.334209 -86.079261) (xy 199.375235 -86.130659) (xy 199.410244 -86.186329)
			(xy 199.438797 -86.245571) (xy 199.460532 -86.307639) (xy 199.475177 -86.371751) (xy 199.482546 -86.4371)
			(xy 199.482964 -86.469982) (xy 199.482964 -88.408764) (xy 208.564986 -88.408764) (xy 208.569057 -88.353142)
			(xy 208.581183 -88.298705) (xy 208.601106 -88.246614) (xy 208.628402 -88.197979) (xy 208.662488 -88.153836)
			(xy 208.702637 -88.115127) (xy 208.747995 -88.082676) (xy 208.797595 -88.057175) (xy 208.850379 -88.039168)
			(xy 208.905222 -88.029038) (xy 208.960956 -88.027001) (xy 209.016393 -88.033101) (xy 209.07035 -88.047207)
			(xy 209.121679 -88.069019) (xy 209.169285 -88.098073) (xy 209.212153 -88.133748) (xy 209.24937 -88.175285)
			(xy 209.280143 -88.221798) (xy 209.303815 -88.272295) (xy 209.319883 -88.325702) (xy 209.328003 -88.380878)
			(xy 209.328512 -88.408764) (xy 209.328003 -88.43665) (xy 209.319883 -88.491826) (xy 209.303815 -88.545233)
			(xy 209.280143 -88.59573) (xy 209.24937 -88.642243) (xy 209.212153 -88.68378) (xy 209.169285 -88.719455)
			(xy 209.121679 -88.748509) (xy 209.07035 -88.770321) (xy 209.016393 -88.784427) (xy 208.960956 -88.790527)
			(xy 208.905222 -88.78849) (xy 208.850379 -88.77836) (xy 208.797595 -88.760353) (xy 208.747995 -88.734852)
			(xy 208.702637 -88.702401) (xy 208.662488 -88.663692) (xy 208.628402 -88.619549) (xy 208.601106 -88.570914)
			(xy 208.581183 -88.518823) (xy 208.569057 -88.464386) (xy 208.564986 -88.408764) (xy 199.482964 -88.408764)
			(xy 199.482964 -88.993472) (xy 202.091796 -88.993472) (xy 202.095867 -88.93785) (xy 202.107993 -88.883413)
			(xy 202.127916 -88.831322) (xy 202.155212 -88.782687) (xy 202.189298 -88.738544) (xy 202.229447 -88.699835)
			(xy 202.274805 -88.667384) (xy 202.324405 -88.641883) (xy 202.377189 -88.623876) (xy 202.432032 -88.613746)
			(xy 202.487766 -88.611709) (xy 202.543203 -88.617809) (xy 202.59716 -88.631915) (xy 202.648489 -88.653727)
			(xy 202.696095 -88.682781) (xy 202.738963 -88.718456) (xy 202.77618 -88.759993) (xy 202.806953 -88.806506)
			(xy 202.830625 -88.857003) (xy 202.846693 -88.91041) (xy 202.854813 -88.965586) (xy 202.855322 -88.993472)
			(xy 202.854813 -89.021358) (xy 202.846693 -89.076534) (xy 202.830625 -89.129941) (xy 202.806953 -89.180438)
			(xy 202.77618 -89.226951) (xy 202.738963 -89.268488) (xy 202.696095 -89.304163) (xy 202.648489 -89.333217)
			(xy 202.59716 -89.355029) (xy 202.543203 -89.369135) (xy 202.487766 -89.375235) (xy 202.432032 -89.373198)
			(xy 202.377189 -89.363068) (xy 202.324405 -89.345061) (xy 202.274805 -89.31956) (xy 202.229447 -89.287109)
			(xy 202.189298 -89.2484) (xy 202.155212 -89.204257) (xy 202.127916 -89.155622) (xy 202.107993 -89.103531)
			(xy 202.095867 -89.049094) (xy 202.091796 -88.993472) (xy 199.482964 -88.993472) (xy 199.482964 -92.6338)
			(xy 199.48339 -92.642892) (xy 199.489839 -92.659898) (xy 199.501819 -92.673583) (xy 199.509634 -92.67825)
			(xy 199.514714 -92.680282) (xy 199.521746 -92.683005) (xy 199.536739 -92.684562) (xy 199.544178 -92.68333)
			(xy 199.550782 -92.68206) (xy 199.56399 -92.674948) (xy 201.670412 -90.568526) (xy 201.676762 -90.557858)
			(xy 201.67854 -90.552016) (xy 201.686985 -90.526447) (xy 201.71006 -90.477795) (xy 201.739744 -90.432868)
			(xy 201.775446 -90.392558) (xy 201.816459 -90.357667) (xy 201.861969 -90.328885) (xy 201.911072 -90.306784)
			(xy 201.962793 -90.291804) (xy 202.016106 -90.28424) (xy 202.04303 -90.283792) (xy 202.07028 -90.28428)
			(xy 202.124224 -90.29204) (xy 202.176515 -90.307398) (xy 202.226089 -90.33004) (xy 202.271936 -90.359507)
			(xy 202.313122 -90.395199) (xy 202.348811 -90.436388) (xy 202.378274 -90.482237) (xy 202.400913 -90.531813)
			(xy 202.416267 -90.584105) (xy 202.424022 -90.63805) (xy 202.424538 -90.6653) (xy 202.424792 -90.6653)
			(xy 202.424336 -90.692237) (xy 202.416772 -90.745577) (xy 202.401782 -90.797324) (xy 202.379662 -90.846447)
			(xy 202.350853 -90.891971) (xy 202.315927 -90.93299) (xy 202.275579 -90.96869) (xy 202.230611 -90.998359)
			(xy 202.181917 -91.021409) (xy 202.156314 -91.02979) (xy 202.15606 -91.02979) (xy 202.150225 -91.0318)
			(xy 202.139689 -91.038221) (xy 202.135232 -91.04249) (xy 199.928988 -93.24848) (xy 199.924293 -93.253493)
			(xy 199.917599 -93.265479) (xy 199.91578 -93.272102) (xy 199.914256 -93.284294) (xy 199.914256 -98.766863)
			(xy 206.090008 -98.766863) (xy 206.090008 -98.633301) (xy 206.098072 -98.499983) (xy 206.114172 -98.367395)
			(xy 206.138247 -98.236021) (xy 206.17021 -98.10634) (xy 206.209945 -97.978826) (xy 206.257307 -97.853943)
			(xy 206.312122 -97.732148) (xy 206.374192 -97.613885) (xy 206.443288 -97.499586) (xy 206.51916 -97.389666)
			(xy 206.60153 -97.284529) (xy 206.690098 -97.184556) (xy 206.78454 -97.090114) (xy 206.884513 -97.001546)
			(xy 206.98965 -96.919176) (xy 207.09957 -96.843304) (xy 207.213869 -96.774208) (xy 207.332132 -96.712138)
			(xy 207.453927 -96.657323) (xy 207.57881 -96.609961) (xy 207.706324 -96.570226) (xy 207.836005 -96.538263)
			(xy 207.967379 -96.514188) (xy 208.099967 -96.498088) (xy 208.233285 -96.490024) (xy 208.366847 -96.490024)
			(xy 208.500165 -96.498088) (xy 208.632753 -96.514188) (xy 208.764127 -96.538263) (xy 208.893808 -96.570226)
			(xy 209.021322 -96.609961) (xy 209.146205 -96.657323) (xy 209.268 -96.712138) (xy 209.386263 -96.774208)
			(xy 209.500562 -96.843304) (xy 209.610482 -96.919176) (xy 209.715619 -97.001546) (xy 209.815592 -97.090114)
			(xy 209.910034 -97.184556) (xy 209.998602 -97.284529) (xy 210.080972 -97.389666) (xy 210.156844 -97.499586)
			(xy 210.22594 -97.613885) (xy 210.28801 -97.732148) (xy 210.342825 -97.853943) (xy 210.390187 -97.978826)
			(xy 210.429922 -98.10634) (xy 210.461885 -98.236021) (xy 210.48596 -98.367395) (xy 210.50206 -98.499983)
			(xy 210.510124 -98.633301) (xy 210.510628 -98.700082) (xy 210.510124 -98.766863) (xy 210.50206 -98.900181)
			(xy 210.48596 -99.032769) (xy 210.461885 -99.164143) (xy 210.429922 -99.293824) (xy 210.390187 -99.421338)
			(xy 210.342825 -99.546221) (xy 210.28801 -99.668016) (xy 210.22594 -99.786279) (xy 210.156844 -99.900578)
			(xy 210.080972 -100.010498) (xy 209.998602 -100.115635) (xy 209.910034 -100.215608) (xy 209.815592 -100.31005)
			(xy 209.715619 -100.398618) (xy 209.610482 -100.480988) (xy 209.500562 -100.55686) (xy 209.386263 -100.625956)
			(xy 209.268 -100.688026) (xy 209.146205 -100.742841) (xy 209.021322 -100.790203) (xy 208.893808 -100.829938)
			(xy 208.764127 -100.861901) (xy 208.632753 -100.885976) (xy 208.500165 -100.902076) (xy 208.366847 -100.91014)
			(xy 208.233285 -100.91014) (xy 208.099967 -100.902076) (xy 207.967379 -100.885976) (xy 207.836005 -100.861901)
			(xy 207.706324 -100.829938) (xy 207.57881 -100.790203) (xy 207.453927 -100.742841) (xy 207.332132 -100.688026)
			(xy 207.213869 -100.625956) (xy 207.09957 -100.55686) (xy 206.98965 -100.480988) (xy 206.884513 -100.398618)
			(xy 206.78454 -100.31005) (xy 206.690098 -100.215608) (xy 206.60153 -100.115635) (xy 206.51916 -100.010498)
			(xy 206.443288 -99.900578) (xy 206.374192 -99.786279) (xy 206.312122 -99.668016) (xy 206.257307 -99.546221)
			(xy 206.209945 -99.421338) (xy 206.17021 -99.293824) (xy 206.138247 -99.164143) (xy 206.114172 -99.032769)
			(xy 206.098072 -98.900181) (xy 206.090008 -98.766863) (xy 199.914256 -98.766863) (xy 199.914256 -102.872794)
			(xy 200.171556 -102.872794) (xy 200.175627 -102.817172) (xy 200.187753 -102.762735) (xy 200.207676 -102.710644)
			(xy 200.234972 -102.662009) (xy 200.269058 -102.617866) (xy 200.309207 -102.579157) (xy 200.354565 -102.546706)
			(xy 200.404165 -102.521205) (xy 200.456949 -102.503198) (xy 200.511792 -102.493068) (xy 200.567526 -102.491031)
			(xy 200.622963 -102.497131) (xy 200.67692 -102.511237) (xy 200.728249 -102.533049) (xy 200.775855 -102.562103)
			(xy 200.818723 -102.597778) (xy 200.85594 -102.639315) (xy 200.886713 -102.685828) (xy 200.910385 -102.736325)
			(xy 200.926453 -102.789732) (xy 200.934573 -102.844908) (xy 200.935082 -102.872794) (xy 200.934573 -102.90068)
			(xy 200.926453 -102.955856) (xy 200.910385 -103.009263) (xy 200.886713 -103.05976) (xy 200.85594 -103.106273)
			(xy 200.818723 -103.14781) (xy 200.775855 -103.183485) (xy 200.728249 -103.212539) (xy 200.67692 -103.234351)
			(xy 200.622963 -103.248457) (xy 200.567526 -103.254557) (xy 200.511792 -103.25252) (xy 200.456949 -103.24239)
			(xy 200.404165 -103.224383) (xy 200.354565 -103.198882) (xy 200.309207 -103.166431) (xy 200.269058 -103.127722)
			(xy 200.234972 -103.083579) (xy 200.207676 -103.034944) (xy 200.187753 -102.982853) (xy 200.175627 -102.928416)
			(xy 200.171556 -102.872794) (xy 199.914256 -102.872794) (xy 199.914256 -102.940358) (xy 199.915272 -102.95001)
			(xy 199.916896 -102.957256) (xy 199.923734 -102.970429) (xy 199.928734 -102.975918) (xy 201.10069 -104.14762)
			(xy 201.107661 -104.153014) (xy 201.124174 -104.159142) (xy 201.141786 -104.159323) (xy 201.15022 -104.156764)
			(xy 201.155808 -104.154478) (xy 201.241914 -104.112314) (xy 201.248948 -104.108574) (xy 201.260466 -104.097581)
			(xy 201.26452 -104.090724) (xy 201.267953 -104.083686) (xy 201.2708 -104.068297) (xy 201.270108 -104.060498)
			(xy 201.270108 -104.060244) (xy 201.268788 -104.048605) (xy 201.26739 -104.025221) (xy 201.267314 -104.013508)
			(xy 201.2678 -103.986259) (xy 201.275554 -103.932314) (xy 201.290907 -103.880023) (xy 201.313546 -103.830448)
			(xy 201.343009 -103.7846) (xy 201.378697 -103.743412) (xy 201.419883 -103.707721) (xy 201.46573 -103.678256)
			(xy 201.515303 -103.655615) (xy 201.567594 -103.640259) (xy 201.621538 -103.632501) (xy 201.676037 -103.632499)
			(xy 201.729981 -103.640253) (xy 201.782273 -103.655606) (xy 201.831848 -103.678244) (xy 201.877696 -103.707706)
			(xy 201.918885 -103.743394) (xy 201.954576 -103.78458) (xy 201.984042 -103.830426) (xy 202.006684 -103.879999)
			(xy 202.02204 -103.932289) (xy 202.029799 -103.986233) (xy 202.029801 -104.040732) (xy 202.022048 -104.094677)
			(xy 202.006696 -104.146969) (xy 201.984059 -104.196544) (xy 201.954597 -104.242392) (xy 201.91891 -104.283582)
			(xy 201.877724 -104.319273) (xy 201.831878 -104.34874) (xy 201.782306 -104.371382) (xy 201.730015 -104.386739)
			(xy 201.676071 -104.394498) (xy 201.648822 -104.395016) (xy 201.637108 -104.394954) (xy 201.613723 -104.393559)
			(xy 201.602086 -104.392222) (xy 201.601832 -104.392222) (xy 201.594033 -104.39153) (xy 201.578646 -104.394381)
			(xy 201.571606 -104.39781) (xy 201.564727 -104.401836) (xy 201.553729 -104.413363) (xy 201.550016 -104.420416)
			(xy 201.507852 -104.506522) (xy 201.50582 -104.511856) (xy 201.503106 -104.520299) (xy 201.503128 -104.538023)
			(xy 201.509241 -104.554659) (xy 201.51471 -104.56164) (xy 203.035408 -106.082338) (xy 203.036424 -106.083354)
			(xy 203.049552 -106.096882) (xy 203.072977 -106.126418) (xy 203.08316 -106.142282) (xy 203.086208 -106.147362)
			(xy 203.258166 -106.31932) (xy 203.275723 -106.337534) (xy 203.305463 -106.378457) (xy 203.32843 -106.42353)
			(xy 203.344058 -106.471643) (xy 203.351961 -106.52161) (xy 203.3524 -106.546904) (xy 203.3524 -110.631732)
			(xy 209.194654 -110.631732) (xy 209.195149 -110.602992) (xy 209.20378 -110.546164) (xy 209.220838 -110.491273)
			(xy 209.245935 -110.439562) (xy 209.278505 -110.392201) (xy 209.297778 -110.370874) (xy 209.304382 -110.364016)
			(xy 209.311494 -110.345982) (xy 209.311494 -110.257082) (xy 209.304382 -110.239048) (xy 209.297778 -110.23219)
			(xy 209.278541 -110.210835) (xy 209.245979 -110.163476) (xy 209.220888 -110.111768) (xy 209.203838 -110.056882)
			(xy 209.195214 -110.00006) (xy 209.19521 -109.942587) (xy 209.203828 -109.885763) (xy 209.220871 -109.830875)
			(xy 209.245955 -109.779165) (xy 209.278512 -109.731802) (xy 209.297778 -109.710474) (xy 209.304382 -109.703616)
			(xy 209.311494 -109.685582) (xy 209.311494 -109.596682) (xy 209.304382 -109.578648) (xy 209.297778 -109.57179)
			(xy 209.278529 -109.550444) (xy 209.245958 -109.503088) (xy 209.220861 -109.451381) (xy 209.203805 -109.396494)
			(xy 209.195177 -109.33967) (xy 209.194654 -109.310932) (xy 209.19514 -109.283681) (xy 209.202896 -109.229733)
			(xy 209.218251 -109.177438) (xy 209.240893 -109.127861) (xy 209.270359 -109.082011) (xy 209.30605 -109.04082)
			(xy 209.347241 -109.005129) (xy 209.393091 -108.975663) (xy 209.442668 -108.953021) (xy 209.494963 -108.937666)
			(xy 209.548911 -108.92991) (xy 209.603413 -108.92991) (xy 209.657361 -108.937666) (xy 209.709656 -108.953021)
			(xy 209.759233 -108.975663) (xy 209.805083 -109.005129) (xy 209.846274 -109.04082) (xy 209.881965 -109.082011)
			(xy 209.911431 -109.127861) (xy 209.934073 -109.177438) (xy 209.949428 -109.229733) (xy 209.957184 -109.283681)
			(xy 209.95767 -109.310932) (xy 209.957147 -109.339671) (xy 209.948521 -109.396497) (xy 209.93147 -109.451387)
			(xy 209.906379 -109.503099) (xy 209.873815 -109.550462) (xy 209.854546 -109.57179) (xy 209.847942 -109.578648)
			(xy 209.84083 -109.596682) (xy 209.84083 -109.685582) (xy 209.847942 -109.703616) (xy 209.854546 -109.710474)
			(xy 209.87385 -109.731773) (xy 209.906417 -109.779139) (xy 209.931508 -109.830855) (xy 209.948558 -109.885751)
			(xy 209.957178 -109.942582) (xy 209.957174 -110.000064) (xy 209.948547 -110.056895) (xy 209.931491 -110.111788)
			(xy 209.906393 -110.163501) (xy 209.873821 -110.210864) (xy 209.854546 -110.23219) (xy 209.847942 -110.239048)
			(xy 209.84083 -110.257082) (xy 209.84083 -110.345982) (xy 209.847942 -110.364016) (xy 209.854546 -110.370874)
			(xy 209.873829 -110.39219) (xy 209.906394 -110.439555) (xy 209.931485 -110.491269) (xy 209.948532 -110.546163)
			(xy 209.957151 -110.602992) (xy 209.95767 -110.631732) (xy 209.957184 -110.658983) (xy 209.956428 -110.664244)
			(xy 210.788504 -110.664244) (xy 210.788993 -110.635504) (xy 210.797624 -110.578675) (xy 210.814682 -110.523784)
			(xy 210.839781 -110.472072) (xy 210.872354 -110.424712) (xy 210.891628 -110.403386) (xy 210.898232 -110.396528)
			(xy 210.905344 -110.378494) (xy 210.905344 -110.289594) (xy 210.898232 -110.27156) (xy 210.891628 -110.264702)
			(xy 210.872401 -110.243337) (xy 210.839834 -110.195982) (xy 210.814739 -110.144276) (xy 210.797686 -110.089391)
			(xy 210.789059 -110.032569) (xy 210.789054 -109.975095) (xy 210.797671 -109.918272) (xy 210.814716 -109.863384)
			(xy 210.839801 -109.811674) (xy 210.87236 -109.764313) (xy 210.891628 -109.742986) (xy 210.898232 -109.736128)
			(xy 210.905344 -109.718094) (xy 210.905344 -109.629194) (xy 210.898232 -109.61116) (xy 210.891628 -109.604302)
			(xy 210.872329 -109.582999) (xy 210.839767 -109.535631) (xy 210.81468 -109.483913) (xy 210.797636 -109.429017)
			(xy 210.789021 -109.372185) (xy 210.788504 -109.343444) (xy 210.78899 -109.316193) (xy 210.796746 -109.262245)
			(xy 210.812101 -109.20995) (xy 210.834743 -109.160373) (xy 210.864209 -109.114523) (xy 210.8999 -109.073332)
			(xy 210.941091 -109.037641) (xy 210.986941 -109.008175) (xy 211.036518 -108.985533) (xy 211.088813 -108.970178)
			(xy 211.142761 -108.962422) (xy 211.197263 -108.962422) (xy 211.251211 -108.970178) (xy 211.303506 -108.985533)
			(xy 211.353083 -109.008175) (xy 211.398933 -109.037641) (xy 211.440124 -109.073332) (xy 211.475815 -109.114523)
			(xy 211.505281 -109.160373) (xy 211.527923 -109.20995) (xy 211.543278 -109.262245) (xy 211.551034 -109.316193)
			(xy 211.55152 -109.343444) (xy 211.551018 -109.372184) (xy 211.542389 -109.429012) (xy 211.525334 -109.483902)
			(xy 211.500238 -109.535614) (xy 211.467668 -109.582976) (xy 211.448396 -109.604302) (xy 211.441792 -109.61116)
			(xy 211.43468 -109.629194) (xy 211.43468 -109.718094) (xy 211.441792 -109.736128) (xy 211.448396 -109.742986)
			(xy 211.46771 -109.764275) (xy 211.500272 -109.811645) (xy 211.52536 -109.863363) (xy 211.542405 -109.918259)
			(xy 211.551023 -109.975091) (xy 211.551018 -110.032573) (xy 211.542391 -110.089404) (xy 211.525336 -110.144297)
			(xy 211.500239 -110.196011) (xy 211.467669 -110.243375) (xy 211.448396 -110.264702) (xy 211.441792 -110.27156)
			(xy 211.43468 -110.289594) (xy 211.43468 -110.378494) (xy 211.441792 -110.396528) (xy 211.448396 -110.403386)
			(xy 211.467676 -110.424705) (xy 211.500244 -110.472068) (xy 211.525335 -110.523782) (xy 211.542383 -110.578675)
			(xy 211.551002 -110.635504) (xy 211.55152 -110.664244) (xy 211.551034 -110.691495) (xy 211.543278 -110.745443)
			(xy 211.527923 -110.797738) (xy 211.505281 -110.847315) (xy 211.475815 -110.893165) (xy 211.440124 -110.934356)
			(xy 211.398933 -110.970047) (xy 211.353083 -110.999513) (xy 211.303506 -111.022155) (xy 211.251211 -111.03751)
			(xy 211.197263 -111.045266) (xy 211.142761 -111.045266) (xy 211.088813 -111.03751) (xy 211.036518 -111.022155)
			(xy 210.986941 -110.999513) (xy 210.941091 -110.970047) (xy 210.8999 -110.934356) (xy 210.864209 -110.893165)
			(xy 210.834743 -110.847315) (xy 210.812101 -110.797738) (xy 210.796746 -110.745443) (xy 210.78899 -110.691495)
			(xy 210.788504 -110.664244) (xy 209.956428 -110.664244) (xy 209.949428 -110.712931) (xy 209.934073 -110.765226)
			(xy 209.911431 -110.814803) (xy 209.881965 -110.860653) (xy 209.846274 -110.901844) (xy 209.805083 -110.937535)
			(xy 209.759233 -110.967001) (xy 209.709656 -110.989643) (xy 209.657361 -111.004998) (xy 209.603413 -111.012754)
			(xy 209.548911 -111.012754) (xy 209.494963 -111.004998) (xy 209.442668 -110.989643) (xy 209.393091 -110.967001)
			(xy 209.347241 -110.937535) (xy 209.30605 -110.901844) (xy 209.270359 -110.860653) (xy 209.240893 -110.814803)
			(xy 209.218251 -110.765226) (xy 209.202896 -110.712931) (xy 209.19514 -110.658983) (xy 209.194654 -110.631732)
			(xy 203.3524 -110.631732) (xy 203.3524 -112.560653) (xy 205.549185 -112.560653) (xy 205.549185 -112.506147)
			(xy 205.556943 -112.452196) (xy 205.5723 -112.399899) (xy 205.594944 -112.35032) (xy 205.624414 -112.304468)
			(xy 205.66011 -112.263277) (xy 205.701305 -112.227587) (xy 205.74716 -112.198122) (xy 205.796742 -112.175484)
			(xy 205.849041 -112.160133) (xy 205.902993 -112.152382) (xy 205.930246 -112.151922) (xy 205.9305 -112.151922)
			(xy 205.95846 -112.152404) (xy 206.013778 -112.160584) (xy 206.067304 -112.17677) (xy 206.092806 -112.188244)
			(xy 206.104265 -112.193019) (xy 206.12904 -112.191947) (xy 206.14005 -112.186212) (xy 206.21244 -112.144302)
			(xy 206.222682 -112.137528) (xy 206.235819 -112.116829) (xy 206.237586 -112.104678) (xy 206.237586 -112.10417)
			(xy 206.240354 -112.075838) (xy 206.253235 -112.020389) (xy 206.274214 -111.967471) (xy 206.302826 -111.918258)
			(xy 206.338433 -111.873844) (xy 206.380246 -111.835216) (xy 206.427336 -111.803231) (xy 206.478657 -111.7786)
			(xy 206.533068 -111.761871) (xy 206.589361 -111.753414) (xy 206.617824 -111.752888) (xy 206.647802 -111.753455)
			(xy 206.707019 -111.76285) (xy 206.764038 -111.78139) (xy 206.817456 -111.808618) (xy 206.865959 -111.843864)
			(xy 206.887572 -111.864648) (xy 206.887826 -111.864902) (xy 206.895317 -111.871548) (xy 206.913886 -111.878995)
			(xy 206.923894 -111.87938) (xy 207.007206 -111.878364) (xy 207.025748 -111.87049) (xy 207.03286 -111.86287)
			(xy 207.050958 -111.844577) (xy 207.09117 -111.812468) (xy 207.13533 -111.786052) (xy 207.182639 -111.765808)
			(xy 207.232238 -111.752102) (xy 207.283229 -111.745184) (xy 207.308958 -111.74476) (xy 207.336208 -111.745294)
			(xy 207.390155 -111.753045) (xy 207.44245 -111.768394) (xy 207.492028 -111.791029) (xy 207.537879 -111.82049)
			(xy 207.579072 -111.856176) (xy 207.614766 -111.897361) (xy 207.644235 -111.943207) (xy 207.66688 -111.992781)
			(xy 207.68224 -112.045073) (xy 207.69 -112.099018) (xy 207.690466 -112.126268) (xy 207.690035 -112.152714)
			(xy 207.682721 -112.205097) (xy 207.668242 -112.255968) (xy 207.646877 -112.304352) (xy 207.619034 -112.349322)
			(xy 207.585248 -112.390016) (xy 207.546165 -112.425653) (xy 207.524604 -112.440974) (xy 207.51593 -112.447449)
			(xy 207.504608 -112.46587) (xy 207.50276 -112.476534) (xy 207.49895 -112.508792) (xy 207.498044 -112.519483)
			(xy 207.504222 -112.540009) (xy 207.510888 -112.548416) (xy 207.52435 -112.564672) (xy 207.531976 -112.573458)
			(xy 207.552863 -112.58365) (xy 207.564482 -112.58423) (xy 207.644238 -112.58423) (xy 207.655875 -112.583723)
			(xy 207.676785 -112.573514) (xy 207.68437 -112.564672) (xy 207.702571 -112.542197) (xy 207.744589 -112.502463)
			(xy 207.792123 -112.469523) (xy 207.844082 -112.444134) (xy 207.899277 -112.426875) (xy 207.956445 -112.418143)
			(xy 207.98536 -112.417606) (xy 208.012616 -112.418038) (xy 208.066573 -112.425791) (xy 208.118878 -112.441144)
			(xy 208.168465 -112.463785) (xy 208.214325 -112.493253) (xy 208.255524 -112.528948) (xy 208.291223 -112.570143)
			(xy 208.320696 -112.616) (xy 208.343342 -112.665585) (xy 208.358701 -112.717888) (xy 208.366459 -112.771844)
			(xy 208.366459 -112.826356) (xy 208.358701 -112.880312) (xy 208.343342 -112.932615) (xy 208.320696 -112.9822)
			(xy 208.291223 -113.028057) (xy 208.255524 -113.069252) (xy 208.214325 -113.104947) (xy 208.168465 -113.134415)
			(xy 208.118878 -113.157056) (xy 208.066573 -113.172409) (xy 208.012616 -113.180162) (xy 207.98536 -113.180622)
			(xy 207.956443 -113.18009) (xy 207.899271 -113.171368) (xy 207.844072 -113.154115) (xy 207.792109 -113.128726)
			(xy 207.744575 -113.095783) (xy 207.702559 -113.056042) (xy 207.68437 -113.033556) (xy 207.676774 -113.024738)
			(xy 207.655864 -113.014562) (xy 207.644238 -113.013998) (xy 207.564482 -113.013998) (xy 207.552851 -113.014542)
			(xy 207.531941 -113.024727) (xy 207.52435 -113.033556) (xy 207.50612 -113.056006) (xy 207.464109 -113.095746)
			(xy 207.416583 -113.12869) (xy 207.364629 -113.154084) (xy 207.309438 -113.171347) (xy 207.252274 -113.180083)
			(xy 207.22336 -113.180622) (xy 207.196108 -113.180159) (xy 207.142161 -113.172398) (xy 207.089866 -113.157038)
			(xy 207.04029 -113.134394) (xy 206.99444 -113.104924) (xy 206.953251 -113.069231) (xy 206.91756 -113.028039)
			(xy 206.888094 -112.982187) (xy 206.865453 -112.932609) (xy 206.850097 -112.880314) (xy 206.842339 -112.826366)
			(xy 206.841852 -112.799114) (xy 206.842337 -112.77267) (xy 206.849641 -112.720289) (xy 206.864109 -112.669418)
			(xy 206.885465 -112.621034) (xy 206.9133 -112.576063) (xy 206.94708 -112.535369) (xy 206.986156 -112.49973)
			(xy 207.007714 -112.484408) (xy 207.016398 -112.477945) (xy 207.027714 -112.459515) (xy 207.029558 -112.448848)
			(xy 207.033622 -112.41659) (xy 207.034441 -112.405878) (xy 207.028135 -112.38536) (xy 207.02143 -112.376966)
			(xy 207.021176 -112.376712) (xy 207.013541 -112.368696) (xy 206.993377 -112.359614) (xy 206.982314 -112.359186)
			(xy 206.949802 -112.359694) (xy 206.938787 -112.360335) (xy 206.918897 -112.36984) (xy 206.911448 -112.377982)
			(xy 206.893221 -112.399159) (xy 206.851659 -112.436499) (xy 206.805096 -112.467377) (xy 206.754527 -112.491135)
			(xy 206.701033 -112.507262) (xy 206.64576 -112.515414) (xy 206.617824 -112.515904) (xy 206.61757 -112.515904)
			(xy 206.58961 -112.515431) (xy 206.534291 -112.507246) (xy 206.480765 -112.491058) (xy 206.455264 -112.479582)
			(xy 206.44381 -112.474794) (xy 206.419032 -112.475877) (xy 206.40802 -112.481614) (xy 206.33563 -112.523524)
			(xy 206.325391 -112.530303) (xy 206.312249 -112.550997) (xy 206.310484 -112.563148) (xy 206.310484 -112.563656)
			(xy 206.307683 -112.591985) (xy 206.294811 -112.647435) (xy 206.273839 -112.700356) (xy 206.245234 -112.749571)
			(xy 206.20963 -112.793987) (xy 206.16782 -112.832616) (xy 206.120732 -112.864602) (xy 206.069412 -112.889232)
			(xy 206.015001 -112.90596) (xy 205.958708 -112.914414) (xy 205.930246 -112.914938) (xy 205.902993 -112.914418)
			(xy 205.849041 -112.906667) (xy 205.796742 -112.891316) (xy 205.74716 -112.868678) (xy 205.701305 -112.839213)
			(xy 205.66011 -112.803523) (xy 205.624414 -112.762332) (xy 205.594944 -112.71648) (xy 205.5723 -112.666901)
			(xy 205.556943 -112.614604) (xy 205.549185 -112.560653) (xy 203.3524 -112.560653) (xy 203.3524 -113.489232)
			(xy 203.352872 -113.498574) (xy 203.35965 -113.515992) (xy 203.372194 -113.529847) (xy 203.38034 -113.534444)
			(xy 203.460858 -113.57483) (xy 203.471565 -113.57962) (xy 203.494993 -113.579865) (xy 203.505816 -113.575338)
			(xy 203.51242 -113.572036) (xy 203.51623 -113.569242) (xy 203.540942 -113.551842) (xy 203.594704 -113.524234)
			(xy 203.652139 -113.505428) (xy 203.711818 -113.495893) (xy 203.742036 -113.495328) (xy 203.742544 -113.495328)
			(xy 203.769791 -113.495817) (xy 203.823728 -113.503578) (xy 203.876013 -113.518936) (xy 203.92558 -113.541577)
			(xy 203.97142 -113.571042) (xy 204.012601 -113.60673) (xy 204.048285 -113.647915) (xy 204.077744 -113.693759)
			(xy 204.10038 -113.743328) (xy 204.115731 -113.795615) (xy 204.123026 -113.846356) (xy 205.461106 -113.846356)
			(xy 205.465177 -113.790734) (xy 205.477303 -113.736297) (xy 205.497226 -113.684206) (xy 205.524522 -113.635571)
			(xy 205.558608 -113.591428) (xy 205.598757 -113.552719) (xy 205.644115 -113.520268) (xy 205.693715 -113.494767)
			(xy 205.746499 -113.47676) (xy 205.801342 -113.46663) (xy 205.857076 -113.464593) (xy 205.912513 -113.470693)
			(xy 205.96647 -113.484799) (xy 206.017799 -113.506611) (xy 206.065405 -113.535665) (xy 206.108273 -113.57134)
			(xy 206.14549 -113.612877) (xy 206.176263 -113.65939) (xy 206.199935 -113.709887) (xy 206.216003 -113.763294)
			(xy 206.224123 -113.81847) (xy 206.224632 -113.846356) (xy 206.224123 -113.874242) (xy 206.216003 -113.929418)
			(xy 206.199935 -113.982825) (xy 206.176263 -114.033322) (xy 206.14549 -114.079835) (xy 206.108273 -114.121372)
			(xy 206.065405 -114.157047) (xy 206.017799 -114.186101) (xy 205.96647 -114.207913) (xy 205.912513 -114.222019)
			(xy 205.857076 -114.228119) (xy 205.801342 -114.226082) (xy 205.746499 -114.215952) (xy 205.693715 -114.197945)
			(xy 205.644115 -114.172444) (xy 205.598757 -114.139993) (xy 205.558608 -114.101284) (xy 205.524522 -114.057141)
			(xy 205.497226 -114.008506) (xy 205.477303 -113.956415) (xy 205.465177 -113.901978) (xy 205.461106 -113.846356)
			(xy 204.123026 -113.846356) (xy 204.123486 -113.849553) (xy 204.123486 -113.904047) (xy 204.115731 -113.957985)
			(xy 204.10038 -114.010272) (xy 204.077744 -114.059841) (xy 204.048285 -114.105685) (xy 204.012601 -114.14687)
			(xy 203.97142 -114.182558) (xy 203.92558 -114.212023) (xy 203.876013 -114.234664) (xy 203.823728 -114.250022)
			(xy 203.769791 -114.257783) (xy 203.742544 -114.258344) (xy 203.71201 -114.25774) (xy 203.651723 -114.248012)
			(xy 203.593752 -114.228812) (xy 203.539576 -114.200631) (xy 203.514706 -114.182906) (xy 203.512674 -114.181382)
			(xy 203.50724 -114.177992) (xy 203.495159 -114.173749) (xy 203.488798 -114.173) (xy 203.482194 -114.172492)
			(xy 203.475336 -114.173762) (xy 203.471781 -114.174484) (xy 203.4649 -114.176783) (xy 203.46162 -114.178334)
			(xy 203.426314 -114.196114) (xy 203.377292 -114.220752) (xy 203.374752 -114.222276) (xy 203.366108 -114.228691)
			(xy 203.354805 -114.246985) (xy 203.352908 -114.257582) (xy 203.352908 -114.25809) (xy 203.3524 -114.26444)
			(xy 203.3524 -114.308636) (xy 209.079082 -114.308636) (xy 209.083153 -114.253014) (xy 209.095279 -114.198577)
			(xy 209.115202 -114.146486) (xy 209.142498 -114.097851) (xy 209.176584 -114.053708) (xy 209.216733 -114.014999)
			(xy 209.262091 -113.982548) (xy 209.311691 -113.957047) (xy 209.364475 -113.93904) (xy 209.419318 -113.92891)
			(xy 209.475052 -113.926873) (xy 209.530489 -113.932973) (xy 209.584446 -113.947079) (xy 209.635775 -113.968891)
			(xy 209.683381 -113.997945) (xy 209.726249 -114.03362) (xy 209.763466 -114.075157) (xy 209.794239 -114.12167)
			(xy 209.817911 -114.172167) (xy 209.833979 -114.225574) (xy 209.842099 -114.28075) (xy 209.842608 -114.308636)
			(xy 209.842099 -114.336522) (xy 209.833979 -114.391698) (xy 209.817911 -114.445105) (xy 209.794239 -114.495602)
			(xy 209.763466 -114.542115) (xy 209.726249 -114.583652) (xy 209.683381 -114.619327) (xy 209.635775 -114.648381)
			(xy 209.584446 -114.670193) (xy 209.530489 -114.684299) (xy 209.475052 -114.690399) (xy 209.419318 -114.688362)
			(xy 209.364475 -114.678232) (xy 209.311691 -114.660225) (xy 209.262091 -114.634724) (xy 209.216733 -114.602273)
			(xy 209.176584 -114.563564) (xy 209.142498 -114.519421) (xy 209.115202 -114.470786) (xy 209.095279 -114.418695)
			(xy 209.083153 -114.364258) (xy 209.079082 -114.308636) (xy 203.3524 -114.308636) (xy 203.3524 -115.14582)
			(xy 205.473044 -115.14582) (xy 205.477115 -115.090198) (xy 205.489241 -115.035761) (xy 205.509164 -114.98367)
			(xy 205.53646 -114.935035) (xy 205.570546 -114.890892) (xy 205.610695 -114.852183) (xy 205.656053 -114.819732)
			(xy 205.705653 -114.794231) (xy 205.758437 -114.776224) (xy 205.81328 -114.766094) (xy 205.869014 -114.764057)
			(xy 205.924451 -114.770157) (xy 205.978408 -114.784263) (xy 206.029737 -114.806075) (xy 206.077343 -114.835129)
			(xy 206.120211 -114.870804) (xy 206.157428 -114.912341) (xy 206.188201 -114.958854) (xy 206.211873 -115.009351)
			(xy 206.227941 -115.062758) (xy 206.236061 -115.117934) (xy 206.23657 -115.14582) (xy 206.236061 -115.173706)
			(xy 206.227941 -115.228882) (xy 206.211873 -115.282289) (xy 206.188201 -115.332786) (xy 206.157428 -115.379299)
			(xy 206.120211 -115.420836) (xy 206.077343 -115.456511) (xy 206.029737 -115.485565) (xy 205.978408 -115.507377)
			(xy 205.924451 -115.521483) (xy 205.869014 -115.527583) (xy 205.81328 -115.525546) (xy 205.758437 -115.515416)
			(xy 205.705653 -115.497409) (xy 205.656053 -115.471908) (xy 205.610695 -115.439457) (xy 205.570546 -115.400748)
			(xy 205.53646 -115.356605) (xy 205.509164 -115.30797) (xy 205.489241 -115.255879) (xy 205.477115 -115.201442)
			(xy 205.473044 -115.14582) (xy 203.3524 -115.14582) (xy 203.3524 -115.866447) (xy 206.842418 -115.866447)
			(xy 206.842418 -115.811953) (xy 206.850173 -115.758015) (xy 206.865524 -115.705729) (xy 206.88816 -115.65616)
			(xy 206.917619 -115.610316) (xy 206.953303 -115.569131) (xy 206.994484 -115.533443) (xy 207.040324 -115.503979)
			(xy 207.089891 -115.481338) (xy 207.142176 -115.465981) (xy 207.196114 -115.458221) (xy 207.22336 -115.457732)
			(xy 207.252276 -115.458267) (xy 207.309447 -115.466991) (xy 207.364646 -115.484245) (xy 207.416609 -115.509633)
			(xy 207.464143 -115.542574) (xy 207.50616 -115.582313) (xy 207.52435 -115.604798) (xy 207.531989 -115.613572)
			(xy 207.552865 -115.623774) (xy 207.564482 -115.624356) (xy 207.644238 -115.624356) (xy 207.655873 -115.62384)
			(xy 207.676783 -115.613636) (xy 207.68437 -115.604798) (xy 207.702577 -115.582328) (xy 207.744594 -115.542592)
			(xy 207.792125 -115.509652) (xy 207.844083 -115.484261) (xy 207.899278 -115.467002) (xy 207.956445 -115.458269)
			(xy 207.98536 -115.457732) (xy 208.012618 -115.458112) (xy 208.066579 -115.465865) (xy 208.118887 -115.48122)
			(xy 208.168477 -115.503862) (xy 208.21434 -115.533332) (xy 208.255542 -115.56903) (xy 208.263867 -115.578636)
			(xy 209.079082 -115.578636) (xy 209.083153 -115.523014) (xy 209.095279 -115.468577) (xy 209.115202 -115.416486)
			(xy 209.142498 -115.367851) (xy 209.176584 -115.323708) (xy 209.216733 -115.284999) (xy 209.262091 -115.252548)
			(xy 209.311691 -115.227047) (xy 209.364475 -115.20904) (xy 209.419318 -115.19891) (xy 209.475052 -115.196873)
			(xy 209.530489 -115.202973) (xy 209.584446 -115.217079) (xy 209.635775 -115.238891) (xy 209.683381 -115.267945)
			(xy 209.726249 -115.30362) (xy 209.763466 -115.345157) (xy 209.794239 -115.39167) (xy 209.817911 -115.442167)
			(xy 209.833979 -115.495574) (xy 209.842099 -115.55075) (xy 209.842608 -115.578636) (xy 209.842099 -115.606522)
			(xy 209.833979 -115.661698) (xy 209.817911 -115.715105) (xy 209.794239 -115.765602) (xy 209.763466 -115.812115)
			(xy 209.726249 -115.853652) (xy 209.683381 -115.889327) (xy 209.635775 -115.918381) (xy 209.584446 -115.940193)
			(xy 209.530489 -115.954299) (xy 209.475052 -115.960399) (xy 209.419318 -115.958362) (xy 209.364475 -115.948232)
			(xy 209.311691 -115.930225) (xy 209.262091 -115.904724) (xy 209.216733 -115.872273) (xy 209.176584 -115.833564)
			(xy 209.142498 -115.789421) (xy 209.115202 -115.740786) (xy 209.095279 -115.688695) (xy 209.083153 -115.634258)
			(xy 209.079082 -115.578636) (xy 208.263867 -115.578636) (xy 208.291244 -115.610228) (xy 208.320719 -115.656088)
			(xy 208.343366 -115.705676) (xy 208.358726 -115.757982) (xy 208.366485 -115.811942) (xy 208.366485 -115.866458)
			(xy 208.358726 -115.920418) (xy 208.343366 -115.972724) (xy 208.320719 -116.022312) (xy 208.291244 -116.068172)
			(xy 208.255542 -116.10937) (xy 208.21434 -116.145068) (xy 208.168477 -116.174538) (xy 208.118887 -116.19718)
			(xy 208.066579 -116.212535) (xy 208.012618 -116.220288) (xy 207.98536 -116.220748) (xy 207.956444 -116.220207)
			(xy 207.899273 -116.211485) (xy 207.844073 -116.194233) (xy 207.792111 -116.168846) (xy 207.744577 -116.135905)
			(xy 207.70256 -116.096167) (xy 207.68437 -116.073682) (xy 207.676769 -116.064868) (xy 207.655864 -116.054689)
			(xy 207.644238 -116.054124) (xy 207.564482 -116.054124) (xy 207.552849 -116.054659) (xy 207.531939 -116.06485)
			(xy 207.52435 -116.073682) (xy 207.506126 -116.096138) (xy 207.464114 -116.135876) (xy 207.416586 -116.168818)
			(xy 207.364631 -116.194212) (xy 207.309439 -116.211474) (xy 207.252274 -116.220209) (xy 207.22336 -116.220748)
			(xy 207.196114 -116.220179) (xy 207.142176 -116.212419) (xy 207.089891 -116.197062) (xy 207.040324 -116.174421)
			(xy 206.994484 -116.144957) (xy 206.953303 -116.109269) (xy 206.917619 -116.068084) (xy 206.88816 -116.02224)
			(xy 206.865524 -115.972671) (xy 206.850173 -115.920385) (xy 206.842418 -115.866447) (xy 203.3524 -115.866447)
			(xy 203.3524 -117.191028) (xy 213.616792 -117.191028) (xy 213.620863 -117.135406) (xy 213.632989 -117.080969)
			(xy 213.652912 -117.028878) (xy 213.680208 -116.980243) (xy 213.714294 -116.9361) (xy 213.754443 -116.897391)
			(xy 213.799801 -116.86494) (xy 213.849401 -116.839439) (xy 213.902185 -116.821432) (xy 213.957028 -116.811302)
			(xy 214.012762 -116.809265) (xy 214.068199 -116.815365) (xy 214.122156 -116.829471) (xy 214.173485 -116.851283)
			(xy 214.221091 -116.880337) (xy 214.263959 -116.916012) (xy 214.301176 -116.957549) (xy 214.331949 -117.004062)
			(xy 214.355621 -117.054559) (xy 214.371689 -117.107966) (xy 214.379809 -117.163142) (xy 214.380318 -117.191028)
			(xy 214.379809 -117.218914) (xy 214.371689 -117.27409) (xy 214.355621 -117.327497) (xy 214.331949 -117.377994)
			(xy 214.301176 -117.424507) (xy 214.263959 -117.466044) (xy 214.221091 -117.501719) (xy 214.173485 -117.530773)
			(xy 214.122156 -117.552585) (xy 214.068199 -117.566691) (xy 214.012762 -117.572791) (xy 213.957028 -117.570754)
			(xy 213.902185 -117.560624) (xy 213.849401 -117.542617) (xy 213.799801 -117.517116) (xy 213.754443 -117.484665)
			(xy 213.714294 -117.445956) (xy 213.680208 -117.401813) (xy 213.652912 -117.353178) (xy 213.632989 -117.301087)
			(xy 213.620863 -117.24665) (xy 213.616792 -117.191028) (xy 203.3524 -117.191028) (xy 203.3524 -118.620286)
			(xy 213.718646 -118.620286) (xy 213.722717 -118.564664) (xy 213.734843 -118.510227) (xy 213.754766 -118.458136)
			(xy 213.782062 -118.409501) (xy 213.816148 -118.365358) (xy 213.856297 -118.326649) (xy 213.901655 -118.294198)
			(xy 213.951255 -118.268697) (xy 214.004039 -118.25069) (xy 214.058882 -118.24056) (xy 214.114616 -118.238523)
			(xy 214.170053 -118.244623) (xy 214.22401 -118.258729) (xy 214.275339 -118.280541) (xy 214.322945 -118.309595)
			(xy 214.365813 -118.34527) (xy 214.40303 -118.386807) (xy 214.433803 -118.43332) (xy 214.457475 -118.483817)
			(xy 214.473543 -118.537224) (xy 214.481663 -118.5924) (xy 214.482172 -118.620286) (xy 214.481663 -118.648172)
			(xy 214.473543 -118.703348) (xy 214.457475 -118.756755) (xy 214.433803 -118.807252) (xy 214.40303 -118.853765)
			(xy 214.365813 -118.895302) (xy 214.322945 -118.930977) (xy 214.275339 -118.960031) (xy 214.22401 -118.981843)
			(xy 214.170053 -118.995949) (xy 214.114616 -119.002049) (xy 214.058882 -119.000012) (xy 214.004039 -118.989882)
			(xy 213.951255 -118.971875) (xy 213.901655 -118.946374) (xy 213.856297 -118.913923) (xy 213.816148 -118.875214)
			(xy 213.782062 -118.831071) (xy 213.754766 -118.782436) (xy 213.734843 -118.730345) (xy 213.722717 -118.675908)
			(xy 213.718646 -118.620286) (xy 203.3524 -118.620286) (xy 203.3524 -120.922034) (xy 205.550516 -120.922034)
			(xy 205.550998 -120.894664) (xy 205.558811 -120.840486) (xy 205.574297 -120.787983) (xy 205.597135 -120.738236)
			(xy 205.626856 -120.692268) (xy 205.644496 -120.671336) (xy 205.64475 -120.671082) (xy 205.650356 -120.664009)
			(xy 205.65659 -120.647082) (xy 205.656942 -120.638062) (xy 205.656942 -120.571006) (xy 205.656595 -120.561988)
			(xy 205.650342 -120.54507) (xy 205.64475 -120.537986) (xy 205.644496 -120.537986) (xy 205.644496 -120.537732)
			(xy 205.62689 -120.516772) (xy 205.597166 -120.470808) (xy 205.574321 -120.421066) (xy 205.558823 -120.368568)
			(xy 205.550992 -120.314394) (xy 205.550988 -120.259657) (xy 205.558812 -120.205482) (xy 205.574303 -120.152982)
			(xy 205.597141 -120.103237) (xy 205.626859 -120.057269) (xy 205.644496 -120.036336) (xy 205.64475 -120.036082)
			(xy 205.650356 -120.029009) (xy 205.65659 -120.012082) (xy 205.656942 -120.003062) (xy 205.656942 -119.936006)
			(xy 205.656595 -119.926988) (xy 205.650342 -119.91007) (xy 205.64475 -119.902986) (xy 205.644496 -119.902986)
			(xy 205.644496 -119.902732) (xy 205.62689 -119.881772) (xy 205.597166 -119.835808) (xy 205.574321 -119.786066)
			(xy 205.558823 -119.733568) (xy 205.550992 -119.679394) (xy 205.550988 -119.624657) (xy 205.558812 -119.570482)
			(xy 205.574303 -119.517982) (xy 205.597141 -119.468237) (xy 205.626859 -119.422269) (xy 205.644496 -119.401336)
			(xy 205.64475 -119.401082) (xy 205.650356 -119.394009) (xy 205.65659 -119.377082) (xy 205.656942 -119.368062)
			(xy 205.656942 -119.301006) (xy 205.656595 -119.291988) (xy 205.650342 -119.27507) (xy 205.64475 -119.267986)
			(xy 205.644496 -119.267986) (xy 205.644496 -119.267732) (xy 205.626858 -119.246799) (xy 205.597146 -119.200827)
			(xy 205.57431 -119.151079) (xy 205.558819 -119.098579) (xy 205.55099 -119.044403) (xy 205.550516 -119.017034)
			(xy 205.551002 -118.989783) (xy 205.558758 -118.935835) (xy 205.574113 -118.88354) (xy 205.596755 -118.833963)
			(xy 205.626221 -118.788113) (xy 205.661912 -118.746922) (xy 205.703103 -118.711231) (xy 205.748953 -118.681765)
			(xy 205.79853 -118.659123) (xy 205.850825 -118.643768) (xy 205.904773 -118.636012) (xy 205.959275 -118.636012)
			(xy 206.013223 -118.643768) (xy 206.065518 -118.659123) (xy 206.115095 -118.681765) (xy 206.160945 -118.711231)
			(xy 206.202136 -118.746922) (xy 206.237827 -118.788113) (xy 206.267293 -118.833963) (xy 206.289935 -118.88354)
			(xy 206.30529 -118.935835) (xy 206.313046 -118.989783) (xy 206.313532 -119.017034) (xy 206.313102 -119.044406)
			(xy 206.308435 -119.076724) (xy 206.521812 -119.076724) (xy 206.522278 -119.049471) (xy 206.530032 -118.995519)
			(xy 206.545386 -118.94322) (xy 206.568027 -118.893639) (xy 206.597494 -118.847784) (xy 206.633188 -118.806591)
			(xy 206.674381 -118.770897) (xy 206.720235 -118.741429) (xy 206.769816 -118.718787) (xy 206.822115 -118.703433)
			(xy 206.876067 -118.695678) (xy 206.90332 -118.695216) (xy 206.929635 -118.695665) (xy 206.981764 -118.702903)
			(xy 207.032407 -118.717225) (xy 207.080606 -118.738361) (xy 207.125449 -118.765911) (xy 207.166088 -118.799353)
			(xy 207.184244 -118.818406) (xy 207.191747 -118.82583) (xy 207.211041 -118.834341) (xy 207.221582 -118.834916)
			(xy 207.296258 -118.834916) (xy 207.306806 -118.834373) (xy 207.326101 -118.825847) (xy 207.333596 -118.818406)
			(xy 207.351762 -118.799361) (xy 207.392389 -118.765902) (xy 207.437227 -118.738342) (xy 207.485426 -118.717201)
			(xy 207.536072 -118.702882) (xy 207.588204 -118.695656) (xy 207.61452 -118.695216) (xy 207.641774 -118.695636)
			(xy 207.695728 -118.703397) (xy 207.748028 -118.718756) (xy 207.79761 -118.741403) (xy 207.843464 -118.770875)
			(xy 207.884658 -118.806574) (xy 207.920351 -118.847771) (xy 207.949818 -118.893628) (xy 207.972459 -118.943213)
			(xy 207.987813 -118.995515) (xy 207.995567 -119.049469) (xy 207.996028 -119.076724) (xy 207.995484 -119.105052)
			(xy 207.987121 -119.161088) (xy 207.970565 -119.215272) (xy 207.946183 -119.266414) (xy 207.914508 -119.31339)
			(xy 207.876238 -119.355167) (xy 207.832213 -119.390828) (xy 207.808068 -119.405654) (xy 207.800771 -119.410375)
			(xy 207.789587 -119.423659) (xy 207.783456 -119.439907) (xy 207.782922 -119.44858) (xy 207.781652 -119.535194)
			(xy 207.781921 -119.543867) (xy 207.787448 -119.560299) (xy 207.798142 -119.573943) (xy 207.805274 -119.578882)
			(xy 207.828199 -119.593999) (xy 207.869907 -119.629718) (xy 207.906067 -119.671043) (xy 207.935935 -119.717122)
			(xy 207.958893 -119.767004) (xy 207.974469 -119.819661) (xy 207.982341 -119.874006) (xy 207.98282 -119.901462)
			(xy 207.982309 -119.928713) (xy 207.974558 -119.982662) (xy 207.959207 -120.034958) (xy 207.93657 -120.084537)
			(xy 207.907107 -120.13039) (xy 207.871418 -120.171583) (xy 207.83023 -120.207277) (xy 207.784381 -120.236746)
			(xy 207.734805 -120.25939) (xy 207.682511 -120.274747) (xy 207.628563 -120.282506) (xy 207.601312 -120.28297)
			(xy 207.573942 -120.282504) (xy 207.519762 -120.274687) (xy 207.467259 -120.259199) (xy 207.417512 -120.236357)
			(xy 207.371545 -120.206632) (xy 207.350614 -120.18899) (xy 207.35036 -120.188736) (xy 207.343266 -120.183161)
			(xy 207.326355 -120.176909) (xy 207.31734 -120.176544) (xy 207.250284 -120.176544) (xy 207.241265 -120.176884)
			(xy 207.224348 -120.183142) (xy 207.217264 -120.188736) (xy 207.217264 -120.18899) (xy 207.21701 -120.18899)
			(xy 207.196084 -120.206636) (xy 207.150109 -120.236347) (xy 207.100361 -120.259182) (xy 207.047858 -120.274671)
			(xy 206.993682 -120.282497) (xy 206.966312 -120.28297) (xy 206.939058 -120.282533) (xy 206.885104 -120.274777)
			(xy 206.832803 -120.259421) (xy 206.783221 -120.236777) (xy 206.737366 -120.207306) (xy 206.696172 -120.17161)
			(xy 206.660478 -120.130414) (xy 206.631011 -120.084557) (xy 206.60837 -120.034972) (xy 206.593017 -119.982671)
			(xy 206.585265 -119.928716) (xy 206.584804 -119.901462) (xy 206.585272 -119.875526) (xy 206.592293 -119.824132)
			(xy 206.606213 -119.774163) (xy 206.626776 -119.726542) (xy 206.653603 -119.682146) (xy 206.686198 -119.641795)
			(xy 206.723961 -119.606233) (xy 206.744824 -119.59082) (xy 206.755746 -119.5832) (xy 206.766922 -119.55907)
			(xy 206.759556 -119.458994) (xy 206.758535 -119.450283) (xy 206.751384 -119.43428) (xy 206.739282 -119.421601)
			(xy 206.731616 -119.417338) (xy 206.708293 -119.405108) (xy 206.664963 -119.375173) (xy 206.626166 -119.339561)
			(xy 206.592639 -119.298948) (xy 206.56502 -119.254107) (xy 206.543835 -119.205892) (xy 206.529488 -119.15522)
			(xy 206.52225 -119.103056) (xy 206.521812 -119.076724) (xy 206.308435 -119.076724) (xy 206.305278 -119.098587)
			(xy 206.289782 -119.151091) (xy 206.266931 -119.200838) (xy 206.237198 -119.246802) (xy 206.219552 -119.267732)
			(xy 206.219298 -119.267986) (xy 206.213711 -119.275072) (xy 206.207465 -119.291989) (xy 206.207106 -119.301006)
			(xy 206.207106 -119.368062) (xy 206.20748 -119.377077) (xy 206.213716 -119.393994) (xy 206.219298 -119.401082)
			(xy 206.219552 -119.401082) (xy 206.219552 -119.401336) (xy 206.237227 -119.422241) (xy 206.266952 -119.468213)
			(xy 206.289797 -119.517964) (xy 206.305291 -119.57047) (xy 206.313117 -119.624653) (xy 206.313113 -119.679398)
			(xy 206.30528 -119.73358) (xy 206.289779 -119.786084) (xy 206.266927 -119.835832) (xy 206.237196 -119.8818)
			(xy 206.219552 -119.902732) (xy 206.219298 -119.902986) (xy 206.213711 -119.910072) (xy 206.207465 -119.926989)
			(xy 206.207106 -119.936006) (xy 206.207106 -120.003062) (xy 206.20748 -120.012077) (xy 206.213716 -120.028994)
			(xy 206.219298 -120.036082) (xy 206.219552 -120.036082) (xy 206.219552 -120.036336) (xy 206.237227 -120.057241)
			(xy 206.266952 -120.103213) (xy 206.289797 -120.152964) (xy 206.305291 -120.20547) (xy 206.313117 -120.259653)
			(xy 206.313113 -120.314398) (xy 206.310753 -120.330722) (xy 208.104232 -120.330722) (xy 208.104703 -120.303352)
			(xy 208.112519 -120.249173) (xy 208.128006 -120.196669) (xy 208.150847 -120.146922) (xy 208.180571 -120.100956)
			(xy 208.198212 -120.080024) (xy 208.198466 -120.07977) (xy 208.204037 -120.072673) (xy 208.210291 -120.055764)
			(xy 208.210658 -120.04675) (xy 208.210658 -119.979694) (xy 208.210313 -119.970676) (xy 208.204058 -119.953759)
			(xy 208.198466 -119.946674) (xy 208.198212 -119.946674) (xy 208.198212 -119.94642) (xy 208.180571 -119.92549)
			(xy 208.150859 -119.879517) (xy 208.128023 -119.829769) (xy 208.112533 -119.777268) (xy 208.104705 -119.723091)
			(xy 208.104232 -119.695722) (xy 208.104676 -119.668468) (xy 208.112431 -119.614514) (xy 208.127786 -119.562214)
			(xy 208.150429 -119.512631) (xy 208.179898 -119.466776) (xy 208.215594 -119.425582) (xy 208.25679 -119.389888)
			(xy 208.302647 -119.36042) (xy 208.35223 -119.33778) (xy 208.404532 -119.322427) (xy 208.458486 -119.314675)
			(xy 208.48574 -119.314214) (xy 208.514863 -119.314748) (xy 208.572435 -119.32358) (xy 208.627995 -119.341064)
			(xy 208.680251 -119.366792) (xy 208.727987 -119.400166) (xy 208.770093 -119.440411) (xy 208.80559 -119.48659)
			(xy 208.833653 -119.53763) (xy 208.853629 -119.592343) (xy 208.859882 -119.620792) (xy 208.862168 -119.632476)
			(xy 208.876646 -119.651272) (xy 208.96072 -119.691658) (xy 208.971533 -119.696221) (xy 208.994973 -119.69596)
			(xy 209.005678 -119.69115) (xy 209.006186 -119.69115) (xy 209.033242 -119.677863) (xy 209.090519 -119.659086)
			(xy 209.150038 -119.649569) (xy 209.180176 -119.648986) (xy 209.207428 -119.649478) (xy 209.261378 -119.657231)
			(xy 209.313675 -119.672584) (xy 209.363254 -119.695223) (xy 209.409107 -119.724688) (xy 209.4503 -119.760379)
			(xy 209.485994 -119.801569) (xy 209.515462 -119.847419) (xy 209.538106 -119.896997) (xy 209.553462 -119.949293)
			(xy 209.56122 -120.003242) (xy 209.561684 -120.030494) (xy 209.561218 -120.057864) (xy 209.553401 -120.112044)
			(xy 209.538869 -120.161304) (xy 213.683848 -120.161304) (xy 213.687919 -120.105682) (xy 213.700045 -120.051245)
			(xy 213.719968 -119.999154) (xy 213.747264 -119.950519) (xy 213.78135 -119.906376) (xy 213.821499 -119.867667)
			(xy 213.866857 -119.835216) (xy 213.916457 -119.809715) (xy 213.969241 -119.791708) (xy 214.024084 -119.781578)
			(xy 214.079818 -119.779541) (xy 214.135255 -119.785641) (xy 214.189212 -119.799747) (xy 214.240541 -119.821559)
			(xy 214.288147 -119.850613) (xy 214.331015 -119.886288) (xy 214.368232 -119.927825) (xy 214.399005 -119.974338)
			(xy 214.422677 -120.024835) (xy 214.438745 -120.078242) (xy 214.446865 -120.133418) (xy 214.447374 -120.161304)
			(xy 214.446865 -120.18919) (xy 214.438745 -120.244366) (xy 214.422677 -120.297773) (xy 214.399005 -120.34827)
			(xy 214.368232 -120.394783) (xy 214.331015 -120.43632) (xy 214.288147 -120.471995) (xy 214.240541 -120.501049)
			(xy 214.189212 -120.522861) (xy 214.135255 -120.536967) (xy 214.079818 -120.543067) (xy 214.024084 -120.54103)
			(xy 213.969241 -120.5309) (xy 213.916457 -120.512893) (xy 213.866857 -120.487392) (xy 213.821499 -120.454941)
			(xy 213.78135 -120.416232) (xy 213.747264 -120.372089) (xy 213.719968 -120.323454) (xy 213.700045 -120.271363)
			(xy 213.687919 -120.216926) (xy 213.683848 -120.161304) (xy 209.538869 -120.161304) (xy 209.537912 -120.164547)
			(xy 209.51507 -120.214294) (xy 209.485345 -120.26026) (xy 209.467704 -120.281192) (xy 209.46745 -120.281446)
			(xy 209.461874 -120.28854) (xy 209.455622 -120.305451) (xy 209.455258 -120.314466) (xy 209.455258 -120.381522)
			(xy 209.455592 -120.390541) (xy 209.461854 -120.407459) (xy 209.46745 -120.414542) (xy 209.467704 -120.414542)
			(xy 209.467704 -120.414796) (xy 209.485355 -120.435718) (xy 209.515065 -120.481694) (xy 209.537899 -120.531444)
			(xy 209.553387 -120.583947) (xy 209.561212 -120.638124) (xy 209.561684 -120.665494) (xy 209.561239 -120.692748)
			(xy 209.553482 -120.746701) (xy 209.538126 -120.799) (xy 209.515482 -120.848582) (xy 209.486013 -120.894436)
			(xy 209.450317 -120.93563) (xy 209.409122 -120.971323) (xy 209.363266 -121.000791) (xy 209.313683 -121.023432)
			(xy 209.261383 -121.038786) (xy 209.20743 -121.04654) (xy 209.180176 -121.047002) (xy 209.151054 -121.046441)
			(xy 209.093484 -121.037611) (xy 209.037925 -121.020131) (xy 208.98567 -120.994406) (xy 208.937935 -120.961035)
			(xy 208.895828 -120.920794) (xy 208.86033 -120.874618) (xy 208.832266 -120.823582) (xy 208.812288 -120.768872)
			(xy 208.806034 -120.740424) (xy 208.803748 -120.72874) (xy 208.78927 -120.709944) (xy 208.705196 -120.669558)
			(xy 208.694379 -120.665004) (xy 208.670943 -120.665258) (xy 208.660238 -120.670066) (xy 208.65973 -120.670066)
			(xy 208.632671 -120.683349) (xy 208.575396 -120.702127) (xy 208.515877 -120.711646) (xy 208.48574 -120.71223)
			(xy 208.458489 -120.711708) (xy 208.404541 -120.703957) (xy 208.352246 -120.688607) (xy 208.302668 -120.665971)
			(xy 208.256815 -120.636509) (xy 208.215623 -120.600821) (xy 208.179928 -120.559634) (xy 208.150459 -120.513787)
			(xy 208.127815 -120.464212) (xy 208.112457 -120.411919) (xy 208.104697 -120.357973) (xy 208.104232 -120.330722)
			(xy 206.310753 -120.330722) (xy 206.30528 -120.36858) (xy 206.289779 -120.421084) (xy 206.266927 -120.470832)
			(xy 206.237196 -120.5168) (xy 206.219552 -120.537732) (xy 206.219298 -120.537986) (xy 206.213711 -120.545072)
			(xy 206.207465 -120.561989) (xy 206.207106 -120.571006) (xy 206.207106 -120.638062) (xy 206.20748 -120.647077)
			(xy 206.213716 -120.663994) (xy 206.219298 -120.671082) (xy 206.219552 -120.671082) (xy 206.219552 -120.671336)
			(xy 206.237167 -120.692288) (xy 206.266884 -120.738254) (xy 206.289726 -120.787997) (xy 206.305222 -120.840493)
			(xy 206.313055 -120.894666) (xy 206.313532 -120.922034) (xy 206.313046 -120.949285) (xy 206.30529 -121.003233)
			(xy 206.289935 -121.055528) (xy 206.267293 -121.105105) (xy 206.237827 -121.150955) (xy 206.202136 -121.192146)
			(xy 206.160945 -121.227837) (xy 206.115095 -121.257303) (xy 206.065518 -121.279945) (xy 206.013223 -121.2953)
			(xy 205.959275 -121.303056) (xy 205.904773 -121.303056) (xy 205.850825 -121.2953) (xy 205.79853 -121.279945)
			(xy 205.748953 -121.257303) (xy 205.703103 -121.227837) (xy 205.661912 -121.192146) (xy 205.626221 -121.150955)
			(xy 205.596755 -121.105105) (xy 205.574113 -121.055528) (xy 205.558758 -121.003233) (xy 205.551002 -120.949285)
			(xy 205.550516 -120.922034) (xy 203.3524 -120.922034) (xy 203.3524 -122.094549) (xy 210.164198 -122.094549)
			(xy 210.164198 -122.040051) (xy 210.171954 -121.986109) (xy 210.187306 -121.933819) (xy 210.209944 -121.884247)
			(xy 210.239406 -121.8384) (xy 210.275093 -121.797213) (xy 210.316278 -121.761523) (xy 210.362122 -121.732058)
			(xy 210.411693 -121.709416) (xy 210.463982 -121.694059) (xy 210.517924 -121.6863) (xy 210.545172 -121.685812)
			(xy 210.572542 -121.686292) (xy 210.62672 -121.694106) (xy 210.679223 -121.709591) (xy 210.728971 -121.73243)
			(xy 210.774938 -121.762152) (xy 210.79587 -121.779792) (xy 210.796124 -121.780046) (xy 210.803196 -121.785654)
			(xy 210.820124 -121.791887) (xy 210.829144 -121.792238) (xy 210.8962 -121.792238) (xy 210.905216 -121.791873)
			(xy 210.922132 -121.78563) (xy 210.92922 -121.780046) (xy 210.92922 -121.779792) (xy 210.929474 -121.779792)
			(xy 210.950407 -121.762151) (xy 210.996375 -121.732427) (xy 211.046121 -121.709581) (xy 211.098623 -121.694085)
			(xy 211.152801 -121.686256) (xy 211.207543 -121.686256) (xy 211.261721 -121.694085) (xy 211.314223 -121.709581)
			(xy 211.363969 -121.732427) (xy 211.409937 -121.762151) (xy 211.43087 -121.779792) (xy 211.431124 -121.780046)
			(xy 211.438196 -121.785654) (xy 211.455124 -121.791887) (xy 211.464144 -121.792238) (xy 211.5312 -121.792238)
			(xy 211.540216 -121.791873) (xy 211.557132 -121.78563) (xy 211.56422 -121.780046) (xy 211.56422 -121.779792)
			(xy 211.564474 -121.779792) (xy 211.585404 -121.76215) (xy 211.631378 -121.732439) (xy 211.681126 -121.709604)
			(xy 211.733627 -121.694113) (xy 211.787803 -121.686286) (xy 211.815172 -121.685812) (xy 211.842428 -121.686233)
			(xy 211.896384 -121.693987) (xy 211.948688 -121.709342) (xy 211.998275 -121.731984) (xy 212.044134 -121.761452)
			(xy 212.085332 -121.797148) (xy 212.121031 -121.838344) (xy 212.150503 -121.884201) (xy 212.173149 -121.933785)
			(xy 212.188507 -121.986088) (xy 212.196265 -122.040044) (xy 212.196265 -122.094556) (xy 212.188507 -122.148512)
			(xy 212.173149 -122.200815) (xy 212.150503 -122.250399) (xy 212.121031 -122.296256) (xy 212.085332 -122.337452)
			(xy 212.044134 -122.373148) (xy 211.998275 -122.402616) (xy 211.948688 -122.425258) (xy 211.896384 -122.440613)
			(xy 211.842428 -122.448367) (xy 211.815172 -122.448828) (xy 211.7878 -122.448396) (xy 211.733619 -122.440573)
			(xy 211.681115 -122.425077) (xy 211.631369 -122.402227) (xy 211.585404 -122.372494) (xy 211.564474 -122.354848)
			(xy 211.56422 -122.354594) (xy 211.557132 -122.349009) (xy 211.540216 -122.342762) (xy 211.5312 -122.342402)
			(xy 211.464144 -122.342402) (xy 211.455129 -122.34278) (xy 211.438212 -122.349013) (xy 211.431124 -122.354594)
			(xy 211.43087 -122.354848) (xy 211.409937 -122.372489) (xy 211.363969 -122.402213) (xy 211.314223 -122.425059)
			(xy 211.261721 -122.440555) (xy 211.207543 -122.448384) (xy 211.152801 -122.448384) (xy 211.098623 -122.440555)
			(xy 211.046121 -122.425059) (xy 210.996375 -122.402213) (xy 210.950407 -122.372489) (xy 210.929474 -122.354848)
			(xy 210.92922 -122.354594) (xy 210.922132 -122.349009) (xy 210.905216 -122.342762) (xy 210.8962 -122.342402)
			(xy 210.829144 -122.342402) (xy 210.820129 -122.34278) (xy 210.803212 -122.349013) (xy 210.796124 -122.354594)
			(xy 210.796124 -122.354848) (xy 210.79587 -122.354848) (xy 210.774916 -122.37246) (xy 210.72895 -122.402177)
			(xy 210.679208 -122.425019) (xy 210.626712 -122.440517) (xy 210.57254 -122.448351) (xy 210.545172 -122.448828)
			(xy 210.517924 -122.4483) (xy 210.463982 -122.440541) (xy 210.411693 -122.425184) (xy 210.362122 -122.402542)
			(xy 210.316278 -122.373077) (xy 210.275093 -122.337387) (xy 210.239406 -122.2962) (xy 210.209944 -122.250353)
			(xy 210.187306 -122.200781) (xy 210.171954 -122.148491) (xy 210.164198 -122.094549) (xy 203.3524 -122.094549)
			(xy 203.3524 -122.525028) (xy 213.607396 -122.525028) (xy 213.607877 -122.49828) (xy 213.615373 -122.44531)
			(xy 213.630194 -122.393907) (xy 213.65205 -122.345077) (xy 213.680512 -122.29978) (xy 213.715021 -122.258901)
			(xy 213.754902 -122.223244) (xy 213.799373 -122.193506) (xy 213.847561 -122.170271) (xy 213.898522 -122.153995)
			(xy 213.951257 -122.144996) (xy 213.977982 -122.143774) (xy 213.991505 -122.142968) (xy 214.017415 -122.135085)
			(xy 214.040341 -122.120668) (xy 214.058671 -122.100731) (xy 214.071115 -122.076676) (xy 214.076798 -122.050197)
			(xy 214.075319 -122.023155) (xy 214.071454 -122.01017) (xy 214.062467 -121.98108) (xy 214.052766 -121.920976)
			(xy 214.05215 -121.890536) (xy 214.05215 -121.890028) (xy 214.052636 -121.862777) (xy 214.060392 -121.808829)
			(xy 214.075747 -121.756534) (xy 214.098389 -121.706957) (xy 214.127855 -121.661107) (xy 214.163546 -121.619916)
			(xy 214.204737 -121.584225) (xy 214.250587 -121.554759) (xy 214.300164 -121.532117) (xy 214.352459 -121.516762)
			(xy 214.406407 -121.509006) (xy 214.460909 -121.509006) (xy 214.514857 -121.516762) (xy 214.567152 -121.532117)
			(xy 214.616729 -121.554759) (xy 214.662579 -121.584225) (xy 214.70377 -121.619916) (xy 214.739461 -121.661107)
			(xy 214.768927 -121.706957) (xy 214.791569 -121.756534) (xy 214.806924 -121.808829) (xy 214.81468 -121.862777)
			(xy 214.815166 -121.890028) (xy 214.814681 -121.916777) (xy 214.80719 -121.969748) (xy 214.792372 -122.021154)
			(xy 214.770519 -122.069985) (xy 214.742059 -122.115285) (xy 214.707549 -122.156165) (xy 214.667667 -122.191823)
			(xy 214.623195 -122.221561) (xy 214.575005 -122.244794) (xy 214.524042 -122.261067) (xy 214.471305 -122.270062)
			(xy 214.44458 -122.271282) (xy 214.431061 -122.272115) (xy 214.40516 -122.280002) (xy 214.382241 -122.294418)
			(xy 214.363916 -122.314349) (xy 214.351472 -122.338396) (xy 214.345783 -122.364867) (xy 214.34725 -122.391903)
			(xy 214.351108 -122.404886) (xy 214.360107 -122.433973) (xy 214.3698 -122.494079) (xy 214.370412 -122.52452)
			(xy 214.370412 -122.525028) (xy 214.369926 -122.552279) (xy 214.36217 -122.606227) (xy 214.346815 -122.658522)
			(xy 214.324173 -122.708099) (xy 214.294707 -122.753949) (xy 214.259016 -122.79514) (xy 214.217825 -122.830831)
			(xy 214.171975 -122.860297) (xy 214.122398 -122.882939) (xy 214.070103 -122.898294) (xy 214.016155 -122.90605)
			(xy 213.961653 -122.90605) (xy 213.907705 -122.898294) (xy 213.85541 -122.882939) (xy 213.805833 -122.860297)
			(xy 213.759983 -122.830831) (xy 213.718792 -122.79514) (xy 213.683101 -122.753949) (xy 213.653635 -122.708099)
			(xy 213.630993 -122.658522) (xy 213.615638 -122.606227) (xy 213.607882 -122.552279) (xy 213.607396 -122.525028)
			(xy 203.3524 -122.525028) (xy 203.3524 -122.972347) (xy 210.707522 -122.972347) (xy 210.707522 -122.917853)
			(xy 210.715277 -122.863913) (xy 210.730629 -122.811626) (xy 210.753266 -122.762057) (xy 210.782727 -122.716213)
			(xy 210.818412 -122.675028) (xy 210.859595 -122.63934) (xy 210.905437 -122.609877) (xy 210.955006 -122.587237)
			(xy 211.007292 -122.571882) (xy 211.061231 -122.564124) (xy 211.088478 -122.563636) (xy 211.116082 -122.564094)
			(xy 211.170715 -122.572036) (xy 211.223632 -122.587773) (xy 211.273727 -122.610975) (xy 211.319953 -122.641157)
			(xy 211.361345 -122.677689) (xy 211.397036 -122.719807) (xy 211.412074 -122.74296) (xy 211.420048 -122.754782)
			(xy 211.441213 -122.773872) (xy 211.466832 -122.786362) (xy 211.494906 -122.791279) (xy 211.523245 -122.78824)
			(xy 211.549637 -122.77748) (xy 211.572024 -122.759841) (xy 211.58073 -122.748548) (xy 211.596147 -122.7278)
			(xy 211.631687 -122.690264) (xy 211.67197 -122.657871) (xy 211.716258 -122.631215) (xy 211.76374 -122.610784)
			(xy 211.813546 -122.596953) (xy 211.864764 -122.589973) (xy 211.89061 -122.589544) (xy 211.917857 -122.590127)
			(xy 211.971797 -122.597884) (xy 212.024084 -122.613238) (xy 212.073654 -122.635876) (xy 212.119497 -122.665339)
			(xy 212.160681 -122.701026) (xy 212.196367 -122.742211) (xy 212.225828 -122.788055) (xy 212.248466 -122.837625)
			(xy 212.263819 -122.889913) (xy 212.271574 -122.943853) (xy 212.271574 -122.998347) (xy 212.263819 -123.052287)
			(xy 212.248466 -123.104575) (xy 212.225828 -123.154145) (xy 212.196367 -123.199989) (xy 212.160681 -123.241174)
			(xy 212.119497 -123.276861) (xy 212.073654 -123.306324) (xy 212.024084 -123.328962) (xy 211.971797 -123.344316)
			(xy 211.917857 -123.352073) (xy 211.89061 -123.35256) (xy 211.863008 -123.352036) (xy 211.808378 -123.344106)
			(xy 211.755463 -123.328381) (xy 211.705368 -123.30519) (xy 211.659141 -123.275018) (xy 211.617747 -123.238495)
			(xy 211.582053 -123.196385) (xy 211.567014 -123.173236) (xy 211.559055 -123.161403) (xy 211.537887 -123.142314)
			(xy 211.512265 -123.129824) (xy 211.484188 -123.124908) (xy 211.455847 -123.12795) (xy 211.429452 -123.138712)
			(xy 211.407064 -123.156354) (xy 211.398358 -123.167648) (xy 211.382947 -123.188401) (xy 211.347407 -123.225937)
			(xy 211.307123 -123.258329) (xy 211.262833 -123.284985) (xy 211.21535 -123.305415) (xy 211.165543 -123.319246)
			(xy 211.114324 -123.326223) (xy 211.088478 -123.326652) (xy 211.061231 -123.326076) (xy 211.007292 -123.318318)
			(xy 210.955006 -123.302963) (xy 210.905437 -123.280323) (xy 210.859595 -123.25086) (xy 210.818412 -123.215172)
			(xy 210.782727 -123.173987) (xy 210.753266 -123.128143) (xy 210.730629 -123.078574) (xy 210.715277 -123.026287)
			(xy 210.707522 -122.972347) (xy 203.3524 -122.972347) (xy 203.3524 -124.621544) (xy 211.274914 -124.621544)
			(xy 211.27534 -124.595229) (xy 211.282582 -124.543098) (xy 211.296909 -124.492454) (xy 211.31805 -124.444255)
			(xy 211.345603 -124.399413) (xy 211.379049 -124.358775) (xy 211.398104 -124.34062) (xy 211.405499 -124.333093)
			(xy 211.414027 -124.313817) (xy 211.414614 -124.303282) (xy 211.414614 -124.228606) (xy 211.414091 -124.218056)
			(xy 211.405551 -124.198761) (xy 211.398104 -124.191268) (xy 211.379041 -124.17312) (xy 211.345584 -124.132489)
			(xy 211.318026 -124.087647) (xy 211.296889 -124.039445) (xy 211.282573 -123.988796) (xy 211.275351 -123.936661)
			(xy 211.274914 -123.910344) (xy 211.2754 -123.883093) (xy 211.283156 -123.829145) (xy 211.298511 -123.77685)
			(xy 211.321153 -123.727273) (xy 211.350619 -123.681423) (xy 211.38631 -123.640232) (xy 211.427501 -123.604541)
			(xy 211.473351 -123.575075) (xy 211.522928 -123.552433) (xy 211.575223 -123.537078) (xy 211.629171 -123.529322)
			(xy 211.683673 -123.529322) (xy 211.737621 -123.537078) (xy 211.789916 -123.552433) (xy 211.839493 -123.575075)
			(xy 211.885343 -123.604541) (xy 211.926534 -123.640232) (xy 211.962225 -123.681423) (xy 211.991691 -123.727273)
			(xy 212.014333 -123.77685) (xy 212.029688 -123.829145) (xy 212.037444 -123.883093) (xy 212.03793 -123.910344)
			(xy 212.037482 -123.936659) (xy 212.030242 -123.988788) (xy 212.015918 -124.03943) (xy 211.994782 -124.087629)
			(xy 211.967233 -124.132472) (xy 211.933792 -124.173111) (xy 211.91474 -124.191268) (xy 211.907357 -124.198805)
			(xy 211.898821 -124.218073) (xy 211.89823 -124.228606) (xy 211.89823 -124.303282) (xy 211.898746 -124.313833)
			(xy 211.90729 -124.333129) (xy 211.91474 -124.34062) (xy 211.933806 -124.358765) (xy 211.967261 -124.399398)
			(xy 211.994817 -124.444241) (xy 212.015954 -124.492443) (xy 212.030269 -124.543092) (xy 212.037492 -124.595227)
			(xy 212.03793 -124.621544) (xy 212.037444 -124.648795) (xy 212.029688 -124.702743) (xy 212.014333 -124.755038)
			(xy 211.991691 -124.804615) (xy 211.962225 -124.850465) (xy 211.926534 -124.891656) (xy 211.885343 -124.927347)
			(xy 211.839493 -124.956813) (xy 211.789916 -124.979455) (xy 211.737621 -124.99481) (xy 211.683673 -125.002566)
			(xy 211.629171 -125.002566) (xy 211.575223 -124.99481) (xy 211.522928 -124.979455) (xy 211.473351 -124.956813)
			(xy 211.427501 -124.927347) (xy 211.38631 -124.891656) (xy 211.350619 -124.850465) (xy 211.321153 -124.804615)
			(xy 211.298511 -124.755038) (xy 211.283156 -124.702743) (xy 211.2754 -124.648795) (xy 211.274914 -124.621544)
			(xy 203.3524 -124.621544) (xy 203.3524 -126.83998) (xy 203.353416 -126.849632) (xy 203.355041 -126.856878)
			(xy 203.361877 -126.870052) (xy 203.366878 -126.87554) (xy 205.18882 -128.697482) (xy 211.268308 -128.697482)
			(xy 211.272379 -128.64186) (xy 211.284505 -128.587423) (xy 211.304428 -128.535332) (xy 211.331724 -128.486697)
			(xy 211.36581 -128.442554) (xy 211.405959 -128.403845) (xy 211.451317 -128.371394) (xy 211.500917 -128.345893)
			(xy 211.553701 -128.327886) (xy 211.608544 -128.317756) (xy 211.664278 -128.315719) (xy 211.719715 -128.321819)
			(xy 211.773672 -128.335925) (xy 211.825001 -128.357737) (xy 211.872607 -128.386791) (xy 211.915475 -128.422466)
			(xy 211.952692 -128.464003) (xy 211.983465 -128.510516) (xy 212.007137 -128.561013) (xy 212.023205 -128.61442)
			(xy 212.031325 -128.669596) (xy 212.031834 -128.697482) (xy 212.031325 -128.725368) (xy 212.023205 -128.780544)
			(xy 212.007137 -128.833951) (xy 211.983465 -128.884448) (xy 211.952692 -128.930961) (xy 211.915475 -128.972498)
			(xy 211.872607 -129.008173) (xy 211.825001 -129.037227) (xy 211.773672 -129.059039) (xy 211.719715 -129.073145)
			(xy 211.664278 -129.079245) (xy 211.608544 -129.077208) (xy 211.553701 -129.067078) (xy 211.500917 -129.049071)
			(xy 211.451317 -129.02357) (xy 211.405959 -128.991119) (xy 211.36581 -128.95241) (xy 211.331724 -128.908267)
			(xy 211.304428 -128.859632) (xy 211.284505 -128.807541) (xy 211.272379 -128.753104) (xy 211.268308 -128.697482)
			(xy 205.18882 -128.697482) (xy 205.901798 -129.41046) (xy 205.91991 -129.429241) (xy 205.950593 -129.471438)
			(xy 205.97429 -129.517919) (xy 205.990418 -129.567538) (xy 205.998578 -129.619069) (xy 205.99908 -129.645156)
			(xy 205.99908 -131.772406) (xy 206.000096 -131.782058) (xy 206.001723 -131.789302) (xy 206.008562 -131.802474)
			(xy 206.013558 -131.807966) (xy 208.983326 -134.777734) (xy 211.442044 -134.777734) (xy 211.446115 -134.722112)
			(xy 211.458241 -134.667675) (xy 211.478164 -134.615584) (xy 211.50546 -134.566949) (xy 211.539546 -134.522806)
			(xy 211.579695 -134.484097) (xy 211.625053 -134.451646) (xy 211.674653 -134.426145) (xy 211.727437 -134.408138)
			(xy 211.78228 -134.398008) (xy 211.838014 -134.395971) (xy 211.893451 -134.402071) (xy 211.947408 -134.416177)
			(xy 211.998737 -134.437989) (xy 212.046343 -134.467043) (xy 212.089211 -134.502718) (xy 212.126428 -134.544255)
			(xy 212.157201 -134.590768) (xy 212.180873 -134.641265) (xy 212.196941 -134.694672) (xy 212.205061 -134.749848)
			(xy 212.20557 -134.777734) (xy 212.205061 -134.80562) (xy 212.196941 -134.860796) (xy 212.180873 -134.914203)
			(xy 212.157201 -134.9647) (xy 212.126428 -135.011213) (xy 212.089211 -135.05275) (xy 212.046343 -135.088425)
			(xy 211.998737 -135.117479) (xy 211.947408 -135.139291) (xy 211.893451 -135.153397) (xy 211.838014 -135.159497)
			(xy 211.78228 -135.15746) (xy 211.727437 -135.14733) (xy 211.674653 -135.129323) (xy 211.625053 -135.103822)
			(xy 211.579695 -135.071371) (xy 211.539546 -135.032662) (xy 211.50546 -134.988519) (xy 211.478164 -134.939884)
			(xy 211.458241 -134.887793) (xy 211.446115 -134.833356) (xy 211.442044 -134.777734) (xy 208.983326 -134.777734)
			(xy 209.587084 -135.381492) (xy 209.593806 -135.387641) (xy 209.610386 -135.395159) (xy 209.628546 -135.39643)
			(xy 209.637376 -135.394192) (xy 209.73669 -135.364474) (xy 209.755486 -135.3439) (xy 209.75828 -135.330184)
			(xy 209.764676 -135.301904) (xy 209.784867 -135.247554) (xy 209.813048 -135.196885) (xy 209.848572 -135.151064)
			(xy 209.89062 -135.111145) (xy 209.938224 -135.078048) (xy 209.990288 -135.052535) (xy 210.045613 -135.035194)
			(xy 210.102925 -135.026423) (xy 210.131914 -135.025892) (xy 210.159165 -135.026379) (xy 210.213111 -135.034137)
			(xy 210.265404 -135.049493) (xy 210.314979 -135.072135) (xy 210.360828 -135.101602) (xy 210.402017 -135.137293)
			(xy 210.437707 -135.178483) (xy 210.467172 -135.224333) (xy 210.489812 -135.273909) (xy 210.505166 -135.326203)
			(xy 210.512922 -135.380149) (xy 210.513422 -135.4074) (xy 210.512714 -135.440194) (xy 210.501468 -135.504813)
			(xy 210.49107 -135.535924) (xy 210.488266 -135.544902) (xy 210.48879 -135.563691) (xy 210.492086 -135.5725)
			(xy 210.518502 -135.635746) (xy 210.52242 -135.6442) (xy 210.535186 -135.657751) (xy 210.543394 -135.662162)
			(xy 210.567609 -135.674071) (xy 210.612712 -135.703694) (xy 210.653194 -135.739375) (xy 210.688246 -135.780402)
			(xy 210.71717 -135.825957) (xy 210.739388 -135.875132) (xy 210.754459 -135.926947) (xy 210.762081 -135.980367)
			(xy 210.762596 -136.007348) (xy 210.761072 -136.041638) (xy 210.761326 -136.052814) (xy 210.762539 -136.06268)
			(xy 210.764062 -136.082502) (xy 210.764374 -136.092438) (xy 210.764374 -136.102852) (xy 210.763848 -136.13114)
			(xy 210.755463 -136.187091) (xy 210.7389 -136.241188) (xy 210.714523 -136.292242) (xy 210.699096 -136.315958)
			(xy 210.695286 -136.322562) (xy 210.690714 -136.332214) (xy 210.688428 -136.339072) (xy 210.688174 -136.339834)
			(xy 210.68411 -136.351772) (xy 210.683856 -136.35228) (xy 210.683856 -136.352534) (xy 210.68123 -136.362084)
			(xy 210.682664 -136.381821) (xy 210.68665 -136.390888) (xy 210.68792 -136.393428) (xy 210.690714 -136.41832)
			(xy 210.69173 -136.427972) (xy 210.70824 -136.459214) (xy 210.714844 -136.46531) (xy 210.737869 -136.487155)
			(xy 210.777067 -136.537071) (xy 210.792822 -136.564624) (xy 210.801581 -136.581112) (xy 210.816209 -136.615465)
			(xy 210.822032 -136.633204) (xy 210.823048 -136.636506) (xy 210.829614 -136.659493) (xy 210.83764 -136.706621)
			(xy 210.83905 -136.730486) (xy 210.83905 -136.732264) (xy 210.839304 -136.74725) (xy 210.839304 -136.74852)
			(xy 210.838736 -136.775703) (xy 210.830845 -136.829496) (xy 210.815398 -136.881624) (xy 210.792706 -136.931031)
			(xy 210.76323 -136.976716) (xy 210.727567 -137.017753) (xy 210.686438 -137.053312) (xy 210.640679 -137.082672)
			(xy 210.591214 -137.105238) (xy 210.539047 -137.120553) (xy 210.485234 -137.128307) (xy 210.45805 -137.128758)
			(xy 210.449668 -137.128758) (xy 210.418657 -137.12749) (xy 210.357641 -137.116149) (xy 210.299262 -137.095086)
			(xy 210.271868 -137.080498) (xy 210.249262 -137.066782) (xy 210.241642 -137.061702) (xy 210.231736 -137.056368)
			(xy 210.221651 -137.052947) (xy 210.200394 -137.053736) (xy 210.190588 -137.057892) (xy 210.16468 -137.070338)
			(xy 210.156244 -137.074822) (xy 210.143218 -137.088778) (xy 210.136157 -137.106515) (xy 210.135724 -137.116058)
			(xy 210.135724 -137.332974) (xy 210.135894 -137.338983) (xy 210.138724 -137.350662) (xy 210.141312 -137.356088)
			(xy 210.14315 -137.359563) (xy 210.147742 -137.365944) (xy 210.150456 -137.368788) (xy 210.499198 -137.71753)
			(xy 210.50661 -137.724214) (xy 210.525043 -137.731811) (xy 210.544981 -137.731811) (xy 210.563414 -137.724214)
			(xy 210.570826 -137.71753) (xy 211.675472 -136.612884) (xy 211.682606 -136.604919) (xy 211.69023 -136.584968)
			(xy 211.690204 -136.574276) (xy 211.68614 -136.498584) (xy 211.68572 -136.493367) (xy 211.683035 -136.483253)
			(xy 211.680806 -136.478518) (xy 211.676234 -136.46912) (xy 211.667344 -136.462008) (xy 211.645696 -136.443777)
			(xy 211.607498 -136.402017) (xy 211.575882 -136.355077) (xy 211.55154 -136.303985) (xy 211.535005 -136.24986)
			(xy 211.52664 -136.193887) (xy 211.52612 -136.16559) (xy 211.526584 -136.138338) (xy 211.534342 -136.08439)
			(xy 211.5497 -136.032095) (xy 211.572343 -135.982518) (xy 211.601812 -135.936668) (xy 211.637506 -135.895479)
			(xy 211.678698 -135.859789) (xy 211.724551 -135.830325) (xy 211.774131 -135.807686) (xy 211.826427 -135.792334)
			(xy 211.880376 -135.784581) (xy 211.907628 -135.784082) (xy 211.907628 -135.783828) (xy 211.935956 -135.784346)
			(xy 211.991989 -135.792723) (xy 212.046169 -135.809289) (xy 212.097305 -135.83368) (xy 212.144276 -135.865361)
			(xy 212.186048 -135.903635) (xy 212.2043 -135.925306) (xy 212.204554 -135.92556) (xy 212.208048 -135.929762)
			(xy 212.216513 -135.936671) (xy 212.221318 -135.939276) (xy 212.229954 -135.943594) (xy 212.316314 -135.948166)
			(xy 212.327028 -135.948299) (xy 212.347039 -135.940689) (xy 212.354922 -135.933434) (xy 216.27973 -132.008626)
			(xy 216.284721 -132.003128) (xy 216.291574 -131.989964) (xy 216.293192 -131.982718) (xy 216.294208 -131.973066)
			(xy 216.294208 -119.921782) (xy 216.294045 -119.915771) (xy 216.291228 -119.904085) (xy 216.28862 -119.898668)
			(xy 216.28678 -119.895194) (xy 216.282187 -119.888815) (xy 216.279476 -119.885968) (xy 215.984836 -119.591328)
			(xy 215.975184 -119.58828) (xy 215.949422 -119.579957) (xy 215.900368 -119.557055) (xy 215.85504 -119.527453)
			(xy 215.814349 -119.491744) (xy 215.77911 -119.450646) (xy 215.750031 -119.404981) (xy 215.727695 -119.355666)
			(xy 215.712548 -119.303691) (xy 215.704897 -119.250097) (xy 215.70442 -119.223028) (xy 215.704881 -119.195775)
			(xy 215.712635 -119.141822) (xy 215.727989 -119.089523) (xy 215.750631 -119.039941) (xy 215.780098 -118.994086)
			(xy 215.815792 -118.952892) (xy 215.856986 -118.917198) (xy 215.902841 -118.887731) (xy 215.952423 -118.865089)
			(xy 216.004722 -118.849735) (xy 216.058675 -118.841981) (xy 216.085928 -118.84152) (xy 216.08669 -118.84152)
			(xy 216.116326 -118.842104) (xy 216.174884 -118.851291) (xy 216.203276 -118.859808) (xy 216.210896 -118.862348)
			(xy 216.229946 -118.862348) (xy 216.23655 -118.86184) (xy 216.242141 -118.860974) (xy 216.252777 -118.857125)
			(xy 216.257632 -118.85422) (xy 216.288112 -118.832376) (xy 216.323672 -118.806976) (xy 216.328091 -118.803547)
			(xy 216.335399 -118.795082) (xy 216.33815 -118.790212) (xy 216.342722 -118.778274) (xy 216.343992 -118.76659)
			(xy 216.343992 -118.66499) (xy 216.343478 -118.654571) (xy 216.335203 -118.635444) (xy 216.32799 -118.627906)
			(xy 216.327482 -118.627652) (xy 216.32291 -118.623842) (xy 216.258394 -118.577106) (xy 216.25217 -118.573344)
			(xy 216.238231 -118.569225) (xy 216.230962 -118.568978) (xy 216.210896 -118.568978) (xy 216.206832 -118.570248)
			(xy 216.192608 -118.574566) (xy 216.168512 -118.580858) (xy 216.119205 -118.587865) (xy 216.09431 -118.588536)
			(xy 216.090754 -118.588536) (xy 216.08923 -118.588536) (xy 216.088722 -118.588536) (xy 216.06153 -118.587963)
			(xy 216.007719 -118.58006) (xy 215.955576 -118.564594) (xy 215.906157 -118.541881) (xy 215.860465 -118.51238)
			(xy 215.819425 -118.47669) (xy 215.783869 -118.435533) (xy 215.754518 -118.389745) (xy 215.731967 -118.340252)
			(xy 215.716673 -118.288059) (xy 215.708945 -118.234222) (xy 215.708484 -118.207028) (xy 215.708945 -118.179774)
			(xy 215.716699 -118.125819) (xy 215.732053 -118.073518) (xy 215.754693 -118.023933) (xy 215.784161 -117.978076)
			(xy 215.819854 -117.93688) (xy 215.861047 -117.901182) (xy 215.906902 -117.871711) (xy 215.956484 -117.849065)
			(xy 216.008784 -117.833707) (xy 216.062738 -117.825948) (xy 216.089992 -117.82552) (xy 216.091262 -117.82552)
			(xy 216.092024 -117.82552) (xy 216.121597 -117.826118) (xy 216.180025 -117.835306) (xy 216.208356 -117.843808)
			(xy 216.21242 -117.845078) (xy 216.221056 -117.846348) (xy 216.230272 -117.847342) (xy 216.248379 -117.843439)
			(xy 216.256362 -117.838728) (xy 216.301828 -117.805454) (xy 216.323418 -117.789452) (xy 216.326212 -117.787166)
			(xy 216.332054 -117.781324) (xy 216.334537 -117.778321) (xy 216.33862 -117.771685) (xy 216.340182 -117.768116)
			(xy 216.343992 -117.758718) (xy 216.343992 -116.774976) (xy 216.34392 -116.770968) (xy 216.342638 -116.763057)
			(xy 216.341452 -116.759228) (xy 216.340436 -116.75618) (xy 216.33688 -116.747544) (xy 216.330022 -116.740432)
			(xy 216.327736 -116.737638) (xy 216.325958 -116.735352) (xy 211.905088 -112.314482) (xy 211.888801 -112.297573)
			(xy 211.860796 -112.259894) (xy 211.838549 -112.218552) (xy 211.830158 -112.196626) (xy 211.830158 -112.195356)
			(xy 211.823808 -112.178592) (xy 211.82203 -112.171226) (xy 211.821268 -112.168178) (xy 211.821268 -112.167924)
			(xy 211.816469 -112.148014) (xy 211.811378 -112.107377) (xy 211.811108 -112.086898) (xy 211.811108 -105.461816)
			(xy 211.811108 -105.461562) (xy 211.811159 -105.449133) (xy 211.812939 -105.424341) (xy 211.814664 -105.412032)
			(xy 211.815172 -105.40873) (xy 211.817712 -105.395268) (xy 211.817712 -105.39476) (xy 211.820211 -105.383653)
			(xy 211.82657 -105.361789) (xy 211.830412 -105.351072) (xy 211.833206 -105.34396) (xy 211.833714 -105.34269)
			(xy 211.833968 -105.342182) (xy 211.94649 -105.070402) (xy 211.949284 -105.05694) (xy 211.949284 -104.881426)
			(xy 211.950011 -104.851072) (xy 211.961135 -104.79139) (xy 211.971382 -104.762808) (xy 211.971382 -104.7623)
			(xy 211.974684 -104.754426) (xy 212.941154 -102.420674) (xy 213.352888 -101.426264) (xy 213.35492 -101.41966)
			(xy 213.423754 -101.07295) (xy 213.468966 -100.845112) (xy 213.59622 -100.203254) (xy 213.597236 -100.193348)
			(xy 213.597236 -82.702146) (xy 213.59495 -82.697828) (xy 213.580034 -82.669402) (xy 213.558872 -82.608801)
			(xy 213.548122 -82.545518) (xy 213.547452 -82.513424) (xy 213.547452 -82.512916) (xy 213.547938 -82.485665)
			(xy 213.555694 -82.431717) (xy 213.571049 -82.379422) (xy 213.593691 -82.329845) (xy 213.623157 -82.283995)
			(xy 213.658848 -82.242804) (xy 213.700039 -82.207113) (xy 213.745889 -82.177647) (xy 213.795466 -82.155005)
			(xy 213.847761 -82.13965) (xy 213.901709 -82.131894) (xy 213.956211 -82.131894) (xy 214.010159 -82.13965)
			(xy 214.062454 -82.155005) (xy 214.112031 -82.177647) (xy 214.157881 -82.207113) (xy 214.199072 -82.242804)
			(xy 214.234763 -82.283995) (xy 214.264229 -82.329845) (xy 214.286871 -82.379422) (xy 214.302226 -82.431717)
			(xy 214.309982 -82.485665) (xy 214.310468 -82.512916) (xy 214.310468 -82.51317) (xy 214.310076 -82.537418)
			(xy 214.303913 -82.585523) (xy 214.29172 -82.632462) (xy 214.273692 -82.677484) (xy 214.262208 -82.698844)
			(xy 214.260684 -82.701638) (xy 214.260684 -90.166952) (xy 214.260684 -90.16873) (xy 214.261437 -90.178093)
			(xy 214.268773 -90.195367) (xy 214.281802 -90.208874) (xy 214.290148 -90.21318) (xy 214.29472 -90.214958)
			(xy 214.385398 -90.246454) (xy 214.392871 -90.248812) (xy 214.408524 -90.249342) (xy 214.416132 -90.24747)
			(xy 214.423752 -90.245184) (xy 214.436706 -90.236548) (xy 214.441786 -90.230198) (xy 214.459995 -90.208134)
			(xy 214.501895 -90.169188) (xy 214.549138 -90.136929) (xy 214.600665 -90.112081) (xy 214.655322 -90.095199)
			(xy 214.711887 -90.086662) (xy 214.74049 -90.08618) (xy 214.74176 -90.08618) (xy 214.778336 -90.087704)
			(xy 214.780622 -90.087958) (xy 214.781384 -90.087958) (xy 214.790494 -90.08841) (xy 214.808076 -90.083605)
			(xy 214.815674 -90.07856) (xy 214.874602 -90.026236) (xy 214.87638 -90.024458) (xy 214.876888 -90.02395)
			(xy 214.878158 -90.02268) (xy 214.883137 -90.017249) (xy 214.889982 -90.00421) (xy 214.89162 -89.997026)
			(xy 214.89162 -89.996518) (xy 214.892636 -89.98712) (xy 214.892636 -80.294226) (xy 214.893065 -80.266773)
			(xy 214.902141 -80.212628) (xy 214.91067 -80.18653) (xy 214.910924 -80.186276) (xy 214.911178 -80.185514)
			(xy 214.91194 -80.183736) (xy 214.912956 -80.181196) (xy 214.91321 -80.180688) (xy 214.920576 -80.162654)
			(xy 214.987124 -80.06715) (xy 214.992966 -80.060292) (xy 217.342974 -77.71003) (xy 217.347579 -77.704981)
			(xy 217.354153 -77.693007) (xy 217.355928 -77.686408) (xy 217.357452 -77.67447) (xy 217.357452 -77.534516)
			(xy 217.357937 -77.508428) (xy 217.366102 -77.456896) (xy 217.382232 -77.407276) (xy 217.405931 -77.360794)
			(xy 217.436614 -77.318594) (xy 217.454734 -77.29982) (xy 219.700094 -75.05446) (xy 219.705081 -75.048961)
			(xy 219.711922 -75.035793) (xy 219.713556 -75.028552) (xy 219.714572 -75.0189) (xy 219.714572 -68.013326)
			(xy 219.71381 -68.005198) (xy 219.71381 -68.004944) (xy 219.713556 -68.003674) (xy 219.711778 -67.993768)
			(xy 219.70873 -67.984116) (xy 219.707206 -67.980306) (xy 219.700856 -67.973448) (xy 219.693236 -67.966844)
			(xy 219.686632 -67.963034) (xy 219.67317 -67.956176) (xy 219.661994 -67.948556) (xy 219.640658 -67.928744)
			(xy 219.635192 -67.924498) (xy 219.622572 -67.918826) (xy 219.615766 -67.917568) (xy 219.60332 -67.917314)
			(xy 219.602304 -67.917314) (xy 219.600018 -67.917568) (xy 219.59001 -67.918471) (xy 219.569934 -67.919361)
			(xy 219.559886 -67.919346) (xy 219.534553 -67.918749) (xy 219.484377 -67.911671) (xy 219.435583 -67.898003)
			(xy 219.389032 -67.877985) (xy 219.345546 -67.85197) (xy 219.325444 -67.836542) (xy 219.32519 -67.836288)
			(xy 219.322142 -67.833748) (xy 219.316032 -67.830017) (xy 219.302367 -67.825763) (xy 219.295218 -67.825366)
			(xy 219.27185 -67.825366) (xy 219.266411 -67.825221) (xy 219.255782 -67.822909) (xy 219.250768 -67.820794)
			(xy 219.237052 -67.814444) (xy 219.232348 -67.812378) (xy 219.222367 -67.809943) (xy 219.21724 -67.809618)
			(xy 219.208604 -67.810126) (xy 219.201318 -67.811409) (xy 219.187891 -67.817605) (xy 219.182188 -67.822318)
			(xy 219.181934 -67.822572) (xy 219.160863 -67.840679) (xy 219.114469 -67.871238) (xy 219.064136 -67.894752)
			(xy 219.010927 -67.910724) (xy 218.955965 -67.918816) (xy 218.928188 -67.919346) (xy 218.92768 -67.919346)
			(xy 218.900427 -67.918859) (xy 218.846476 -67.911099) (xy 218.794178 -67.895741) (xy 218.744599 -67.873096)
			(xy 218.698746 -67.843626) (xy 218.657554 -67.807931) (xy 218.621862 -67.766738) (xy 218.592394 -67.720884)
			(xy 218.569752 -67.671303) (xy 218.554397 -67.619004) (xy 218.54664 -67.565053) (xy 218.54664 -67.510547)
			(xy 218.554397 -67.456596) (xy 218.569752 -67.404297) (xy 218.592394 -67.354716) (xy 218.621862 -67.308862)
			(xy 218.657554 -67.267669) (xy 218.698746 -67.231974) (xy 218.744599 -67.202504) (xy 218.794178 -67.179859)
			(xy 218.846476 -67.164501) (xy 218.900427 -67.156741) (xy 218.92768 -67.15633) (xy 218.928188 -67.15633)
			(xy 218.953814 -67.15676) (xy 219.0046 -67.163658) (xy 219.054002 -67.177305) (xy 219.101128 -67.197453)
			(xy 219.145126 -67.22374) (xy 219.165424 -67.239388) (xy 219.172028 -67.244468) (xy 219.183204 -67.248278)
			(xy 219.196666 -67.25031) (xy 219.216732 -67.25031) (xy 219.222742 -67.250475) (xy 219.234426 -67.253296)
			(xy 219.239846 -67.255898) (xy 219.2401 -67.256152) (xy 219.241116 -67.25666) (xy 219.242386 -67.257168)
			(xy 219.252292 -67.261994) (xy 219.263774 -67.266103) (xy 219.288052 -67.264247) (xy 219.298774 -67.258438)
			(xy 219.312998 -67.249294) (xy 219.3163 -67.2465) (xy 219.317824 -67.24523) (xy 219.318332 -67.244722)
			(xy 219.32138 -67.242182) (xy 219.32646 -67.237102) (xy 219.330092 -67.233277) (xy 219.335853 -67.224442)
			(xy 219.33789 -67.219576) (xy 219.339272 -67.215776) (xy 219.340923 -67.207862) (xy 219.341192 -67.203828)
			(xy 219.343732 -67.156076) (xy 219.343732 -67.155568) (xy 219.345256 -67.130422) (xy 219.345764 -67.11823)
			(xy 219.341954 -67.10807) (xy 219.339913 -67.103105) (xy 219.334014 -67.094138) (xy 219.33027 -67.09029)
			(xy 218.209876 -65.969896) (xy 218.207023 -65.967193) (xy 218.200642 -65.962606) (xy 218.197176 -65.960752)
			(xy 218.19175 -65.958164) (xy 218.18007 -65.955333) (xy 218.174062 -65.955164) (xy 215.946482 -65.955164)
			(xy 215.938354 -65.957958) (xy 215.910668 -65.966086) (xy 215.891162 -65.970541) (xy 215.851427 -65.975254)
			(xy 215.83142 -65.975484) (xy 215.156796 -65.975484) (xy 215.130774 -65.974953) (xy 215.079374 -65.966779)
			(xy 215.029881 -65.95068) (xy 214.983509 -65.927051) (xy 214.941395 -65.89647) (xy 214.922608 -65.878456)
			(xy 214.517732 -65.47358) (xy 214.507064 -65.46723) (xy 214.501222 -65.465452) (xy 214.473912 -65.456424)
			(xy 214.422163 -65.431316) (xy 214.374769 -65.398725) (xy 214.332802 -65.359391) (xy 214.297214 -65.314205)
			(xy 214.26881 -65.264189) (xy 214.248233 -65.210477) (xy 214.23595 -65.154286) (xy 214.23224 -65.096887)
			(xy 214.234268 -65.068196) (xy 214.234522 -65.066164) (xy 214.234522 -65.065402) (xy 214.235792 -65.052956)
			(xy 214.232998 -65.041526) (xy 214.231351 -65.036453) (xy 214.226231 -65.027099) (xy 214.222838 -65.022984)
			(xy 214.178642 -64.9732) (xy 214.170514 -64.964056) (xy 214.165816 -64.95972) (xy 214.154759 -64.953309)
			(xy 214.14867 -64.951356) (xy 214.148162 -64.951102) (xy 214.140288 -64.948816) (xy 213.61527 -64.948816)
			(xy 213.611664 -64.948881) (xy 213.604526 -64.949903) (xy 213.601046 -64.950848) (xy 213.596474 -64.952372)
			(xy 213.58733 -64.956182) (xy 212.560408 -65.983104) (xy 212.543536 -65.999375) (xy 212.505937 -66.027365)
			(xy 212.464683 -66.049617) (xy 212.442806 -66.058034) (xy 212.432138 -66.06159) (xy 212.424518 -66.064384)
			(xy 212.417406 -66.066416) (xy 212.417152 -66.066416) (xy 212.413088 -66.067178) (xy 212.411818 -66.067432)
			(xy 212.41131 -66.067432) (xy 212.384034 -66.076664) (xy 212.327323 -66.086625) (xy 212.298534 -66.087244)
			(xy 209.01787 -66.087244) (xy 209.013552 -66.08953) (xy 208.985127 -66.104449) (xy 208.924526 -66.125615)
			(xy 208.861243 -66.13637) (xy 208.829148 -66.137028) (xy 208.82864 -66.137028) (xy 208.801384 -66.136568)
			(xy 208.747426 -66.128815) (xy 208.69512 -66.113462) (xy 208.645532 -66.09082) (xy 208.599672 -66.061352)
			(xy 208.558472 -66.025656) (xy 208.522772 -65.98446) (xy 208.493299 -65.938603) (xy 208.470652 -65.889017)
			(xy 208.455293 -65.836713) (xy 208.447535 -65.782756) (xy 208.447535 -65.728244) (xy 208.455293 -65.674287)
			(xy 208.470652 -65.621983) (xy 208.493299 -65.572397) (xy 208.522772 -65.52654) (xy 208.558472 -65.485344)
			(xy 208.599672 -65.449648) (xy 208.645532 -65.42018) (xy 208.69512 -65.397538) (xy 208.747426 -65.382185)
			(xy 208.801384 -65.374432) (xy 208.82864 -65.374012) (xy 208.828894 -65.374012) (xy 208.853142 -65.374405)
			(xy 208.901245 -65.380571) (xy 208.948184 -65.392766) (xy 208.993204 -65.410796) (xy 209.014568 -65.422272)
			(xy 209.017362 -65.423796) (xy 212.139784 -65.423796) (xy 212.148928 -65.423034) (xy 212.156417 -65.421401)
			(xy 212.169986 -65.414286) (xy 212.175598 -65.409064) (xy 213.040976 -64.543432) (xy 213.202012 -64.382396)
			(xy 213.219044 -64.365924) (xy 213.256974 -64.337529) (xy 213.298568 -64.314836) (xy 213.32063 -64.306196)
			(xy 213.324694 -64.304672) (xy 213.331298 -64.302132) (xy 213.896702 -63.736474) (xy 213.897464 -63.735458)
			(xy 213.917623 -63.715279) (xy 213.963696 -63.681661) (xy 214.014969 -63.656681) (xy 214.042244 -63.648336)
			(xy 214.045038 -63.647828) (xy 214.047832 -63.647066) (xy 214.067911 -63.642056) (xy 214.10893 -63.636584)
			(xy 214.12962 -63.636144) (xy 216.2683 -63.636144) (xy 216.27545 -63.635756) (xy 216.289113 -63.631494)
			(xy 216.295224 -63.627762) (xy 216.302082 -63.622936) (xy 216.306654 -63.618872) (xy 216.311174 -63.614056)
			(xy 216.317738 -63.602601) (xy 216.319608 -63.596266) (xy 216.323164 -63.583312) (xy 216.327482 -63.572898)
			(xy 216.332054 -63.56096) (xy 216.333818 -63.556818) (xy 216.338547 -63.549159) (xy 216.341452 -63.54572)
			(xy 216.342468 -63.54445) (xy 216.346777 -63.539) (xy 216.352568 -63.526378) (xy 216.353898 -63.519558)
			(xy 216.354914 -63.5127) (xy 216.354152 -63.505842) (xy 216.353602 -63.502169) (xy 216.351555 -63.49503)
			(xy 216.350088 -63.491618) (xy 216.341452 -63.472314) (xy 216.341452 -63.471806) (xy 216.33688 -63.461392)
			(xy 216.330276 -63.454534) (xy 216.330022 -63.45428) (xy 216.329514 -63.453772) (xy 216.309283 -63.432375)
			(xy 216.274987 -63.384508) (xy 216.248451 -63.331942) (xy 216.230305 -63.275923) (xy 216.220979 -63.217781)
			(xy 216.220294 -63.188342) (xy 216.220294 -63.180214) (xy 216.221294 -63.151263) (xy 216.230965 -63.094148)
			(xy 216.249161 -63.039153) (xy 216.275462 -62.987541) (xy 216.309265 -62.940499) (xy 216.349792 -62.899109)
			(xy 216.396112 -62.864322) (xy 216.447158 -62.836939) (xy 216.501758 -62.817589) (xy 216.558656 -62.806717)
			(xy 216.587578 -62.805056) (xy 216.587832 -62.805056) (xy 216.601802 -62.804802) (xy 216.60231 -62.804802)
			(xy 216.627936 -62.805233) (xy 216.678721 -62.812134) (xy 216.728122 -62.825782) (xy 216.775246 -62.845931)
			(xy 216.819244 -62.872218) (xy 216.839546 -62.88786) (xy 216.84615 -62.89294) (xy 216.857326 -62.89675)
			(xy 216.870788 -62.898782) (xy 216.892632 -62.898782) (xy 216.896237 -62.898847) (xy 216.903375 -62.899871)
			(xy 216.906856 -62.900814) (xy 216.910412 -62.901576) (xy 216.96426 -62.901576) (xy 216.972864 -62.901241)
			(xy 216.989094 -62.895529) (xy 216.99601 -62.8904) (xy 216.996264 -62.890146) (xy 216.997026 -62.889638)
			(xy 217.001598 -62.886082) (xy 217.004138 -62.88405) (xy 217.0049 -62.883288) (xy 217.026998 -62.86754)
			(xy 217.028014 -62.867032) (xy 217.035888 -62.861698) (xy 217.039444 -62.859666) (xy 217.056082 -62.849894)
			(xy 217.090948 -62.833357) (xy 217.10904 -62.826646) (xy 217.109802 -62.826392) (xy 217.113612 -62.825122)
			(xy 217.138636 -62.817069) (xy 217.190257 -62.80713) (xy 217.216482 -62.80531) (xy 217.23604 -62.804802)
			(xy 217.236802 -62.804802) (xy 217.252804 -62.805056) (xy 217.257122 -62.80531) (xy 217.28653 -62.807454)
			(xy 217.344216 -62.819656) (xy 217.399343 -62.840574) (xy 217.450603 -62.86971) (xy 217.474038 -62.887606)
			(xy 217.474292 -62.88786) (xy 217.47734 -62.8904) (xy 217.483449 -62.894137) (xy 217.497114 -62.898399)
			(xy 217.504264 -62.898782) (xy 217.527632 -62.898782) (xy 217.533072 -62.898925) (xy 217.543704 -62.901232)
			(xy 217.548714 -62.903354) (xy 217.56243 -62.909704) (xy 217.567133 -62.911773) (xy 217.577114 -62.914214)
			(xy 217.582242 -62.91453) (xy 217.590878 -62.914022) (xy 217.598164 -62.91274) (xy 217.61159 -62.906542)
			(xy 217.617294 -62.90183) (xy 217.617548 -62.901576) (xy 217.638617 -62.883466) (xy 217.68501 -62.852901)
			(xy 217.735343 -62.829381) (xy 217.788553 -62.813405) (xy 217.843516 -62.805309) (xy 217.871294 -62.804802)
			(xy 217.871802 -62.804802) (xy 217.899054 -62.805265) (xy 217.953005 -62.813023) (xy 218.005302 -62.828379)
			(xy 218.054881 -62.851022) (xy 218.100733 -62.88049) (xy 218.141925 -62.916184) (xy 218.177617 -62.957377)
			(xy 218.207084 -63.00323) (xy 218.229725 -63.05281) (xy 218.24508 -63.105107) (xy 218.252835 -63.159057)
			(xy 218.25331 -63.18631) (xy 218.25274 -63.216037) (xy 218.243514 -63.27477) (xy 218.225285 -63.331361)
			(xy 218.198496 -63.384437) (xy 218.163796 -63.432714) (xy 218.143328 -63.45428) (xy 218.143074 -63.454534)
			(xy 218.136978 -63.460884) (xy 218.132914 -63.46952) (xy 218.129104 -63.477648) (xy 218.127072 -63.483744)
			(xy 218.124024 -63.497968) (xy 218.123157 -63.504155) (xy 218.124044 -63.516612) (xy 218.125802 -63.522606)
			(xy 218.144852 -63.569342) (xy 218.144852 -63.56985) (xy 218.160346 -63.606934) (xy 218.167204 -63.617856)
			(xy 218.174812 -63.626102) (xy 218.195113 -63.635587) (xy 218.20632 -63.636144) (xy 219.47124 -63.636144)
			(xy 219.483083 -63.635518) (xy 219.504267 -63.624919) (xy 219.51188 -63.615824) (xy 219.51188 -58.142124)
			(xy 219.51171 -58.136115) (xy 219.508879 -58.124436) (xy 219.506292 -58.11901) (xy 219.504454 -58.115535)
			(xy 219.499862 -58.109154) (xy 219.497148 -58.10631) (xy 219.126562 -57.735724) (xy 219.108453 -57.716942)
			(xy 219.077776 -57.674743) (xy 219.054083 -57.628261) (xy 219.03796 -57.578644) (xy 219.029804 -57.527114)
			(xy 219.02928 -57.501028) (xy 219.02928 -56.577992) (xy 219.025206 -56.572854) (xy 219.014911 -56.564741)
			(xy 219.00896 -56.56199) (xy 218.916504 -56.528208) (xy 218.90913 -56.525742) (xy 218.893608 -56.524968)
			(xy 218.886024 -56.526684) (xy 218.878658 -56.528716) (xy 218.86545 -56.537098) (xy 218.86037 -56.543194)
			(xy 218.842115 -56.564014) (xy 218.800631 -56.600686) (xy 218.754291 -56.630991) (xy 218.704063 -56.654293)
			(xy 218.650999 -56.670105) (xy 218.596209 -56.678096) (xy 218.568524 -56.678576) (xy 218.541272 -56.678114)
			(xy 218.487323 -56.670361) (xy 218.435027 -56.655008) (xy 218.385448 -56.632369) (xy 218.339596 -56.602904)
			(xy 218.298404 -56.567213) (xy 218.26271 -56.526024) (xy 218.233243 -56.480173) (xy 218.2106 -56.430596)
			(xy 218.195244 -56.3783) (xy 218.187487 -56.324352) (xy 218.187487 -56.269848) (xy 218.195244 -56.2159)
			(xy 218.2106 -56.163604) (xy 218.233243 -56.114027) (xy 218.26271 -56.068176) (xy 218.298404 -56.026987)
			(xy 218.339596 -55.991296) (xy 218.385448 -55.961831) (xy 218.435027 -55.939192) (xy 218.487323 -55.923839)
			(xy 218.541272 -55.916086) (xy 218.568524 -55.91556) (xy 218.5955 -55.916026) (xy 218.648916 -55.92362)
			(xy 218.700732 -55.938654) (xy 218.749917 -55.960828) (xy 218.795493 -55.989701) (xy 218.836554 -56.0247)
			(xy 218.854782 -56.044592) (xy 218.860624 -56.051196) (xy 218.876372 -56.06161) (xy 218.885614 -56.066299)
			(xy 218.906185 -56.068654) (xy 218.91625 -56.066182) (xy 218.972892 -56.045608) (xy 219.006166 -56.033416)
			(xy 219.012965 -56.030663) (xy 219.024705 -56.021878) (xy 219.02928 -56.016144) (xy 219.02928 -55.113428)
			(xy 219.029764 -55.08734) (xy 219.037928 -55.035807) (xy 219.054058 -54.986187) (xy 219.077757 -54.939705)
			(xy 219.108441 -54.897505) (xy 219.126562 -54.878732) (xy 221.050612 -52.954682) (xy 221.056962 -52.944014)
			(xy 221.05874 -52.938172) (xy 221.067175 -52.912592) (xy 221.090233 -52.863915) (xy 221.119905 -52.818964)
			(xy 221.155602 -52.77863) (xy 221.196615 -52.743716) (xy 221.242129 -52.714913) (xy 221.29124 -52.692796)
			(xy 221.342972 -52.677802) (xy 221.396299 -52.67023) (xy 221.450161 -52.67023) (xy 221.503488 -52.677802)
			(xy 221.55522 -52.692796) (xy 221.604331 -52.714913) (xy 221.649845 -52.743716) (xy 221.690858 -52.77863)
			(xy 221.726555 -52.818964) (xy 221.756227 -52.863915) (xy 221.779285 -52.912592) (xy 221.78772 -52.938172)
			(xy 221.789498 -52.944014) (xy 221.795848 -52.954682) (xy 221.890082 -53.048916) (xy 221.896094 -53.054456)
			(xy 221.910735 -53.061709) (xy 221.918784 -53.06314) (xy 221.933251 -53.064616) (xy 221.962001 -53.060349)
			(xy 221.975426 -53.054758) (xy 221.975934 -53.054758) (xy 221.987592 -53.048777) (xy 222.007648 -53.03193)
			(xy 222.015558 -53.021484) (xy 222.019604 -53.015074) (xy 222.024112 -53.00061) (xy 222.024448 -52.993036)
			(xy 222.024448 -48.51273) (xy 222.024279 -48.506721) (xy 222.021454 -48.495039) (xy 222.01886 -48.489616)
			(xy 222.017021 -48.486141) (xy 222.012428 -48.479762) (xy 222.009716 -48.476916) (xy 221.34703 -47.81423)
			(xy 221.336362 -47.80788) (xy 221.33052 -47.806102) (xy 221.304955 -47.797652) (xy 221.256309 -47.77457)
			(xy 221.21139 -47.744883) (xy 221.171087 -47.709179) (xy 221.1362 -47.668166) (xy 221.107422 -47.622659)
			(xy 221.085323 -47.57356) (xy 221.070341 -47.521843) (xy 221.062774 -47.468534) (xy 221.062296 -47.441612)
			(xy 221.062759 -47.414359) (xy 221.070514 -47.360407) (xy 221.085869 -47.308108) (xy 221.108511 -47.258526)
			(xy 221.137979 -47.212672) (xy 221.173672 -47.171478) (xy 221.214866 -47.135784) (xy 221.260719 -47.106315)
			(xy 221.3103 -47.083672) (xy 221.362599 -47.068316) (xy 221.416551 -47.060559) (xy 221.443804 -47.060104)
			(xy 221.470727 -47.060566) (xy 221.524039 -47.068132) (xy 221.575759 -47.083114) (xy 221.62486 -47.105213)
			(xy 221.67037 -47.133993) (xy 221.711385 -47.168881) (xy 221.74709 -47.209186) (xy 221.776779 -47.254108)
			(xy 221.799861 -47.302756) (xy 221.808294 -47.328328) (xy 221.810072 -47.33417) (xy 221.816422 -47.344838)
			(xy 222.280226 -47.808642) (xy 222.286237 -47.814183) (xy 222.300879 -47.821435) (xy 222.308928 -47.822866)
			(xy 222.323342 -47.824381) (xy 222.352008 -47.820203) (xy 222.378347 -47.80814) (xy 222.400236 -47.789164)
			(xy 222.415913 -47.764803) (xy 222.424115 -47.737019) (xy 222.424752 -47.722536) (xy 222.424752 -41.727882)
			(xy 222.424688 -41.724276) (xy 222.423667 -41.717138) (xy 222.42272 -41.713658) (xy 222.421196 -41.709086)
			(xy 222.417386 -41.699942) (xy 217.270838 -36.553394) (xy 217.25328 -36.53518) (xy 217.223538 -36.494258)
			(xy 217.200568 -36.449185) (xy 217.184938 -36.401071) (xy 217.177033 -36.351104) (xy 217.176604 -36.32581)
			(xy 217.176604 -29.63291) (xy 217.177206 -29.604943) (xy 217.186883 -29.549853) (xy 217.205948 -29.497268)
			(xy 217.233825 -29.448775) (xy 217.25128 -29.426916) (xy 217.252804 -29.425138) (xy 217.256868 -29.419296)
			(xy 217.25763 -29.418026) (xy 217.269822 -29.399484) (xy 217.278082 -29.388024) (xy 217.29627 -29.366407)
			(xy 217.306144 -29.356304) (xy 217.464132 -29.198316) (xy 217.785696 -28.877006) (xy 217.792183 -28.869547)
			(xy 217.799436 -28.851178) (xy 217.799242 -28.831429) (xy 217.795856 -28.822142) (xy 217.78468 -28.795218)
			(xy 217.778076 -28.7909) (xy 215.172798 -28.7909) (xy 215.146815 -28.790345) (xy 215.09553 -28.781948)
			(xy 215.046256 -28.765436) (xy 215.000267 -28.741236) (xy 214.958754 -28.709974) (xy 214.940388 -28.691586)
			(xy 214.939626 -28.69057) (xy 214.893398 -28.644342) (xy 214.02802 -27.77871) (xy 214.022268 -27.773334)
			(xy 214.008295 -27.766098) (xy 214.000588 -27.764486) (xy 213.991952 -27.763724) (xy 213.810596 -27.763724)
			(xy 213.800934 -27.764203) (xy 213.783021 -27.771467) (xy 213.76907 -27.784847) (xy 213.764622 -27.793442)
			(xy 213.752684 -27.821128) (xy 213.727284 -27.88031) (xy 213.725378 -27.885171) (xy 213.723334 -27.895409)
			(xy 213.72322 -27.90063) (xy 213.736936 -27.934666) (xy 213.743032 -27.941524) (xy 213.761826 -27.962673)
			(xy 213.794601 -28.008794) (xy 213.821441 -28.058603) (xy 213.841937 -28.111341) (xy 213.855775 -28.166202)
			(xy 213.862744 -28.222352) (xy 213.863174 -28.250642) (xy 213.86292 -28.734512) (xy 213.86292 -29.114242)
			(xy 213.86243 -29.14421) (xy 213.854607 -29.203632) (xy 213.839094 -29.261525) (xy 213.816158 -29.316898)
			(xy 213.786191 -29.368804) (xy 213.749704 -29.416354) (xy 213.707324 -29.458734) (xy 213.659774 -29.495221)
			(xy 213.607868 -29.525188) (xy 213.552495 -29.548124) (xy 213.494602 -29.563637) (xy 213.43518 -29.57146)
			(xy 213.375244 -29.57146) (xy 213.315822 -29.563637) (xy 213.257929 -29.548124) (xy 213.202556 -29.525188)
			(xy 213.15065 -29.495221) (xy 213.1031 -29.458734) (xy 213.06072 -29.416354) (xy 213.024233 -29.368804)
			(xy 212.994266 -29.316898) (xy 212.97133 -29.261525) (xy 212.955817 -29.203632) (xy 212.947994 -29.14421)
			(xy 212.947504 -29.114242) (xy 212.947504 -28.734512) (xy 212.94725 -28.250642) (xy 212.947675 -28.222353)
			(xy 212.954655 -28.166207) (xy 212.968501 -28.11135) (xy 212.989003 -28.058617) (xy 213.015847 -28.008812)
			(xy 213.048625 -27.962696) (xy 213.067392 -27.941524) (xy 213.073488 -27.934666) (xy 213.087204 -27.90063)
			(xy 213.087143 -27.895404) (xy 213.085098 -27.885156) (xy 213.08314 -27.88031) (xy 213.05774 -27.821128)
			(xy 213.045802 -27.793442) (xy 213.041406 -27.784817) (xy 213.027433 -27.77144) (xy 213.009498 -27.764192)
			(xy 212.999828 -27.763724) (xy 212.934042 -27.763724) (xy 212.908019 -27.763196) (xy 212.856617 -27.755028)
			(xy 212.807121 -27.738931) (xy 212.760746 -27.715303) (xy 212.718631 -27.684722) (xy 212.699854 -27.666696)
			(xy 211.648548 -26.615136) (xy 211.64463 -26.61139) (xy 211.635532 -26.605502) (xy 211.630514 -26.603452)
			(xy 211.620004 -26.600113) (xy 211.598032 -26.601713) (xy 211.588096 -26.6065) (xy 211.584032 -26.608786)
			(xy 211.570627 -26.618606) (xy 211.550505 -26.645022) (xy 211.539952 -26.676508) (xy 211.539328 -26.693114)
			(xy 211.539328 -27.342846) (xy 211.538838 -27.37283) (xy 211.53101 -27.432286) (xy 211.515489 -27.490211)
			(xy 211.49254 -27.545615) (xy 211.462556 -27.597549) (xy 211.42605 -27.645125) (xy 211.383645 -27.68753)
			(xy 211.336069 -27.724036) (xy 211.284135 -27.75402) (xy 211.228731 -27.776969) (xy 211.170806 -27.79249)
			(xy 211.11135 -27.800318) (xy 211.051382 -27.800318) (xy 210.991926 -27.79249) (xy 210.934001 -27.776969)
			(xy 210.878597 -27.75402) (xy 210.826663 -27.724036) (xy 210.779087 -27.68753) (xy 210.736682 -27.645125)
			(xy 210.700176 -27.597549) (xy 210.670192 -27.545615) (xy 210.647243 -27.490211) (xy 210.631722 -27.432286)
			(xy 210.623894 -27.37283) (xy 210.623404 -27.342846) (xy 210.623404 -26.479246) (xy 210.623935 -26.448026)
			(xy 210.632418 -26.386164) (xy 210.64922 -26.326026) (xy 210.67403 -26.268725) (xy 210.706388 -26.215323)
			(xy 210.745696 -26.166807) (xy 210.791225 -26.124076) (xy 210.842133 -26.08792) (xy 210.897478 -26.05901)
			(xy 210.92668 -26.047954) (xy 210.937094 -26.044144) (xy 210.952334 -26.029412) (xy 210.955636 -26.025602)
			(xy 210.958714 -26.021651) (xy 210.963452 -26.012828) (xy 210.965034 -26.008076) (xy 210.967828 -25.99563)
			(xy 210.967828 -25.995122) (xy 210.973416 -25.970992) (xy 210.974689 -25.961252) (xy 210.970641 -25.942049)
			(xy 210.965542 -25.933654) (xy 210.96351 -25.93086) (xy 210.959446 -25.926288) (xy 210.769962 -25.736804)
			(xy 210.767109 -25.734101) (xy 210.760727 -25.729515) (xy 210.757262 -25.72766) (xy 210.751836 -25.725074)
			(xy 210.740156 -25.722245) (xy 210.734148 -25.722072) (xy 208.479898 -25.722072) (xy 208.474056 -25.72512)
			(xy 208.468468 -25.727914) (xy 208.440968 -25.741687) (xy 208.382632 -25.761163) (xy 208.321927 -25.771027)
			(xy 208.291176 -25.771602) (xy 208.263926 -25.771115) (xy 208.209981 -25.763355) (xy 208.15769 -25.747998)
			(xy 208.108116 -25.725355) (xy 208.062269 -25.695888) (xy 208.021082 -25.660197) (xy 207.985394 -25.619007)
			(xy 207.95593 -25.573158) (xy 207.933292 -25.523582) (xy 207.917938 -25.471289) (xy 207.910183 -25.417344)
			(xy 207.909668 -25.390094) (xy 207.910156 -25.362164) (xy 207.918302 -25.306901) (xy 207.934419 -25.253416)
			(xy 207.958163 -25.202853) (xy 207.989026 -25.156293) (xy 208.026348 -25.11473) (xy 208.069331 -25.079054)
			(xy 208.117058 -25.050027) (xy 208.168507 -25.028269) (xy 208.195418 -25.020778) (xy 208.202276 -25.019)
			(xy 208.209134 -25.014936) (xy 208.21904 -25.007316) (xy 208.227168 -24.999188) (xy 208.235075 -24.99034)
			(xy 208.242481 -24.967826) (xy 208.241392 -24.956008) (xy 207.889602 -24.604218) (xy 207.864456 -24.578276)
			(xy 207.82004 -24.52129) (xy 207.78296 -24.45928) (xy 207.753775 -24.393186) (xy 207.732929 -24.324008)
			(xy 207.72628 -24.288496) (xy 207.722216 -24.263858) (xy 207.718165 -24.260143) (xy 207.708817 -24.254366)
			(xy 207.703674 -24.252428) (xy 207.636618 -24.231092) (xy 207.63611 -24.231092) (xy 207.623918 -24.227282)
			(xy 207.615282 -24.225504) (xy 207.608678 -24.224996) (xy 207.60309 -24.224996) (xy 207.593946 -24.228806)
			(xy 207.589382 -24.230812) (xy 207.581064 -24.236309) (xy 207.577436 -24.239728) (xy 207.392524 -24.42464)
			(xy 207.373754 -24.442674) (xy 207.331639 -24.473259) (xy 207.285263 -24.496889) (xy 207.235765 -24.512985)
			(xy 207.18436 -24.521152) (xy 207.158336 -24.521668) (xy 205.970124 -24.521668) (xy 205.965806 -24.523954)
			(xy 205.93738 -24.538868) (xy 205.876779 -24.560026) (xy 205.813496 -24.570773) (xy 205.781402 -24.571452)
			(xy 205.780894 -24.571452) (xy 205.75364 -24.570966) (xy 205.699687 -24.563208) (xy 205.647387 -24.54785)
			(xy 205.597804 -24.525206) (xy 205.551949 -24.495736) (xy 205.510755 -24.460041) (xy 205.47506 -24.418846)
			(xy 205.445591 -24.37299) (xy 205.422948 -24.323408) (xy 205.407591 -24.271108) (xy 205.399834 -24.217154)
			(xy 205.399834 -24.162646) (xy 205.407591 -24.108692) (xy 205.422948 -24.056392) (xy 205.445591 -24.00681)
			(xy 205.47506 -23.960954) (xy 205.510755 -23.919759) (xy 205.551949 -23.884064) (xy 205.597804 -23.854594)
			(xy 205.647387 -23.83195) (xy 205.699687 -23.816592) (xy 205.75364 -23.808834) (xy 205.780894 -23.808436)
			(xy 205.781148 -23.808436) (xy 205.805395 -23.808832) (xy 205.853496 -23.815005) (xy 205.90043 -23.827207)
			(xy 205.945447 -23.845242) (xy 205.966822 -23.856696) (xy 205.969616 -23.85822) (xy 206.999332 -23.85822)
			(xy 207.002634 -23.85822) (xy 207.011656 -23.857276) (xy 207.028197 -23.849862) (xy 207.034892 -23.843742)
			(xy 207.114902 -23.763478) (xy 207.154018 -23.724362) (xy 207.154272 -23.710646) (xy 207.15224 -23.701756)
			(xy 207.142842 -23.673562) (xy 207.142842 -23.673054) (xy 207.121506 -23.603712) (xy 207.11414 -23.597108)
			(xy 207.089502 -23.59279) (xy 207.056654 -23.586395) (xy 206.992578 -23.567079) (xy 206.931122 -23.540585)
			(xy 206.873088 -23.507257) (xy 206.81923 -23.467531) (xy 206.770253 -23.421924) (xy 206.726794 -23.371032)
			(xy 206.68942 -23.315516) (xy 206.658619 -23.256102) (xy 206.646272 -23.224998) (xy 206.63789 -23.203154)
			(xy 206.633857 -23.200571) (xy 206.625033 -23.196852) (xy 206.620364 -23.195788) (xy 206.571088 -23.185374)
			(xy 206.57058 -23.185374) (xy 206.534766 -23.177754) (xy 206.520542 -23.178008) (xy 206.258922 -23.439628)
			(xy 206.235346 -23.462576) (xy 206.183906 -23.503597) (xy 206.128196 -23.538601) (xy 206.068918 -23.567148)
			(xy 206.006816 -23.588877) (xy 205.942671 -23.603517) (xy 205.877291 -23.610883) (xy 205.844394 -23.611332)
			(xy 205.808966 -23.610797) (xy 205.738627 -23.602256) (xy 205.66983 -23.585298) (xy 205.603579 -23.560172)
			(xy 205.540839 -23.527243) (xy 205.482526 -23.486992) (xy 205.42949 -23.440006) (xy 205.382504 -23.386969)
			(xy 205.342254 -23.328655) (xy 205.309326 -23.265916) (xy 205.2842 -23.199664) (xy 205.267243 -23.130867)
			(xy 205.258703 -23.060528) (xy 205.258162 -23.0251) (xy 205.258623 -22.992204) (xy 205.265989 -22.926825)
			(xy 205.280629 -22.862682) (xy 205.302359 -22.800582) (xy 205.330905 -22.741305) (xy 205.365909 -22.685596)
			(xy 205.406929 -22.634157) (xy 205.429866 -22.610572) (xy 205.922626 -22.117812) (xy 205.9462 -22.094861)
			(xy 205.997638 -22.053832) (xy 206.053347 -22.018821) (xy 206.112625 -21.990267) (xy 206.174727 -21.96853)
			(xy 206.238873 -21.953884) (xy 206.304256 -21.946511) (xy 206.337154 -21.946108) (xy 206.35849 -21.946616)
			(xy 210.168998 -21.946616) (xy 210.170522 -21.94433) (xy 210.171538 -21.942806) (xy 210.202018 -21.892514)
			(xy 210.202018 -21.892006) (xy 210.217512 -21.866098) (xy 210.222338 -21.85416) (xy 210.223862 -21.842476)
			(xy 210.224116 -21.830792) (xy 210.218528 -21.818854) (xy 210.21802 -21.817838) (xy 210.20412 -21.790283)
			(xy 210.184434 -21.731793) (xy 210.174433 -21.670894) (xy 210.173824 -21.640038) (xy 210.173824 -21.63572)
			(xy 210.174592 -21.607317) (xy 210.183503 -21.551204) (xy 210.200641 -21.497034) (xy 210.225625 -21.446006)
			(xy 210.257903 -21.399249) (xy 210.276948 -21.378164) (xy 210.283806 -21.371052) (xy 210.287362 -21.362162)
			(xy 210.289902 -21.353018) (xy 210.290664 -21.344128) (xy 210.290664 -21.27377) (xy 210.2906 -21.269636)
			(xy 210.28933 -21.261468) (xy 210.288124 -21.257514) (xy 210.287362 -21.255736) (xy 210.28406 -21.2471)
			(xy 210.276948 -21.23948) (xy 210.257674 -21.218154) (xy 210.225104 -21.170791) (xy 210.200008 -21.119079)
			(xy 210.182953 -21.064186) (xy 210.174328 -21.007356) (xy 210.174325 -20.949876) (xy 210.182946 -20.893045)
			(xy 210.199996 -20.838151) (xy 210.225088 -20.786436) (xy 210.257654 -20.739071) (xy 210.276948 -20.717764)
			(xy 210.28406 -20.710144) (xy 210.287362 -20.701508) (xy 210.288124 -20.69973) (xy 210.289356 -20.695781)
			(xy 210.290633 -20.68761) (xy 210.290664 -20.683474) (xy 210.290664 -20.61337) (xy 210.2906 -20.609236)
			(xy 210.28933 -20.601068) (xy 210.288124 -20.597114) (xy 210.287362 -20.595336) (xy 210.28406 -20.5867)
			(xy 210.276948 -20.57908) (xy 210.257674 -20.557754) (xy 210.225104 -20.510391) (xy 210.200008 -20.458679)
			(xy 210.182953 -20.403786) (xy 210.174328 -20.346956) (xy 210.174325 -20.289476) (xy 210.182946 -20.232645)
			(xy 210.199996 -20.177751) (xy 210.225088 -20.126036) (xy 210.257654 -20.078671) (xy 210.276948 -20.057364)
			(xy 210.28406 -20.049744) (xy 210.287362 -20.041108) (xy 210.288124 -20.03933) (xy 210.289356 -20.035381)
			(xy 210.290633 -20.02721) (xy 210.290664 -20.023074) (xy 210.290664 -19.95297) (xy 210.2906 -19.948836)
			(xy 210.28933 -19.940668) (xy 210.288124 -19.936714) (xy 210.287362 -19.934936) (xy 210.28406 -19.9263)
			(xy 210.276948 -19.91868) (xy 210.257674 -19.897354) (xy 210.225104 -19.849991) (xy 210.200008 -19.798279)
			(xy 210.182953 -19.743386) (xy 210.174328 -19.686556) (xy 210.174325 -19.629076) (xy 210.182946 -19.572245)
			(xy 210.199996 -19.517351) (xy 210.225088 -19.465636) (xy 210.257654 -19.418271) (xy 210.276948 -19.396964)
			(xy 210.28406 -19.389344) (xy 210.287362 -19.380708) (xy 210.288124 -19.37893) (xy 210.289356 -19.374981)
			(xy 210.290633 -19.36681) (xy 210.290664 -19.362674) (xy 210.290664 -19.29257) (xy 210.2906 -19.288436)
			(xy 210.28933 -19.280268) (xy 210.288124 -19.276314) (xy 210.287362 -19.274536) (xy 210.28406 -19.2659)
			(xy 210.276948 -19.25828) (xy 210.257679 -19.236952) (xy 210.225118 -19.189588) (xy 210.200028 -19.137876)
			(xy 210.182979 -19.082987) (xy 210.174355 -19.02616) (xy 210.173824 -18.997422) (xy 210.17431 -18.970171)
			(xy 210.182066 -18.916223) (xy 210.197421 -18.863928) (xy 210.220063 -18.814351) (xy 210.249529 -18.768501)
			(xy 210.28522 -18.72731) (xy 210.326411 -18.691619) (xy 210.372261 -18.662153) (xy 210.421838 -18.639511)
			(xy 210.474133 -18.624156) (xy 210.528081 -18.6164) (xy 210.582583 -18.6164) (xy 210.636531 -18.624156)
			(xy 210.688826 -18.639511) (xy 210.738403 -18.662153) (xy 210.784253 -18.691619) (xy 210.825444 -18.72731)
			(xy 210.861135 -18.768501) (xy 210.890601 -18.814351) (xy 210.913243 -18.863928) (xy 210.928598 -18.916223)
			(xy 210.936354 -18.970171) (xy 210.93684 -18.997422) (xy 210.936317 -19.02616) (xy 210.927691 -19.082985)
			(xy 210.910636 -19.137873) (xy 210.885539 -19.18958) (xy 210.852969 -19.236937) (xy 210.833716 -19.25828)
			(xy 210.826604 -19.2659) (xy 210.823302 -19.274536) (xy 210.82254 -19.276314) (xy 210.82131 -19.280263)
			(xy 210.820039 -19.288434) (xy 210.82 -19.29257) (xy 210.82 -19.362674) (xy 210.820067 -19.366807)
			(xy 210.821343 -19.374974) (xy 210.82254 -19.37893) (xy 210.823302 -19.380708) (xy 210.826604 -19.389344)
			(xy 210.833716 -19.396964) (xy 210.852983 -19.418292) (xy 210.885542 -19.465655) (xy 210.910628 -19.517366)
			(xy 210.927673 -19.572254) (xy 210.936292 -19.629079) (xy 210.936289 -19.686553) (xy 210.927666 -19.743377)
			(xy 210.910616 -19.798264) (xy 210.885526 -19.849973) (xy 210.852963 -19.897333) (xy 210.833716 -19.91868)
			(xy 210.826604 -19.9263) (xy 210.823302 -19.934936) (xy 210.82254 -19.936714) (xy 210.82131 -19.940663)
			(xy 210.820039 -19.948834) (xy 210.82 -19.95297) (xy 210.82 -20.023074) (xy 210.820067 -20.027207)
			(xy 210.821343 -20.035374) (xy 210.82254 -20.03933) (xy 210.823302 -20.041108) (xy 210.826604 -20.049744)
			(xy 210.833716 -20.057364) (xy 210.852983 -20.078692) (xy 210.885542 -20.126055) (xy 210.910628 -20.177766)
			(xy 210.927673 -20.232654) (xy 210.936292 -20.289479) (xy 210.936289 -20.346953) (xy 210.927666 -20.403777)
			(xy 210.910616 -20.458664) (xy 210.885526 -20.510373) (xy 210.852963 -20.557733) (xy 210.833716 -20.57908)
			(xy 210.826604 -20.5867) (xy 210.823302 -20.595336) (xy 210.82254 -20.597114) (xy 210.82131 -20.601063)
			(xy 210.820039 -20.609234) (xy 210.82 -20.61337) (xy 210.82 -20.683474) (xy 210.820067 -20.687607)
			(xy 210.821343 -20.695774) (xy 210.82254 -20.69973) (xy 210.823302 -20.701508) (xy 210.826604 -20.710144)
			(xy 210.833716 -20.717764) (xy 210.852983 -20.739092) (xy 210.885542 -20.786455) (xy 210.910628 -20.838166)
			(xy 210.927673 -20.893054) (xy 210.936292 -20.949879) (xy 210.936289 -21.007353) (xy 210.927666 -21.064177)
			(xy 210.910616 -21.119064) (xy 210.885526 -21.170773) (xy 210.852963 -21.218133) (xy 210.833716 -21.23948)
			(xy 210.826604 -21.2471) (xy 210.823302 -21.255736) (xy 210.82254 -21.257514) (xy 210.82131 -21.261463)
			(xy 210.820039 -21.269634) (xy 210.82 -21.27377) (xy 210.82 -21.344128) (xy 210.820762 -21.353018)
			(xy 210.823302 -21.362162) (xy 210.826858 -21.371052) (xy 210.834224 -21.378672) (xy 210.853164 -21.39972)
			(xy 210.885256 -21.446369) (xy 210.910102 -21.497249) (xy 210.927155 -21.551241) (xy 210.936042 -21.607161)
			(xy 210.93684 -21.635466) (xy 210.93684 -21.63953) (xy 210.936239 -21.67047) (xy 210.926262 -21.73154)
			(xy 210.906572 -21.790204) (xy 210.892644 -21.817838) (xy 210.89112 -21.820632) (xy 210.888999 -21.825769)
			(xy 210.886814 -21.836664) (xy 210.886802 -21.842222) (xy 210.887056 -21.855684) (xy 210.908646 -21.892006)
			(xy 210.908646 -21.892514) (xy 210.939126 -21.942552) (xy 210.94192 -21.946616) (xy 215.366854 -21.946616)
			(xy 215.372188 -21.946362) (xy 215.380812 -21.945087) (xy 215.396515 -21.937544) (xy 215.402922 -21.93163)
			(xy 215.71458 -21.619718) (xy 215.721269 -21.61231) (xy 215.728861 -21.593874) (xy 215.729312 -21.583904)
			(xy 215.729312 -21.567902) (xy 215.726264 -21.555964) (xy 215.72347 -21.55063) (xy 215.709472 -21.523009)
			(xy 215.68961 -21.464361) (xy 215.679455 -21.40328) (xy 215.678766 -21.372322) (xy 215.678766 -21.36394)
			(xy 215.679761 -21.337046) (xy 215.688381 -21.283923) (xy 215.704383 -21.232539) (xy 215.727449 -21.183915)
			(xy 215.757122 -21.139016) (xy 215.792811 -21.098735) (xy 215.833808 -21.06387) (xy 215.879299 -21.035114)
			(xy 215.928381 -21.013039) (xy 215.980078 -20.998082) (xy 216.033365 -20.990541) (xy 216.060274 -20.990052)
			(xy 216.060528 -20.990052) (xy 216.07653 -20.990306) (xy 216.087198 -20.990814) (xy 216.096342 -20.987258)
			(xy 216.100707 -20.985507) (xy 216.108761 -20.980652) (xy 216.112344 -20.977606) (xy 216.12606 -20.964652)
			(xy 216.126568 -20.964144) (xy 216.168478 -20.923758) (xy 216.172288 -20.919186) (xy 216.172288 -19.452844)
			(xy 216.172853 -19.417134) (xy 216.181601 -19.346249) (xy 216.198898 -19.276954) (xy 216.22449 -19.210274)
			(xy 216.257996 -19.147199) (xy 216.298919 -19.088664) (xy 216.346653 -19.035536) (xy 216.373202 -19.011646)
			(xy 216.38387 -19.002248) (xy 216.385902 -18.99793) (xy 216.38791 -18.993217) (xy 216.390211 -18.983235)
			(xy 216.390474 -18.978118) (xy 216.391998 -18.922238) (xy 216.391998 -18.921476) (xy 216.392506 -18.906998)
			(xy 216.343992 -18.858738) (xy 216.317285 -18.831161) (xy 216.270577 -18.770235) (xy 216.232229 -18.703729)
			(xy 216.216992 -18.668492) (xy 216.202962 -18.633086) (xy 216.183142 -18.55955) (xy 216.173023 -18.484066)
			(xy 216.172288 -18.445988) (xy 216.172288 -18.44421) (xy 216.172822 -18.408796) (xy 216.181358 -18.338484)
			(xy 216.198307 -18.269714) (xy 216.223421 -18.203488) (xy 216.256334 -18.140772) (xy 216.296567 -18.082481)
			(xy 216.343533 -18.029464) (xy 216.396546 -17.982494) (xy 216.454835 -17.942257) (xy 216.517548 -17.909339)
			(xy 216.583772 -17.88422) (xy 216.652541 -17.867266) (xy 216.722852 -17.858725) (xy 216.758266 -17.858232)
			(xy 216.767664 -17.858232) (xy 216.804459 -17.85943) (xy 216.877335 -17.869874) (xy 216.948333 -17.889348)
			(xy 216.982548 -17.902936) (xy 217.017777 -17.918188) (xy 217.084279 -17.956538) (xy 217.145209 -18.003239)
			(xy 217.172794 -18.029936) (xy 217.503502 -18.360898) (xy 217.741246 -18.598642) (xy 217.764144 -18.622206)
			(xy 217.805098 -18.673589) (xy 217.840047 -18.729232) (xy 217.868551 -18.788435) (xy 217.890252 -18.850456)
			(xy 217.904877 -18.914515) (xy 217.912244 -18.979808) (xy 217.912696 -19.012662) (xy 217.912696 -21.474684)
			(xy 217.915628 -21.478426) (xy 217.922665 -21.484815) (xy 217.926666 -21.487384) (xy 217.932508 -21.49094)
			(xy 218.019884 -21.527516) (xy 218.0265 -21.530024) (xy 218.040547 -21.531688) (xy 218.04757 -21.530818)
			(xy 218.63685 -20.941538) (xy 218.637357 -20.937744) (xy 218.637359 -20.930091) (xy 218.63685 -20.926298)
			(xy 218.63685 -20.925536) (xy 218.631516 -20.892516) (xy 218.623642 -20.842986) (xy 218.620805 -20.83192)
			(xy 218.606917 -20.813809) (xy 218.596972 -20.808188) (xy 218.590114 -20.804632) (xy 218.564339 -20.79026)
			(xy 218.517162 -20.754808) (xy 218.475999 -20.712523) (xy 218.441828 -20.66441) (xy 218.415464 -20.611614)
			(xy 218.397532 -20.555391) (xy 218.388461 -20.49708) (xy 218.38793 -20.467574) (xy 218.388395 -20.440323)
			(xy 218.396155 -20.386377) (xy 218.411514 -20.334085) (xy 218.434158 -20.28451) (xy 218.463628 -20.238663)
			(xy 218.499322 -20.197477) (xy 218.540514 -20.161789) (xy 218.586367 -20.132328) (xy 218.635945 -20.109692)
			(xy 218.68824 -20.094342) (xy 218.742187 -20.086591) (xy 218.769438 -20.086066) (xy 218.796584 -20.086547)
			(xy 218.850328 -20.094249) (xy 218.902437 -20.109492) (xy 218.951859 -20.131968) (xy 218.997596 -20.161223)
			(xy 219.038724 -20.196666) (xy 219.074412 -20.237582) (xy 219.103939 -20.283144) (xy 219.126709 -20.332431)
			(xy 219.142262 -20.384448) (xy 219.150284 -20.438145) (xy 219.150946 -20.465288) (xy 219.150946 -20.467828)
			(xy 219.150349 -20.498333) (xy 219.140656 -20.558568) (xy 219.131642 -20.587716) (xy 219.130118 -20.592288)
			(xy 219.128848 -20.601432) (xy 219.128848 -20.601686) (xy 219.127324 -20.611338) (xy 219.130372 -20.623276)
			(xy 219.131495 -20.627114) (xy 219.134813 -20.634391) (xy 219.136976 -20.637754) (xy 219.14231 -20.645374)
			(xy 219.147898 -20.652994) (xy 219.152858 -20.659369) (xy 219.165945 -20.668819) (xy 219.173552 -20.671536)
			(xy 219.177324 -20.672683) (xy 219.185105 -20.673962) (xy 219.189046 -20.674076) (xy 220.724984 -20.674076)
			(xy 220.757838 -20.674535) (xy 220.823133 -20.68189) (xy 220.887195 -20.696509) (xy 220.949217 -20.718207)
			(xy 220.963594 -20.72513) (xy 237.380538 -20.72513) (xy 237.384508 -20.594996) (xy 237.396404 -20.465346)
			(xy 237.416183 -20.336663) (xy 237.443769 -20.209424) (xy 237.479062 -20.084105) (xy 237.521928 -19.961169)
			(xy 237.57221 -19.841076) (xy 237.629719 -19.724272) (xy 237.694243 -19.61119) (xy 237.76554 -19.502253)
			(xy 237.843345 -19.397865) (xy 237.92737 -19.298414) (xy 238.017302 -19.204271) (xy 238.112806 -19.115786)
			(xy 238.213526 -19.033287) (xy 238.319088 -18.957082) (xy 238.4291 -18.887455) (xy 238.543152 -18.824664)
			(xy 238.66082 -18.768942) (xy 238.781666 -18.720498) (xy 238.905241 -18.679511) (xy 239.031084 -18.646134)
			(xy 239.158729 -18.620491) (xy 239.287699 -18.602677) (xy 239.417515 -18.592759) (xy 239.547694 -18.590774)
			(xy 239.677753 -18.596728) (xy 239.807206 -18.610601) (xy 239.935573 -18.632339) (xy 240.062376 -18.661863)
			(xy 240.187143 -18.699062) (xy 240.30941 -18.743798) (xy 240.428723 -18.795906) (xy 240.544636 -18.855189)
			(xy 240.656721 -18.92143) (xy 240.764558 -18.99438) (xy 240.867747 -19.073768) (xy 240.965905 -19.1593)
			(xy 241.058666 -19.250657) (xy 241.145685 -19.347499) (xy 241.226638 -19.449466) (xy 241.301224 -19.556178)
			(xy 241.369165 -19.667239) (xy 241.43021 -19.782235) (xy 241.484131 -19.900739) (xy 241.530726 -20.02231)
			(xy 241.569824 -20.146495) (xy 241.601278 -20.272833) (xy 241.624972 -20.400854) (xy 241.640816 -20.53008)
			(xy 241.648754 -20.660033) (xy 241.64925 -20.72513) (xy 241.648754 -20.790227) (xy 241.640816 -20.92018)
			(xy 241.624972 -21.049406) (xy 241.601278 -21.177427) (xy 241.569824 -21.303765) (xy 241.530726 -21.42795)
			(xy 241.484131 -21.549521) (xy 241.43021 -21.668025) (xy 241.369165 -21.783021) (xy 241.301224 -21.894082)
			(xy 241.226638 -22.000794) (xy 241.145685 -22.102761) (xy 241.058666 -22.199603) (xy 240.965905 -22.29096)
			(xy 240.867747 -22.376492) (xy 240.764558 -22.45588) (xy 240.656721 -22.52883) (xy 240.544636 -22.595071)
			(xy 240.428723 -22.654354) (xy 240.30941 -22.706462) (xy 240.187143 -22.751198) (xy 240.062376 -22.788397)
			(xy 239.935573 -22.817921) (xy 239.807206 -22.839659) (xy 239.677753 -22.853532) (xy 239.547694 -22.859486)
			(xy 239.417515 -22.857501) (xy 239.287699 -22.847583) (xy 239.158729 -22.829769) (xy 239.031084 -22.804126)
			(xy 238.905241 -22.770749) (xy 238.781666 -22.729762) (xy 238.66082 -22.681318) (xy 238.543152 -22.625596)
			(xy 238.4291 -22.562805) (xy 238.319088 -22.493178) (xy 238.213526 -22.416973) (xy 238.112806 -22.334474)
			(xy 238.017302 -22.245989) (xy 237.92737 -22.151846) (xy 237.843345 -22.052395) (xy 237.76554 -21.948007)
			(xy 237.694243 -21.83907) (xy 237.629719 -21.725988) (xy 237.57221 -21.609184) (xy 237.521928 -21.489091)
			(xy 237.479062 -21.366155) (xy 237.443769 -21.240836) (xy 237.416183 -21.113597) (xy 237.396404 -20.984914)
			(xy 237.384508 -20.855264) (xy 237.380538 -20.72513) (xy 220.963594 -20.72513) (xy 221.008419 -20.746714)
			(xy 221.064058 -20.781669) (xy 221.115434 -20.822633) (xy 221.139004 -20.845526) (xy 221.387924 -21.094446)
			(xy 221.734888 -21.441156) (xy 221.757834 -21.464711) (xy 221.798854 -21.51611) (xy 221.833857 -21.571781)
			(xy 221.862403 -21.631023) (xy 221.884132 -21.693091) (xy 221.898771 -21.757202) (xy 221.906135 -21.822549)
			(xy 221.906476 -21.847048) (xy 222.172782 -21.847048) (xy 222.176853 -21.791426) (xy 222.188979 -21.736989)
			(xy 222.208902 -21.684898) (xy 222.236198 -21.636263) (xy 222.270284 -21.59212) (xy 222.310433 -21.553411)
			(xy 222.355791 -21.52096) (xy 222.405391 -21.495459) (xy 222.458175 -21.477452) (xy 222.513018 -21.467322)
			(xy 222.568752 -21.465285) (xy 222.624189 -21.471385) (xy 222.678146 -21.485491) (xy 222.729475 -21.507303)
			(xy 222.777081 -21.536357) (xy 222.819949 -21.572032) (xy 222.857166 -21.613569) (xy 222.887939 -21.660082)
			(xy 222.911611 -21.710579) (xy 222.927679 -21.763986) (xy 222.935799 -21.819162) (xy 222.936308 -21.847048)
			(xy 222.935799 -21.874934) (xy 222.927679 -21.93011) (xy 222.911611 -21.983517) (xy 222.887939 -22.034014)
			(xy 222.857166 -22.080527) (xy 222.819949 -22.122064) (xy 222.777081 -22.157739) (xy 222.729475 -22.186793)
			(xy 222.678146 -22.208605) (xy 222.624189 -22.222711) (xy 222.568752 -22.228811) (xy 222.513018 -22.226774)
			(xy 222.458175 -22.216644) (xy 222.405391 -22.198637) (xy 222.355791 -22.173136) (xy 222.310433 -22.140685)
			(xy 222.270284 -22.101976) (xy 222.236198 -22.057833) (xy 222.208902 -22.009198) (xy 222.188979 -21.957107)
			(xy 222.176853 -21.90267) (xy 222.172782 -21.847048) (xy 221.906476 -21.847048) (xy 221.906592 -21.85543)
			(xy 221.906592 -21.869908) (xy 221.906338 -21.87575) (xy 221.904649 -21.910354) (xy 221.894136 -21.978835)
			(xy 221.875616 -22.045597) (xy 221.849349 -22.109708) (xy 221.815702 -22.170271) (xy 221.775144 -22.226442)
			(xy 221.728241 -22.277436) (xy 221.67565 -22.322539) (xy 221.618105 -22.361122) (xy 221.556409 -22.392647)
			(xy 221.491425 -22.416672) (xy 221.42406 -22.432862) (xy 221.355256 -22.440991) (xy 221.320614 -22.441408)
			(xy 221.28774 -22.440981) (xy 221.222402 -22.43365) (xy 221.158296 -22.419047) (xy 221.09623 -22.397354)
			(xy 221.036985 -22.368845) (xy 220.981306 -22.333878) (xy 220.929895 -22.292894) (xy 220.90634 -22.269958)
			(xy 220.847666 -22.211284) (xy 220.841824 -22.210776) (xy 220.829378 -22.210776) (xy 220.820363 -22.211139)
			(xy 220.80345 -22.217389) (xy 220.796358 -22.222968) (xy 220.794834 -22.224238) (xy 220.768398 -22.245838)
			(xy 220.71139 -22.283398) (xy 220.650403 -22.314075) (xy 220.586262 -22.337455) (xy 220.519838 -22.35322)
			(xy 220.452032 -22.361157) (xy 220.417898 -22.361652) (xy 220.260164 -22.361652) (xy 220.25102 -22.370542)
			(xy 220.232478 -22.393656) (xy 220.199458 -22.43455) (xy 220.196918 -22.438614) (xy 220.193108 -22.447758)
			(xy 220.189044 -22.463506) (xy 220.191584 -22.474936) (xy 220.195431 -22.494203) (xy 220.199632 -22.533269)
			(xy 220.199966 -22.552914) (xy 220.199966 -22.553422) (xy 220.199966 -22.559264) (xy 220.199203 -22.586807)
			(xy 220.19073 -22.641249) (xy 220.174516 -22.693907) (xy 220.150899 -22.743686) (xy 220.12037 -22.789553)
			(xy 220.083563 -22.830553) (xy 220.041244 -22.865835) (xy 219.994291 -22.894665) (xy 219.943681 -22.916445)
			(xy 219.890465 -22.930721) (xy 219.863162 -22.934422) (xy 219.848938 -22.935946) (xy 219.815664 -22.937216)
			(xy 219.813632 -22.937216) (xy 219.7886 -22.936489) (xy 219.739042 -22.929276) (xy 219.690855 -22.915641)
			(xy 219.644866 -22.895817) (xy 219.601867 -22.870146) (xy 219.581984 -22.85492) (xy 219.56522 -22.84095)
			(xy 219.563696 -22.83968) (xy 219.561918 -22.838156) (xy 219.55379 -22.832822) (xy 219.543371 -22.827185)
			(xy 219.519796 -22.825205) (xy 219.508578 -22.829012) (xy 219.484702 -22.839426) (xy 219.484194 -22.839426)
			(xy 219.423234 -22.866604) (xy 219.421202 -22.86762) (xy 219.407486 -22.874478) (xy 219.40266 -22.882352)
			(xy 219.40266 -23.965154) (xy 220.177358 -23.965154) (xy 220.181429 -23.909532) (xy 220.193555 -23.855095)
			(xy 220.213478 -23.803004) (xy 220.240774 -23.754369) (xy 220.27486 -23.710226) (xy 220.315009 -23.671517)
			(xy 220.360367 -23.639066) (xy 220.409967 -23.613565) (xy 220.462751 -23.595558) (xy 220.517594 -23.585428)
			(xy 220.573328 -23.583391) (xy 220.628765 -23.589491) (xy 220.682722 -23.603597) (xy 220.734051 -23.625409)
			(xy 220.781657 -23.654463) (xy 220.824525 -23.690138) (xy 220.861742 -23.731675) (xy 220.892515 -23.778188)
			(xy 220.916187 -23.828685) (xy 220.932255 -23.882092) (xy 220.940375 -23.937268) (xy 220.94055 -23.946866)
			(xy 221.180404 -23.946866) (xy 221.184475 -23.891244) (xy 221.196601 -23.836807) (xy 221.216524 -23.784716)
			(xy 221.24382 -23.736081) (xy 221.277906 -23.691938) (xy 221.318055 -23.653229) (xy 221.363413 -23.620778)
			(xy 221.413013 -23.595277) (xy 221.465797 -23.57727) (xy 221.52064 -23.56714) (xy 221.576374 -23.565103)
			(xy 221.631811 -23.571203) (xy 221.685768 -23.585309) (xy 221.737097 -23.607121) (xy 221.784703 -23.636175)
			(xy 221.827571 -23.67185) (xy 221.864788 -23.713387) (xy 221.895561 -23.7599) (xy 221.919233 -23.810397)
			(xy 221.935301 -23.863804) (xy 221.943421 -23.91898) (xy 221.94393 -23.946866) (xy 221.94349 -23.970996)
			(xy 222.172782 -23.970996) (xy 222.176853 -23.915374) (xy 222.188979 -23.860937) (xy 222.208902 -23.808846)
			(xy 222.236198 -23.760211) (xy 222.270284 -23.716068) (xy 222.310433 -23.677359) (xy 222.355791 -23.644908)
			(xy 222.405391 -23.619407) (xy 222.458175 -23.6014) (xy 222.513018 -23.59127) (xy 222.568752 -23.589233)
			(xy 222.624189 -23.595333) (xy 222.678146 -23.609439) (xy 222.729475 -23.631251) (xy 222.777081 -23.660305)
			(xy 222.819949 -23.69598) (xy 222.857166 -23.737517) (xy 222.887939 -23.78403) (xy 222.911611 -23.834527)
			(xy 222.927679 -23.887934) (xy 222.935799 -23.94311) (xy 222.936308 -23.970996) (xy 222.935799 -23.998882)
			(xy 222.927679 -24.054058) (xy 222.911611 -24.107465) (xy 222.887939 -24.157962) (xy 222.857166 -24.204475)
			(xy 222.819949 -24.246012) (xy 222.777081 -24.281687) (xy 222.729475 -24.310741) (xy 222.678146 -24.332553)
			(xy 222.624189 -24.346659) (xy 222.568752 -24.352759) (xy 222.513018 -24.350722) (xy 222.458175 -24.340592)
			(xy 222.405391 -24.322585) (xy 222.355791 -24.297084) (xy 222.310433 -24.264633) (xy 222.270284 -24.225924)
			(xy 222.236198 -24.181781) (xy 222.208902 -24.133146) (xy 222.188979 -24.081055) (xy 222.176853 -24.026618)
			(xy 222.172782 -23.970996) (xy 221.94349 -23.970996) (xy 221.943421 -23.974752) (xy 221.935301 -24.029928)
			(xy 221.919233 -24.083335) (xy 221.895561 -24.133832) (xy 221.864788 -24.180345) (xy 221.827571 -24.221882)
			(xy 221.784703 -24.257557) (xy 221.737097 -24.286611) (xy 221.685768 -24.308423) (xy 221.631811 -24.322529)
			(xy 221.576374 -24.328629) (xy 221.52064 -24.326592) (xy 221.465797 -24.316462) (xy 221.413013 -24.298455)
			(xy 221.363413 -24.272954) (xy 221.318055 -24.240503) (xy 221.277906 -24.201794) (xy 221.24382 -24.157651)
			(xy 221.216524 -24.109016) (xy 221.196601 -24.056925) (xy 221.184475 -24.002488) (xy 221.180404 -23.946866)
			(xy 220.94055 -23.946866) (xy 220.940884 -23.965154) (xy 220.940375 -23.99304) (xy 220.932255 -24.048216)
			(xy 220.916187 -24.101623) (xy 220.892515 -24.15212) (xy 220.861742 -24.198633) (xy 220.824525 -24.24017)
			(xy 220.781657 -24.275845) (xy 220.734051 -24.304899) (xy 220.682722 -24.326711) (xy 220.628765 -24.340817)
			(xy 220.573328 -24.346917) (xy 220.517594 -24.34488) (xy 220.462751 -24.33475) (xy 220.409967 -24.316743)
			(xy 220.360367 -24.291242) (xy 220.315009 -24.258791) (xy 220.27486 -24.220082) (xy 220.240774 -24.175939)
			(xy 220.213478 -24.127304) (xy 220.193555 -24.075213) (xy 220.181429 -24.020776) (xy 220.177358 -23.965154)
			(xy 219.40266 -23.965154) (xy 219.40266 -24.807418) (xy 238.571276 -24.807418) (xy 238.575347 -24.751796)
			(xy 238.587473 -24.697359) (xy 238.607396 -24.645268) (xy 238.634692 -24.596633) (xy 238.668778 -24.55249)
			(xy 238.708927 -24.513781) (xy 238.754285 -24.48133) (xy 238.803885 -24.455829) (xy 238.856669 -24.437822)
			(xy 238.911512 -24.427692) (xy 238.967246 -24.425655) (xy 239.022683 -24.431755) (xy 239.07664 -24.445861)
			(xy 239.127969 -24.467673) (xy 239.175575 -24.496727) (xy 239.218443 -24.532402) (xy 239.25566 -24.573939)
			(xy 239.286433 -24.620452) (xy 239.310105 -24.670949) (xy 239.326173 -24.724356) (xy 239.334293 -24.779532)
			(xy 239.334802 -24.807418) (xy 239.334293 -24.835304) (xy 239.326173 -24.89048) (xy 239.310105 -24.943887)
			(xy 239.286433 -24.994384) (xy 239.25566 -25.040897) (xy 239.218443 -25.082434) (xy 239.175575 -25.118109)
			(xy 239.127969 -25.147163) (xy 239.07664 -25.168975) (xy 239.022683 -25.183081) (xy 238.967246 -25.189181)
			(xy 238.911512 -25.187144) (xy 238.856669 -25.177014) (xy 238.803885 -25.159007) (xy 238.754285 -25.133506)
			(xy 238.708927 -25.101055) (xy 238.668778 -25.062346) (xy 238.634692 -25.018203) (xy 238.607396 -24.969568)
			(xy 238.587473 -24.917477) (xy 238.575347 -24.86304) (xy 238.571276 -24.807418) (xy 219.40266 -24.807418)
			(xy 219.40266 -25.909778) (xy 219.402756 -25.914938) (xy 219.40481 -25.925051) (xy 219.406724 -25.929844)
			(xy 219.410788 -25.939242) (xy 219.416376 -25.944576) (xy 219.438474 -25.951434) (xy 219.467002 -25.960941)
			(xy 219.520924 -25.987548) (xy 219.570062 -26.022204) (xy 219.581946 -26.03373) (xy 237.4679 -26.03373)
			(xy 237.471971 -25.978108) (xy 237.484097 -25.923671) (xy 237.50402 -25.87158) (xy 237.531316 -25.822945)
			(xy 237.565402 -25.778802) (xy 237.605551 -25.740093) (xy 237.650909 -25.707642) (xy 237.700509 -25.682141)
			(xy 237.753293 -25.664134) (xy 237.808136 -25.654004) (xy 237.86387 -25.651967) (xy 237.919307 -25.658067)
			(xy 237.973264 -25.672173) (xy 238.024593 -25.693985) (xy 238.072199 -25.723039) (xy 238.115067 -25.758714)
			(xy 238.152284 -25.800251) (xy 238.183057 -25.846764) (xy 238.206729 -25.897261) (xy 238.222797 -25.950668)
			(xy 238.230917 -26.005844) (xy 238.231426 -26.03373) (xy 238.230917 -26.061616) (xy 238.222797 -26.116792)
			(xy 238.206729 -26.170199) (xy 238.183057 -26.220696) (xy 238.152284 -26.267209) (xy 238.115067 -26.308746)
			(xy 238.072199 -26.344421) (xy 238.024593 -26.373475) (xy 237.973264 -26.395287) (xy 237.919307 -26.409393)
			(xy 237.86387 -26.415493) (xy 237.808136 -26.413456) (xy 237.753293 -26.403326) (xy 237.700509 -26.385319)
			(xy 237.650909 -26.359818) (xy 237.605551 -26.327367) (xy 237.565402 -26.288658) (xy 237.531316 -26.244515)
			(xy 237.50402 -26.19588) (xy 237.484097 -26.143789) (xy 237.471971 -26.089352) (xy 237.4679 -26.03373)
			(xy 219.581946 -26.03373) (xy 219.613225 -26.064067) (xy 219.649366 -26.112123) (xy 219.664026 -26.138378)
			(xy 219.673691 -26.157078) (xy 219.689342 -26.196157) (xy 219.695268 -26.216356) (xy 219.697808 -26.22423)
			(xy 220.63583 -27.162252) (xy 220.653941 -27.181033) (xy 220.684622 -27.223232) (xy 220.708318 -27.269713)
			(xy 220.724445 -27.319331) (xy 220.732606 -27.370861) (xy 220.733112 -27.396948) (xy 220.733112 -28.139136)
			(xy 234.597954 -28.139136) (xy 234.602025 -28.083514) (xy 234.614151 -28.029077) (xy 234.634074 -27.976986)
			(xy 234.66137 -27.928351) (xy 234.695456 -27.884208) (xy 234.735605 -27.845499) (xy 234.780963 -27.813048)
			(xy 234.830563 -27.787547) (xy 234.883347 -27.76954) (xy 234.93819 -27.75941) (xy 234.993924 -27.757373)
			(xy 235.049361 -27.763473) (xy 235.103318 -27.777579) (xy 235.154647 -27.799391) (xy 235.202253 -27.828445)
			(xy 235.245121 -27.86412) (xy 235.282338 -27.905657) (xy 235.313111 -27.95217) (xy 235.336783 -28.002667)
			(xy 235.352851 -28.056074) (xy 235.360971 -28.11125) (xy 235.36148 -28.139136) (xy 235.867954 -28.139136)
			(xy 235.872025 -28.083514) (xy 235.884151 -28.029077) (xy 235.904074 -27.976986) (xy 235.93137 -27.928351)
			(xy 235.965456 -27.884208) (xy 236.005605 -27.845499) (xy 236.050963 -27.813048) (xy 236.100563 -27.787547)
			(xy 236.153347 -27.76954) (xy 236.20819 -27.75941) (xy 236.263924 -27.757373) (xy 236.319361 -27.763473)
			(xy 236.373318 -27.777579) (xy 236.424647 -27.799391) (xy 236.472253 -27.828445) (xy 236.515121 -27.86412)
			(xy 236.552338 -27.905657) (xy 236.583111 -27.95217) (xy 236.606783 -28.002667) (xy 236.622851 -28.056074)
			(xy 236.630971 -28.11125) (xy 236.63148 -28.139136) (xy 236.630971 -28.167022) (xy 236.622851 -28.222198)
			(xy 236.606783 -28.275605) (xy 236.583111 -28.326102) (xy 236.552338 -28.372615) (xy 236.515121 -28.414152)
			(xy 236.472253 -28.449827) (xy 236.424647 -28.478881) (xy 236.373318 -28.500693) (xy 236.319361 -28.514799)
			(xy 236.263924 -28.520899) (xy 236.20819 -28.518862) (xy 236.153347 -28.508732) (xy 236.100563 -28.490725)
			(xy 236.050963 -28.465224) (xy 236.005605 -28.432773) (xy 235.965456 -28.394064) (xy 235.93137 -28.349921)
			(xy 235.904074 -28.301286) (xy 235.884151 -28.249195) (xy 235.872025 -28.194758) (xy 235.867954 -28.139136)
			(xy 235.36148 -28.139136) (xy 235.360971 -28.167022) (xy 235.352851 -28.222198) (xy 235.336783 -28.275605)
			(xy 235.313111 -28.326102) (xy 235.282338 -28.372615) (xy 235.245121 -28.414152) (xy 235.202253 -28.449827)
			(xy 235.154647 -28.478881) (xy 235.103318 -28.500693) (xy 235.049361 -28.514799) (xy 234.993924 -28.520899)
			(xy 234.93819 -28.518862) (xy 234.883347 -28.508732) (xy 234.830563 -28.490725) (xy 234.780963 -28.465224)
			(xy 234.735605 -28.432773) (xy 234.695456 -28.394064) (xy 234.66137 -28.349921) (xy 234.634074 -28.301286)
			(xy 234.614151 -28.249195) (xy 234.602025 -28.194758) (xy 234.597954 -28.139136) (xy 220.733112 -28.139136)
			(xy 220.733112 -30.175962) (xy 220.732629 -30.202051) (xy 220.724468 -30.253586) (xy 220.708343 -30.30321)
			(xy 220.684649 -30.349698) (xy 220.664895 -30.376876) (xy 233.088942 -30.376876) (xy 233.089499 -30.34796)
			(xy 233.098218 -30.29079) (xy 233.115467 -30.235592) (xy 233.140851 -30.183629) (xy 233.173789 -30.136095)
			(xy 233.213525 -30.094077) (xy 233.236008 -30.075886) (xy 233.244813 -30.068276) (xy 233.254997 -30.047378)
			(xy 233.255566 -30.035754) (xy 233.255566 -29.955998) (xy 233.255026 -29.944366) (xy 233.244839 -29.923456)
			(xy 233.236008 -29.915866) (xy 233.21351 -29.897692) (xy 233.173775 -29.855669) (xy 233.140838 -29.808131)
			(xy 233.115452 -29.756166) (xy 233.098199 -29.700965) (xy 233.089474 -29.643793) (xy 233.088942 -29.614876)
			(xy 233.089428 -29.587625) (xy 233.097184 -29.533677) (xy 233.112539 -29.481382) (xy 233.135181 -29.431805)
			(xy 233.164647 -29.385955) (xy 233.200338 -29.344764) (xy 233.241529 -29.309073) (xy 233.287379 -29.279607)
			(xy 233.336956 -29.256965) (xy 233.389251 -29.24161) (xy 233.443199 -29.233854) (xy 233.497701 -29.233854)
			(xy 233.551649 -29.24161) (xy 233.603944 -29.256965) (xy 233.653521 -29.279607) (xy 233.699371 -29.309073)
			(xy 233.740562 -29.344764) (xy 233.776253 -29.385955) (xy 233.805719 -29.431805) (xy 233.828361 -29.481382)
			(xy 233.843716 -29.533677) (xy 233.851472 -29.587625) (xy 233.851958 -29.614876) (xy 233.851438 -29.643793)
			(xy 233.842712 -29.700965) (xy 233.825455 -29.756164) (xy 233.800064 -29.808126) (xy 233.76712 -29.85566)
			(xy 233.727378 -29.897676) (xy 233.704892 -29.915866) (xy 233.696109 -29.923497) (xy 233.685912 -29.944379)
			(xy 233.685334 -29.955998) (xy 233.685334 -30.035754) (xy 233.685845 -30.04739) (xy 233.696053 -30.0683)
			(xy 233.704892 -30.075886) (xy 233.727367 -30.094087) (xy 233.767103 -30.136104) (xy 233.800043 -30.183637)
			(xy 233.825433 -30.235597) (xy 233.842691 -30.290792) (xy 233.851422 -30.347961) (xy 233.851958 -30.376876)
			(xy 233.851472 -30.404127) (xy 233.843716 -30.458075) (xy 233.828361 -30.51037) (xy 233.805719 -30.559947)
			(xy 233.776253 -30.605797) (xy 233.740562 -30.646988) (xy 233.699371 -30.682679) (xy 233.653521 -30.712145)
			(xy 233.603944 -30.734787) (xy 233.551649 -30.750142) (xy 233.497701 -30.757898) (xy 233.443199 -30.757898)
			(xy 233.389251 -30.750142) (xy 233.336956 -30.734787) (xy 233.287379 -30.712145) (xy 233.241529 -30.682679)
			(xy 233.200338 -30.646988) (xy 233.164647 -30.605797) (xy 233.135181 -30.559947) (xy 233.112539 -30.51037)
			(xy 233.097184 -30.458075) (xy 233.089428 -30.404127) (xy 233.088942 -30.376876) (xy 220.664895 -30.376876)
			(xy 220.653972 -30.391904) (xy 220.63583 -30.410658) (xy 219.726256 -31.319978) (xy 219.720968 -31.325692)
			(xy 219.713849 -31.339529) (xy 219.712286 -31.347156) (xy 219.711524 -31.355792) (xy 219.711524 -31.567882)
			(xy 233.198668 -31.567882) (xy 233.202739 -31.51226) (xy 233.214865 -31.457823) (xy 233.234788 -31.405732)
			(xy 233.262084 -31.357097) (xy 233.29617 -31.312954) (xy 233.336319 -31.274245) (xy 233.381677 -31.241794)
			(xy 233.431277 -31.216293) (xy 233.484061 -31.198286) (xy 233.538904 -31.188156) (xy 233.594638 -31.186119)
			(xy 233.650075 -31.192219) (xy 233.704032 -31.206325) (xy 233.755361 -31.228137) (xy 233.802967 -31.257191)
			(xy 233.845835 -31.292866) (xy 233.883052 -31.334403) (xy 233.913825 -31.380916) (xy 233.937497 -31.431413)
			(xy 233.953565 -31.48482) (xy 233.961685 -31.539996) (xy 233.962194 -31.567882) (xy 233.961685 -31.595768)
			(xy 233.953565 -31.650944) (xy 233.937497 -31.704351) (xy 233.930505 -31.719266) (xy 234.485432 -31.719266)
			(xy 234.489503 -31.663644) (xy 234.501629 -31.609207) (xy 234.521552 -31.557116) (xy 234.548848 -31.508481)
			(xy 234.582934 -31.464338) (xy 234.623083 -31.425629) (xy 234.668441 -31.393178) (xy 234.718041 -31.367677)
			(xy 234.770825 -31.34967) (xy 234.825668 -31.33954) (xy 234.881402 -31.337503) (xy 234.936839 -31.343603)
			(xy 234.990796 -31.357709) (xy 235.042125 -31.379521) (xy 235.089731 -31.408575) (xy 235.132599 -31.44425)
			(xy 235.169816 -31.485787) (xy 235.200589 -31.5323) (xy 235.224261 -31.582797) (xy 235.240329 -31.636204)
			(xy 235.244479 -31.664402) (xy 235.76102 -31.664402) (xy 235.765091 -31.60878) (xy 235.777217 -31.554343)
			(xy 235.79714 -31.502252) (xy 235.824436 -31.453617) (xy 235.858522 -31.409474) (xy 235.898671 -31.370765)
			(xy 235.944029 -31.338314) (xy 235.993629 -31.312813) (xy 236.046413 -31.294806) (xy 236.101256 -31.284676)
			(xy 236.15699 -31.282639) (xy 236.212427 -31.288739) (xy 236.266384 -31.302845) (xy 236.317713 -31.324657)
			(xy 236.365319 -31.353711) (xy 236.408187 -31.389386) (xy 236.445404 -31.430923) (xy 236.476177 -31.477436)
			(xy 236.499849 -31.527933) (xy 236.515917 -31.58134) (xy 236.524037 -31.636516) (xy 236.524546 -31.664402)
			(xy 236.524037 -31.692288) (xy 236.515917 -31.747464) (xy 236.499849 -31.800871) (xy 236.476177 -31.851368)
			(xy 236.445404 -31.897881) (xy 236.408187 -31.939418) (xy 236.365319 -31.975093) (xy 236.317713 -32.004147)
			(xy 236.266384 -32.025959) (xy 236.212427 -32.040065) (xy 236.15699 -32.046165) (xy 236.101256 -32.044128)
			(xy 236.046413 -32.033998) (xy 235.993629 -32.015991) (xy 235.944029 -31.99049) (xy 235.898671 -31.958039)
			(xy 235.858522 -31.91933) (xy 235.824436 -31.875187) (xy 235.79714 -31.826552) (xy 235.777217 -31.774461)
			(xy 235.765091 -31.720024) (xy 235.76102 -31.664402) (xy 235.244479 -31.664402) (xy 235.248449 -31.69138)
			(xy 235.248958 -31.719266) (xy 235.248449 -31.747152) (xy 235.240329 -31.802328) (xy 235.224261 -31.855735)
			(xy 235.200589 -31.906232) (xy 235.169816 -31.952745) (xy 235.132599 -31.994282) (xy 235.089731 -32.029957)
			(xy 235.042125 -32.059011) (xy 234.990796 -32.080823) (xy 234.936839 -32.094929) (xy 234.881402 -32.101029)
			(xy 234.825668 -32.098992) (xy 234.770825 -32.088862) (xy 234.718041 -32.070855) (xy 234.668441 -32.045354)
			(xy 234.623083 -32.012903) (xy 234.582934 -31.974194) (xy 234.548848 -31.930051) (xy 234.521552 -31.881416)
			(xy 234.501629 -31.829325) (xy 234.489503 -31.774888) (xy 234.485432 -31.719266) (xy 233.930505 -31.719266)
			(xy 233.913825 -31.754848) (xy 233.883052 -31.801361) (xy 233.845835 -31.842898) (xy 233.802967 -31.878573)
			(xy 233.755361 -31.907627) (xy 233.704032 -31.929439) (xy 233.650075 -31.943545) (xy 233.594638 -31.949645)
			(xy 233.538904 -31.947608) (xy 233.484061 -31.937478) (xy 233.431277 -31.919471) (xy 233.381677 -31.89397)
			(xy 233.336319 -31.861519) (xy 233.29617 -31.82281) (xy 233.262084 -31.778667) (xy 233.234788 -31.730032)
			(xy 233.214865 -31.677941) (xy 233.202739 -31.623504) (xy 233.198668 -31.567882) (xy 219.711524 -31.567882)
			(xy 219.711524 -35.264852) (xy 236.102396 -35.264852) (xy 236.106467 -35.20923) (xy 236.118593 -35.154793)
			(xy 236.138516 -35.102702) (xy 236.165812 -35.054067) (xy 236.199898 -35.009924) (xy 236.240047 -34.971215)
			(xy 236.285405 -34.938764) (xy 236.335005 -34.913263) (xy 236.387789 -34.895256) (xy 236.442632 -34.885126)
			(xy 236.498366 -34.883089) (xy 236.553803 -34.889189) (xy 236.60776 -34.903295) (xy 236.659089 -34.925107)
			(xy 236.706695 -34.954161) (xy 236.749563 -34.989836) (xy 236.78678 -35.031373) (xy 236.817553 -35.077886)
			(xy 236.841225 -35.128383) (xy 236.857293 -35.18179) (xy 236.865413 -35.236966) (xy 236.865922 -35.264852)
			(xy 236.865413 -35.292738) (xy 236.857293 -35.347914) (xy 236.841225 -35.401321) (xy 236.817553 -35.451818)
			(xy 236.78678 -35.498331) (xy 236.749563 -35.539868) (xy 236.706695 -35.575543) (xy 236.659089 -35.604597)
			(xy 236.60776 -35.626409) (xy 236.553803 -35.640515) (xy 236.498366 -35.646615) (xy 236.442632 -35.644578)
			(xy 236.387789 -35.634448) (xy 236.335005 -35.616441) (xy 236.285405 -35.59094) (xy 236.240047 -35.558489)
			(xy 236.199898 -35.51978) (xy 236.165812 -35.475637) (xy 236.138516 -35.427002) (xy 236.118593 -35.374911)
			(xy 236.106467 -35.320474) (xy 236.102396 -35.264852) (xy 219.711524 -35.264852) (xy 219.711524 -35.401504)
			(xy 219.711575 -35.405576) (xy 219.712846 -35.41362) (xy 219.714064 -35.417506) (xy 219.716075 -35.423027)
			(xy 219.722242 -35.433026) (xy 219.726256 -35.437318) (xy 220.165698 -35.876738) (xy 224.917252 -35.876738)
			(xy 224.921323 -35.821116) (xy 224.933449 -35.766679) (xy 224.953372 -35.714588) (xy 224.980668 -35.665953)
			(xy 225.014754 -35.62181) (xy 225.054903 -35.583101) (xy 225.100261 -35.55065) (xy 225.149861 -35.525149)
			(xy 225.202645 -35.507142) (xy 225.257488 -35.497012) (xy 225.313222 -35.494975) (xy 225.368659 -35.501075)
			(xy 225.422616 -35.515181) (xy 225.473945 -35.536993) (xy 225.521551 -35.566047) (xy 225.564419 -35.601722)
			(xy 225.601636 -35.643259) (xy 225.632409 -35.689772) (xy 225.656081 -35.740269) (xy 225.672149 -35.793676)
			(xy 225.680269 -35.848852) (xy 225.680778 -35.876738) (xy 225.680281 -35.903948) (xy 228.989916 -35.903948)
			(xy 228.989916 -35.849452) (xy 228.997672 -35.795511) (xy 229.013025 -35.743222) (xy 229.035663 -35.69365)
			(xy 229.065125 -35.647805) (xy 229.100812 -35.606619) (xy 229.141997 -35.570931) (xy 229.187842 -35.541468)
			(xy 229.237412 -35.518828) (xy 229.289701 -35.503474) (xy 229.343642 -35.495717) (xy 229.37089 -35.49523)
			(xy 229.401693 -35.495846) (xy 229.462494 -35.505768) (xy 229.520907 -35.52534) (xy 229.548436 -35.539172)
			(xy 229.548944 -35.539426) (xy 229.554265 -35.541901) (xy 229.565684 -35.544596) (xy 229.57155 -35.54476)
			(xy 233.18216 -35.54476) (xy 233.208248 -35.54524) (xy 233.259781 -35.553404) (xy 233.3094 -35.569536)
			(xy 233.355881 -35.593239) (xy 233.398077 -35.623927) (xy 233.416856 -35.642042) (xy 234.061762 -36.286948)
			(xy 237.400336 -36.286948) (xy 237.404407 -36.231326) (xy 237.416533 -36.176889) (xy 237.436456 -36.124798)
			(xy 237.463752 -36.076163) (xy 237.497838 -36.03202) (xy 237.537987 -35.993311) (xy 237.583345 -35.96086)
			(xy 237.632945 -35.935359) (xy 237.685729 -35.917352) (xy 237.740572 -35.907222) (xy 237.796306 -35.905185)
			(xy 237.851743 -35.911285) (xy 237.9057 -35.925391) (xy 237.957029 -35.947203) (xy 238.004635 -35.976257)
			(xy 238.047503 -36.011932) (xy 238.08472 -36.053469) (xy 238.115493 -36.099982) (xy 238.139165 -36.150479)
			(xy 238.155233 -36.203886) (xy 238.163353 -36.259062) (xy 238.163862 -36.286948) (xy 238.163353 -36.314834)
			(xy 238.155233 -36.37001) (xy 238.139165 -36.423417) (xy 238.115493 -36.473914) (xy 238.08472 -36.520427)
			(xy 238.047503 -36.561964) (xy 238.004635 -36.597639) (xy 237.957029 -36.626693) (xy 237.9057 -36.648505)
			(xy 237.851743 -36.662611) (xy 237.796306 -36.668711) (xy 237.740572 -36.666674) (xy 237.685729 -36.656544)
			(xy 237.632945 -36.638537) (xy 237.583345 -36.613036) (xy 237.537987 -36.580585) (xy 237.497838 -36.541876)
			(xy 237.463752 -36.497733) (xy 237.436456 -36.449098) (xy 237.416533 -36.397007) (xy 237.404407 -36.34257)
			(xy 237.400336 -36.286948) (xy 234.061762 -36.286948) (xy 235.548932 -37.774118) (xy 237.66475 -37.774118)
			(xy 237.668821 -37.718496) (xy 237.680947 -37.664059) (xy 237.70087 -37.611968) (xy 237.728166 -37.563333)
			(xy 237.762252 -37.51919) (xy 237.802401 -37.480481) (xy 237.847759 -37.44803) (xy 237.897359 -37.422529)
			(xy 237.950143 -37.404522) (xy 238.004986 -37.394392) (xy 238.06072 -37.392355) (xy 238.116157 -37.398455)
			(xy 238.170114 -37.412561) (xy 238.221443 -37.434373) (xy 238.269049 -37.463427) (xy 238.311917 -37.499102)
			(xy 238.349134 -37.540639) (xy 238.379907 -37.587152) (xy 238.403579 -37.637649) (xy 238.419647 -37.691056)
			(xy 238.427767 -37.746232) (xy 238.428276 -37.774118) (xy 238.427767 -37.802004) (xy 238.419647 -37.85718)
			(xy 238.403579 -37.910587) (xy 238.379907 -37.961084) (xy 238.349134 -38.007597) (xy 238.311917 -38.049134)
			(xy 238.269049 -38.084809) (xy 238.221443 -38.113863) (xy 238.170114 -38.135675) (xy 238.116157 -38.149781)
			(xy 238.06072 -38.155881) (xy 238.004986 -38.153844) (xy 237.950143 -38.143714) (xy 237.897359 -38.125707)
			(xy 237.847759 -38.100206) (xy 237.802401 -38.067755) (xy 237.762252 -38.029046) (xy 237.728166 -37.984903)
			(xy 237.70087 -37.936268) (xy 237.680947 -37.884177) (xy 237.668821 -37.82974) (xy 237.66475 -37.774118)
			(xy 235.548932 -37.774118) (xy 242.28552 -44.510706) (xy 242.303527 -44.5295) (xy 242.33411 -44.571611)
			(xy 242.357741 -44.617982) (xy 242.373842 -44.667473) (xy 242.382016 -44.718872) (xy 242.382548 -44.744894)
			(xy 242.382548 -57.21477) (xy 242.382059 -57.240795) (xy 242.373886 -57.292201) (xy 242.357784 -57.3417)
			(xy 242.334148 -57.388075) (xy 242.303557 -57.430189) (xy 242.28552 -57.448958) (xy 241.48542 -58.249058)
			(xy 241.478765 -58.256493) (xy 241.471165 -58.274916) (xy 241.471158 -58.294845) (xy 241.478743 -58.313274)
			(xy 241.48542 -58.320686) (xy 242.679982 -59.515248) (xy 242.69807 -59.534051) (xy 242.728757 -59.576243)
			(xy 242.752461 -59.622719) (xy 242.768599 -59.672331) (xy 242.776774 -59.723858) (xy 242.777264 -59.749944)
			(xy 242.777264 -73.61809) (xy 242.776796 -73.644178) (xy 242.768628 -73.695711) (xy 242.752493 -73.74533)
			(xy 242.728788 -73.791811) (xy 242.698097 -73.834007) (xy 242.679982 -73.852786) (xy 242.243356 -74.289412)
			(xy 242.224577 -74.307436) (xy 242.182462 -74.338017) (xy 242.136088 -74.361645) (xy 242.086593 -74.377742)
			(xy 242.035191 -74.385911) (xy 242.009168 -74.38644) (xy 241.494564 -74.38644) (xy 241.488413 -74.38662)
			(xy 241.476473 -74.389583) (xy 241.470942 -74.392282) (xy 241.44341 -74.406106) (xy 241.384996 -74.425675)
			(xy 241.324198 -74.435612) (xy 241.293396 -74.436224) (xy 241.266146 -74.435705) (xy 241.212201 -74.427949)
			(xy 241.159909 -74.412594) (xy 241.110335 -74.389954) (xy 241.064487 -74.360489) (xy 241.023299 -74.324799)
			(xy 240.987609 -74.28361) (xy 240.958144 -74.237762) (xy 240.935505 -74.188187) (xy 240.92015 -74.135895)
			(xy 240.912394 -74.08195) (xy 240.912394 -74.02745) (xy 240.92015 -73.973505) (xy 240.935505 -73.921213)
			(xy 240.958144 -73.871638) (xy 240.987609 -73.82579) (xy 241.023299 -73.784601) (xy 241.064487 -73.748911)
			(xy 241.110335 -73.719446) (xy 241.159909 -73.696806) (xy 241.212201 -73.681451) (xy 241.266146 -73.673695)
			(xy 241.293396 -73.673208) (xy 241.324198 -73.673824) (xy 241.384999 -73.683747) (xy 241.443413 -73.703318)
			(xy 241.470942 -73.71715) (xy 241.476459 -73.719881) (xy 241.48841 -73.722827) (xy 241.494564 -73.722992)
			(xy 241.850164 -73.722992) (xy 241.860231 -73.72255) (xy 241.87883 -73.714841) (xy 241.886232 -73.708006)
			(xy 242.098322 -73.495662) (xy 242.105174 -73.488272) (xy 242.112886 -73.469665) (xy 242.113308 -73.459594)
			(xy 242.113308 -59.90844) (xy 242.112886 -59.89837) (xy 242.105165 -59.879771) (xy 242.098322 -59.872372)
			(xy 240.887504 -58.661554) (xy 240.883097 -58.657454) (xy 240.872843 -58.651159) (xy 240.867184 -58.649108)
			(xy 240.866676 -58.649108) (xy 240.841124 -58.64065) (xy 240.792489 -58.617593) (xy 240.74758 -58.587927)
			(xy 240.707286 -58.552243) (xy 240.67241 -58.511248) (xy 240.643644 -58.465757) (xy 240.621558 -58.416674)
			(xy 240.606593 -58.364973) (xy 240.599044 -58.311682) (xy 240.599062 -58.257859) (xy 240.606647 -58.204573)
			(xy 240.621648 -58.152883) (xy 240.643767 -58.103814) (xy 240.672564 -58.058343) (xy 240.707468 -58.017372)
			(xy 240.747786 -57.981715) (xy 240.792715 -57.95208) (xy 240.841365 -57.929056) (xy 240.86693 -57.920636)
			(xy 240.867184 -57.920636) (xy 240.872883 -57.918671) (xy 240.883154 -57.912365) (xy 240.887504 -57.90819)
			(xy 241.704114 -57.091834) (xy 241.710933 -57.084418) (xy 241.718665 -57.065831) (xy 241.7191 -57.055766)
			(xy 241.7191 -55.194454) (xy 241.71872 -55.185221) (xy 241.712162 -55.167959) (xy 241.699912 -55.15414)
			(xy 241.691922 -55.149496) (xy 241.61242 -55.107332) (xy 241.60409 -55.103389) (xy 241.58581 -55.101142)
			(xy 241.567917 -55.105503) (xy 241.560096 -55.11038) (xy 241.536182 -55.126052) (xy 241.48469 -55.150899)
			(xy 241.430071 -55.167797) (xy 241.373544 -55.176368) (xy 241.344958 -55.176928) (xy 241.31771 -55.176399)
			(xy 241.26377 -55.168638) (xy 241.211483 -55.15328) (xy 241.161914 -55.130638) (xy 241.116071 -55.101172)
			(xy 241.074888 -55.065482) (xy 241.039203 -55.024295) (xy 241.009742 -54.978449) (xy 240.987105 -54.928878)
			(xy 240.971753 -54.876589) (xy 240.963998 -54.822648) (xy 240.963998 -54.768152) (xy 240.971753 -54.714211)
			(xy 240.987105 -54.661922) (xy 241.009742 -54.612351) (xy 241.039203 -54.566505) (xy 241.074888 -54.525318)
			(xy 241.116071 -54.489628) (xy 241.161914 -54.460162) (xy 241.211483 -54.43752) (xy 241.26377 -54.422162)
			(xy 241.31771 -54.414401) (xy 241.344958 -54.413912) (xy 241.37355 -54.414421) (xy 241.430091 -54.422963)
			(xy 241.484721 -54.439862) (xy 241.53621 -54.464737) (xy 241.560096 -54.48046) (xy 241.567922 -54.485326)
			(xy 241.585811 -54.489682) (xy 241.604086 -54.487438) (xy 241.61242 -54.483508) (xy 241.691922 -54.441344)
			(xy 241.699901 -54.436685) (xy 241.712152 -54.422875) (xy 241.718702 -54.405616) (xy 241.7191 -54.396386)
			(xy 241.7191 -51.27625) (xy 241.702082 -51.250596) (xy 241.687604 -51.244754) (xy 241.678224 -51.241374)
			(xy 241.658302 -51.241389) (xy 241.639888 -51.248993) (xy 241.632486 -51.255676) (xy 238.687102 -54.20106)
			(xy 239.961418 -54.20106) (xy 239.965489 -54.145438) (xy 239.977615 -54.091001) (xy 239.997538 -54.03891)
			(xy 240.024834 -53.990275) (xy 240.05892 -53.946132) (xy 240.099069 -53.907423) (xy 240.144427 -53.874972)
			(xy 240.194027 -53.849471) (xy 240.246811 -53.831464) (xy 240.301654 -53.821334) (xy 240.357388 -53.819297)
			(xy 240.412825 -53.825397) (xy 240.466782 -53.839503) (xy 240.518111 -53.861315) (xy 240.565717 -53.890369)
			(xy 240.608585 -53.926044) (xy 240.645802 -53.967581) (xy 240.676575 -54.014094) (xy 240.700247 -54.064591)
			(xy 240.716315 -54.117998) (xy 240.724435 -54.173174) (xy 240.724944 -54.20106) (xy 240.724435 -54.228946)
			(xy 240.716315 -54.284122) (xy 240.700247 -54.337529) (xy 240.676575 -54.388026) (xy 240.645802 -54.434539)
			(xy 240.608585 -54.476076) (xy 240.565717 -54.511751) (xy 240.518111 -54.540805) (xy 240.466782 -54.562617)
			(xy 240.412825 -54.576723) (xy 240.357388 -54.582823) (xy 240.301654 -54.580786) (xy 240.246811 -54.570656)
			(xy 240.194027 -54.552649) (xy 240.144427 -54.527148) (xy 240.099069 -54.494697) (xy 240.05892 -54.455988)
			(xy 240.024834 -54.411845) (xy 239.997538 -54.36321) (xy 239.977615 -54.311119) (xy 239.965489 -54.256682)
			(xy 239.961418 -54.20106) (xy 238.687102 -54.20106) (xy 238.485934 -54.402228) (xy 238.481824 -54.406627)
			(xy 238.475535 -54.416887) (xy 238.473488 -54.422548) (xy 238.473488 -54.423056) (xy 238.464995 -54.448584)
			(xy 238.441929 -54.497186) (xy 238.412264 -54.542065) (xy 238.376589 -54.582332) (xy 238.335611 -54.617189)
			(xy 238.290143 -54.645943) (xy 238.241086 -54.668025) (xy 238.189414 -54.682997) (xy 238.136151 -54.690562)
			(xy 238.109252 -54.691026) (xy 238.082 -54.690567) (xy 238.028053 -54.682804) (xy 237.975759 -54.667444)
			(xy 237.926182 -54.644799) (xy 237.880333 -54.615329) (xy 237.839144 -54.579635) (xy 237.803453 -54.538443)
			(xy 237.773987 -54.492591) (xy 237.751345 -54.443013) (xy 237.735989 -54.390718) (xy 237.728231 -54.33677)
			(xy 237.727744 -54.309518) (xy 237.72814 -54.282605) (xy 237.735729 -54.229316) (xy 237.75073 -54.177623)
			(xy 237.772846 -54.12855) (xy 237.801638 -54.083071) (xy 237.836534 -54.042089) (xy 237.876843 -54.006417)
			(xy 237.921764 -53.976763) (xy 237.970406 -53.953715) (xy 237.995968 -53.945282) (xy 237.996222 -53.945282)
			(xy 238.00191 -53.943291) (xy 238.012188 -53.937003) (xy 238.016542 -53.932836) (xy 241.30889 -50.640742)
			(xy 241.315703 -50.63332) (xy 241.323439 -50.614738) (xy 241.323876 -50.604674) (xy 241.323876 -45.137578)
			(xy 241.323468 -45.127507) (xy 241.315736 -45.108909) (xy 241.30889 -45.10151) (xy 236.52607 -40.31869)
			(xy 236.518675 -40.311843) (xy 236.500072 -40.304128) (xy 236.490002 -40.303704) (xy 232.678986 -40.303704)
			(xy 232.672835 -40.303885) (xy 232.660894 -40.306846) (xy 232.655364 -40.309546) (xy 232.627826 -40.323359)
			(xy 232.569415 -40.342933) (xy 232.508619 -40.352874) (xy 232.477818 -40.353488) (xy 232.450563 -40.353066)
			(xy 232.396607 -40.345311) (xy 232.344304 -40.329956) (xy 232.294719 -40.307313) (xy 232.248861 -40.277844)
			(xy 232.207664 -40.242148) (xy 232.171967 -40.200953) (xy 232.142496 -40.155097) (xy 232.119851 -40.105513)
			(xy 232.104493 -40.053211) (xy 232.096735 -39.999255) (xy 232.096735 -39.944745) (xy 232.104493 -39.890789)
			(xy 232.119851 -39.838487) (xy 232.142496 -39.788903) (xy 232.171967 -39.743047) (xy 232.207664 -39.701852)
			(xy 232.248861 -39.666156) (xy 232.294719 -39.636687) (xy 232.344304 -39.614044) (xy 232.396607 -39.598689)
			(xy 232.450563 -39.590934) (xy 232.477818 -39.590472) (xy 232.508621 -39.591083) (xy 232.569422 -39.601009)
			(xy 232.627835 -39.620581) (xy 232.655364 -39.634414) (xy 232.660893 -39.637117) (xy 232.672834 -39.640081)
			(xy 232.678986 -39.640256) (xy 236.369098 -39.640256) (xy 236.394752 -39.623238) (xy 236.400594 -39.60876)
			(xy 236.403939 -39.599368) (xy 236.403943 -39.579453) (xy 236.396351 -39.561042) (xy 236.389672 -39.553642)
			(xy 233.059732 -36.223702) (xy 233.052315 -36.216884) (xy 233.033729 -36.209151) (xy 233.023664 -36.208716)
			(xy 230.971852 -36.208716) (xy 230.959905 -36.209314) (xy 230.938567 -36.220059) (xy 230.930958 -36.22929)
			(xy 230.875078 -36.304982) (xy 230.871268 -36.328858) (xy 230.874824 -36.340288) (xy 230.882873 -36.367916)
			(xy 230.89155 -36.424801) (xy 230.892096 -36.453572) (xy 230.89161 -36.480823) (xy 230.883854 -36.534771)
			(xy 230.868499 -36.587066) (xy 230.845857 -36.636643) (xy 230.816391 -36.682493) (xy 230.7807 -36.723684)
			(xy 230.739509 -36.759375) (xy 230.693659 -36.788841) (xy 230.644082 -36.811483) (xy 230.591787 -36.826838)
			(xy 230.537839 -36.834594) (xy 230.483337 -36.834594) (xy 230.429389 -36.826838) (xy 230.377094 -36.811483)
			(xy 230.327517 -36.788841) (xy 230.281667 -36.759375) (xy 230.240476 -36.723684) (xy 230.204785 -36.682493)
			(xy 230.175319 -36.636643) (xy 230.152677 -36.587066) (xy 230.137322 -36.534771) (xy 230.129566 -36.480823)
			(xy 230.12908 -36.453572) (xy 230.129613 -36.4248) (xy 230.138288 -36.367912) (xy 230.146352 -36.340288)
			(xy 230.149908 -36.328858) (xy 230.146098 -36.304982) (xy 230.090218 -36.22929) (xy 230.08261 -36.220067)
			(xy 230.061265 -36.209351) (xy 230.049324 -36.208716) (xy 229.565454 -36.208716) (xy 229.554278 -36.211256)
			(xy 229.548944 -36.21405) (xy 229.547928 -36.214558) (xy 229.520449 -36.228272) (xy 229.462204 -36.247729)
			(xy 229.401594 -36.257609) (xy 229.37089 -36.258246) (xy 229.343642 -36.257683) (xy 229.289701 -36.249926)
			(xy 229.237412 -36.234572) (xy 229.187842 -36.211932) (xy 229.141997 -36.182469) (xy 229.100812 -36.146781)
			(xy 229.065125 -36.105595) (xy 229.035663 -36.05975) (xy 229.013025 -36.010178) (xy 228.997672 -35.957889)
			(xy 228.989916 -35.903948) (xy 225.680281 -35.903948) (xy 225.680269 -35.904624) (xy 225.672149 -35.9598)
			(xy 225.656081 -36.013207) (xy 225.632409 -36.063704) (xy 225.601636 -36.110217) (xy 225.564419 -36.151754)
			(xy 225.521551 -36.187429) (xy 225.473945 -36.216483) (xy 225.422616 -36.238295) (xy 225.368659 -36.252401)
			(xy 225.313222 -36.258501) (xy 225.257488 -36.256464) (xy 225.202645 -36.246334) (xy 225.149861 -36.228327)
			(xy 225.100261 -36.202826) (xy 225.054903 -36.170375) (xy 225.014754 -36.131666) (xy 224.980668 -36.087523)
			(xy 224.953372 -36.038888) (xy 224.933449 -35.986797) (xy 224.921323 -35.93236) (xy 224.917252 -35.876738)
			(xy 220.165698 -35.876738) (xy 220.798951 -36.50996) (xy 226.81387 -36.50996) (xy 226.817941 -36.454338)
			(xy 226.830067 -36.399901) (xy 226.84999 -36.34781) (xy 226.877286 -36.299175) (xy 226.911372 -36.255032)
			(xy 226.951521 -36.216323) (xy 226.996879 -36.183872) (xy 227.046479 -36.158371) (xy 227.099263 -36.140364)
			(xy 227.154106 -36.130234) (xy 227.20984 -36.128197) (xy 227.265277 -36.134297) (xy 227.319234 -36.148403)
			(xy 227.370563 -36.170215) (xy 227.418169 -36.199269) (xy 227.461037 -36.234944) (xy 227.498254 -36.276481)
			(xy 227.529027 -36.322994) (xy 227.552699 -36.373491) (xy 227.568767 -36.426898) (xy 227.576887 -36.482074)
			(xy 227.577396 -36.50996) (xy 227.576887 -36.537846) (xy 227.568767 -36.593022) (xy 227.552699 -36.646429)
			(xy 227.529027 -36.696926) (xy 227.498254 -36.743439) (xy 227.461037 -36.784976) (xy 227.418169 -36.820651)
			(xy 227.370563 -36.849705) (xy 227.319234 -36.871517) (xy 227.265277 -36.885623) (xy 227.20984 -36.891723)
			(xy 227.154106 -36.889686) (xy 227.099263 -36.879556) (xy 227.046479 -36.861549) (xy 226.996879 -36.836048)
			(xy 226.951521 -36.803597) (xy 226.911372 -36.764888) (xy 226.877286 -36.720745) (xy 226.84999 -36.67211)
			(xy 226.830067 -36.620019) (xy 226.817941 -36.565582) (xy 226.81387 -36.50996) (xy 220.798951 -36.50996)
			(xy 221.764199 -37.47516) (xy 223.959164 -37.47516) (xy 223.963235 -37.419538) (xy 223.975361 -37.365101)
			(xy 223.995284 -37.31301) (xy 224.02258 -37.264375) (xy 224.056666 -37.220232) (xy 224.096815 -37.181523)
			(xy 224.142173 -37.149072) (xy 224.191773 -37.123571) (xy 224.244557 -37.105564) (xy 224.2994 -37.095434)
			(xy 224.355134 -37.093397) (xy 224.410571 -37.099497) (xy 224.464528 -37.113603) (xy 224.515857 -37.135415)
			(xy 224.563463 -37.164469) (xy 224.606331 -37.200144) (xy 224.643548 -37.241681) (xy 224.674321 -37.288194)
			(xy 224.697993 -37.338691) (xy 224.714061 -37.392098) (xy 224.722181 -37.447274) (xy 224.72269 -37.47516)
			(xy 224.722181 -37.503046) (xy 224.714061 -37.558222) (xy 224.697993 -37.611629) (xy 224.674321 -37.662126)
			(xy 224.674168 -37.662358) (xy 226.14839 -37.662358) (xy 226.152461 -37.606736) (xy 226.164587 -37.552299)
			(xy 226.18451 -37.500208) (xy 226.211806 -37.451573) (xy 226.245892 -37.40743) (xy 226.286041 -37.368721)
			(xy 226.331399 -37.33627) (xy 226.380999 -37.310769) (xy 226.433783 -37.292762) (xy 226.488626 -37.282632)
			(xy 226.54436 -37.280595) (xy 226.599797 -37.286695) (xy 226.653754 -37.300801) (xy 226.705083 -37.322613)
			(xy 226.752689 -37.351667) (xy 226.795557 -37.387342) (xy 226.832774 -37.428879) (xy 226.863547 -37.475392)
			(xy 226.887219 -37.525889) (xy 226.903287 -37.579296) (xy 226.911407 -37.634472) (xy 226.911916 -37.662358)
			(xy 226.911407 -37.690244) (xy 226.903287 -37.74542) (xy 226.887219 -37.798827) (xy 226.863547 -37.849324)
			(xy 226.832774 -37.895837) (xy 226.795557 -37.937374) (xy 226.752689 -37.973049) (xy 226.705083 -38.002103)
			(xy 226.653754 -38.023915) (xy 226.599797 -38.038021) (xy 226.54436 -38.044121) (xy 226.488626 -38.042084)
			(xy 226.433783 -38.031954) (xy 226.380999 -38.013947) (xy 226.331399 -37.988446) (xy 226.286041 -37.955995)
			(xy 226.245892 -37.917286) (xy 226.211806 -37.873143) (xy 226.18451 -37.824508) (xy 226.164587 -37.772417)
			(xy 226.152461 -37.71798) (xy 226.14839 -37.662358) (xy 224.674168 -37.662358) (xy 224.643548 -37.708639)
			(xy 224.606331 -37.750176) (xy 224.563463 -37.785851) (xy 224.515857 -37.814905) (xy 224.464528 -37.836717)
			(xy 224.410571 -37.850823) (xy 224.355134 -37.856923) (xy 224.2994 -37.854886) (xy 224.244557 -37.844756)
			(xy 224.191773 -37.826749) (xy 224.142173 -37.801248) (xy 224.096815 -37.768797) (xy 224.056666 -37.730088)
			(xy 224.02258 -37.685945) (xy 223.995284 -37.63731) (xy 223.975361 -37.585219) (xy 223.963235 -37.530782)
			(xy 223.959164 -37.47516) (xy 221.764199 -37.47516) (xy 223.019049 -38.729948) (xy 229.90102 -38.729948)
			(xy 229.90102 -38.675452) (xy 229.908775 -38.621512) (xy 229.924128 -38.569224) (xy 229.946766 -38.519653)
			(xy 229.976228 -38.473808) (xy 230.011914 -38.432623) (xy 230.053098 -38.396935) (xy 230.098942 -38.367472)
			(xy 230.148512 -38.344832) (xy 230.2008 -38.329478) (xy 230.25474 -38.321721) (xy 230.281988 -38.321234)
			(xy 230.310293 -38.321717) (xy 230.366282 -38.330068) (xy 230.420422 -38.346604) (xy 230.471523 -38.37096)
			(xy 230.518463 -38.402602) (xy 230.56021 -38.440834) (xy 230.595847 -38.484818) (xy 230.610664 -38.50894)
			(xy 230.618212 -38.521009) (xy 230.638841 -38.540613) (xy 230.664084 -38.553754) (xy 230.691975 -38.55941)
			(xy 230.720342 -38.557139) (xy 230.746979 -38.547119) (xy 230.769809 -38.53013) (xy 230.778812 -38.5191)
			(xy 230.796997 -38.496222) (xy 230.83916 -38.455758) (xy 230.886996 -38.422191) (xy 230.939388 -38.396304)
			(xy 230.995113 -38.378703) (xy 231.052869 -38.369797) (xy 231.082088 -38.36924) (xy 231.109345 -38.369606)
			(xy 231.163304 -38.377363) (xy 231.21561 -38.39272) (xy 231.265198 -38.415364) (xy 231.311058 -38.444836)
			(xy 231.352258 -38.480534) (xy 231.387957 -38.521732) (xy 231.41743 -38.567592) (xy 231.440076 -38.617179)
			(xy 231.455435 -38.669484) (xy 231.463193 -38.723443) (xy 231.463193 -38.777957) (xy 231.455435 -38.831916)
			(xy 231.440076 -38.884221) (xy 231.41743 -38.933808) (xy 231.387957 -38.979668) (xy 231.352258 -39.020866)
			(xy 231.311058 -39.056564) (xy 231.265198 -39.086036) (xy 231.21561 -39.10868) (xy 231.163304 -39.124037)
			(xy 231.109345 -39.131794) (xy 231.082088 -39.132256) (xy 231.053785 -39.131718) (xy 230.997798 -39.123377)
			(xy 230.943659 -39.106852) (xy 230.892558 -39.082505) (xy 230.845617 -39.050872) (xy 230.803869 -39.012646)
			(xy 230.76823 -38.968669) (xy 230.753412 -38.94455) (xy 230.745765 -38.93255) (xy 230.725156 -38.912952)
			(xy 230.699935 -38.89981) (xy 230.672064 -38.894147) (xy 230.643714 -38.896404) (xy 230.617091 -38.906405)
			(xy 230.594266 -38.923372) (xy 230.585264 -38.93439) (xy 230.567091 -38.957277) (xy 230.524925 -38.997741)
			(xy 230.477087 -39.031307) (xy 230.424693 -39.057193) (xy 230.368966 -39.074792) (xy 230.311208 -39.083695)
			(xy 230.281988 -39.08425) (xy 230.25474 -39.083679) (xy 230.2008 -39.075922) (xy 230.148512 -39.060568)
			(xy 230.098942 -39.037928) (xy 230.053098 -39.008465) (xy 230.011914 -38.972777) (xy 229.976228 -38.931592)
			(xy 229.946766 -38.885747) (xy 229.924128 -38.836176) (xy 229.908775 -38.783888) (xy 229.90102 -38.729948)
			(xy 223.019049 -38.729948) (xy 224.470703 -40.18153) (xy 228.109524 -40.18153) (xy 228.113595 -40.125908)
			(xy 228.125721 -40.071471) (xy 228.145644 -40.01938) (xy 228.17294 -39.970745) (xy 228.207026 -39.926602)
			(xy 228.247175 -39.887893) (xy 228.292533 -39.855442) (xy 228.342133 -39.829941) (xy 228.394917 -39.811934)
			(xy 228.44976 -39.801804) (xy 228.505494 -39.799767) (xy 228.560931 -39.805867) (xy 228.614888 -39.819973)
			(xy 228.666217 -39.841785) (xy 228.713823 -39.870839) (xy 228.756691 -39.906514) (xy 228.793908 -39.948051)
			(xy 228.824681 -39.994564) (xy 228.848353 -40.045061) (xy 228.864421 -40.098468) (xy 228.872541 -40.153644)
			(xy 228.87305 -40.18153) (xy 228.872541 -40.209416) (xy 228.864421 -40.264592) (xy 228.848353 -40.317999)
			(xy 228.824681 -40.368496) (xy 228.793908 -40.415009) (xy 228.756691 -40.456546) (xy 228.713823 -40.492221)
			(xy 228.666217 -40.521275) (xy 228.614888 -40.543087) (xy 228.560931 -40.557193) (xy 228.505494 -40.563293)
			(xy 228.44976 -40.561256) (xy 228.394917 -40.551126) (xy 228.342133 -40.533119) (xy 228.292533 -40.507618)
			(xy 228.247175 -40.475167) (xy 228.207026 -40.436458) (xy 228.17294 -40.392315) (xy 228.145644 -40.34368)
			(xy 228.125721 -40.291589) (xy 228.113595 -40.237152) (xy 228.109524 -40.18153) (xy 224.470703 -40.18153)
			(xy 224.846896 -40.557704) (xy 224.865366 -40.576928) (xy 224.896552 -40.620162) (xy 224.920438 -40.667818)
			(xy 224.928938 -40.693086) (xy 224.931875 -40.702793) (xy 224.936706 -40.722491) (xy 224.93859 -40.732456)
			(xy 224.93859 -40.732964) (xy 224.939352 -40.736266) (xy 224.941227 -40.742809) (xy 224.94792 -40.754655)
			(xy 224.95256 -40.759634) (xy 225.16465 -40.971724) (xy 232.794046 -40.971724) (xy 232.798117 -40.916102)
			(xy 232.810243 -40.861665) (xy 232.830166 -40.809574) (xy 232.857462 -40.760939) (xy 232.891548 -40.716796)
			(xy 232.931697 -40.678087) (xy 232.977055 -40.645636) (xy 233.026655 -40.620135) (xy 233.079439 -40.602128)
			(xy 233.134282 -40.591998) (xy 233.190016 -40.589961) (xy 233.245453 -40.596061) (xy 233.29941 -40.610167)
			(xy 233.350739 -40.631979) (xy 233.398345 -40.661033) (xy 233.441213 -40.696708) (xy 233.47843 -40.738245)
			(xy 233.509203 -40.784758) (xy 233.532875 -40.835255) (xy 233.548943 -40.888662) (xy 233.557063 -40.943838)
			(xy 233.557572 -40.971724) (xy 233.557063 -40.99961) (xy 233.548943 -41.054786) (xy 233.532875 -41.108193)
			(xy 233.509203 -41.15869) (xy 233.47843 -41.205203) (xy 233.441213 -41.24674) (xy 233.398345 -41.282415)
			(xy 233.350739 -41.311469) (xy 233.29941 -41.333281) (xy 233.245453 -41.347387) (xy 233.190016 -41.353487)
			(xy 233.134282 -41.35145) (xy 233.079439 -41.34132) (xy 233.026655 -41.323313) (xy 232.977055 -41.297812)
			(xy 232.931697 -41.265361) (xy 232.891548 -41.226652) (xy 232.857462 -41.182509) (xy 232.830166 -41.133874)
			(xy 232.810243 -41.081783) (xy 232.798117 -41.027346) (xy 232.794046 -40.971724) (xy 225.16465 -40.971724)
			(xy 225.183954 -40.991028) (xy 225.202738 -41.011401) (xy 225.233738 -41.057328) (xy 225.256421 -41.107882)
			(xy 225.270121 -41.161572) (xy 225.272854 -41.189148) (xy 225.272854 -41.190926) (xy 225.273616 -41.213532)
			(xy 225.273616 -42.66565) (xy 232.397044 -42.66565) (xy 232.401115 -42.610028) (xy 232.413241 -42.555591)
			(xy 232.433164 -42.5035) (xy 232.46046 -42.454865) (xy 232.494546 -42.410722) (xy 232.534695 -42.372013)
			(xy 232.580053 -42.339562) (xy 232.629653 -42.314061) (xy 232.682437 -42.296054) (xy 232.73728 -42.285924)
			(xy 232.793014 -42.283887) (xy 232.848451 -42.289987) (xy 232.902408 -42.304093) (xy 232.953737 -42.325905)
			(xy 233.001343 -42.354959) (xy 233.044211 -42.390634) (xy 233.081428 -42.432171) (xy 233.112201 -42.478684)
			(xy 233.135873 -42.529181) (xy 233.151941 -42.582588) (xy 233.160061 -42.637764) (xy 233.16057 -42.66565)
			(xy 233.160061 -42.693536) (xy 233.151941 -42.748712) (xy 233.135873 -42.802119) (xy 233.112201 -42.852616)
			(xy 233.081428 -42.899129) (xy 233.044211 -42.940666) (xy 233.001343 -42.976341) (xy 232.953737 -43.005395)
			(xy 232.902408 -43.027207) (xy 232.848451 -43.041313) (xy 232.793014 -43.047413) (xy 232.73728 -43.045376)
			(xy 232.682437 -43.035246) (xy 232.629653 -43.017239) (xy 232.580053 -42.991738) (xy 232.534695 -42.959287)
			(xy 232.494546 -42.920578) (xy 232.46046 -42.876435) (xy 232.433164 -42.8278) (xy 232.413241 -42.775709)
			(xy 232.401115 -42.721272) (xy 232.397044 -42.66565) (xy 225.273616 -42.66565) (xy 225.273616 -45.835351)
			(xy 238.482093 -45.835351) (xy 238.482093 -45.780849) (xy 238.48985 -45.726901) (xy 238.505206 -45.674607)
			(xy 238.527848 -45.62503) (xy 238.557315 -45.57918) (xy 238.593008 -45.537991) (xy 238.634199 -45.502301)
			(xy 238.680051 -45.472836) (xy 238.729629 -45.450197) (xy 238.781925 -45.434845) (xy 238.835873 -45.427092)
			(xy 238.863124 -45.42663) (xy 238.890495 -45.427075) (xy 238.944675 -45.434897) (xy 238.997179 -45.45039)
			(xy 239.046926 -45.473237) (xy 239.092891 -45.502966) (xy 239.113822 -45.52061) (xy 239.114076 -45.520864)
			(xy 239.12116 -45.526454) (xy 239.138079 -45.532697) (xy 239.147096 -45.533056) (xy 239.214152 -45.533056)
			(xy 239.223168 -45.532686) (xy 239.240085 -45.526448) (xy 239.247172 -45.520864) (xy 239.247172 -45.52061)
			(xy 239.247426 -45.52061) (xy 239.268359 -45.502969) (xy 239.314327 -45.473245) (xy 239.364073 -45.450399)
			(xy 239.416575 -45.434903) (xy 239.470753 -45.427074) (xy 239.525495 -45.427074) (xy 239.579673 -45.434903)
			(xy 239.632175 -45.450399) (xy 239.681921 -45.473245) (xy 239.727889 -45.502969) (xy 239.748822 -45.52061)
			(xy 239.749076 -45.520864) (xy 239.75616 -45.526454) (xy 239.773079 -45.532697) (xy 239.782096 -45.533056)
			(xy 239.849152 -45.533056) (xy 239.858168 -45.532686) (xy 239.875085 -45.526448) (xy 239.882172 -45.520864)
			(xy 239.882172 -45.52061) (xy 239.882426 -45.52061) (xy 239.903359 -45.502969) (xy 239.949327 -45.473245)
			(xy 239.999073 -45.450399) (xy 240.051575 -45.434903) (xy 240.105753 -45.427074) (xy 240.160495 -45.427074)
			(xy 240.214673 -45.434903) (xy 240.267175 -45.450399) (xy 240.316921 -45.473245) (xy 240.362889 -45.502969)
			(xy 240.383822 -45.52061) (xy 240.384076 -45.520864) (xy 240.39116 -45.526454) (xy 240.408079 -45.532697)
			(xy 240.417096 -45.533056) (xy 240.484152 -45.533056) (xy 240.493168 -45.532686) (xy 240.510085 -45.526448)
			(xy 240.517172 -45.520864) (xy 240.517172 -45.52061) (xy 240.517426 -45.52061) (xy 240.538376 -45.502994)
			(xy 240.584344 -45.473278) (xy 240.634087 -45.450438) (xy 240.686584 -45.434941) (xy 240.740756 -45.427107)
			(xy 240.768124 -45.42663) (xy 240.795377 -45.427042) (xy 240.849327 -45.434802) (xy 240.901624 -45.45016)
			(xy 240.951204 -45.472805) (xy 240.997056 -45.502275) (xy 241.038247 -45.53797) (xy 241.073939 -45.579164)
			(xy 241.103406 -45.625018) (xy 241.126048 -45.674598) (xy 241.141404 -45.726896) (xy 241.14916 -45.780847)
			(xy 241.14916 -45.835353) (xy 241.141404 -45.889304) (xy 241.126048 -45.941602) (xy 241.103406 -45.991182)
			(xy 241.073939 -46.037036) (xy 241.038247 -46.07823) (xy 240.997056 -46.113925) (xy 240.951204 -46.143395)
			(xy 240.901624 -46.16604) (xy 240.849327 -46.181398) (xy 240.795377 -46.189158) (xy 240.768124 -46.189646)
			(xy 240.740754 -46.189179) (xy 240.686574 -46.181363) (xy 240.63407 -46.165875) (xy 240.584324 -46.143033)
			(xy 240.538357 -46.113308) (xy 240.517426 -46.095666) (xy 240.517172 -46.095412) (xy 240.510068 -46.089851)
			(xy 240.493165 -46.083588) (xy 240.484152 -46.08322) (xy 240.417096 -46.08322) (xy 240.408078 -46.083571)
			(xy 240.391161 -46.089822) (xy 240.384076 -46.095412) (xy 240.383822 -46.095666) (xy 240.362889 -46.113307)
			(xy 240.316921 -46.143031) (xy 240.267175 -46.165877) (xy 240.214673 -46.181373) (xy 240.160495 -46.189202)
			(xy 240.105753 -46.189202) (xy 240.051575 -46.181373) (xy 239.999073 -46.165877) (xy 239.949327 -46.143031)
			(xy 239.903359 -46.113307) (xy 239.882426 -46.095666) (xy 239.882172 -46.095412) (xy 239.875068 -46.089851)
			(xy 239.858165 -46.083588) (xy 239.849152 -46.08322) (xy 239.782096 -46.08322) (xy 239.773078 -46.083571)
			(xy 239.756161 -46.089822) (xy 239.749076 -46.095412) (xy 239.749076 -46.095666) (xy 239.748822 -46.095666)
			(xy 239.727889 -46.113307) (xy 239.681921 -46.143031) (xy 239.632175 -46.165877) (xy 239.579673 -46.181373)
			(xy 239.525495 -46.189202) (xy 239.470753 -46.189202) (xy 239.416575 -46.181373) (xy 239.364073 -46.165877)
			(xy 239.314327 -46.143031) (xy 239.268359 -46.113307) (xy 239.247426 -46.095666) (xy 239.247172 -46.095412)
			(xy 239.240068 -46.089851) (xy 239.223165 -46.083588) (xy 239.214152 -46.08322) (xy 239.147096 -46.08322)
			(xy 239.138078 -46.083571) (xy 239.121161 -46.089822) (xy 239.114076 -46.095412) (xy 239.114076 -46.095666)
			(xy 239.113822 -46.095666) (xy 239.092888 -46.113303) (xy 239.046916 -46.143016) (xy 238.997169 -46.165853)
			(xy 238.944669 -46.181345) (xy 238.890493 -46.189172) (xy 238.863124 -46.189646) (xy 238.835873 -46.189108)
			(xy 238.781925 -46.181355) (xy 238.729629 -46.166003) (xy 238.680051 -46.143364) (xy 238.634199 -46.113899)
			(xy 238.593008 -46.078209) (xy 238.557315 -46.03702) (xy 238.527848 -45.99117) (xy 238.505206 -45.941593)
			(xy 238.48985 -45.889299) (xy 238.482093 -45.835351) (xy 225.273616 -45.835351) (xy 225.273616 -47.477426)
			(xy 239.502188 -47.477426) (xy 239.502672 -47.450056) (xy 239.510486 -47.395878) (xy 239.525971 -47.343375)
			(xy 239.548809 -47.293628) (xy 239.578529 -47.247661) (xy 239.596168 -47.226728) (xy 239.596422 -47.226474)
			(xy 239.601986 -47.219372) (xy 239.608246 -47.202467) (xy 239.608614 -47.193454) (xy 239.608614 -47.126398)
			(xy 239.608255 -47.117381) (xy 239.602008 -47.100465) (xy 239.596422 -47.093378) (xy 239.596168 -47.093378)
			(xy 239.596168 -47.093124) (xy 239.578522 -47.072198) (xy 239.548812 -47.026223) (xy 239.525978 -46.976474)
			(xy 239.510489 -46.923972) (xy 239.502662 -46.869795) (xy 239.502188 -46.842426) (xy 239.502679 -46.815174)
			(xy 239.510433 -46.761224) (xy 239.525785 -46.708927) (xy 239.548425 -46.659347) (xy 239.577889 -46.613494)
			(xy 239.61358 -46.572301) (xy 239.65477 -46.536607) (xy 239.700621 -46.507139) (xy 239.750199 -46.484496)
			(xy 239.802495 -46.469139) (xy 239.856444 -46.461382) (xy 239.883696 -46.460918) (xy 239.912613 -46.461433)
			(xy 239.969785 -46.470161) (xy 240.024984 -46.48742) (xy 240.076946 -46.512812) (xy 240.12448 -46.545756)
			(xy 240.166496 -46.585498) (xy 240.184686 -46.607984) (xy 240.192294 -46.616789) (xy 240.213195 -46.626971)
			(xy 240.224818 -46.627542) (xy 240.304574 -46.627542) (xy 240.316205 -46.626994) (xy 240.337116 -46.616813)
			(xy 240.344706 -46.607984) (xy 240.36289 -46.585494) (xy 240.404911 -46.54576) (xy 240.452448 -46.512822)
			(xy 240.504411 -46.487435) (xy 240.559609 -46.47018) (xy 240.61678 -46.461452) (xy 240.645696 -46.460918)
			(xy 240.67295 -46.461359) (xy 240.726903 -46.469116) (xy 240.779203 -46.484473) (xy 240.828785 -46.507117)
			(xy 240.874639 -46.536587) (xy 240.915832 -46.572283) (xy 240.951526 -46.613479) (xy 240.980994 -46.659335)
			(xy 241.003635 -46.708918) (xy 241.018988 -46.761219) (xy 241.026742 -46.815172) (xy 241.027204 -46.842426)
			(xy 241.026753 -46.86874) (xy 241.019514 -46.92087) (xy 241.005192 -46.971513) (xy 240.984057 -47.019712)
			(xy 240.956508 -47.064555) (xy 240.923067 -47.105194) (xy 240.904014 -47.12335) (xy 240.89659 -47.130853)
			(xy 240.888078 -47.150147) (xy 240.887504 -47.160688) (xy 240.887504 -47.235364) (xy 240.888038 -47.245913)
			(xy 240.89657 -47.265209) (xy 240.904014 -47.272702) (xy 240.923066 -47.290861) (xy 240.956523 -47.33149)
			(xy 240.984082 -47.37633) (xy 241.005221 -47.42453) (xy 241.019539 -47.475177) (xy 241.026765 -47.52731)
			(xy 241.027204 -47.553626) (xy 241.026746 -47.580878) (xy 241.018986 -47.634827) (xy 241.003628 -47.687123)
			(xy 240.980983 -47.7367) (xy 240.951514 -47.782551) (xy 240.915819 -47.823741) (xy 240.874627 -47.859432)
			(xy 240.828774 -47.888898) (xy 240.779194 -47.911538) (xy 240.726898 -47.926893) (xy 240.672948 -47.934649)
			(xy 240.645696 -47.935134) (xy 240.618029 -47.934655) (xy 240.563277 -47.926654) (xy 240.510254 -47.910834)
			(xy 240.460068 -47.887526) (xy 240.413773 -47.857219) (xy 240.372336 -47.820547) (xy 240.336627 -47.778278)
			(xy 240.321592 -47.755048) (xy 240.314961 -47.745367) (xy 240.295096 -47.732925) (xy 240.283492 -47.731172)
			(xy 240.203482 -47.723298) (xy 240.191844 -47.722678) (xy 240.170009 -47.730752) (xy 240.161572 -47.738792)
			(xy 240.161318 -47.739046) (xy 240.143201 -47.757591) (xy 240.102878 -47.790175) (xy 240.058511 -47.816994)
			(xy 240.01092 -47.837553) (xy 239.960982 -47.851474) (xy 239.909617 -47.858499) (xy 239.883696 -47.858934)
			(xy 239.856446 -47.858426) (xy 239.8025 -47.85067) (xy 239.750208 -47.835315) (xy 239.700632 -47.812676)
			(xy 239.654783 -47.783211) (xy 239.613593 -47.747522) (xy 239.577902 -47.706335) (xy 239.548435 -47.660487)
			(xy 239.525792 -47.610913) (xy 239.510435 -47.558621) (xy 239.502676 -47.504676) (xy 239.502188 -47.477426)
			(xy 225.273616 -47.477426) (xy 225.273616 -48.789458) (xy 238.952913 -48.789458) (xy 238.952913 -48.734942)
			(xy 238.960672 -48.680982) (xy 238.976032 -48.628675) (xy 238.99868 -48.579087) (xy 239.028155 -48.533227)
			(xy 239.063857 -48.492028) (xy 239.105059 -48.456331) (xy 239.150922 -48.42686) (xy 239.200513 -48.404218)
			(xy 239.252821 -48.388863) (xy 239.306782 -48.38111) (xy 239.33404 -48.38065) (xy 239.36141 -48.381139)
			(xy 239.415588 -48.388949) (xy 239.468091 -48.404432) (xy 239.517839 -48.427269) (xy 239.563806 -48.45699)
			(xy 239.584738 -48.47463) (xy 239.584992 -48.474884) (xy 239.592078 -48.480472) (xy 239.608995 -48.486718)
			(xy 239.618012 -48.487076) (xy 239.685068 -48.487076) (xy 239.694084 -48.486709) (xy 239.711001 -48.480469)
			(xy 239.718088 -48.474884) (xy 239.718088 -48.47463) (xy 239.718342 -48.47463) (xy 239.739289 -48.457009)
			(xy 239.785257 -48.427294) (xy 239.835001 -48.404454) (xy 239.887498 -48.388958) (xy 239.941672 -48.381126)
			(xy 239.96904 -48.38065) (xy 239.996286 -48.381223) (xy 240.050224 -48.388983) (xy 240.102508 -48.40434)
			(xy 240.152075 -48.426981) (xy 240.197915 -48.456445) (xy 240.239096 -48.492133) (xy 240.274779 -48.533317)
			(xy 240.304238 -48.579161) (xy 240.326874 -48.62873) (xy 240.342225 -48.681015) (xy 240.34998 -48.734954)
			(xy 240.34998 -48.789446) (xy 240.342225 -48.843385) (xy 240.326874 -48.89567) (xy 240.304238 -48.945239)
			(xy 240.274779 -48.991083) (xy 240.239096 -49.032267) (xy 240.197915 -49.067955) (xy 240.152075 -49.097419)
			(xy 240.102508 -49.12006) (xy 240.050224 -49.135417) (xy 239.996286 -49.143177) (xy 239.96904 -49.143666)
			(xy 239.94167 -49.143185) (xy 239.887491 -49.135372) (xy 239.834988 -49.119887) (xy 239.785241 -49.097048)
			(xy 239.739274 -49.067326) (xy 239.718342 -49.049686) (xy 239.718088 -49.049432) (xy 239.711015 -49.043826)
			(xy 239.694088 -49.037593) (xy 239.685068 -49.03724) (xy 239.618012 -49.03724) (xy 239.608995 -49.037594)
			(xy 239.592077 -49.043843) (xy 239.584992 -49.049432) (xy 239.584992 -49.049686) (xy 239.584738 -49.049686)
			(xy 239.563801 -49.067319) (xy 239.51783 -49.097032) (xy 239.468083 -49.119869) (xy 239.415584 -49.135362)
			(xy 239.361409 -49.143191) (xy 239.33404 -49.143666) (xy 239.306782 -49.14329) (xy 239.252821 -49.135537)
			(xy 239.200513 -49.120182) (xy 239.150922 -49.09754) (xy 239.105059 -49.068069) (xy 239.063857 -49.032372)
			(xy 239.028155 -48.991173) (xy 238.99868 -48.945313) (xy 238.976032 -48.895725) (xy 238.960672 -48.843418)
			(xy 238.952913 -48.789458) (xy 225.273616 -48.789458) (xy 225.273616 -49.72995) (xy 238.502698 -49.72995)
			(xy 238.502698 -49.67545) (xy 238.510454 -49.621506) (xy 238.525808 -49.569214) (xy 238.548448 -49.519639)
			(xy 238.577913 -49.473792) (xy 238.613602 -49.432604) (xy 238.65479 -49.396914) (xy 238.700638 -49.367449)
			(xy 238.750212 -49.344809) (xy 238.802504 -49.329455) (xy 238.856448 -49.321698) (xy 238.883698 -49.321212)
			(xy 238.911068 -49.321676) (xy 238.965248 -49.329494) (xy 239.017751 -49.344983) (xy 239.067498 -49.367826)
			(xy 239.113464 -49.397551) (xy 239.134396 -49.415192) (xy 239.13465 -49.415446) (xy 239.141743 -49.421023)
			(xy 239.158655 -49.427274) (xy 239.16767 -49.427638) (xy 239.234726 -49.427638) (xy 239.243743 -49.427285)
			(xy 239.26066 -49.421034) (xy 239.267746 -49.415446) (xy 239.267746 -49.415192) (xy 239.268 -49.415192)
			(xy 239.28892 -49.397538) (xy 239.334896 -49.367829) (xy 239.384647 -49.344996) (xy 239.43715 -49.329508)
			(xy 239.491328 -49.321684) (xy 239.518698 -49.321212) (xy 239.545952 -49.321635) (xy 239.599906 -49.329392)
			(xy 239.652207 -49.344749) (xy 239.70179 -49.367392) (xy 239.747646 -49.396862) (xy 239.788841 -49.432557)
			(xy 239.824537 -49.473752) (xy 239.854007 -49.519608) (xy 239.876651 -49.569191) (xy 239.892008 -49.621492)
			(xy 239.899765 -49.675446) (xy 239.899765 -49.729954) (xy 239.892008 -49.783908) (xy 239.876651 -49.836209)
			(xy 239.854007 -49.885792) (xy 239.824537 -49.931648) (xy 239.788841 -49.972843) (xy 239.747646 -50.008538)
			(xy 239.70179 -50.038008) (xy 239.652207 -50.060651) (xy 239.599906 -50.076008) (xy 239.545952 -50.083765)
			(xy 239.518698 -50.084228) (xy 239.491327 -50.083781) (xy 239.437146 -50.075961) (xy 239.384642 -50.060469)
			(xy 239.334896 -50.037622) (xy 239.28893 -50.007892) (xy 239.268 -49.990248) (xy 239.267746 -49.989994)
			(xy 239.260651 -49.98442) (xy 239.243741 -49.978166) (xy 239.234726 -49.977802) (xy 239.16767 -49.977802)
			(xy 239.158652 -49.978144) (xy 239.141735 -49.984402) (xy 239.13465 -49.989994) (xy 239.13465 -49.990248)
			(xy 239.134396 -49.990248) (xy 239.11347 -50.007894) (xy 239.067496 -50.037607) (xy 239.017747 -50.060442)
			(xy 238.965245 -50.075931) (xy 238.911068 -50.083756) (xy 238.883698 -50.084228) (xy 238.856448 -50.083702)
			(xy 238.802504 -50.075945) (xy 238.750212 -50.060591) (xy 238.700638 -50.037951) (xy 238.65479 -50.008486)
			(xy 238.613602 -49.972796) (xy 238.577913 -49.931608) (xy 238.548448 -49.885761) (xy 238.525808 -49.836186)
			(xy 238.510454 -49.783894) (xy 238.502698 -49.72995) (xy 225.273616 -49.72995) (xy 225.273616 -51.222449)
			(xy 236.270302 -51.222449) (xy 236.270302 -51.167951) (xy 236.278058 -51.114007) (xy 236.293412 -51.061717)
			(xy 236.316051 -51.012143) (xy 236.345514 -50.966296) (xy 236.381203 -50.925109) (xy 236.42239 -50.889419)
			(xy 236.468236 -50.859955) (xy 236.517809 -50.837315) (xy 236.570099 -50.82196) (xy 236.624043 -50.814203)
			(xy 236.651292 -50.813716) (xy 236.679384 -50.814201) (xy 236.734962 -50.822428) (xy 236.788732 -50.838719)
			(xy 236.83953 -50.862723) (xy 236.886257 -50.89392) (xy 236.927902 -50.931634) (xy 236.963562 -50.97505)
			(xy 236.978444 -50.998882) (xy 236.983778 -51.007772) (xy 237.000796 -51.019964) (xy 237.094014 -51.040284)
			(xy 237.114588 -51.035966) (xy 237.123224 -51.030124) (xy 237.147282 -51.014114) (xy 237.199215 -50.988773)
			(xy 237.254375 -50.97155) (xy 237.311501 -50.962838) (xy 237.340394 -50.962306) (xy 237.367647 -50.962761)
			(xy 237.421599 -50.970517) (xy 237.473898 -50.985873) (xy 237.523479 -51.008516) (xy 237.569333 -51.037985)
			(xy 237.610526 -51.07368) (xy 237.64622 -51.114873) (xy 237.675688 -51.160728) (xy 237.698329 -51.210309)
			(xy 237.713684 -51.262609) (xy 237.72144 -51.316561) (xy 237.721902 -51.343814) (xy 237.721444 -51.371185)
			(xy 237.713624 -51.425364) (xy 237.698133 -51.477867) (xy 237.67529 -51.527614) (xy 237.645564 -51.57358)
			(xy 237.627922 -51.594512) (xy 237.627668 -51.594766) (xy 237.622086 -51.601856) (xy 237.615838 -51.61877)
			(xy 237.615476 -51.627786) (xy 237.615476 -51.694842) (xy 237.615866 -51.703855) (xy 237.622091 -51.720772)
			(xy 237.627668 -51.727862) (xy 237.627922 -51.727862) (xy 237.627922 -51.728116) (xy 237.645574 -51.749039)
			(xy 237.675295 -51.795009) (xy 237.698136 -51.844758) (xy 237.713629 -51.897261) (xy 237.721456 -51.95144)
			(xy 237.721454 -52.006181) (xy 237.713625 -52.06036) (xy 237.698129 -52.112862) (xy 237.675285 -52.162609)
			(xy 237.645562 -52.208578) (xy 237.627922 -52.229512) (xy 237.627668 -52.229766) (xy 237.622086 -52.236856)
			(xy 237.615838 -52.25377) (xy 237.615476 -52.262786) (xy 237.615476 -52.329842) (xy 237.615866 -52.338855)
			(xy 237.622091 -52.355772) (xy 237.627668 -52.362862) (xy 237.627922 -52.362862) (xy 237.627922 -52.363116)
			(xy 237.645539 -52.384066) (xy 237.675253 -52.430034) (xy 237.698093 -52.479777) (xy 237.713589 -52.532274)
			(xy 237.721424 -52.586446) (xy 237.721902 -52.613814) (xy 237.721416 -52.641065) (xy 237.71366 -52.695013)
			(xy 237.698305 -52.747308) (xy 237.675663 -52.796885) (xy 237.646197 -52.842735) (xy 237.610506 -52.883926)
			(xy 237.569315 -52.919617) (xy 237.523465 -52.949083) (xy 237.473888 -52.971725) (xy 237.421593 -52.98708)
			(xy 237.367645 -52.994836) (xy 237.313143 -52.994836) (xy 237.259195 -52.98708) (xy 237.2069 -52.971725)
			(xy 237.157323 -52.949083) (xy 237.111473 -52.919617) (xy 237.070282 -52.883926) (xy 237.034591 -52.842735)
			(xy 237.005125 -52.796885) (xy 236.982483 -52.747308) (xy 236.967128 -52.695013) (xy 236.959372 -52.641065)
			(xy 236.958886 -52.613814) (xy 236.959364 -52.586444) (xy 236.967179 -52.532266) (xy 236.982666 -52.479763)
			(xy 237.005505 -52.430016) (xy 237.035226 -52.384048) (xy 237.052866 -52.363116) (xy 237.05312 -52.362862)
			(xy 237.058689 -52.355763) (xy 237.064946 -52.338856) (xy 237.065312 -52.329842) (xy 237.065312 -52.262786)
			(xy 237.064959 -52.253769) (xy 237.058708 -52.236852) (xy 237.05312 -52.229766) (xy 237.052866 -52.229766)
			(xy 237.052866 -52.229512) (xy 237.035237 -52.208569) (xy 237.005509 -52.162604) (xy 236.98266 -52.11286)
			(xy 236.967161 -52.060359) (xy 236.959331 -52.006181) (xy 236.959329 -51.95144) (xy 236.967157 -51.897262)
			(xy 236.982653 -51.84476) (xy 237.005499 -51.795015) (xy 237.035225 -51.749048) (xy 237.052866 -51.728116)
			(xy 237.05312 -51.727862) (xy 237.058689 -51.720763) (xy 237.064946 -51.703856) (xy 237.065312 -51.694842)
			(xy 237.065312 -51.627786) (xy 237.064959 -51.618769) (xy 237.058708 -51.601852) (xy 237.05312 -51.594766)
			(xy 237.052866 -51.594258) (xy 237.041923 -51.581523) (xy 237.022081 -51.554432) (xy 237.013242 -51.540156)
			(xy 237.007908 -51.531266) (xy 236.99089 -51.519074) (xy 236.897672 -51.498754) (xy 236.877098 -51.503072)
			(xy 236.868462 -51.508914) (xy 236.844411 -51.524934) (xy 236.792475 -51.550272) (xy 236.737313 -51.567492)
			(xy 236.680186 -51.576201) (xy 236.651292 -51.576732) (xy 236.624043 -51.576197) (xy 236.570099 -51.56844)
			(xy 236.517809 -51.553085) (xy 236.468236 -51.530445) (xy 236.42239 -51.500981) (xy 236.381203 -51.465291)
			(xy 236.345514 -51.424104) (xy 236.316051 -51.378257) (xy 236.293412 -51.328683) (xy 236.278058 -51.276393)
			(xy 236.270302 -51.222449) (xy 225.273616 -51.222449) (xy 225.273616 -51.654249) (xy 234.593902 -51.654249)
			(xy 234.593902 -51.599751) (xy 234.601658 -51.545807) (xy 234.617012 -51.493517) (xy 234.639651 -51.443943)
			(xy 234.669114 -51.398096) (xy 234.704803 -51.356909) (xy 234.74599 -51.321219) (xy 234.791836 -51.291755)
			(xy 234.841409 -51.269115) (xy 234.893699 -51.25376) (xy 234.947643 -51.246003) (xy 234.974892 -51.245516)
			(xy 235.001206 -51.245984) (xy 235.053335 -51.253218) (xy 235.103978 -51.267536) (xy 235.152177 -51.288669)
			(xy 235.19702 -51.316215) (xy 235.23766 -51.349654) (xy 235.255816 -51.368706) (xy 235.263329 -51.376117)
			(xy 235.282616 -51.384636) (xy 235.293154 -51.385216) (xy 235.36783 -51.385216) (xy 235.378376 -51.384658)
			(xy 235.397672 -51.376143) (xy 235.405168 -51.368706) (xy 235.423299 -51.349626) (xy 235.463934 -51.31617)
			(xy 235.508779 -51.288615) (xy 235.556985 -51.26748) (xy 235.607637 -51.253169) (xy 235.659774 -51.245951)
			(xy 235.686092 -51.245516) (xy 235.713347 -51.24593) (xy 235.767302 -51.253687) (xy 235.819604 -51.269043)
			(xy 235.869189 -51.291687) (xy 235.915046 -51.321156) (xy 235.956242 -51.356852) (xy 235.991939 -51.398048)
			(xy 236.021409 -51.443904) (xy 236.044054 -51.493488) (xy 236.059411 -51.54579) (xy 236.067169 -51.599745)
			(xy 236.067169 -51.654255) (xy 236.059411 -51.70821) (xy 236.044054 -51.760512) (xy 236.021409 -51.810096)
			(xy 235.991939 -51.855952) (xy 235.956242 -51.897148) (xy 235.915046 -51.932844) (xy 235.869189 -51.962313)
			(xy 235.819604 -51.984957) (xy 235.767302 -52.000313) (xy 235.713347 -52.00807) (xy 235.686092 -52.008532)
			(xy 235.659778 -52.00806) (xy 235.60765 -52.000824) (xy 235.557008 -51.986506) (xy 235.508809 -51.965374)
			(xy 235.463966 -51.937829) (xy 235.423325 -51.904393) (xy 235.405168 -51.885342) (xy 235.397654 -51.877931)
			(xy 235.378369 -51.869411) (xy 235.36783 -51.868832) (xy 235.293154 -51.868832) (xy 235.282605 -51.869367)
			(xy 235.263309 -51.877897) (xy 235.255816 -51.885342) (xy 235.237654 -51.904391) (xy 235.197025 -51.937847)
			(xy 235.152185 -51.965406) (xy 235.103986 -51.986545) (xy 235.05334 -52.000864) (xy 235.001208 -52.008092)
			(xy 234.974892 -52.008532) (xy 234.947643 -52.007997) (xy 234.893699 -52.00024) (xy 234.841409 -51.984885)
			(xy 234.791836 -51.962245) (xy 234.74599 -51.932781) (xy 234.704803 -51.897091) (xy 234.669114 -51.855904)
			(xy 234.639651 -51.810057) (xy 234.617012 -51.760483) (xy 234.601658 -51.708193) (xy 234.593902 -51.654249)
			(xy 225.273616 -51.654249) (xy 225.273616 -53.718714) (xy 236.97514 -53.718714) (xy 236.979211 -53.663092)
			(xy 236.991337 -53.608655) (xy 237.01126 -53.556564) (xy 237.038556 -53.507929) (xy 237.072642 -53.463786)
			(xy 237.112791 -53.425077) (xy 237.158149 -53.392626) (xy 237.207749 -53.367125) (xy 237.260533 -53.349118)
			(xy 237.315376 -53.338988) (xy 237.37111 -53.336951) (xy 237.426547 -53.343051) (xy 237.480504 -53.357157)
			(xy 237.531833 -53.378969) (xy 237.579439 -53.408023) (xy 237.622307 -53.443698) (xy 237.659524 -53.485235)
			(xy 237.690297 -53.531748) (xy 237.713969 -53.582245) (xy 237.730037 -53.635652) (xy 237.738157 -53.690828)
			(xy 237.738666 -53.718714) (xy 237.738157 -53.7466) (xy 237.730037 -53.801776) (xy 237.713969 -53.855183)
			(xy 237.690297 -53.90568) (xy 237.659524 -53.952193) (xy 237.622307 -53.99373) (xy 237.579439 -54.029405)
			(xy 237.531833 -54.058459) (xy 237.480504 -54.080271) (xy 237.426547 -54.094377) (xy 237.37111 -54.100477)
			(xy 237.315376 -54.09844) (xy 237.260533 -54.08831) (xy 237.207749 -54.070303) (xy 237.158149 -54.044802)
			(xy 237.112791 -54.012351) (xy 237.072642 -53.973642) (xy 237.038556 -53.929499) (xy 237.01126 -53.880864)
			(xy 236.991337 -53.828773) (xy 236.979211 -53.774336) (xy 236.97514 -53.718714) (xy 225.273616 -53.718714)
			(xy 225.273616 -54.794658) (xy 238.931448 -54.794658) (xy 238.935519 -54.739036) (xy 238.947645 -54.684599)
			(xy 238.967568 -54.632508) (xy 238.994864 -54.583873) (xy 239.02895 -54.53973) (xy 239.069099 -54.501021)
			(xy 239.114457 -54.46857) (xy 239.164057 -54.443069) (xy 239.216841 -54.425062) (xy 239.271684 -54.414932)
			(xy 239.327418 -54.412895) (xy 239.382855 -54.418995) (xy 239.436812 -54.433101) (xy 239.488141 -54.454913)
			(xy 239.535747 -54.483967) (xy 239.578615 -54.519642) (xy 239.615832 -54.561179) (xy 239.646605 -54.607692)
			(xy 239.670277 -54.658189) (xy 239.686345 -54.711596) (xy 239.694465 -54.766772) (xy 239.694974 -54.794658)
			(xy 239.694465 -54.822544) (xy 239.686345 -54.87772) (xy 239.670277 -54.931127) (xy 239.646605 -54.981624)
			(xy 239.615832 -55.028137) (xy 239.578615 -55.069674) (xy 239.535747 -55.105349) (xy 239.488141 -55.134403)
			(xy 239.436812 -55.156215) (xy 239.382855 -55.170321) (xy 239.327418 -55.176421) (xy 239.271684 -55.174384)
			(xy 239.216841 -55.164254) (xy 239.164057 -55.146247) (xy 239.114457 -55.120746) (xy 239.069099 -55.088295)
			(xy 239.02895 -55.049586) (xy 238.994864 -55.005443) (xy 238.967568 -54.956808) (xy 238.947645 -54.904717)
			(xy 238.935519 -54.85028) (xy 238.931448 -54.794658) (xy 225.273616 -54.794658) (xy 225.273616 -55.408068)
			(xy 237.462312 -55.408068) (xy 237.466383 -55.352446) (xy 237.478509 -55.298009) (xy 237.498432 -55.245918)
			(xy 237.525728 -55.197283) (xy 237.559814 -55.15314) (xy 237.599963 -55.114431) (xy 237.645321 -55.08198)
			(xy 237.694921 -55.056479) (xy 237.747705 -55.038472) (xy 237.802548 -55.028342) (xy 237.858282 -55.026305)
			(xy 237.913719 -55.032405) (xy 237.967676 -55.046511) (xy 238.019005 -55.068323) (xy 238.066611 -55.097377)
			(xy 238.109479 -55.133052) (xy 238.146696 -55.174589) (xy 238.177469 -55.221102) (xy 238.201141 -55.271599)
			(xy 238.217209 -55.325006) (xy 238.225329 -55.380182) (xy 238.225838 -55.408068) (xy 238.225329 -55.435954)
			(xy 238.217209 -55.49113) (xy 238.201141 -55.544537) (xy 238.177469 -55.595034) (xy 238.146696 -55.641547)
			(xy 238.109479 -55.683084) (xy 238.066611 -55.718759) (xy 238.019005 -55.747813) (xy 237.967676 -55.769625)
			(xy 237.913719 -55.783731) (xy 237.858282 -55.789831) (xy 237.802548 -55.787794) (xy 237.747705 -55.777664)
			(xy 237.694921 -55.759657) (xy 237.645321 -55.734156) (xy 237.599963 -55.701705) (xy 237.559814 -55.662996)
			(xy 237.525728 -55.618853) (xy 237.498432 -55.570218) (xy 237.478509 -55.518127) (xy 237.466383 -55.46369)
			(xy 237.462312 -55.408068) (xy 225.273616 -55.408068) (xy 225.273616 -56.86679) (xy 240.166142 -56.86679)
			(xy 240.170213 -56.811168) (xy 240.182339 -56.756731) (xy 240.202262 -56.70464) (xy 240.229558 -56.656005)
			(xy 240.263644 -56.611862) (xy 240.303793 -56.573153) (xy 240.349151 -56.540702) (xy 240.398751 -56.515201)
			(xy 240.451535 -56.497194) (xy 240.506378 -56.487064) (xy 240.562112 -56.485027) (xy 240.617549 -56.491127)
			(xy 240.671506 -56.505233) (xy 240.722835 -56.527045) (xy 240.770441 -56.556099) (xy 240.813309 -56.591774)
			(xy 240.850526 -56.633311) (xy 240.881299 -56.679824) (xy 240.904971 -56.730321) (xy 240.921039 -56.783728)
			(xy 240.929159 -56.838904) (xy 240.929668 -56.86679) (xy 240.929159 -56.894676) (xy 240.921039 -56.949852)
			(xy 240.904971 -57.003259) (xy 240.881299 -57.053756) (xy 240.850526 -57.100269) (xy 240.813309 -57.141806)
			(xy 240.770441 -57.177481) (xy 240.722835 -57.206535) (xy 240.671506 -57.228347) (xy 240.617549 -57.242453)
			(xy 240.562112 -57.248553) (xy 240.506378 -57.246516) (xy 240.451535 -57.236386) (xy 240.398751 -57.218379)
			(xy 240.349151 -57.192878) (xy 240.303793 -57.160427) (xy 240.263644 -57.121718) (xy 240.229558 -57.077575)
			(xy 240.202262 -57.02894) (xy 240.182339 -56.976849) (xy 240.170213 -56.922412) (xy 240.166142 -56.86679)
			(xy 225.273616 -56.86679) (xy 225.273616 -62.931802) (xy 225.273679 -62.935408) (xy 225.274697 -62.942547)
			(xy 225.275648 -62.946026) (xy 225.278442 -62.954916) (xy 225.286316 -62.966346) (xy 225.289618 -62.971172)
			(xy 225.312224 -62.992) (xy 225.34499 -63.022226) (xy 225.348864 -63.02565) (xy 225.357696 -63.031022)
			(xy 225.362516 -63.032894) (xy 225.36912 -63.03518) (xy 225.371152 -63.035434) (xy 225.373692 -63.035688)
			(xy 225.376232 -63.035942) (xy 225.382582 -63.035434) (xy 225.402648 -63.034672) (xy 225.403664 -63.034672)
			(xy 225.409252 -63.034418) (xy 225.4123 -63.034418) (xy 225.439685 -63.034998) (xy 225.493865 -63.043043)
			(xy 225.546339 -63.058752) (xy 225.596027 -63.081803) (xy 225.641908 -63.111721) (xy 225.683041 -63.147892)
			(xy 225.718579 -63.189573) (xy 225.73361 -63.212472) (xy 225.739706 -63.222632) (xy 225.744278 -63.23076)
			(xy 225.754438 -63.250318) (xy 225.760534 -63.263526) (xy 225.764598 -63.27267) (xy 225.782124 -63.290196)
			(xy 225.787035 -63.294644) (xy 225.798613 -63.301076) (xy 225.804984 -63.302896) (xy 225.80854 -63.303658)
			(xy 225.83775 -63.3095) (xy 225.842024 -63.310279) (xy 225.850708 -63.310528) (xy 225.855022 -63.310008)
			(xy 226.045522 -63.119254) (xy 226.139756 -63.02502) (xy 226.146437 -63.017609) (xy 226.154018 -62.999173)
			(xy 226.154488 -62.989206) (xy 226.154488 -62.457838) (xy 226.154433 -62.453767) (xy 226.153152 -62.445726)
			(xy 226.151948 -62.441836) (xy 226.147122 -62.427104) (xy 226.145842 -62.423594) (xy 226.142393 -62.416967)
			(xy 226.140264 -62.413896) (xy 226.125866 -62.392758) (xy 226.103062 -62.346981) (xy 226.087571 -62.298241)
			(xy 226.079761 -62.247698) (xy 226.079304 -62.222126) (xy 226.079304 -61.962792) (xy 226.076256 -61.95695)
			(xy 226.073462 -61.951362) (xy 226.059728 -61.923845) (xy 226.040261 -61.865514) (xy 226.030386 -61.804817)
			(xy 226.029774 -61.77407) (xy 226.029774 -61.773562) (xy 226.030262 -61.746312) (xy 226.038023 -61.692367)
			(xy 226.053381 -61.640076) (xy 226.076024 -61.590503) (xy 226.105491 -61.544656) (xy 226.141183 -61.503469)
			(xy 226.182372 -61.467779) (xy 226.22822 -61.438315) (xy 226.277795 -61.415674) (xy 226.330087 -61.400319)
			(xy 226.384032 -61.392561) (xy 226.411282 -61.392054) (xy 226.438206 -61.39307) (xy 226.440492 -61.39307)
			(xy 226.448874 -61.393578) (xy 226.47148 -61.392308) (xy 226.486466 -61.392054) (xy 226.51372 -61.392537)
			(xy 226.567673 -61.40029) (xy 226.619974 -61.415642) (xy 226.669558 -61.43828) (xy 226.715416 -61.467745)
			(xy 226.756613 -61.503436) (xy 226.792312 -61.544627) (xy 226.821785 -61.590479) (xy 226.844433 -61.640058)
			(xy 226.859795 -61.692356) (xy 226.867557 -61.746308) (xy 226.867974 -61.773562) (xy 226.867974 -61.77407)
			(xy 226.867582 -61.798616) (xy 226.861255 -61.847299) (xy 226.84873 -61.894766) (xy 226.830212 -61.940231)
			(xy 226.818444 -61.961776) (xy 226.815396 -61.96711) (xy 226.809808 -61.986668) (xy 226.808284 -61.99886)
			(xy 226.808284 -62.21603) (xy 226.809554 -62.221872) (xy 226.814888 -62.248796) (xy 226.814888 -62.249304)
			(xy 226.816544 -62.261237) (xy 226.818327 -62.285264) (xy 226.818444 -62.29731) (xy 226.818444 -62.779148)
			(xy 226.818863 -62.788242) (xy 226.825308 -62.805253) (xy 226.837293 -62.818938) (xy 226.845114 -62.823598)
			(xy 226.850194 -62.82563) (xy 226.857225 -62.828358) (xy 226.87222 -62.829922) (xy 226.879658 -62.828678)
			(xy 226.886262 -62.827408) (xy 226.89947 -62.820296) (xy 227.2792 -62.440566) (xy 227.286006 -62.433084)
			(xy 227.293614 -62.41436) (xy 227.293436 -62.39415) (xy 227.289868 -62.384686) (xy 227.28936 -62.383162)
			(xy 227.280411 -62.361991) (xy 227.267774 -62.317798) (xy 227.261352 -62.272285) (xy 227.260912 -62.249304)
			(xy 227.260912 -62.001146) (xy 227.2607 -61.99506) (xy 227.257739 -61.983252) (xy 227.25507 -61.977778)
			(xy 227.25507 -61.977524) (xy 227.241231 -61.949997) (xy 227.221647 -61.891584) (xy 227.211711 -61.830782)
			(xy 227.211128 -61.799978) (xy 227.211128 -61.79947) (xy 227.211583 -61.774117) (xy 227.218369 -61.723866)
			(xy 227.23174 -61.674953) (xy 227.25146 -61.628238) (xy 227.26396 -61.606176) (xy 227.266754 -61.601096)
			(xy 227.270056 -61.590428) (xy 227.272342 -61.5823) (xy 227.272088 -61.573918) (xy 227.269548 -61.560202)
			(xy 227.268532 -61.557916) (xy 227.268532 -61.557662) (xy 227.26142 -61.539882) (xy 227.255832 -61.533532)
			(xy 227.243099 -61.518126) (xy 227.221312 -61.484619) (xy 227.212398 -61.46673) (xy 227.187252 -61.414152)
			(xy 227.184904 -61.40893) (xy 227.182333 -61.397777) (xy 227.182172 -61.392054) (xy 227.182172 -60.776104)
			(xy 227.182313 -60.771214) (xy 227.184238 -60.761625) (xy 227.185982 -60.757054) (xy 227.224844 -60.661042)
			(xy 227.22696 -60.65623) (xy 227.232842 -60.647518) (xy 227.236528 -60.64377) (xy 227.265484 -60.61583)
			(xy 227.27285 -60.606178) (xy 227.275853 -60.600712) (xy 227.279437 -60.588771) (xy 227.279962 -60.582556)
			(xy 227.280216 -60.580524) (xy 227.280513 -60.573773) (xy 227.277929 -60.560516) (xy 227.275136 -60.554362)
			(xy 227.274374 -60.553092) (xy 227.269697 -60.544673) (xy 227.255343 -60.531855) (xy 227.246434 -60.5282)
			(xy 227.241608 -60.526422) (xy 227.233841 -60.523886) (xy 227.217518 -60.523374) (xy 227.209604 -60.525406)
			(xy 227.198174 -60.528708) (xy 227.190046 -60.533026) (xy 227.181664 -60.537598) (xy 227.16446 -60.546391)
			(xy 227.128852 -60.561395) (xy 227.110544 -60.56757) (xy 227.089462 -60.57392) (xy 227.076 -60.577222)
			(xy 227.05822 -60.581286) (xy 227.056188 -60.581286) (xy 227.051108 -60.582556) (xy 227.04679 -60.583318)
			(xy 227.043488 -60.583826) (xy 227.039932 -60.583826) (xy 227.036122 -60.584334) (xy 227.019588 -60.586737)
			(xy 226.98628 -60.589406) (xy 226.969574 -60.589668) (xy 226.969066 -60.589668) (xy 226.936554 -60.588398)
			(xy 226.935538 -60.588398) (xy 226.932744 -60.588144) (xy 226.894136 -60.589668) (xy 226.864166 -60.589201)
			(xy 226.80474 -60.581381) (xy 226.746842 -60.565871) (xy 226.691465 -60.542935) (xy 226.639555 -60.512967)
			(xy 226.592002 -60.476479) (xy 226.549619 -60.434095) (xy 226.513131 -60.386542) (xy 226.483163 -60.334632)
			(xy 226.460228 -60.279254) (xy 226.444718 -60.221357) (xy 226.436899 -60.16193) (xy 226.436428 -60.13196)
			(xy 226.436428 -59.26836) (xy 226.436921 -59.238395) (xy 226.444748 -59.178978) (xy 226.460264 -59.121091)
			(xy 226.483203 -59.065725) (xy 226.513173 -59.013826) (xy 226.54966 -58.966283) (xy 226.592041 -58.92391)
			(xy 226.639589 -58.887431) (xy 226.691493 -58.85747) (xy 226.746863 -58.83454) (xy 226.804753 -58.819033)
			(xy 226.864171 -58.811216) (xy 226.894136 -58.810652) (xy 226.92868 -58.811922) (xy 226.93249 -58.812176)
			(xy 226.935538 -58.811922) (xy 226.936554 -58.811922) (xy 226.938332 -58.811668) (xy 226.96932 -58.810652)
			(xy 226.999288 -58.811143) (xy 227.05871 -58.818968) (xy 227.116603 -58.834482) (xy 227.171976 -58.857419)
			(xy 227.223882 -58.887387) (xy 227.271432 -58.923873) (xy 227.313814 -58.966253) (xy 227.350302 -59.013801)
			(xy 227.380272 -59.065706) (xy 227.403211 -59.121078) (xy 227.418728 -59.17897) (xy 227.426555 -59.238392)
			(xy 227.427028 -59.26836) (xy 227.427028 -60.132722) (xy 227.426573 -60.161615) (xy 227.41927 -60.218938)
			(xy 227.404809 -60.274885) (xy 227.394516 -60.301886) (xy 227.394262 -60.302394) (xy 227.391214 -60.310268)
			(xy 227.38588 -60.324238) (xy 227.384491 -60.328357) (xy 227.382957 -60.336911) (xy 227.382832 -60.341256)
			(xy 227.383341 -60.353142) (xy 227.393812 -60.374469) (xy 227.402898 -60.38215) (xy 227.427536 -60.399422)
			(xy 227.428298 -60.39993) (xy 227.429314 -60.400692) (xy 227.430838 -60.401708) (xy 227.438458 -60.408312)
			(xy 227.458524 -60.429902) (xy 227.459032 -60.43041) (xy 227.463604 -60.435236) (xy 227.463858 -60.43549)
			(xy 227.469192 -60.441078) (xy 227.47478 -60.44438) (xy 227.48748 -60.449714) (xy 227.495862 -60.451492)
			(xy 227.508054 -60.451238) (xy 227.51415 -60.449714) (xy 227.514404 -60.449714) (xy 227.519022 -60.448644)
			(xy 227.528479 -60.448011) (xy 227.5332 -60.448444) (xy 227.577142 -60.454286) (xy 227.589588 -60.455556)
			(xy 227.59035 -60.455556) (xy 227.603304 -60.456318) (xy 227.617033 -60.455945) (xy 227.643857 -60.450071)
			(xy 227.668812 -60.438615) (xy 227.680012 -60.430664) (xy 227.682298 -60.428886) (xy 227.698046 -60.415678)
			(xy 227.700078 -60.4139) (xy 227.71354 -60.402216) (xy 227.715572 -60.400184) (xy 227.71886 -60.396705)
			(xy 227.724231 -60.388781) (xy 227.72624 -60.384436) (xy 227.730812 -60.372498) (xy 227.730304 -60.361576)
			(xy 227.730304 -60.361322) (xy 227.73005 -60.334652) (xy 227.73005 -60.329064) (xy 227.729288 -60.315856)
			(xy 227.729034 -60.312046) (xy 227.722938 -60.256166) (xy 227.722472 -60.250506) (xy 227.723758 -60.239226)
			(xy 227.725478 -60.233814) (xy 227.763832 -60.124848) (xy 227.765833 -60.119534) (xy 227.771853 -60.109908)
			(xy 227.77577 -60.105798) (xy 229.494842 -58.38698) (xy 229.5121 -58.370274) (xy 229.550896 -58.341955)
			(xy 229.593647 -58.320062) (xy 229.6393 -58.305135) (xy 229.686727 -58.297541) (xy 229.710742 -58.297064)
			(xy 229.808532 -58.297064) (xy 229.820724 -58.297572) (xy 229.826058 -58.297572) (xy 229.834254 -58.297269)
			(xy 229.849806 -58.292095) (xy 229.856538 -58.287412) (xy 229.862634 -58.28284) (xy 229.871524 -58.270394)
			(xy 229.874064 -58.263536) (xy 229.889546 -58.220647) (xy 229.926295 -58.137188) (xy 229.969432 -58.056844)
			(xy 230.018695 -57.980104) (xy 230.073784 -57.907433) (xy 230.134365 -57.839272) (xy 230.166926 -57.807352)
			(xy 230.202148 -57.774146) (xy 230.277225 -57.713028) (xy 230.3571 -57.658329) (xy 230.441226 -57.610424)
			(xy 230.529025 -57.56964) (xy 230.619896 -57.536257) (xy 230.713217 -57.510505) (xy 230.808348 -57.492558)
			(xy 230.904638 -57.482542) (xy 231.001426 -57.480523) (xy 231.098049 -57.486516) (xy 231.193846 -57.50048)
			(xy 231.28816 -57.522318) (xy 231.380344 -57.551883) (xy 231.469767 -57.58897) (xy 231.555817 -57.633326)
			(xy 231.637903 -57.684646) (xy 231.715464 -57.74258) (xy 231.787968 -57.80673) (xy 231.854917 -57.876657)
			(xy 231.915854 -57.951881) (xy 231.970361 -58.031888) (xy 232.018064 -58.116128) (xy 232.058636 -58.204025)
			(xy 232.075736 -58.249312) (xy 232.07853 -58.256932) (xy 232.082848 -58.262774) (xy 232.085122 -58.265631)
			(xy 232.090351 -58.270729) (xy 232.093262 -58.272934) (xy 232.116122 -58.288936) (xy 232.12806 -58.294778)
			(xy 232.137966 -58.297064) (xy 232.138474 -58.297064) (xy 232.144316 -58.297572) (xy 232.312972 -58.297572)
			(xy 232.322878 -58.297064) (xy 233.109008 -58.297064) (xy 233.133553 -58.29757) (xy 233.182005 -58.305452)
			(xy 233.228575 -58.320979) (xy 233.272062 -58.343753) (xy 233.311349 -58.373187) (xy 233.328718 -58.390536)
			(xy 233.416348 -58.481976) (xy 233.419503 -58.485481) (xy 233.424612 -58.493406) (xy 233.426508 -58.497724)
			(xy 233.426762 -58.498232) (xy 233.428794 -58.502804) (xy 233.428794 -58.503566) (xy 233.4641 -58.597292)
			(xy 233.465743 -58.602135) (xy 233.467279 -58.612245) (xy 233.467148 -58.617358) (xy 233.464862 -58.668158)
			(xy 233.464608 -58.672476) (xy 233.464608 -58.674254) (xy 233.46527 -58.69163) (xy 233.474767 -58.725065)
			(xy 233.492909 -58.754712) (xy 233.505248 -58.766964) (xy 233.505756 -58.767472) (xy 233.55427 -58.812938)
			(xy 233.558588 -58.816494) (xy 233.567766 -58.822703) (xy 233.589415 -58.827311) (xy 233.610987 -58.822352)
			(xy 233.620056 -58.815986) (xy 233.67111 -58.77306) (xy 233.673142 -58.771282) (xy 233.686889 -58.75893)
			(xy 233.70722 -58.728087) (xy 233.717895 -58.692722) (xy 233.718608 -58.674254) (xy 233.718608 -58.668158)
			(xy 233.717338 -58.643012) (xy 233.717338 -58.642504) (xy 233.716322 -58.621676) (xy 233.715814 -58.60796)
			(xy 233.755692 -58.50001) (xy 233.757601 -58.495166) (xy 233.763103 -58.486329) (xy 233.766614 -58.482484)
			(xy 233.85399 -58.391552) (xy 233.871364 -58.374139) (xy 233.910654 -58.344547) (xy 233.954181 -58.32164)
			(xy 234.00082 -58.306012) (xy 234.049361 -58.298067) (xy 234.073954 -58.297572) (xy 234.128056 -58.297572)
			(xy 234.137454 -58.297064) (xy 237.800896 -58.297064) (xy 237.824719 -58.297537) (xy 237.871783 -58.304971)
			(xy 237.91712 -58.319627) (xy 237.959629 -58.34115) (xy 237.998277 -58.369017) (xy 238.015526 -58.385456)
			(xy 238.101886 -58.4708) (xy 238.105375 -58.474412) (xy 238.111001 -58.48273) (xy 238.113062 -58.48731)
			(xy 238.12881 -58.524648) (xy 238.12881 -58.525156) (xy 238.153702 -58.58256) (xy 238.154718 -58.585608)
			(xy 238.156491 -58.591206) (xy 238.157658 -58.602887) (xy 238.157004 -58.608722) (xy 238.156496 -58.612278)
			(xy 238.15675 -58.641742) (xy 238.15675 -58.648092) (xy 238.15753 -58.664564) (xy 238.16648 -58.696292)
			(xy 238.183264 -58.724664) (xy 238.206761 -58.747786) (xy 238.2354 -58.764112) (xy 238.267267 -58.77255)
			(xy 238.28375 -58.77306) (xy 238.284258 -58.77306) (xy 238.29169 -58.773001) (xy 238.306461 -58.771346)
			(xy 238.313722 -58.769758) (xy 238.314738 -58.769504) (xy 238.322104 -58.767726) (xy 238.377222 -58.753756)
			(xy 238.377984 -58.753502) (xy 238.38154 -58.75274) (xy 238.387128 -58.751216) (xy 238.389414 -58.750708)
			(xy 238.392462 -58.75147) (xy 238.529622 -58.790332) (xy 238.531146 -58.790586) (xy 238.5441 -58.794396)
			(xy 238.544354 -58.794396) (xy 239.88776 -60.138056) (xy 239.904468 -60.155313) (xy 239.93279 -60.194107)
			(xy 239.954686 -60.236859) (xy 239.969614 -60.282512) (xy 239.977207 -60.32994) (xy 239.977676 -60.353956)
			(xy 239.977676 -60.527438) (xy 239.978692 -60.536836) (xy 239.978692 -60.537344) (xy 239.980404 -60.544499)
			(xy 239.987247 -60.557516) (xy 239.992154 -60.562998) (xy 240.005616 -60.57646) (xy 240.012982 -60.58027)
			(xy 240.037879 -60.593575) (xy 240.083805 -60.626396) (xy 240.124402 -60.665619) (xy 240.158785 -60.710388)
			(xy 240.186206 -60.759729) (xy 240.206069 -60.812567) (xy 240.217941 -60.867754) (xy 240.221562 -60.924086)
			(xy 240.216856 -60.980339) (xy 240.203923 -61.035286) (xy 240.183046 -61.087732) (xy 240.154679 -61.136536)
			(xy 240.119439 -61.180634) (xy 240.078094 -61.219066) (xy 240.031544 -61.250997) (xy 240.006378 -61.263784)
			(xy 240.006124 -61.263784) (xy 240.005616 -61.264038) (xy 239.999481 -61.267368) (xy 239.989176 -61.276777)
			(xy 239.985296 -61.28258) (xy 239.981486 -61.288422) (xy 239.979454 -61.295534) (xy 239.977676 -61.308996)
			(xy 239.977676 -61.585856) (xy 240.609372 -61.585856) (xy 240.613443 -61.530234) (xy 240.625569 -61.475797)
			(xy 240.645492 -61.423706) (xy 240.672788 -61.375071) (xy 240.706874 -61.330928) (xy 240.747023 -61.292219)
			(xy 240.792381 -61.259768) (xy 240.841981 -61.234267) (xy 240.894765 -61.21626) (xy 240.949608 -61.20613)
			(xy 241.005342 -61.204093) (xy 241.060779 -61.210193) (xy 241.114736 -61.224299) (xy 241.166065 -61.246111)
			(xy 241.213671 -61.275165) (xy 241.256539 -61.31084) (xy 241.293756 -61.352377) (xy 241.324529 -61.39889)
			(xy 241.348201 -61.449387) (xy 241.364269 -61.502794) (xy 241.372389 -61.55797) (xy 241.372898 -61.585856)
			(xy 241.372389 -61.613742) (xy 241.364269 -61.668918) (xy 241.348201 -61.722325) (xy 241.324529 -61.772822)
			(xy 241.293756 -61.819335) (xy 241.256539 -61.860872) (xy 241.213671 -61.896547) (xy 241.166065 -61.925601)
			(xy 241.114736 -61.947413) (xy 241.060779 -61.961519) (xy 241.005342 -61.967619) (xy 240.949608 -61.965582)
			(xy 240.894765 -61.955452) (xy 240.841981 -61.937445) (xy 240.792381 -61.911944) (xy 240.747023 -61.879493)
			(xy 240.706874 -61.840784) (xy 240.672788 -61.796641) (xy 240.645492 -61.748006) (xy 240.625569 -61.695915)
			(xy 240.613443 -61.641478) (xy 240.609372 -61.585856) (xy 239.977676 -61.585856) (xy 239.977676 -63.648082)
			(xy 241.242594 -63.648082) (xy 241.246665 -63.59246) (xy 241.258791 -63.538023) (xy 241.278714 -63.485932)
			(xy 241.30601 -63.437297) (xy 241.340096 -63.393154) (xy 241.380245 -63.354445) (xy 241.425603 -63.321994)
			(xy 241.475203 -63.296493) (xy 241.527987 -63.278486) (xy 241.58283 -63.268356) (xy 241.638564 -63.266319)
			(xy 241.694001 -63.272419) (xy 241.747958 -63.286525) (xy 241.799287 -63.308337) (xy 241.846893 -63.337391)
			(xy 241.889761 -63.373066) (xy 241.926978 -63.414603) (xy 241.957751 -63.461116) (xy 241.981423 -63.511613)
			(xy 241.997491 -63.56502) (xy 242.005611 -63.620196) (xy 242.00612 -63.648082) (xy 242.005611 -63.675968)
			(xy 241.997491 -63.731144) (xy 241.981423 -63.784551) (xy 241.957751 -63.835048) (xy 241.926978 -63.881561)
			(xy 241.889761 -63.923098) (xy 241.846893 -63.958773) (xy 241.799287 -63.987827) (xy 241.747958 -64.009639)
			(xy 241.694001 -64.023745) (xy 241.638564 -64.029845) (xy 241.58283 -64.027808) (xy 241.527987 -64.017678)
			(xy 241.475203 -63.999671) (xy 241.425603 -63.97417) (xy 241.380245 -63.941719) (xy 241.340096 -63.90301)
			(xy 241.30601 -63.858867) (xy 241.278714 -63.810232) (xy 241.258791 -63.758141) (xy 241.246665 -63.703704)
			(xy 241.242594 -63.648082) (xy 239.977676 -63.648082) (xy 239.977676 -64.653922) (xy 239.97784 -64.660076)
			(xy 239.980786 -64.672027) (xy 239.983518 -64.677544) (xy 239.985674 -64.681507) (xy 239.991166 -64.688664)
			(xy 239.99444 -64.691768) (xy 239.996472 -64.693292) (xy 239.99977 -64.695901) (xy 240.007044 -64.700118)
			(xy 240.01095 -64.701674) (xy 240.011712 -64.701928) (xy 240.013236 -64.70269) (xy 240.01349 -64.70269)
			(xy 240.082578 -64.73317) (xy 240.083086 -64.73317) (xy 240.092484 -64.737488) (xy 240.103975 -64.741727)
			(xy 240.12838 -64.74014) (xy 240.13922 -64.73444) (xy 240.149126 -64.72682) (xy 240.149634 -64.726312)
			(xy 240.170805 -64.707753) (xy 240.217585 -64.676429) (xy 240.268464 -64.652326) (xy 240.322334 -64.635969)
			(xy 240.378024 -64.627713) (xy 240.406174 -64.627252) (xy 240.415064 -64.627252) (xy 240.441912 -64.628314)
			(xy 240.494928 -64.637047) (xy 240.546194 -64.653133) (xy 240.594695 -64.676254) (xy 240.639471 -64.705952)
			(xy 240.679637 -64.74164) (xy 240.714397 -64.782612) (xy 240.743064 -64.828056) (xy 240.765069 -64.877073)
			(xy 240.779979 -64.928693) (xy 240.787496 -64.981895) (xy 240.787936 -65.00876) (xy 240.787477 -65.035366)
			(xy 240.780088 -65.088063) (xy 240.765448 -65.139222) (xy 240.743841 -65.187851) (xy 240.715686 -65.233005)
			(xy 240.68153 -65.273808) (xy 240.642034 -65.309469) (xy 240.597967 -65.339296) (xy 240.550182 -65.36271)
			(xy 240.499608 -65.379256) (xy 240.447225 -65.388614) (xy 240.420652 -65.390014) (xy 240.406682 -65.390268)
			(xy 240.397538 -65.390268) (xy 240.371819 -65.389266) (xy 240.320986 -65.381194) (xy 240.271701 -65.366352)
			(xy 240.224864 -65.345012) (xy 240.181324 -65.317562) (xy 240.161318 -65.301368) (xy 240.161064 -65.301114)
			(xy 240.155984 -65.29705) (xy 240.151157 -65.293764) (xy 240.14038 -65.289277) (xy 240.134648 -65.28816)
			(xy 240.108486 -65.28562) (xy 240.097818 -65.284604) (xy 240.092336 -65.284284) (xy 240.081447 -65.285689)
			(xy 240.076228 -65.287398) (xy 240.07572 -65.287398) (xy 240.072672 -65.288668) (xy 240.009426 -65.316608)
			(xy 240.007394 -65.317624) (xy 240.00714 -65.317624) (xy 240.0046 -65.318894) (xy 239.99378 -65.325454)
			(xy 239.979804 -65.34651) (xy 239.97793 -65.359026) (xy 239.977676 -65.363852) (xy 239.977676 -67.987926)
			(xy 239.977196 -68.011617) (xy 239.969809 -68.058421) (xy 239.95528 -68.103521) (xy 239.933957 -68.145836)
			(xy 239.906352 -68.184347) (xy 239.890046 -68.20154) (xy 239.887506 -68.20408) (xy 238.109506 -69.982334)
			(xy 238.09224 -69.998803) (xy 238.053549 -70.02672) (xy 238.010991 -70.04829) (xy 237.9656 -70.062991)
			(xy 237.918477 -70.070464) (xy 237.894622 -70.07098) (xy 234.169204 -70.07098) (xy 234.158282 -70.070472)
			(xy 234.113578 -70.070472) (xy 234.111292 -70.070726) (xy 234.104942 -70.070726) (xy 234.076928 -70.070096)
			(xy 234.021842 -70.059871) (xy 233.995468 -70.050406) (xy 233.968001 -70.039034) (xy 233.917734 -70.007311)
			(xy 233.895646 -69.987414) (xy 233.809286 -69.905626) (xy 233.805868 -69.902242) (xy 233.80024 -69.894444)
			(xy 233.79811 -69.890132) (xy 233.79176 -69.87667) (xy 233.781092 -69.85381) (xy 233.758232 -69.80428)
			(xy 233.75747 -69.802756) (xy 233.754422 -69.795898) (xy 233.75366 -69.78777) (xy 233.75366 -69.786754)
			(xy 233.74985 -69.73824) (xy 233.749596 -69.7357) (xy 233.747955 -69.718391) (xy 233.736577 -69.685553)
			(xy 233.716769 -69.656998) (xy 233.689996 -69.634839) (xy 233.658242 -69.620718) (xy 233.641138 -69.61759)
			(xy 233.63428 -69.617082) (xy 233.631486 -69.616828) (xy 233.615771 -69.616196) (xy 233.584825 -69.621752)
			(xy 233.556188 -69.634729) (xy 233.531608 -69.654334) (xy 233.512589 -69.67937) (xy 233.500293 -69.708306)
			(xy 233.497374 -69.723762) (xy 233.497374 -69.724524) (xy 233.496866 -69.727826) (xy 233.492294 -69.787516)
			(xy 233.491864 -69.792054) (xy 233.48957 -69.800875) (xy 233.487722 -69.805042) (xy 233.46791 -69.847206)
			(xy 233.46664 -69.849746) (xy 233.465878 -69.850762) (xy 233.45394 -69.876416) (xy 233.45394 -69.876924)
			(xy 233.44886 -69.887592) (xy 233.448606 -69.888354) (xy 233.446982 -69.891992) (xy 233.442778 -69.898759)
			(xy 233.440224 -69.901816) (xy 233.436414 -69.905626) (xy 233.434636 -69.90715) (xy 233.43362 -69.908166)
			(xy 233.411268 -69.929502) (xy 233.410506 -69.930518) (xy 233.407712 -69.933566) (xy 233.40314 -69.937884)
			(xy 233.402886 -69.938138) (xy 233.351324 -69.986906) (xy 233.334601 -70.002237) (xy 233.297466 -70.028296)
			(xy 233.256886 -70.048579) (xy 233.213755 -70.062642) (xy 233.169018 -70.070175) (xy 233.146346 -70.07098)
			(xy 232.272078 -70.07098) (xy 232.262172 -70.070472) (xy 232.155492 -70.070472) (xy 232.151548 -70.070558)
			(xy 232.143762 -70.071831) (xy 232.139998 -70.073012) (xy 232.132632 -70.075298) (xy 232.103168 -70.096888)
			(xy 232.096564 -70.102984) (xy 232.088944 -70.113144) (xy 232.087592 -70.116954) (xy 239.652554 -70.116954)
			(xy 239.656625 -70.061332) (xy 239.668751 -70.006895) (xy 239.688674 -69.954804) (xy 239.71597 -69.906169)
			(xy 239.750056 -69.862026) (xy 239.790205 -69.823317) (xy 239.835563 -69.790866) (xy 239.885163 -69.765365)
			(xy 239.937947 -69.747358) (xy 239.99279 -69.737228) (xy 240.048524 -69.735191) (xy 240.103961 -69.741291)
			(xy 240.157918 -69.755397) (xy 240.209247 -69.777209) (xy 240.256853 -69.806263) (xy 240.299721 -69.841938)
			(xy 240.336938 -69.883475) (xy 240.367711 -69.929988) (xy 240.391383 -69.980485) (xy 240.407451 -70.033892)
			(xy 240.415571 -70.089068) (xy 240.41608 -70.116954) (xy 240.415571 -70.14484) (xy 240.407451 -70.200016)
			(xy 240.391383 -70.253423) (xy 240.367711 -70.30392) (xy 240.336938 -70.350433) (xy 240.299721 -70.39197)
			(xy 240.256853 -70.427645) (xy 240.209247 -70.456699) (xy 240.157918 -70.478511) (xy 240.103961 -70.492617)
			(xy 240.048524 -70.498717) (xy 239.99279 -70.49668) (xy 239.937947 -70.48655) (xy 239.885163 -70.468543)
			(xy 239.835563 -70.443042) (xy 239.790205 -70.410591) (xy 239.750056 -70.371882) (xy 239.71597 -70.327739)
			(xy 239.688674 -70.279104) (xy 239.668751 -70.227013) (xy 239.656625 -70.172576) (xy 239.652554 -70.116954)
			(xy 232.087592 -70.116954) (xy 232.08615 -70.121018) (xy 232.070566 -70.166026) (xy 232.033065 -70.253589)
			(xy 231.988563 -70.337809) (xy 231.937356 -70.418129) (xy 231.879783 -70.494016) (xy 231.816226 -70.564967)
			(xy 231.747106 -70.630511) (xy 231.672882 -70.690213) (xy 231.594047 -70.743677) (xy 231.511122 -70.79055)
			(xy 231.424659 -70.830519) (xy 231.33523 -70.86332) (xy 231.243428 -70.888736) (xy 231.149863 -70.906598)
			(xy 231.055154 -70.916786) (xy 230.959931 -70.919235) (xy 230.864824 -70.913927) (xy 230.770464 -70.900898)
			(xy 230.677478 -70.880234) (xy 230.586481 -70.852072) (xy 230.498078 -70.8166) (xy 230.412854 -70.774051)
			(xy 230.331375 -70.724709) (xy 230.254181 -70.668901) (xy 230.181784 -70.606996) (xy 230.114664 -70.539406)
			(xy 230.083614 -70.503288) (xy 230.051106 -70.463895) (xy 229.992328 -70.380359) (xy 229.941067 -70.292011)
			(xy 229.897713 -70.199526) (xy 229.879652 -70.151752) (xy 229.864158 -70.106286) (xy 229.860344 -70.096284)
			(xy 229.84608 -70.080356) (xy 229.826585 -70.071575) (xy 229.815898 -70.07098) (xy 228.807772 -70.07098)
			(xy 228.803361 -70.070894) (xy 228.794673 -70.069365) (xy 228.7905 -70.067932) (xy 228.74605 -70.05193)
			(xy 228.721808 -70.042329) (xy 228.676755 -70.016089) (xy 228.636812 -69.982579) (xy 228.619558 -69.96303)
			(xy 228.612192 -69.953886) (xy 228.528118 -69.84619) (xy 228.527356 -69.845428) (xy 228.52507 -69.84238)
			(xy 228.520244 -69.83603) (xy 228.519736 -69.833744) (xy 228.51872 -69.829426) (xy 228.517704 -69.825362)
			(xy 228.51745 -69.823076) (xy 228.516942 -69.82079) (xy 228.509576 -69.788532) (xy 228.49205 -69.711062)
			(xy 228.490901 -69.705268) (xy 228.491026 -69.69346) (xy 228.492304 -69.687694) (xy 228.506528 -69.630036)
			(xy 228.506528 -69.629782) (xy 228.508177 -69.622463) (xy 228.509956 -69.607565) (xy 228.510084 -69.600064)
			(xy 228.510084 -69.59981) (xy 228.509542 -69.583195) (xy 228.500941 -69.551097) (xy 228.484326 -69.522319)
			(xy 228.460829 -69.498822) (xy 228.432051 -69.482207) (xy 228.399953 -69.473606) (xy 228.366723 -69.473606)
			(xy 228.334625 -69.482207) (xy 228.305847 -69.498822) (xy 228.28235 -69.522319) (xy 228.265735 -69.551097)
			(xy 228.257134 -69.583195) (xy 228.256592 -69.59981) (xy 228.257354 -69.614288) (xy 228.257862 -69.619114)
			(xy 228.25837 -69.622416) (xy 228.259894 -69.630036) (xy 228.270054 -69.671946) (xy 228.273864 -69.687694)
			(xy 228.275073 -69.69334) (xy 228.275206 -69.704884) (xy 228.274118 -69.710554) (xy 228.2698 -69.730366)
			(xy 228.2698 -69.730874) (xy 228.26472 -69.75348) (xy 228.248972 -69.824854) (xy 228.248972 -69.825362)
			(xy 228.24821 -69.827648) (xy 228.246432 -69.83603) (xy 228.241606 -69.84238) (xy 228.235256 -69.850762)
			(xy 228.154484 -69.953886) (xy 228.139783 -69.97193) (xy 228.10584 -70.003774) (xy 228.067453 -70.030092)
			(xy 228.025515 -70.050273) (xy 227.980997 -70.06385) (xy 227.934934 -70.070506) (xy 227.91166 -70.070726)
			(xy 227.907088 -70.070726) (xy 227.90531 -70.070472) (xy 227.850192 -70.070472) (xy 227.838 -70.068948)
			(xy 227.834698 -70.067932) (xy 227.736654 -70.031356) (xy 227.729796 -70.02526) (xy 227.729542 -70.025006)
			(xy 227.724716 -70.020688) (xy 227.694998 -69.994018) (xy 227.692712 -69.99224) (xy 227.689664 -69.989192)
			(xy 227.685854 -69.986652) (xy 227.6613 -69.967129) (xy 227.607366 -69.935097) (xy 227.549148 -69.911741)
			(xy 227.518722 -69.904102) (xy 227.516436 -69.903594) (xy 227.504244 -69.900546) (xy 227.503736 -69.900546)
			(xy 227.477828 -69.893942) (xy 227.475034 -69.89318) (xy 227.473764 -69.892418) (xy 227.469192 -69.890132)
			(xy 227.409502 -69.857112) (xy 227.407724 -69.85635) (xy 227.405692 -69.855334) (xy 227.403914 -69.854064)
			(xy 227.401882 -69.853048) (xy 227.398072 -69.849238) (xy 227.39731 -69.848476) (xy 227.272088 -69.723254)
			(xy 227.253379 -69.703746) (xy 227.222464 -69.659413) (xy 227.21062 -69.635116) (xy 227.207064 -69.627242)
			(xy 227.203508 -69.619622) (xy 227.198682 -69.605652) (xy 227.195448 -69.597296) (xy 227.18416 -69.583396)
			(xy 227.168774 -69.574236) (xy 227.151174 -69.57094) (xy 227.142294 -69.572124) (xy 227.141532 -69.572378)
			(xy 227.132908 -69.574241) (xy 227.117572 -69.582939) (xy 227.11156 -69.589396) (xy 227.105972 -69.596254)
			(xy 227.102924 -69.604128) (xy 227.101476 -69.608428) (xy 227.099941 -69.617371) (xy 227.099876 -69.621908)
			(xy 227.099876 -69.846952) (xy 227.09938 -69.872205) (xy 227.091488 -69.922091) (xy 227.075906 -69.970134)
			(xy 227.053016 -70.015156) (xy 227.023379 -70.056053) (xy 227.005896 -70.074282) (xy 227.005642 -70.074536)
			(xy 226.990148 -70.090284) (xy 226.983692 -70.097579) (xy 226.976358 -70.115606) (xy 226.975924 -70.125336)
			(xy 226.975924 -70.753732) (xy 226.975969 -70.757402) (xy 226.976987 -70.76467) (xy 226.977956 -70.76821)
			(xy 226.979269 -70.772289) (xy 226.983096 -70.779956) (xy 226.985576 -70.78345) (xy 226.987608 -70.78599)
			(xy 226.990148 -70.789038) (xy 227.039424 -70.83806) (xy 227.048568 -70.847204) (xy 227.069418 -70.868876)
			(xy 227.104784 -70.917513) (xy 227.132115 -70.97108) (xy 227.150738 -71.028259) (xy 227.160196 -71.087647)
			(xy 227.160836 -71.117714) (xy 227.160836 -71.539608) (xy 239.186464 -71.539608) (xy 239.190535 -71.483986)
			(xy 239.202661 -71.429549) (xy 239.222584 -71.377458) (xy 239.24988 -71.328823) (xy 239.283966 -71.28468)
			(xy 239.324115 -71.245971) (xy 239.369473 -71.21352) (xy 239.419073 -71.188019) (xy 239.471857 -71.170012)
			(xy 239.5267 -71.159882) (xy 239.582434 -71.157845) (xy 239.637871 -71.163945) (xy 239.691828 -71.178051)
			(xy 239.743157 -71.199863) (xy 239.790763 -71.228917) (xy 239.833631 -71.264592) (xy 239.870848 -71.306129)
			(xy 239.901621 -71.352642) (xy 239.925293 -71.403139) (xy 239.941361 -71.456546) (xy 239.949481 -71.511722)
			(xy 239.94999 -71.539608) (xy 239.949481 -71.567494) (xy 239.941361 -71.62267) (xy 239.925293 -71.676077)
			(xy 239.901621 -71.726574) (xy 239.870848 -71.773087) (xy 239.833631 -71.814624) (xy 239.790763 -71.850299)
			(xy 239.743157 -71.879353) (xy 239.691828 -71.901165) (xy 239.637871 -71.915271) (xy 239.582434 -71.921371)
			(xy 239.5267 -71.919334) (xy 239.471857 -71.909204) (xy 239.419073 -71.891197) (xy 239.369473 -71.865696)
			(xy 239.324115 -71.833245) (xy 239.283966 -71.794536) (xy 239.24988 -71.750393) (xy 239.222584 -71.701758)
			(xy 239.202661 -71.649667) (xy 239.190535 -71.59523) (xy 239.186464 -71.539608) (xy 227.160836 -71.539608)
			(xy 227.160836 -72.82307) (xy 227.161233 -72.831989) (xy 227.167346 -72.848747) (xy 227.172774 -72.855836)
			(xy 227.173536 -72.856852) (xy 227.201984 -72.86244) (xy 227.230282 -72.868522) (xy 227.284752 -72.888091)
			(xy 227.335639 -72.915668) (xy 227.381772 -72.95062) (xy 227.422093 -72.992143) (xy 227.455673 -73.039284)
			(xy 227.469192 -73.064878) (xy 227.480919 -73.089056) (xy 227.498226 -73.139928) (xy 227.508228 -73.192724)
			(xy 227.510728 -73.246401) (xy 227.505676 -73.299898) (xy 227.493171 -73.352158) (xy 227.473462 -73.402148)
			(xy 227.446937 -73.44888) (xy 227.414121 -73.491431) (xy 227.375662 -73.528959) (xy 227.33232 -73.560724)
			(xy 227.284952 -73.586096) (xy 227.234494 -73.604575) (xy 227.208334 -73.610724) (xy 227.198936 -73.612756)
			(xy 227.192078 -73.617074) (xy 227.188236 -73.619627) (xy 227.181464 -73.62589) (xy 227.178616 -73.62952)
			(xy 227.170996 -73.639934) (xy 227.170234 -73.641204) (xy 227.165935 -73.647732) (xy 227.161149 -73.662604)
			(xy 227.160836 -73.670414) (xy 227.160836 -76.826085) (xy 229.640845 -76.826085) (xy 229.640845 -76.766115)
			(xy 229.648673 -76.706658) (xy 229.664196 -76.648731) (xy 229.687147 -76.593327) (xy 229.717134 -76.541392)
			(xy 229.753643 -76.493816) (xy 229.796051 -76.451413) (xy 229.84363 -76.414908) (xy 229.895568 -76.384926)
			(xy 229.950975 -76.361981) (xy 230.008903 -76.346464) (xy 230.068361 -76.338642) (xy 230.098346 -76.338176)
			(xy 230.961946 -76.338176) (xy 230.991931 -76.338593) (xy 231.051387 -76.346426) (xy 231.109312 -76.361952)
			(xy 231.164715 -76.384906) (xy 231.216648 -76.414894) (xy 231.264223 -76.451404) (xy 231.306626 -76.493811)
			(xy 231.343131 -76.54139) (xy 231.373114 -76.593326) (xy 231.396063 -76.648732) (xy 231.411583 -76.706658)
			(xy 231.41941 -76.766115) (xy 231.41941 -76.826085) (xy 231.411583 -76.885542) (xy 231.396063 -76.943468)
			(xy 231.373114 -76.998874) (xy 231.343131 -77.05081) (xy 231.306626 -77.098389) (xy 231.264223 -77.140796)
			(xy 231.216648 -77.177306) (xy 231.164715 -77.207294) (xy 231.109312 -77.230248) (xy 231.051387 -77.245774)
			(xy 230.991931 -77.253607) (xy 230.961946 -77.2541) (xy 230.098346 -77.2541) (xy 230.068361 -77.253558)
			(xy 230.008903 -77.245736) (xy 229.950975 -77.230219) (xy 229.895568 -77.207274) (xy 229.84363 -77.177292)
			(xy 229.796051 -77.140787) (xy 229.753643 -77.098384) (xy 229.717134 -77.050808) (xy 229.687147 -76.998873)
			(xy 229.664196 -76.943469) (xy 229.648673 -76.885542) (xy 229.640845 -76.826085) (xy 227.160836 -76.826085)
			(xy 227.160836 -79.238094) (xy 227.9777 -79.238094) (xy 227.9777 -78.374494) (xy 227.97819 -78.344526)
			(xy 227.986013 -78.285104) (xy 228.001526 -78.227211) (xy 228.024462 -78.171838) (xy 228.054429 -78.119932)
			(xy 228.090916 -78.072382) (xy 228.133296 -78.030002) (xy 228.180846 -77.993515) (xy 228.232752 -77.963548)
			(xy 228.288125 -77.940612) (xy 228.346018 -77.925099) (xy 228.40544 -77.917276) (xy 228.465376 -77.917276)
			(xy 228.524798 -77.925099) (xy 228.582691 -77.940612) (xy 228.638064 -77.963548) (xy 228.68997 -77.993515)
			(xy 228.73752 -78.030002) (xy 228.7799 -78.072382) (xy 228.792845 -78.089252) (xy 232.193844 -78.089252)
			(xy 232.197915 -78.03363) (xy 232.210041 -77.979193) (xy 232.229964 -77.927102) (xy 232.25726 -77.878467)
			(xy 232.291346 -77.834324) (xy 232.331495 -77.795615) (xy 232.376853 -77.763164) (xy 232.426453 -77.737663)
			(xy 232.479237 -77.719656) (xy 232.53408 -77.709526) (xy 232.589814 -77.707489) (xy 232.645251 -77.713589)
			(xy 232.699208 -77.727695) (xy 232.750537 -77.749507) (xy 232.798143 -77.778561) (xy 232.841011 -77.814236)
			(xy 232.878228 -77.855773) (xy 232.909001 -77.902286) (xy 232.932673 -77.952783) (xy 232.948741 -78.00619)
			(xy 232.956861 -78.061366) (xy 232.95737 -78.089252) (xy 232.956861 -78.117138) (xy 232.948741 -78.172314)
			(xy 232.932673 -78.225721) (xy 232.909001 -78.276218) (xy 232.878228 -78.322731) (xy 232.841011 -78.364268)
			(xy 232.798143 -78.399943) (xy 232.750537 -78.428997) (xy 232.699208 -78.450809) (xy 232.645251 -78.464915)
			(xy 232.589814 -78.471015) (xy 232.53408 -78.468978) (xy 232.479237 -78.458848) (xy 232.426453 -78.440841)
			(xy 232.376853 -78.41534) (xy 232.331495 -78.382889) (xy 232.291346 -78.34418) (xy 232.25726 -78.300037)
			(xy 232.229964 -78.251402) (xy 232.210041 -78.199311) (xy 232.197915 -78.144874) (xy 232.193844 -78.089252)
			(xy 228.792845 -78.089252) (xy 228.816387 -78.119932) (xy 228.846354 -78.171838) (xy 228.86929 -78.227211)
			(xy 228.884803 -78.285104) (xy 228.892626 -78.344526) (xy 228.893116 -78.374494) (xy 228.893116 -79.005684)
			(xy 231.53446 -79.005684) (xy 231.538531 -78.950062) (xy 231.550657 -78.895625) (xy 231.57058 -78.843534)
			(xy 231.597876 -78.794899) (xy 231.631962 -78.750756) (xy 231.672111 -78.712047) (xy 231.717469 -78.679596)
			(xy 231.767069 -78.654095) (xy 231.819853 -78.636088) (xy 231.874696 -78.625958) (xy 231.93043 -78.623921)
			(xy 231.985867 -78.630021) (xy 232.039824 -78.644127) (xy 232.091153 -78.665939) (xy 232.138759 -78.694993)
			(xy 232.181627 -78.730668) (xy 232.218844 -78.772205) (xy 232.249617 -78.818718) (xy 232.273289 -78.869215)
			(xy 232.289357 -78.922622) (xy 232.297477 -78.977798) (xy 232.297986 -79.005684) (xy 232.297477 -79.03357)
			(xy 232.289357 -79.088746) (xy 232.273289 -79.142153) (xy 232.249617 -79.19265) (xy 232.218844 -79.239163)
			(xy 232.181627 -79.2807) (xy 232.138759 -79.316375) (xy 232.091153 -79.345429) (xy 232.039824 -79.367241)
			(xy 231.985867 -79.381347) (xy 231.93043 -79.387447) (xy 231.874696 -79.38541) (xy 231.819853 -79.37528)
			(xy 231.767069 -79.357273) (xy 231.717469 -79.331772) (xy 231.672111 -79.299321) (xy 231.631962 -79.260612)
			(xy 231.597876 -79.216469) (xy 231.57058 -79.167834) (xy 231.550657 -79.115743) (xy 231.538531 -79.061306)
			(xy 231.53446 -79.005684) (xy 228.893116 -79.005684) (xy 228.893116 -79.238094) (xy 228.892626 -79.268062)
			(xy 228.884803 -79.327484) (xy 228.86929 -79.385377) (xy 228.846354 -79.44075) (xy 228.816387 -79.492656)
			(xy 228.7799 -79.540206) (xy 228.73752 -79.582586) (xy 228.68997 -79.619073) (xy 228.638064 -79.64904)
			(xy 228.582691 -79.671976) (xy 228.524798 -79.687489) (xy 228.465376 -79.695312) (xy 228.40544 -79.695312)
			(xy 228.346018 -79.687489) (xy 228.288125 -79.671976) (xy 228.232752 -79.64904) (xy 228.180846 -79.619073)
			(xy 228.133296 -79.582586) (xy 228.090916 -79.540206) (xy 228.054429 -79.492656) (xy 228.024462 -79.44075)
			(xy 228.001526 -79.385377) (xy 227.986013 -79.327484) (xy 227.97819 -79.268062) (xy 227.9777 -79.238094)
			(xy 227.160836 -79.238094) (xy 227.160836 -80.183482) (xy 237.540292 -80.183482) (xy 237.540292 -79.319882)
			(xy 237.540782 -79.289914) (xy 237.548605 -79.230492) (xy 237.564118 -79.172599) (xy 237.587054 -79.117226)
			(xy 237.617021 -79.06532) (xy 237.653508 -79.01777) (xy 237.695888 -78.97539) (xy 237.743438 -78.938903)
			(xy 237.795344 -78.908936) (xy 237.850717 -78.886) (xy 237.90861 -78.870487) (xy 237.968032 -78.862664)
			(xy 238.027968 -78.862664) (xy 238.08739 -78.870487) (xy 238.145283 -78.886) (xy 238.200656 -78.908936)
			(xy 238.252562 -78.938903) (xy 238.300112 -78.97539) (xy 238.342492 -79.01777) (xy 238.378979 -79.06532)
			(xy 238.408946 -79.117226) (xy 238.431882 -79.172599) (xy 238.447395 -79.230492) (xy 238.455218 -79.289914)
			(xy 238.455708 -79.319882) (xy 238.455708 -80.183482) (xy 238.455218 -80.21345) (xy 238.447395 -80.272872)
			(xy 238.431882 -80.330765) (xy 238.408946 -80.386138) (xy 238.378979 -80.438044) (xy 238.342492 -80.485594)
			(xy 238.300112 -80.527974) (xy 238.252562 -80.564461) (xy 238.200656 -80.594428) (xy 238.145283 -80.617364)
			(xy 238.08739 -80.632877) (xy 238.027968 -80.6407) (xy 237.968032 -80.6407) (xy 237.90861 -80.632877)
			(xy 237.850717 -80.617364) (xy 237.795344 -80.594428) (xy 237.743438 -80.564461) (xy 237.695888 -80.527974)
			(xy 237.653508 -80.485594) (xy 237.617021 -80.438044) (xy 237.587054 -80.386138) (xy 237.564118 -80.330765)
			(xy 237.548605 -80.272872) (xy 237.540782 -80.21345) (xy 237.540292 -80.183482) (xy 227.160836 -80.183482)
			(xy 227.160836 -80.758538) (xy 241.160044 -80.758538) (xy 241.164115 -80.702916) (xy 241.176241 -80.648479)
			(xy 241.196164 -80.596388) (xy 241.22346 -80.547753) (xy 241.257546 -80.50361) (xy 241.297695 -80.464901)
			(xy 241.343053 -80.43245) (xy 241.392653 -80.406949) (xy 241.445437 -80.388942) (xy 241.50028 -80.378812)
			(xy 241.556014 -80.376775) (xy 241.611451 -80.382875) (xy 241.665408 -80.396981) (xy 241.716737 -80.418793)
			(xy 241.764343 -80.447847) (xy 241.807211 -80.483522) (xy 241.844428 -80.525059) (xy 241.875201 -80.571572)
			(xy 241.898873 -80.622069) (xy 241.914941 -80.675476) (xy 241.923061 -80.730652) (xy 241.92357 -80.758538)
			(xy 241.923061 -80.786424) (xy 241.914941 -80.8416) (xy 241.898873 -80.895007) (xy 241.875201 -80.945504)
			(xy 241.844428 -80.992017) (xy 241.807211 -81.033554) (xy 241.764343 -81.069229) (xy 241.716737 -81.098283)
			(xy 241.665408 -81.120095) (xy 241.611451 -81.134201) (xy 241.556014 -81.140301) (xy 241.50028 -81.138264)
			(xy 241.445437 -81.128134) (xy 241.392653 -81.110127) (xy 241.343053 -81.084626) (xy 241.297695 -81.052175)
			(xy 241.257546 -81.013466) (xy 241.22346 -80.969323) (xy 241.196164 -80.920688) (xy 241.176241 -80.868597)
			(xy 241.164115 -80.81416) (xy 241.160044 -80.758538) (xy 227.160836 -80.758538) (xy 227.160836 -81.19872)
			(xy 240.342164 -81.19872) (xy 240.346235 -81.143098) (xy 240.358361 -81.088661) (xy 240.378284 -81.03657)
			(xy 240.40558 -80.987935) (xy 240.439666 -80.943792) (xy 240.479815 -80.905083) (xy 240.525173 -80.872632)
			(xy 240.574773 -80.847131) (xy 240.627557 -80.829124) (xy 240.6824 -80.818994) (xy 240.738134 -80.816957)
			(xy 240.793571 -80.823057) (xy 240.847528 -80.837163) (xy 240.898857 -80.858975) (xy 240.946463 -80.888029)
			(xy 240.989331 -80.923704) (xy 241.026548 -80.965241) (xy 241.057321 -81.011754) (xy 241.080993 -81.062251)
			(xy 241.097061 -81.115658) (xy 241.105181 -81.170834) (xy 241.10569 -81.19872) (xy 241.105181 -81.226606)
			(xy 241.097061 -81.281782) (xy 241.080993 -81.335189) (xy 241.057321 -81.385686) (xy 241.026548 -81.432199)
			(xy 240.989331 -81.473736) (xy 240.946463 -81.509411) (xy 240.898857 -81.538465) (xy 240.847528 -81.560277)
			(xy 240.793571 -81.574383) (xy 240.738134 -81.580483) (xy 240.6824 -81.578446) (xy 240.627557 -81.568316)
			(xy 240.574773 -81.550309) (xy 240.525173 -81.524808) (xy 240.479815 -81.492357) (xy 240.439666 -81.453648)
			(xy 240.40558 -81.409505) (xy 240.378284 -81.36087) (xy 240.358361 -81.308779) (xy 240.346235 -81.254342)
			(xy 240.342164 -81.19872) (xy 227.160836 -81.19872) (xy 227.160836 -83.367118) (xy 232.68432 -83.367118)
			(xy 232.68432 -82.503518) (xy 232.68481 -82.47355) (xy 232.692633 -82.414128) (xy 232.708146 -82.356235)
			(xy 232.731082 -82.300862) (xy 232.761049 -82.248956) (xy 232.797536 -82.201406) (xy 232.839916 -82.159026)
			(xy 232.887466 -82.122539) (xy 232.939372 -82.092572) (xy 232.994745 -82.069636) (xy 233.052638 -82.054123)
			(xy 233.11206 -82.0463) (xy 233.171996 -82.0463) (xy 233.231418 -82.054123) (xy 233.289311 -82.069636)
			(xy 233.344684 -82.092572) (xy 233.39659 -82.122539) (xy 233.44414 -82.159026) (xy 233.48652 -82.201406)
			(xy 233.523007 -82.248956) (xy 233.552974 -82.300862) (xy 233.568014 -82.337171) (xy 238.132537 -82.337171)
			(xy 238.132537 -82.277229) (xy 238.140362 -82.217799) (xy 238.155876 -82.159898) (xy 238.178816 -82.104519)
			(xy 238.208788 -82.052607) (xy 238.24528 -82.005052) (xy 238.287667 -81.962667) (xy 238.335224 -81.926177)
			(xy 238.387137 -81.896207) (xy 238.442517 -81.87327) (xy 238.500418 -81.857758) (xy 238.559849 -81.849936)
			(xy 238.58982 -81.849468) (xy 239.45342 -81.849468) (xy 239.483385 -81.850007) (xy 239.542803 -81.857832)
			(xy 239.600691 -81.873345) (xy 239.656058 -81.896282) (xy 239.707959 -81.926248) (xy 239.755504 -81.962733)
			(xy 239.79788 -82.005111) (xy 239.834363 -82.052658) (xy 239.864327 -82.10456) (xy 239.887261 -82.159928)
			(xy 239.902772 -82.217817) (xy 239.910594 -82.277235) (xy 239.910594 -82.337165) (xy 239.902772 -82.396583)
			(xy 239.887261 -82.454472) (xy 239.864327 -82.50984) (xy 239.834363 -82.561742) (xy 239.79788 -82.609289)
			(xy 239.755504 -82.651667) (xy 239.707959 -82.688152) (xy 239.656058 -82.718118) (xy 239.600691 -82.741055)
			(xy 239.542803 -82.756568) (xy 239.483385 -82.764393) (xy 239.45342 -82.764884) (xy 238.58982 -82.764884)
			(xy 238.559849 -82.764464) (xy 238.500418 -82.756642) (xy 238.442517 -82.74113) (xy 238.387137 -82.718193)
			(xy 238.335224 -82.688223) (xy 238.287667 -82.651733) (xy 238.24528 -82.609348) (xy 238.208788 -82.561793)
			(xy 238.178816 -82.509881) (xy 238.155876 -82.454502) (xy 238.140362 -82.396601) (xy 238.132537 -82.337171)
			(xy 233.568014 -82.337171) (xy 233.57591 -82.356235) (xy 233.591423 -82.414128) (xy 233.599246 -82.47355)
			(xy 233.599736 -82.503518) (xy 233.599736 -83.367118) (xy 233.599246 -83.397086) (xy 233.591423 -83.456508)
			(xy 233.57591 -83.514401) (xy 233.552974 -83.569774) (xy 233.523007 -83.62168) (xy 233.48652 -83.66923)
			(xy 233.44414 -83.71161) (xy 233.39659 -83.748097) (xy 233.344684 -83.778064) (xy 233.289311 -83.801)
			(xy 233.231418 -83.816513) (xy 233.171996 -83.824336) (xy 233.11206 -83.824336) (xy 233.052638 -83.816513)
			(xy 232.994745 -83.801) (xy 232.939372 -83.778064) (xy 232.887466 -83.748097) (xy 232.839916 -83.71161)
			(xy 232.797536 -83.66923) (xy 232.761049 -83.62168) (xy 232.731082 -83.569774) (xy 232.708146 -83.514401)
			(xy 232.692633 -83.456508) (xy 232.68481 -83.397086) (xy 232.68432 -83.367118) (xy 227.160836 -83.367118)
			(xy 227.160836 -84.962492) (xy 227.845364 -84.962492) (xy 227.849435 -84.90687) (xy 227.861561 -84.852433)
			(xy 227.881484 -84.800342) (xy 227.90878 -84.751707) (xy 227.942866 -84.707564) (xy 227.983015 -84.668855)
			(xy 228.028373 -84.636404) (xy 228.077973 -84.610903) (xy 228.130757 -84.592896) (xy 228.1856 -84.582766)
			(xy 228.241334 -84.580729) (xy 228.296771 -84.586829) (xy 228.350728 -84.600935) (xy 228.402057 -84.622747)
			(xy 228.449663 -84.651801) (xy 228.492531 -84.687476) (xy 228.529748 -84.729013) (xy 228.560521 -84.775526)
			(xy 228.584193 -84.826023) (xy 228.600261 -84.87943) (xy 228.608381 -84.934606) (xy 228.60889 -84.962492)
			(xy 228.608381 -84.990378) (xy 228.600261 -85.045554) (xy 228.584193 -85.098961) (xy 228.560521 -85.149458)
			(xy 228.529748 -85.195971) (xy 228.492531 -85.237508) (xy 228.449663 -85.273183) (xy 228.402057 -85.302237)
			(xy 228.350728 -85.324049) (xy 228.296771 -85.338155) (xy 228.241334 -85.344255) (xy 228.1856 -85.342218)
			(xy 228.130757 -85.332088) (xy 228.077973 -85.314081) (xy 228.028373 -85.28858) (xy 227.983015 -85.256129)
			(xy 227.942866 -85.21742) (xy 227.90878 -85.173277) (xy 227.881484 -85.124642) (xy 227.861561 -85.072551)
			(xy 227.849435 -85.018114) (xy 227.845364 -84.962492) (xy 227.160836 -84.962492) (xy 227.160836 -85.238844)
			(xy 227.165916 -85.244432) (xy 227.19033 -85.260079) (xy 227.234568 -85.297569) (xy 227.272637 -85.341309)
			(xy 227.303664 -85.390297) (xy 227.315776 -85.416644) (xy 227.32597 -85.440866) (xy 227.331015 -85.458587)
			(xy 232.264389 -85.458587) (xy 232.264389 -85.398613) (xy 232.272218 -85.339151) (xy 232.28774 -85.28122)
			(xy 232.310692 -85.225811) (xy 232.34068 -85.173871) (xy 232.377191 -85.126291) (xy 232.4196 -85.083883)
			(xy 232.467181 -85.047373) (xy 232.519122 -85.017387) (xy 232.574531 -84.994437) (xy 232.632463 -84.978915)
			(xy 232.691925 -84.971088) (xy 232.721912 -84.97062) (xy 233.585512 -84.97062) (xy 233.615495 -84.971147)
			(xy 233.674947 -84.978975) (xy 233.732868 -84.994497) (xy 233.788268 -85.017445) (xy 233.840199 -85.047429)
			(xy 233.887772 -85.083934) (xy 233.930174 -85.126337) (xy 233.963295 -85.169502) (xy 238.555276 -85.169502)
			(xy 238.555276 -84.305902) (xy 238.555766 -84.275918) (xy 238.563594 -84.216462) (xy 238.579115 -84.158537)
			(xy 238.602064 -84.103133) (xy 238.632048 -84.051199) (xy 238.668554 -84.003623) (xy 238.710959 -83.961218)
			(xy 238.758535 -83.924712) (xy 238.810469 -83.894728) (xy 238.865873 -83.871779) (xy 238.923798 -83.856258)
			(xy 238.983254 -83.84843) (xy 239.043222 -83.84843) (xy 239.102678 -83.856258) (xy 239.160603 -83.871779)
			(xy 239.216007 -83.894728) (xy 239.267941 -83.924712) (xy 239.315517 -83.961218) (xy 239.357922 -84.003623)
			(xy 239.394428 -84.051199) (xy 239.424412 -84.103133) (xy 239.447361 -84.158537) (xy 239.462882 -84.216462)
			(xy 239.47071 -84.275918) (xy 239.4712 -84.305902) (xy 239.4712 -85.169502) (xy 239.47071 -85.199486)
			(xy 239.462882 -85.258942) (xy 239.447361 -85.316867) (xy 239.424412 -85.372271) (xy 239.394428 -85.424205)
			(xy 239.357922 -85.471781) (xy 239.315517 -85.514186) (xy 239.267941 -85.550692) (xy 239.216007 -85.580676)
			(xy 239.160603 -85.603625) (xy 239.102678 -85.619146) (xy 239.043222 -85.626974) (xy 238.983254 -85.626974)
			(xy 238.923798 -85.619146) (xy 238.865873 -85.603625) (xy 238.810469 -85.580676) (xy 238.758535 -85.550692)
			(xy 238.710959 -85.514186) (xy 238.668554 -85.471781) (xy 238.632048 -85.424205) (xy 238.602064 -85.372271)
			(xy 238.579115 -85.316867) (xy 238.563594 -85.258942) (xy 238.555766 -85.199486) (xy 238.555276 -85.169502)
			(xy 233.963295 -85.169502) (xy 233.966678 -85.173911) (xy 233.99666 -85.225842) (xy 234.019607 -85.281243)
			(xy 234.035127 -85.339165) (xy 234.042954 -85.398617) (xy 234.042954 -85.458583) (xy 234.035127 -85.518035)
			(xy 234.019607 -85.575957) (xy 233.99666 -85.631358) (xy 233.966678 -85.683289) (xy 233.930174 -85.730863)
			(xy 233.887772 -85.773266) (xy 233.840199 -85.809771) (xy 233.788268 -85.839755) (xy 233.732868 -85.862703)
			(xy 233.674947 -85.878225) (xy 233.615495 -85.886053) (xy 233.585512 -85.886544) (xy 232.721912 -85.886544)
			(xy 232.691925 -85.886112) (xy 232.632463 -85.878285) (xy 232.574531 -85.862763) (xy 232.519122 -85.839813)
			(xy 232.467181 -85.809827) (xy 232.4196 -85.773317) (xy 232.377191 -85.730909) (xy 232.34068 -85.683329)
			(xy 232.310692 -85.631389) (xy 232.28774 -85.57598) (xy 232.272218 -85.518049) (xy 232.264389 -85.458587)
			(xy 227.331015 -85.458587) (xy 227.340359 -85.49141) (xy 227.347677 -85.54345) (xy 227.347784 -85.596002)
			(xy 227.340677 -85.648072) (xy 227.326493 -85.698674) (xy 227.305498 -85.74685) (xy 227.278091 -85.79169)
			(xy 227.244789 -85.832344) (xy 227.206224 -85.868043) (xy 227.184966 -85.883496) (xy 227.18268 -85.88502)
			(xy 227.166678 -85.915246) (xy 227.163942 -85.920831) (xy 227.160979 -85.932905) (xy 227.160836 -85.939122)
			(xy 227.160836 -87.444066) (xy 232.194882 -87.444066) (xy 232.194882 -87.384134) (xy 232.202704 -87.324714)
			(xy 232.218215 -87.266824) (xy 232.241149 -87.211454) (xy 232.271114 -87.15955) (xy 232.307596 -87.112002)
			(xy 232.349973 -87.069621) (xy 232.397519 -87.033135) (xy 232.44942 -87.003166) (xy 232.504788 -86.980227)
			(xy 232.562677 -86.964712) (xy 232.622096 -86.956884) (xy 232.652062 -86.956392) (xy 233.515662 -86.956392)
			(xy 233.545633 -86.956859) (xy 233.605062 -86.964678) (xy 233.662961 -86.980188) (xy 233.718341 -87.003123)
			(xy 233.770254 -87.033091) (xy 233.81781 -87.069578) (xy 233.860197 -87.111961) (xy 233.896688 -87.159515)
			(xy 233.92666 -87.211425) (xy 233.9496 -87.266803) (xy 233.965115 -87.324701) (xy 233.972939 -87.384129)
			(xy 233.972939 -87.416385) (xy 234.381521 -87.416385) (xy 234.381521 -87.356415) (xy 234.389349 -87.296959)
			(xy 234.40487 -87.239032) (xy 234.42782 -87.183628) (xy 234.457804 -87.131692) (xy 234.494312 -87.084115)
			(xy 234.536717 -87.04171) (xy 234.584294 -87.005203) (xy 234.636229 -86.975219) (xy 234.691634 -86.952269)
			(xy 234.749561 -86.936748) (xy 234.809017 -86.928921) (xy 234.839002 -86.928452) (xy 235.702602 -86.928452)
			(xy 235.732587 -86.928914) (xy 235.792044 -86.936742) (xy 235.849971 -86.952264) (xy 235.905376 -86.975214)
			(xy 235.957312 -87.005199) (xy 236.004889 -87.041707) (xy 236.047295 -87.084112) (xy 236.083802 -87.13169)
			(xy 236.113787 -87.183626) (xy 236.136737 -87.239031) (xy 236.152258 -87.296958) (xy 236.160086 -87.356415)
			(xy 236.160086 -87.416385) (xy 236.152258 -87.475842) (xy 236.136737 -87.533769) (xy 236.113787 -87.589174)
			(xy 236.083802 -87.64111) (xy 236.047295 -87.688688) (xy 236.004889 -87.731093) (xy 235.957312 -87.767601)
			(xy 235.905376 -87.797586) (xy 235.849971 -87.820536) (xy 235.792044 -87.836058) (xy 235.732587 -87.843886)
			(xy 235.702602 -87.844376) (xy 234.839002 -87.844376) (xy 234.809017 -87.843879) (xy 234.749561 -87.836052)
			(xy 234.691634 -87.820531) (xy 234.636229 -87.797581) (xy 234.584294 -87.767597) (xy 234.536717 -87.73109)
			(xy 234.494312 -87.688685) (xy 234.457804 -87.641108) (xy 234.42782 -87.589172) (xy 234.40487 -87.533768)
			(xy 234.389349 -87.475841) (xy 234.381521 -87.416385) (xy 233.972939 -87.416385) (xy 233.972939 -87.444071)
			(xy 233.965115 -87.503499) (xy 233.9496 -87.561397) (xy 233.92666 -87.616775) (xy 233.896688 -87.668685)
			(xy 233.860197 -87.716239) (xy 233.81781 -87.758622) (xy 233.770254 -87.795109) (xy 233.718341 -87.825077)
			(xy 233.662961 -87.848012) (xy 233.605062 -87.863522) (xy 233.545633 -87.871341) (xy 233.515662 -87.871808)
			(xy 232.652062 -87.871808) (xy 232.622096 -87.871316) (xy 232.562677 -87.863488) (xy 232.504788 -87.847973)
			(xy 232.44942 -87.825034) (xy 232.397519 -87.795065) (xy 232.349973 -87.758579) (xy 232.307596 -87.716198)
			(xy 232.271114 -87.66865) (xy 232.241149 -87.616746) (xy 232.218215 -87.561376) (xy 232.202704 -87.503486)
			(xy 232.194882 -87.444066) (xy 227.160836 -87.444066) (xy 227.160836 -88.006187) (xy 238.124409 -88.006187)
			(xy 238.124409 -87.946213) (xy 238.132238 -87.886751) (xy 238.147762 -87.82882) (xy 238.170714 -87.773411)
			(xy 238.200704 -87.721472) (xy 238.237216 -87.673892) (xy 238.279627 -87.631486) (xy 238.32721 -87.594978)
			(xy 238.379152 -87.564994) (xy 238.434563 -87.542047) (xy 238.492496 -87.526529) (xy 238.551959 -87.518706)
			(xy 238.581946 -87.51824) (xy 239.445546 -87.51824) (xy 239.475528 -87.518729) (xy 239.53498 -87.526561)
			(xy 239.5929 -87.542086) (xy 239.648299 -87.565038) (xy 239.700228 -87.595024) (xy 239.747799 -87.631531)
			(xy 239.790199 -87.673935) (xy 239.826701 -87.72151) (xy 239.856682 -87.773442) (xy 239.879628 -87.828843)
			(xy 239.895148 -87.886765) (xy 239.902974 -87.946217) (xy 239.902974 -88.006183) (xy 239.895148 -88.065635)
			(xy 239.879628 -88.123557) (xy 239.856682 -88.178958) (xy 239.826701 -88.23089) (xy 239.790199 -88.278465)
			(xy 239.747799 -88.320869) (xy 239.700228 -88.357376) (xy 239.648299 -88.387362) (xy 239.5929 -88.410314)
			(xy 239.53498 -88.425839) (xy 239.475528 -88.433671) (xy 239.445546 -88.434164) (xy 238.581946 -88.434164)
			(xy 238.551959 -88.433694) (xy 238.492496 -88.425871) (xy 238.434563 -88.410353) (xy 238.379152 -88.387406)
			(xy 238.32721 -88.357422) (xy 238.279627 -88.320914) (xy 238.237216 -88.278508) (xy 238.200704 -88.230928)
			(xy 238.170714 -88.178989) (xy 238.147762 -88.12358) (xy 238.132238 -88.065649) (xy 238.124409 -88.006187)
			(xy 227.160836 -88.006187) (xy 227.160836 -89.182956) (xy 227.930708 -89.182956) (xy 227.934779 -89.127334)
			(xy 227.946905 -89.072897) (xy 227.966828 -89.020806) (xy 227.994124 -88.972171) (xy 228.02821 -88.928028)
			(xy 228.068359 -88.889319) (xy 228.113717 -88.856868) (xy 228.163317 -88.831367) (xy 228.216101 -88.81336)
			(xy 228.270944 -88.80323) (xy 228.326678 -88.801193) (xy 228.382115 -88.807293) (xy 228.436072 -88.821399)
			(xy 228.487401 -88.843211) (xy 228.535007 -88.872265) (xy 228.55582 -88.889586) (xy 234.138976 -88.889586)
			(xy 234.143047 -88.833964) (xy 234.155173 -88.779527) (xy 234.175096 -88.727436) (xy 234.202392 -88.678801)
			(xy 234.236478 -88.634658) (xy 234.276627 -88.595949) (xy 234.321985 -88.563498) (xy 234.371585 -88.537997)
			(xy 234.424369 -88.51999) (xy 234.479212 -88.50986) (xy 234.534946 -88.507823) (xy 234.590383 -88.513923)
			(xy 234.64434 -88.528029) (xy 234.695669 -88.549841) (xy 234.743275 -88.578895) (xy 234.786143 -88.61457)
			(xy 234.82336 -88.656107) (xy 234.854133 -88.70262) (xy 234.877805 -88.753117) (xy 234.893873 -88.806524)
			(xy 234.901993 -88.8617) (xy 234.902502 -88.889586) (xy 234.901993 -88.917472) (xy 234.893873 -88.972648)
			(xy 234.877805 -89.026055) (xy 234.854133 -89.076552) (xy 234.82336 -89.123065) (xy 234.786143 -89.164602)
			(xy 234.743275 -89.200277) (xy 234.695669 -89.229331) (xy 234.64434 -89.251143) (xy 234.590383 -89.265249)
			(xy 234.534946 -89.271349) (xy 234.479212 -89.269312) (xy 234.424369 -89.259182) (xy 234.371585 -89.241175)
			(xy 234.321985 -89.215674) (xy 234.276627 -89.183223) (xy 234.236478 -89.144514) (xy 234.202392 -89.100371)
			(xy 234.175096 -89.051736) (xy 234.155173 -88.999645) (xy 234.143047 -88.945208) (xy 234.138976 -88.889586)
			(xy 228.55582 -88.889586) (xy 228.577875 -88.90794) (xy 228.615092 -88.949477) (xy 228.645865 -88.99599)
			(xy 228.669537 -89.046487) (xy 228.685605 -89.099894) (xy 228.693725 -89.15507) (xy 228.694234 -89.182956)
			(xy 228.693725 -89.210842) (xy 228.685605 -89.266018) (xy 228.669537 -89.319425) (xy 228.645865 -89.369922)
			(xy 228.615092 -89.416435) (xy 228.577875 -89.457972) (xy 228.535007 -89.493647) (xy 228.487401 -89.522701)
			(xy 228.436072 -89.544513) (xy 228.382115 -89.558619) (xy 228.326678 -89.564719) (xy 228.270944 -89.562682)
			(xy 228.216101 -89.552552) (xy 228.163317 -89.534545) (xy 228.113717 -89.509044) (xy 228.068359 -89.476593)
			(xy 228.02821 -89.437884) (xy 227.994124 -89.393741) (xy 227.966828 -89.345106) (xy 227.946905 -89.293015)
			(xy 227.934779 -89.238578) (xy 227.930708 -89.182956) (xy 227.160836 -89.182956) (xy 227.160836 -90.009726)
			(xy 227.35235 -90.009726) (xy 227.356421 -89.954104) (xy 227.368547 -89.899667) (xy 227.38847 -89.847576)
			(xy 227.415766 -89.798941) (xy 227.449852 -89.754798) (xy 227.490001 -89.716089) (xy 227.535359 -89.683638)
			(xy 227.584959 -89.658137) (xy 227.637743 -89.64013) (xy 227.692586 -89.63) (xy 227.74832 -89.627963)
			(xy 227.803757 -89.634063) (xy 227.857714 -89.648169) (xy 227.909043 -89.669981) (xy 227.956649 -89.699035)
			(xy 227.999517 -89.73471) (xy 228.036734 -89.776247) (xy 228.067507 -89.82276) (xy 228.091179 -89.873257)
			(xy 228.107247 -89.926664) (xy 228.115367 -89.98184) (xy 228.115876 -90.009726) (xy 228.115367 -90.037612)
			(xy 228.107247 -90.092788) (xy 228.091179 -90.146195) (xy 228.067507 -90.196692) (xy 228.036734 -90.243205)
			(xy 228.018328 -90.263747) (xy 229.611726 -90.263747) (xy 229.611726 -90.209253) (xy 229.619481 -90.155314)
			(xy 229.634833 -90.103027) (xy 229.65747 -90.053457) (xy 229.686931 -90.007614) (xy 229.722616 -89.966429)
			(xy 229.763799 -89.930742) (xy 229.809642 -89.901279) (xy 229.85921 -89.87864) (xy 229.911496 -89.863285)
			(xy 229.965435 -89.855527) (xy 229.992682 -89.85504) (xy 230.019221 -89.85549) (xy 230.071788 -89.862832)
			(xy 230.122829 -89.877391) (xy 230.171359 -89.898886) (xy 230.216441 -89.926901) (xy 230.257203 -89.960896)
			(xy 230.292859 -90.000214) (xy 230.322719 -90.044095) (xy 230.346208 -90.091692) (xy 230.362871 -90.142085)
			(xy 230.372386 -90.194303) (xy 230.373461 -90.212672) (xy 236.886494 -90.212672) (xy 236.890565 -90.15705)
			(xy 236.902691 -90.102613) (xy 236.922614 -90.050522) (xy 236.94991 -90.001887) (xy 236.983996 -89.957744)
			(xy 237.024145 -89.919035) (xy 237.069503 -89.886584) (xy 237.119103 -89.861083) (xy 237.171887 -89.843076)
			(xy 237.22673 -89.832946) (xy 237.282464 -89.830909) (xy 237.337901 -89.837009) (xy 237.391858 -89.851115)
			(xy 237.443187 -89.872927) (xy 237.490793 -89.901981) (xy 237.533661 -89.937656) (xy 237.570878 -89.979193)
			(xy 237.601651 -90.025706) (xy 237.625323 -90.076203) (xy 237.641391 -90.12961) (xy 237.649511 -90.184786)
			(xy 237.65002 -90.212672) (xy 237.649511 -90.240558) (xy 237.641391 -90.295734) (xy 237.625323 -90.349141)
			(xy 237.601651 -90.399638) (xy 237.570878 -90.446151) (xy 237.533661 -90.487688) (xy 237.490793 -90.523363)
			(xy 237.443187 -90.552417) (xy 237.391858 -90.574229) (xy 237.337901 -90.588335) (xy 237.282464 -90.594435)
			(xy 237.22673 -90.592398) (xy 237.171887 -90.582268) (xy 237.119103 -90.564261) (xy 237.069503 -90.53876)
			(xy 237.024145 -90.506309) (xy 236.983996 -90.4676) (xy 236.94991 -90.423457) (xy 236.922614 -90.374822)
			(xy 236.902691 -90.322731) (xy 236.890565 -90.268294) (xy 236.886494 -90.212672) (xy 230.373461 -90.212672)
			(xy 230.373936 -90.2208) (xy 230.374664 -90.230031) (xy 230.38189 -90.247067) (xy 230.394703 -90.260417)
			(xy 230.402892 -90.264742) (xy 230.483918 -90.303096) (xy 230.492374 -90.30672) (xy 230.510698 -90.308241)
			(xy 230.528377 -90.303188) (xy 230.535988 -90.298016) (xy 230.536242 -90.298016) (xy 230.561108 -90.28021)
			(xy 230.615337 -90.251937) (xy 230.673382 -90.232678) (xy 230.733756 -90.222926) (xy 230.764334 -90.222324)
			(xy 230.791588 -90.222746) (xy 230.845539 -90.230508) (xy 230.897837 -90.245869) (xy 230.947417 -90.268517)
			(xy 230.993268 -90.29799) (xy 231.034459 -90.333688) (xy 231.07015 -90.374885) (xy 231.099615 -90.420741)
			(xy 231.122254 -90.470325) (xy 231.137606 -90.522625) (xy 231.145358 -90.576578) (xy 231.145842 -90.603832)
			(xy 231.145409 -90.631204) (xy 231.137585 -90.685385) (xy 231.122089 -90.737889) (xy 231.09924 -90.787635)
			(xy 231.069507 -90.8336) (xy 231.051862 -90.85453) (xy 231.045818 -90.862034) (xy 231.039432 -90.880199)
			(xy 231.039416 -90.889836) (xy 231.042718 -90.969592) (xy 231.050592 -90.986864) (xy 231.05745 -90.993722)
			(xy 231.07528 -91.011731) (xy 231.106509 -91.051642) (xy 231.12844 -91.088972) (xy 236.971838 -91.088972)
			(xy 236.975909 -91.03335) (xy 236.988035 -90.978913) (xy 237.007958 -90.926822) (xy 237.035254 -90.878187)
			(xy 237.06934 -90.834044) (xy 237.109489 -90.795335) (xy 237.154847 -90.762884) (xy 237.204447 -90.737383)
			(xy 237.257231 -90.719376) (xy 237.312074 -90.709246) (xy 237.367808 -90.707209) (xy 237.423245 -90.713309)
			(xy 237.477202 -90.727415) (xy 237.528531 -90.749227) (xy 237.576137 -90.778281) (xy 237.619005 -90.813956)
			(xy 237.656222 -90.855493) (xy 237.686995 -90.902006) (xy 237.710667 -90.952503) (xy 237.726735 -91.00591)
			(xy 237.734855 -91.061086) (xy 237.735364 -91.088972) (xy 237.734855 -91.116858) (xy 237.726735 -91.172034)
			(xy 237.710667 -91.225441) (xy 237.686995 -91.275938) (xy 237.656222 -91.322451) (xy 237.619005 -91.363988)
			(xy 237.576137 -91.399663) (xy 237.528531 -91.428717) (xy 237.477202 -91.450529) (xy 237.423245 -91.464635)
			(xy 237.367808 -91.470735) (xy 237.312074 -91.468698) (xy 237.257231 -91.458568) (xy 237.204447 -91.440561)
			(xy 237.154847 -91.41506) (xy 237.109489 -91.382609) (xy 237.06934 -91.3439) (xy 237.035254 -91.299757)
			(xy 237.007958 -91.251122) (xy 236.988035 -91.199031) (xy 236.975909 -91.144594) (xy 236.971838 -91.088972)
			(xy 231.12844 -91.088972) (xy 231.132179 -91.095337) (xy 231.151837 -91.142047) (xy 231.165137 -91.190948)
			(xy 231.171845 -91.241179) (xy 231.172258 -91.266518) (xy 231.171772 -91.293769) (xy 231.164016 -91.347717)
			(xy 231.148661 -91.400012) (xy 231.126019 -91.449589) (xy 231.096553 -91.495439) (xy 231.060862 -91.53663)
			(xy 231.019671 -91.572321) (xy 230.973821 -91.601787) (xy 230.924244 -91.624429) (xy 230.871949 -91.639784)
			(xy 230.818001 -91.64754) (xy 230.763499 -91.64754) (xy 230.709551 -91.639784) (xy 230.657256 -91.624429)
			(xy 230.607679 -91.601787) (xy 230.561829 -91.572321) (xy 230.520638 -91.53663) (xy 230.484947 -91.495439)
			(xy 230.455481 -91.449589) (xy 230.432839 -91.400012) (xy 230.417484 -91.347717) (xy 230.409728 -91.293769)
			(xy 230.409242 -91.266518) (xy 230.409708 -91.239148) (xy 230.417525 -91.184968) (xy 230.433013 -91.132465)
			(xy 230.455855 -91.082718) (xy 230.48558 -91.036751) (xy 230.503222 -91.01582) (xy 230.509242 -91.008299)
			(xy 230.515643 -90.990147) (xy 230.515668 -90.980514) (xy 230.512366 -90.900758) (xy 230.504492 -90.883486)
			(xy 230.497634 -90.876628) (xy 230.47735 -90.85612) (xy 230.442623 -90.810066) (xy 230.415233 -90.759303)
			(xy 230.395808 -90.704992) (xy 230.38479 -90.648374) (xy 230.38308 -90.61958) (xy 230.382357 -90.610348)
			(xy 230.375127 -90.593314) (xy 230.362313 -90.579964) (xy 230.354124 -90.575638) (xy 230.273098 -90.537284)
			(xy 230.264636 -90.533676) (xy 230.246316 -90.532151) (xy 230.228639 -90.537197) (xy 230.221028 -90.542364)
			(xy 230.220774 -90.542364) (xy 230.19591 -90.560173) (xy 230.14168 -90.588443) (xy 230.083634 -90.607701)
			(xy 230.02326 -90.617453) (xy 229.992682 -90.618056) (xy 229.965435 -90.617473) (xy 229.911496 -90.609715)
			(xy 229.85921 -90.59436) (xy 229.809642 -90.571721) (xy 229.763799 -90.542258) (xy 229.722616 -90.506571)
			(xy 229.686931 -90.465386) (xy 229.65747 -90.419543) (xy 229.634833 -90.369973) (xy 229.619481 -90.317686)
			(xy 229.611726 -90.263747) (xy 228.018328 -90.263747) (xy 227.999517 -90.284742) (xy 227.956649 -90.320417)
			(xy 227.909043 -90.349471) (xy 227.857714 -90.371283) (xy 227.803757 -90.385389) (xy 227.74832 -90.391489)
			(xy 227.692586 -90.389452) (xy 227.637743 -90.379322) (xy 227.584959 -90.361315) (xy 227.535359 -90.335814)
			(xy 227.490001 -90.303363) (xy 227.449852 -90.264654) (xy 227.415766 -90.220511) (xy 227.38847 -90.171876)
			(xy 227.368547 -90.119785) (xy 227.356421 -90.065348) (xy 227.35235 -90.009726) (xy 227.160836 -90.009726)
			(xy 227.160836 -91.025726) (xy 227.35235 -91.025726) (xy 227.356421 -90.970104) (xy 227.368547 -90.915667)
			(xy 227.38847 -90.863576) (xy 227.415766 -90.814941) (xy 227.449852 -90.770798) (xy 227.490001 -90.732089)
			(xy 227.535359 -90.699638) (xy 227.584959 -90.674137) (xy 227.637743 -90.65613) (xy 227.692586 -90.646)
			(xy 227.74832 -90.643963) (xy 227.803757 -90.650063) (xy 227.857714 -90.664169) (xy 227.909043 -90.685981)
			(xy 227.956649 -90.715035) (xy 227.999517 -90.75071) (xy 228.036734 -90.792247) (xy 228.067507 -90.83876)
			(xy 228.091179 -90.889257) (xy 228.107247 -90.942664) (xy 228.115367 -90.99784) (xy 228.115876 -91.025726)
			(xy 228.115367 -91.053612) (xy 228.107247 -91.108788) (xy 228.091179 -91.162195) (xy 228.067507 -91.212692)
			(xy 228.036734 -91.259205) (xy 227.999517 -91.300742) (xy 227.956649 -91.336417) (xy 227.909043 -91.365471)
			(xy 227.857714 -91.387283) (xy 227.803757 -91.401389) (xy 227.74832 -91.407489) (xy 227.692586 -91.405452)
			(xy 227.637743 -91.395322) (xy 227.584959 -91.377315) (xy 227.535359 -91.351814) (xy 227.490001 -91.319363)
			(xy 227.449852 -91.280654) (xy 227.415766 -91.236511) (xy 227.38847 -91.187876) (xy 227.368547 -91.135785)
			(xy 227.356421 -91.081348) (xy 227.35235 -91.025726) (xy 227.160836 -91.025726) (xy 227.160836 -91.988132)
			(xy 229.487982 -91.988132) (xy 229.492053 -91.93251) (xy 229.504179 -91.878073) (xy 229.524102 -91.825982)
			(xy 229.551398 -91.777347) (xy 229.585484 -91.733204) (xy 229.625633 -91.694495) (xy 229.670991 -91.662044)
			(xy 229.720591 -91.636543) (xy 229.773375 -91.618536) (xy 229.828218 -91.608406) (xy 229.883952 -91.606369)
			(xy 229.939389 -91.612469) (xy 229.993346 -91.626575) (xy 230.044675 -91.648387) (xy 230.047829 -91.650312)
			(xy 239.454434 -91.650312) (xy 239.458505 -91.59469) (xy 239.470631 -91.540253) (xy 239.490554 -91.488162)
			(xy 239.51785 -91.439527) (xy 239.551936 -91.395384) (xy 239.592085 -91.356675) (xy 239.637443 -91.324224)
			(xy 239.687043 -91.298723) (xy 239.739827 -91.280716) (xy 239.79467 -91.270586) (xy 239.850404 -91.268549)
			(xy 239.905841 -91.274649) (xy 239.959798 -91.288755) (xy 240.011127 -91.310567) (xy 240.058733 -91.339621)
			(xy 240.101601 -91.375296) (xy 240.138818 -91.416833) (xy 240.169591 -91.463346) (xy 240.193263 -91.513843)
			(xy 240.209331 -91.56725) (xy 240.217451 -91.622426) (xy 240.21796 -91.650312) (xy 240.217451 -91.678198)
			(xy 240.209331 -91.733374) (xy 240.193263 -91.786781) (xy 240.169591 -91.837278) (xy 240.138818 -91.883791)
			(xy 240.101601 -91.925328) (xy 240.058733 -91.961003) (xy 240.011127 -91.990057) (xy 239.959798 -92.011869)
			(xy 239.905841 -92.025975) (xy 239.850404 -92.032075) (xy 239.79467 -92.030038) (xy 239.739827 -92.019908)
			(xy 239.687043 -92.001901) (xy 239.637443 -91.9764) (xy 239.592085 -91.943949) (xy 239.551936 -91.90524)
			(xy 239.51785 -91.861097) (xy 239.490554 -91.812462) (xy 239.470631 -91.760371) (xy 239.458505 -91.705934)
			(xy 239.454434 -91.650312) (xy 230.047829 -91.650312) (xy 230.092281 -91.677441) (xy 230.135149 -91.713116)
			(xy 230.172366 -91.754653) (xy 230.203139 -91.801166) (xy 230.226811 -91.851663) (xy 230.242879 -91.90507)
			(xy 230.250999 -91.960246) (xy 230.251508 -91.988132) (xy 230.250999 -92.016018) (xy 230.242879 -92.071194)
			(xy 230.226811 -92.124601) (xy 230.203139 -92.175098) (xy 230.172366 -92.221611) (xy 230.135149 -92.263148)
			(xy 230.092281 -92.298823) (xy 230.044675 -92.327877) (xy 229.993346 -92.349689) (xy 229.939389 -92.363795)
			(xy 229.883952 -92.369895) (xy 229.828218 -92.367858) (xy 229.773375 -92.357728) (xy 229.720591 -92.339721)
			(xy 229.670991 -92.31422) (xy 229.625633 -92.281769) (xy 229.585484 -92.24306) (xy 229.551398 -92.198917)
			(xy 229.524102 -92.150282) (xy 229.504179 -92.098191) (xy 229.492053 -92.043754) (xy 229.487982 -91.988132)
			(xy 227.160836 -91.988132) (xy 227.160836 -92.665042) (xy 237.406432 -92.665042) (xy 237.410503 -92.60942)
			(xy 237.422629 -92.554983) (xy 237.442552 -92.502892) (xy 237.469848 -92.454257) (xy 237.503934 -92.410114)
			(xy 237.544083 -92.371405) (xy 237.589441 -92.338954) (xy 237.639041 -92.313453) (xy 237.691825 -92.295446)
			(xy 237.746668 -92.285316) (xy 237.802402 -92.283279) (xy 237.857839 -92.289379) (xy 237.911796 -92.303485)
			(xy 237.963125 -92.325297) (xy 238.010731 -92.354351) (xy 238.053599 -92.390026) (xy 238.090816 -92.431563)
			(xy 238.121589 -92.478076) (xy 238.145261 -92.528573) (xy 238.161329 -92.58198) (xy 238.169449 -92.637156)
			(xy 238.169958 -92.665042) (xy 238.169449 -92.692928) (xy 238.161329 -92.748104) (xy 238.145261 -92.801511)
			(xy 238.121589 -92.852008) (xy 238.090816 -92.898521) (xy 238.053599 -92.940058) (xy 238.010731 -92.975733)
			(xy 237.963125 -93.004787) (xy 237.911796 -93.026599) (xy 237.857839 -93.040705) (xy 237.802402 -93.046805)
			(xy 237.746668 -93.044768) (xy 237.691825 -93.034638) (xy 237.639041 -93.016631) (xy 237.589441 -92.99113)
			(xy 237.544083 -92.958679) (xy 237.503934 -92.91997) (xy 237.469848 -92.875827) (xy 237.442552 -92.827192)
			(xy 237.422629 -92.775101) (xy 237.410503 -92.720664) (xy 237.406432 -92.665042) (xy 227.160836 -92.665042)
			(xy 227.160836 -93.266514) (xy 229.782876 -93.266514) (xy 229.786947 -93.210892) (xy 229.799073 -93.156455)
			(xy 229.818996 -93.104364) (xy 229.846292 -93.055729) (xy 229.880378 -93.011586) (xy 229.920527 -92.972877)
			(xy 229.965885 -92.940426) (xy 230.015485 -92.914925) (xy 230.068269 -92.896918) (xy 230.123112 -92.886788)
			(xy 230.178846 -92.884751) (xy 230.234283 -92.890851) (xy 230.28824 -92.904957) (xy 230.339569 -92.926769)
			(xy 230.387175 -92.955823) (xy 230.430043 -92.991498) (xy 230.46726 -93.033035) (xy 230.498033 -93.079548)
			(xy 230.521705 -93.130045) (xy 230.537773 -93.183452) (xy 230.545893 -93.238628) (xy 230.546402 -93.266514)
			(xy 230.545893 -93.2944) (xy 230.537773 -93.349576) (xy 230.521705 -93.402983) (xy 230.498033 -93.45348)
			(xy 230.46726 -93.499993) (xy 230.430043 -93.54153) (xy 230.387175 -93.577205) (xy 230.339569 -93.606259)
			(xy 230.28824 -93.628071) (xy 230.234283 -93.642177) (xy 230.178846 -93.648277) (xy 230.123112 -93.64624)
			(xy 230.068269 -93.63611) (xy 230.015485 -93.618103) (xy 229.965885 -93.592602) (xy 229.920527 -93.560151)
			(xy 229.880378 -93.521442) (xy 229.846292 -93.477299) (xy 229.818996 -93.428664) (xy 229.799073 -93.376573)
			(xy 229.786947 -93.322136) (xy 229.782876 -93.266514) (xy 227.160836 -93.266514) (xy 227.160836 -93.76664)
			(xy 236.86592 -93.76664) (xy 236.869991 -93.711018) (xy 236.882117 -93.656581) (xy 236.90204 -93.60449)
			(xy 236.929336 -93.555855) (xy 236.963422 -93.511712) (xy 237.003571 -93.473003) (xy 237.048929 -93.440552)
			(xy 237.098529 -93.415051) (xy 237.151313 -93.397044) (xy 237.206156 -93.386914) (xy 237.26189 -93.384877)
			(xy 237.317327 -93.390977) (xy 237.371284 -93.405083) (xy 237.422613 -93.426895) (xy 237.470219 -93.455949)
			(xy 237.513087 -93.491624) (xy 237.550304 -93.533161) (xy 237.581077 -93.579674) (xy 237.604749 -93.630171)
			(xy 237.620817 -93.683578) (xy 237.628937 -93.738754) (xy 237.629446 -93.76664) (xy 237.628937 -93.794526)
			(xy 237.620817 -93.849702) (xy 237.604749 -93.903109) (xy 237.581077 -93.953606) (xy 237.550304 -94.000119)
			(xy 237.513087 -94.041656) (xy 237.470219 -94.077331) (xy 237.422613 -94.106385) (xy 237.371284 -94.128197)
			(xy 237.317327 -94.142303) (xy 237.26189 -94.148403) (xy 237.206156 -94.146366) (xy 237.151313 -94.136236)
			(xy 237.098529 -94.118229) (xy 237.048929 -94.092728) (xy 237.003571 -94.060277) (xy 236.963422 -94.021568)
			(xy 236.929336 -93.977425) (xy 236.90204 -93.92879) (xy 236.882117 -93.876699) (xy 236.869991 -93.822262)
			(xy 236.86592 -93.76664) (xy 227.160836 -93.76664) (xy 227.160836 -94.621096) (xy 229.829358 -94.621096)
			(xy 229.833429 -94.565474) (xy 229.845555 -94.511037) (xy 229.865478 -94.458946) (xy 229.892774 -94.410311)
			(xy 229.92686 -94.366168) (xy 229.967009 -94.327459) (xy 230.012367 -94.295008) (xy 230.061967 -94.269507)
			(xy 230.114751 -94.2515) (xy 230.169594 -94.24137) (xy 230.225328 -94.239333) (xy 230.280765 -94.245433)
			(xy 230.334722 -94.259539) (xy 230.386051 -94.281351) (xy 230.433657 -94.310405) (xy 230.476525 -94.34608)
			(xy 230.513742 -94.387617) (xy 230.544515 -94.43413) (xy 230.568187 -94.484627) (xy 230.584255 -94.538034)
			(xy 230.592375 -94.59321) (xy 230.592884 -94.621096) (xy 230.592375 -94.648982) (xy 230.587956 -94.679008)
			(xy 231.593134 -94.679008) (xy 231.597205 -94.623386) (xy 231.609331 -94.568949) (xy 231.629254 -94.516858)
			(xy 231.65655 -94.468223) (xy 231.690636 -94.42408) (xy 231.730785 -94.385371) (xy 231.776143 -94.35292)
			(xy 231.825743 -94.327419) (xy 231.878527 -94.309412) (xy 231.93337 -94.299282) (xy 231.989104 -94.297245)
			(xy 232.044541 -94.303345) (xy 232.098498 -94.317451) (xy 232.149827 -94.339263) (xy 232.197433 -94.368317)
			(xy 232.240301 -94.403992) (xy 232.277518 -94.445529) (xy 232.308291 -94.492042) (xy 232.331963 -94.542539)
			(xy 232.348031 -94.595946) (xy 232.354573 -94.6404) (xy 235.823504 -94.6404) (xy 235.827575 -94.584778)
			(xy 235.839701 -94.530341) (xy 235.859624 -94.47825) (xy 235.88692 -94.429615) (xy 235.921006 -94.385472)
			(xy 235.961155 -94.346763) (xy 236.006513 -94.314312) (xy 236.056113 -94.288811) (xy 236.108897 -94.270804)
			(xy 236.16374 -94.260674) (xy 236.219474 -94.258637) (xy 236.274911 -94.264737) (xy 236.328868 -94.278843)
			(xy 236.380197 -94.300655) (xy 236.427803 -94.329709) (xy 236.470671 -94.365384) (xy 236.507888 -94.406921)
			(xy 236.538661 -94.453434) (xy 236.562333 -94.503931) (xy 236.578401 -94.557338) (xy 236.586521 -94.612514)
			(xy 236.58703 -94.6404) (xy 236.586521 -94.668286) (xy 236.578401 -94.723462) (xy 236.562333 -94.776869)
			(xy 236.538661 -94.827366) (xy 236.507888 -94.873879) (xy 236.470671 -94.915416) (xy 236.427803 -94.951091)
			(xy 236.380197 -94.980145) (xy 236.328868 -95.001957) (xy 236.274911 -95.016063) (xy 236.219474 -95.022163)
			(xy 236.16374 -95.020126) (xy 236.108897 -95.009996) (xy 236.056113 -94.991989) (xy 236.006513 -94.966488)
			(xy 235.961155 -94.934037) (xy 235.921006 -94.895328) (xy 235.88692 -94.851185) (xy 235.859624 -94.80255)
			(xy 235.839701 -94.750459) (xy 235.827575 -94.696022) (xy 235.823504 -94.6404) (xy 232.354573 -94.6404)
			(xy 232.356151 -94.651122) (xy 232.35666 -94.679008) (xy 232.356151 -94.706894) (xy 232.348031 -94.76207)
			(xy 232.331963 -94.815477) (xy 232.308291 -94.865974) (xy 232.277518 -94.912487) (xy 232.240301 -94.954024)
			(xy 232.197433 -94.989699) (xy 232.149827 -95.018753) (xy 232.098498 -95.040565) (xy 232.044541 -95.054671)
			(xy 231.989104 -95.060771) (xy 231.93337 -95.058734) (xy 231.878527 -95.048604) (xy 231.825743 -95.030597)
			(xy 231.776143 -95.005096) (xy 231.730785 -94.972645) (xy 231.690636 -94.933936) (xy 231.65655 -94.889793)
			(xy 231.629254 -94.841158) (xy 231.609331 -94.789067) (xy 231.597205 -94.73463) (xy 231.593134 -94.679008)
			(xy 230.587956 -94.679008) (xy 230.584255 -94.704158) (xy 230.568187 -94.757565) (xy 230.544515 -94.808062)
			(xy 230.513742 -94.854575) (xy 230.476525 -94.896112) (xy 230.433657 -94.931787) (xy 230.386051 -94.960841)
			(xy 230.334722 -94.982653) (xy 230.280765 -94.996759) (xy 230.225328 -95.002859) (xy 230.169594 -95.000822)
			(xy 230.114751 -94.990692) (xy 230.061967 -94.972685) (xy 230.012367 -94.947184) (xy 229.967009 -94.914733)
			(xy 229.92686 -94.876024) (xy 229.892774 -94.831881) (xy 229.865478 -94.783246) (xy 229.845555 -94.731155)
			(xy 229.833429 -94.676718) (xy 229.829358 -94.621096) (xy 227.160836 -94.621096) (xy 227.160836 -94.658688)
			(xy 227.162614 -94.660974) (xy 227.355908 -94.854522) (xy 227.363573 -94.861205) (xy 227.38257 -94.86841)
			(xy 227.392738 -94.868492) (xy 227.404422 -94.86773) (xy 227.408847 -94.867121) (xy 227.417402 -94.864559)
			(xy 227.42144 -94.86265) (xy 227.431346 -94.85757) (xy 227.438204 -94.849188) (xy 227.456395 -94.827567)
			(xy 227.498073 -94.789416) (xy 227.54493 -94.757843) (xy 227.595939 -94.733541) (xy 227.649978 -94.717042)
			(xy 227.705863 -94.70871) (xy 227.734114 -94.708218) (xy 227.734368 -94.708218) (xy 227.761622 -94.708679)
			(xy 227.815575 -94.716433) (xy 227.867875 -94.731786) (xy 227.917457 -94.754427) (xy 227.963313 -94.783895)
			(xy 228.004507 -94.819589) (xy 228.040202 -94.860783) (xy 228.06967 -94.906637) (xy 228.092312 -94.95622)
			(xy 228.107666 -95.008519) (xy 228.11542 -95.062472) (xy 228.115876 -95.089726) (xy 228.115876 -95.090996)
			(xy 228.11486 -95.118174) (xy 228.112661 -95.14279) (xy 228.102728 -95.191204) (xy 228.095048 -95.214694)
			(xy 228.093524 -95.219266) (xy 228.092 -95.228156) (xy 228.092 -95.246444) (xy 228.093028 -95.251513)
			(xy 228.096874 -95.261111) (xy 228.09962 -95.265494) (xy 228.106732 -95.275146) (xy 228.106986 -95.2754)
			(xy 228.11486 -95.286322) (xy 228.12248 -95.293688) (xy 230.053388 -95.293688) (xy 230.083446 -95.294284)
			(xy 230.14282 -95.303697) (xy 230.199992 -95.322277) (xy 230.253556 -95.349568) (xy 230.302194 -95.384898)
			(xy 230.323898 -95.405702) (xy 230.37546 -95.45701) (xy 230.443786 -95.525336) (xy 230.922066 -95.525336)
			(xy 230.926137 -95.469714) (xy 230.938263 -95.415277) (xy 230.958186 -95.363186) (xy 230.985482 -95.314551)
			(xy 231.019568 -95.270408) (xy 231.059717 -95.231699) (xy 231.105075 -95.199248) (xy 231.154675 -95.173747)
			(xy 231.207459 -95.15574) (xy 231.262302 -95.14561) (xy 231.318036 -95.143573) (xy 231.373473 -95.149673)
			(xy 231.42743 -95.163779) (xy 231.478759 -95.185591) (xy 231.526365 -95.214645) (xy 231.569233 -95.25032)
			(xy 231.60645 -95.291857) (xy 231.637223 -95.33837) (xy 231.660895 -95.388867) (xy 231.676963 -95.442274)
			(xy 231.685083 -95.49745) (xy 231.685592 -95.525336) (xy 231.685083 -95.553222) (xy 231.676963 -95.608398)
			(xy 231.660895 -95.661805) (xy 231.637223 -95.712302) (xy 231.60645 -95.758815) (xy 231.569233 -95.800352)
			(xy 231.526365 -95.836027) (xy 231.478759 -95.865081) (xy 231.42743 -95.886893) (xy 231.373473 -95.900999)
			(xy 231.318036 -95.907099) (xy 231.262302 -95.905062) (xy 231.207459 -95.894932) (xy 231.154675 -95.876925)
			(xy 231.105075 -95.851424) (xy 231.059717 -95.818973) (xy 231.019568 -95.780264) (xy 230.985482 -95.736121)
			(xy 230.958186 -95.687486) (xy 230.938263 -95.635395) (xy 230.926137 -95.580958) (xy 230.922066 -95.525336)
			(xy 230.443786 -95.525336) (xy 230.954072 -96.035622) (xy 230.961453 -96.042205) (xy 230.979752 -96.049653)
			(xy 230.989632 -96.0501) (xy 232.36555 -96.0501) (xy 232.368852 -96.042988) (xy 232.368852 -95.99676)
			(xy 232.368598 -95.993204) (xy 232.368344 -95.992188) (xy 232.367163 -95.981304) (xy 232.36589 -95.959447)
			(xy 232.365804 -95.9485) (xy 232.365804 -95.947992) (xy 232.366291 -95.920704) (xy 232.374057 -95.866685)
			(xy 232.389433 -95.814321) (xy 232.412104 -95.764677) (xy 232.44161 -95.718766) (xy 232.477349 -95.677521)
			(xy 232.518594 -95.641782) (xy 232.564505 -95.612276) (xy 232.614149 -95.589605) (xy 232.666513 -95.574229)
			(xy 232.720532 -95.566463) (xy 232.775108 -95.566463) (xy 232.829127 -95.574229) (xy 232.881491 -95.589605)
			(xy 232.931135 -95.612276) (xy 232.977046 -95.641782) (xy 233.018291 -95.677521) (xy 233.05403 -95.718766)
			(xy 233.083536 -95.764677) (xy 233.106207 -95.814321) (xy 233.121583 -95.866685) (xy 233.129349 -95.920704)
			(xy 233.129836 -95.947992) (xy 233.129836 -95.950024) (xy 233.129836 -95.958914) (xy 233.133646 -95.968058)
			(xy 233.135654 -95.972621) (xy 233.141154 -95.980935) (xy 233.144568 -95.984568) (xy 233.195114 -96.035114)
			(xy 233.197862 -96.037721) (xy 233.203985 -96.042182) (xy 233.207306 -96.044004) (xy 233.211889 -96.046346)
			(xy 233.221747 -96.049294) (xy 233.226864 -96.049846) (xy 233.229404 -96.0501) (xy 233.681524 -96.0501)
			(xy 233.685334 -96.049846) (xy 233.695622 -96.048594) (xy 233.713981 -96.039024) (xy 233.720894 -96.031304)
			(xy 233.732324 -96.014794) (xy 233.733397 -96.008786) (xy 233.733015 -95.996591) (xy 233.731562 -95.990664)
			(xy 233.731054 -95.988886) (xy 233.724196 -95.969328) (xy 233.719116 -95.962724) (xy 233.704105 -95.942612)
			(xy 233.678924 -95.899199) (xy 233.659646 -95.852862) (xy 233.646605 -95.804399) (xy 233.640024 -95.754645)
			(xy 233.639614 -95.729552) (xy 233.6401 -95.702301) (xy 233.647856 -95.648353) (xy 233.663211 -95.596058)
			(xy 233.685853 -95.546481) (xy 233.715319 -95.500631) (xy 233.75101 -95.45944) (xy 233.792201 -95.423749)
			(xy 233.838051 -95.394283) (xy 233.887628 -95.371641) (xy 233.939923 -95.356286) (xy 233.993871 -95.34853)
			(xy 234.048373 -95.34853) (xy 234.102321 -95.356286) (xy 234.154616 -95.371641) (xy 234.204193 -95.394283)
			(xy 234.250043 -95.423749) (xy 234.291234 -95.45944) (xy 234.326925 -95.500631) (xy 234.356391 -95.546481)
			(xy 234.379033 -95.596058) (xy 234.394388 -95.648353) (xy 234.402144 -95.702301) (xy 234.40263 -95.729552)
			(xy 234.402235 -95.754647) (xy 234.395662 -95.804405) (xy 234.382624 -95.852872) (xy 234.363344 -95.899211)
			(xy 234.338157 -95.942623) (xy 234.323128 -95.962724) (xy 234.318048 -95.969328) (xy 234.31119 -95.988632)
			(xy 234.309424 -95.995093) (xy 234.308898 -96.008473) (xy 234.310174 -96.015048) (xy 234.322112 -96.031812)
			(xy 234.329666 -96.040024) (xy 234.349831 -96.049512) (xy 234.360974 -96.0501) (xy 235.87964 -96.0501)
			(xy 235.886498 -96.049592) (xy 235.895279 -96.048059) (xy 235.911029 -96.039736) (xy 235.917232 -96.033336)
			(xy 235.93044 -96.01454) (xy 235.931456 -96.003618) (xy 235.931456 -96.00311) (xy 235.931318 -95.998626)
			(xy 235.929664 -95.989809) (xy 235.928154 -95.985584) (xy 235.920788 -95.965772) (xy 235.9152 -95.959168)
			(xy 235.898241 -95.938417) (xy 235.869702 -95.893057) (xy 235.847798 -95.844147) (xy 235.832962 -95.792651)
			(xy 235.825484 -95.739584) (xy 235.82503 -95.712788) (xy 235.82503 -95.70085) (xy 235.825284 -95.696786)
			(xy 235.825284 -95.696532) (xy 235.825538 -95.6945) (xy 235.825538 -95.692468) (xy 235.82757 -95.668084)
			(xy 235.82757 -95.667576) (xy 235.831353 -95.640109) (xy 235.845827 -95.586588) (xy 235.86789 -95.535723)
			(xy 235.897077 -95.488584) (xy 235.932776 -95.446162) (xy 235.974234 -95.409348) (xy 236.020581 -95.378919)
			(xy 236.070841 -95.355512) (xy 236.123959 -95.33962) (xy 236.178816 -95.331578) (xy 236.206538 -95.331026)
			(xy 236.232918 -95.331474) (xy 236.285173 -95.338748) (xy 236.335929 -95.353152) (xy 236.384216 -95.374411)
			(xy 236.429113 -95.40212) (xy 236.469765 -95.43575) (xy 236.505396 -95.47466) (xy 236.520736 -95.496126)
			(xy 236.522006 -95.497904) (xy 236.535702 -95.518755) (xy 236.558148 -95.563306) (xy 236.574596 -95.610403)
			(xy 236.584765 -95.659242) (xy 236.58703 -95.684086) (xy 236.587284 -95.686118) (xy 236.587792 -95.696786)
			(xy 236.587792 -95.70085) (xy 236.588046 -95.70339) (xy 236.588046 -95.714058) (xy 236.587462 -95.74087)
			(xy 236.579702 -95.793936) (xy 236.564595 -95.845394) (xy 236.542438 -95.894233) (xy 236.513667 -95.939492)
			(xy 236.496606 -95.960184) (xy 236.496606 -95.960438) (xy 236.488224 -95.970598) (xy 236.48543 -95.975424)
			(xy 236.482162 -95.982243) (xy 236.479322 -95.99709) (xy 236.479842 -96.004634) (xy 236.480604 -96.013016)
			(xy 236.48416 -96.02089) (xy 236.487208 -96.027494) (xy 236.496352 -96.038162) (xy 236.502702 -96.041972)
			(xy 236.508951 -96.045677) (xy 236.522875 -96.049802) (xy 236.530134 -96.0501) (xy 237.265972 -96.0501)
			(xy 237.296046 -96.050674) (xy 237.355448 -96.060114) (xy 237.412641 -96.078735) (xy 237.466215 -96.106078)
			(xy 237.514849 -96.141469) (xy 237.536482 -96.162368) (xy 241.147092 -99.772978) (xy 243.553486 -99.772978)
			(xy 243.557557 -99.717356) (xy 243.569683 -99.662919) (xy 243.589606 -99.610828) (xy 243.616902 -99.562193)
			(xy 243.650988 -99.51805) (xy 243.691137 -99.479341) (xy 243.736495 -99.44689) (xy 243.786095 -99.421389)
			(xy 243.838879 -99.403382) (xy 243.893722 -99.393252) (xy 243.949456 -99.391215) (xy 244.004893 -99.397315)
			(xy 244.05885 -99.411421) (xy 244.110179 -99.433233) (xy 244.157785 -99.462287) (xy 244.200653 -99.497962)
			(xy 244.23787 -99.539499) (xy 244.268643 -99.586012) (xy 244.292315 -99.636509) (xy 244.308383 -99.689916)
			(xy 244.316503 -99.745092) (xy 244.317012 -99.772978) (xy 244.316503 -99.800864) (xy 244.308383 -99.85604)
			(xy 244.292315 -99.909447) (xy 244.268643 -99.959944) (xy 244.23787 -100.006457) (xy 244.200653 -100.047994)
			(xy 244.157785 -100.083669) (xy 244.110179 -100.112723) (xy 244.05885 -100.134535) (xy 244.004893 -100.148641)
			(xy 243.949456 -100.154741) (xy 243.893722 -100.152704) (xy 243.838879 -100.142574) (xy 243.786095 -100.124567)
			(xy 243.736495 -100.099066) (xy 243.691137 -100.066615) (xy 243.650988 -100.027906) (xy 243.616902 -99.983763)
			(xy 243.589606 -99.935128) (xy 243.569683 -99.883037) (xy 243.557557 -99.8286) (xy 243.553486 -99.772978)
			(xy 241.147092 -99.772978) (xy 244.4877 -103.113586) (xy 244.494383 -103.119714) (xy 244.510875 -103.127219)
			(xy 244.528949 -103.128509) (xy 244.537738 -103.126286) (xy 244.543072 -103.124) (xy 244.549887 -103.120911)
			(xy 244.561501 -103.111487) (xy 244.565932 -103.105458) (xy 244.569742 -103.09987) (xy 244.57406 -103.085392)
			(xy 244.57406 -80.142842) (xy 244.573574 -80.13288) (xy 244.565984 -80.114457) (xy 244.559328 -80.107028)
			(xy 244.16258 -79.71028) (xy 243.356892 -78.904338) (xy 243.350964 -78.898931) (xy 243.33659 -78.891819)
			(xy 243.328698 -78.890368) (xy 243.321332 -78.88986) (xy 239.861598 -78.88986) (xy 239.835576 -78.889329)
			(xy 239.784176 -78.881155) (xy 239.734684 -78.865055) (xy 239.688313 -78.841425) (xy 239.6462 -78.810843)
			(xy 239.62741 -78.792832) (xy 238.545878 -77.7113) (xy 238.543025 -77.708597) (xy 238.536644 -77.704009)
			(xy 238.533178 -77.702156) (xy 238.527752 -77.699568) (xy 238.516073 -77.696736) (xy 238.510064 -77.696568)
			(xy 234.817158 -77.696568) (xy 234.811316 -77.699616) (xy 234.805728 -77.70241) (xy 234.778211 -77.716142)
			(xy 234.719879 -77.735606) (xy 234.659183 -77.745476) (xy 234.628436 -77.746098) (xy 234.627928 -77.746098)
			(xy 234.600675 -77.745637) (xy 234.546722 -77.737883) (xy 234.494422 -77.72253) (xy 234.44484 -77.69989)
			(xy 234.398984 -77.670423) (xy 234.357789 -77.63473) (xy 234.322094 -77.593538) (xy 234.292624 -77.547685)
			(xy 234.26998 -77.498104) (xy 234.254623 -77.445805) (xy 234.246865 -77.391853) (xy 234.246865 -77.337347)
			(xy 234.254623 -77.283395) (xy 234.26998 -77.231096) (xy 234.292624 -77.181515) (xy 234.322094 -77.135662)
			(xy 234.357789 -77.09447) (xy 234.398984 -77.058777) (xy 234.44484 -77.02931) (xy 234.494422 -77.00667)
			(xy 234.546722 -76.991317) (xy 234.600675 -76.983563) (xy 234.627928 -76.983082) (xy 234.628436 -76.983082)
			(xy 234.659187 -76.983663) (xy 234.719893 -76.99352) (xy 234.778232 -77.01299) (xy 234.805728 -77.02677)
			(xy 234.811316 -77.029564) (xy 234.817158 -77.032612) (xy 235.960158 -77.032612) (xy 235.967016 -77.026516)
			(xy 236.017816 -76.965556) (xy 236.024674 -76.954888) (xy 236.026807 -76.950006) (xy 236.029231 -76.939635)
			(xy 236.0295 -76.934314) (xy 236.0295 -76.923392) (xy 236.028738 -76.919074) (xy 236.026131 -76.903008)
			(xy 236.023329 -76.870579) (xy 236.02315 -76.854304) (xy 236.02315 -76.853542) (xy 236.02315 -76.853034)
			(xy 236.023633 -76.82578) (xy 236.031386 -76.771826) (xy 236.046738 -76.719525) (xy 236.069376 -76.669941)
			(xy 236.098841 -76.624083) (xy 236.134532 -76.582886) (xy 236.175722 -76.547186) (xy 236.221574 -76.517713)
			(xy 236.271154 -76.495064) (xy 236.323452 -76.479702) (xy 236.377404 -76.471939) (xy 236.404658 -76.471526)
			(xy 236.431795 -76.472001) (xy 236.485522 -76.479688) (xy 236.537617 -76.494912) (xy 236.587028 -76.517365)
			(xy 236.632758 -76.546596) (xy 236.673884 -76.582012) (xy 236.709574 -76.6229) (xy 236.739109 -76.668434)
			(xy 236.761893 -76.717694) (xy 236.777464 -76.769687) (xy 236.785509 -76.823361) (xy 236.786166 -76.850494)
			(xy 236.786166 -76.853542) (xy 236.785958 -76.870914) (xy 236.782781 -76.905512) (xy 236.779816 -76.92263)
			(xy 236.777784 -76.933806) (xy 236.78134 -76.94676) (xy 236.78272 -76.95106) (xy 236.786812 -76.959109)
			(xy 236.789468 -76.962762) (xy 236.8423 -77.026516) (xy 236.849158 -77.032612) (xy 238.66856 -77.032612)
			(xy 238.694649 -77.033095) (xy 238.746184 -77.041256) (xy 238.795807 -77.057382) (xy 238.842294 -77.081077)
			(xy 238.884499 -77.111756) (xy 238.903256 -77.129894) (xy 239.985042 -78.211934) (xy 239.991018 -78.217382)
			(xy 240.005525 -78.224508) (xy 240.01349 -78.225904) (xy 240.020602 -78.226412) (xy 243.480336 -78.226412)
			(xy 243.50636 -78.226938) (xy 243.557766 -78.235102) (xy 243.607265 -78.251194) (xy 243.653645 -78.274817)
			(xy 243.695767 -78.305393) (xy 243.714524 -78.32344) (xy 244.84584 -79.454756) (xy 244.852523 -79.460881)
			(xy 244.869014 -79.468377) (xy 244.887084 -79.469655) (xy 244.895878 -79.467456) (xy 244.901212 -79.46517)
			(xy 244.908027 -79.462081) (xy 244.919644 -79.45266) (xy 244.924072 -79.446628) (xy 244.927882 -79.44104)
			(xy 244.9322 -79.426562) (xy 244.9322 -42.342054) (xy 244.932033 -42.336044) (xy 244.92921 -42.324361)
			(xy 244.926612 -42.31894) (xy 244.924776 -42.315463) (xy 244.920189 -42.309078) (xy 244.917468 -42.30624)
			(xy 239.499394 -36.888166) (xy 239.488726 -36.881816) (xy 239.482884 -36.880038) (xy 239.457804 -36.871771)
			(xy 239.410021 -36.84929) (xy 239.365794 -36.820435) (xy 239.325967 -36.785759) (xy 239.291301 -36.745922)
			(xy 239.262459 -36.701687) (xy 239.239991 -36.653898) (xy 239.231678 -36.628832) (xy 239.2299 -36.62299)
			(xy 239.22355 -36.612322) (xy 237.72876 -35.117532) (xy 237.710725 -35.098762) (xy 237.68014 -35.056647)
			(xy 237.656509 -35.010271) (xy 237.640411 -34.960773) (xy 237.632243 -34.909368) (xy 237.631732 -34.883344)
			(xy 237.631732 -32.431482) (xy 237.631609 -32.425836) (xy 237.629176 -32.41481) (xy 237.626906 -32.409638)
			(xy 237.62335 -32.402272) (xy 237.622842 -32.401764) (xy 237.593124 -32.377634) (xy 237.56112 -32.351472)
			(xy 237.553246 -32.345376) (xy 237.529878 -32.350202) (xy 237.529624 -32.350202) (xy 237.512941 -32.353666)
			(xy 237.479264 -32.358875) (xy 237.462314 -32.360616) (xy 237.44882 -32.361803) (xy 237.421758 -32.363074)
			(xy 237.408212 -32.363156) (xy 237.361476 -32.363156) (xy 237.361476 -32.361378) (xy 237.328027 -32.358238)
			(xy 237.262106 -32.34526) (xy 237.198104 -32.324823) (xy 237.136861 -32.297197) (xy 237.079181 -32.262743)
			(xy 237.025823 -32.221916) (xy 236.977489 -32.17525) (xy 236.934811 -32.12336) (xy 236.898353 -32.066926)
			(xy 236.868592 -32.006691) (xy 236.84592 -31.943446) (xy 236.830634 -31.878022) (xy 236.822936 -31.811279)
			(xy 236.822488 -31.777686) (xy 236.822488 -30.776164) (xy 236.819694 -30.772862) (xy 236.81563 -30.76829)
			(xy 236.73816 -30.720284) (xy 236.730587 -30.716175) (xy 236.713699 -30.712818) (xy 236.696662 -30.715306)
			(xy 236.688884 -30.719014) (xy 236.686344 -30.720284) (xy 236.677962 -30.724348) (xy 236.670088 -30.727904)
			(xy 236.644928 -30.738835) (xy 236.592293 -30.754287) (xy 236.538003 -30.762146) (xy 236.510576 -30.762702)
			(xy 236.483018 -30.762209) (xy 236.428464 -30.754361) (xy 236.375581 -30.73883) (xy 236.325448 -30.715931)
			(xy 236.279083 -30.68613) (xy 236.237432 -30.650034) (xy 236.201341 -30.608378) (xy 236.171546 -30.56201)
			(xy 236.148653 -30.511874) (xy 236.133128 -30.458989) (xy 236.125288 -30.404434) (xy 236.12475 -30.376876)
			(xy 236.12526 -30.348468) (xy 236.133615 -30.292269) (xy 236.15014 -30.237908) (xy 236.174476 -30.186567)
			(xy 236.206093 -30.13936) (xy 236.244307 -30.097314) (xy 236.265974 -30.078934) (xy 236.266482 -30.078426)
			(xy 236.27207 -30.0736) (xy 236.276134 -30.070298) (xy 236.27969 -30.066234) (xy 236.285532 -30.057344)
			(xy 236.292136 -30.04312) (xy 236.293802 -30.038667) (xy 236.295588 -30.029331) (xy 236.295692 -30.024578)
			(xy 236.295692 -29.967682) (xy 236.29555 -29.962242) (xy 236.293245 -29.951609) (xy 236.29112 -29.9466)
			(xy 236.287818 -29.939742) (xy 236.287818 -29.939234) (xy 236.28096 -29.925518) (xy 236.272578 -29.914088)
			(xy 236.267752 -29.909262) (xy 236.265974 -29.907738) (xy 236.244946 -29.8895) (xy 236.207881 -29.847976)
			(xy 236.177237 -29.80151) (xy 236.153664 -29.751087) (xy 236.137662 -29.697776) (xy 236.12957 -29.642706)
			(xy 236.129068 -29.614876) (xy 236.129555 -29.587625) (xy 236.137315 -29.533679) (xy 236.152672 -29.481386)
			(xy 236.175314 -29.43181) (xy 236.20478 -29.385961) (xy 236.240471 -29.344771) (xy 236.281661 -29.30908)
			(xy 236.32751 -29.279614) (xy 236.377086 -29.256972) (xy 236.429379 -29.241615) (xy 236.483325 -29.233855)
			(xy 236.510576 -29.233368) (xy 236.535945 -29.233783) (xy 236.586237 -29.240505) (xy 236.635193 -29.253833)
			(xy 236.681951 -29.273533) (xy 236.725686 -29.299256) (xy 236.765625 -29.33055) (xy 236.783626 -29.34843)
			(xy 236.785658 -29.350462) (xy 236.79658 -29.358082) (xy 236.82325 -29.37002) (xy 236.827822 -29.372052)
			(xy 236.839506 -29.37129) (xy 236.83976 -29.37129) (xy 236.842808 -29.371036) (xy 236.854238 -29.363416)
			(xy 236.859916 -29.359243) (xy 236.868925 -29.348413) (xy 236.872018 -29.34208) (xy 236.874304 -29.337254)
			(xy 236.889292 -29.3053) (xy 236.925828 -29.244912) (xy 236.969357 -29.189352) (xy 236.993938 -29.164026)
			(xy 239.432338 -26.725626) (xy 239.437328 -26.720128) (xy 239.44418 -26.706963) (xy 239.4458 -26.699718)
			(xy 239.446816 -26.690066) (xy 239.446816 -24.158194) (xy 239.447312 -24.124094) (xy 239.455229 -24.056354)
			(xy 239.470958 -23.989991) (xy 239.494284 -23.925903) (xy 239.524892 -23.864957) (xy 239.562369 -23.807976)
			(xy 239.606208 -23.755731) (xy 239.655815 -23.708928) (xy 239.710521 -23.668202) (xy 239.769585 -23.634101)
			(xy 239.832208 -23.607088) (xy 239.897544 -23.587528) (xy 239.964708 -23.575685) (xy 240.032794 -23.57172)
			(xy 240.10088 -23.575685) (xy 240.168044 -23.587528) (xy 240.23338 -23.607088) (xy 240.296003 -23.634101)
			(xy 240.355067 -23.668202) (xy 240.409773 -23.708928) (xy 240.45938 -23.755731) (xy 240.503219 -23.807976)
			(xy 240.540696 -23.864957) (xy 240.571304 -23.925903) (xy 240.59463 -23.989991) (xy 240.610359 -24.056354)
			(xy 240.618276 -24.124094) (xy 240.618772 -24.158194) (xy 240.618772 -24.807418) (xy 240.820192 -24.807418)
			(xy 240.824263 -24.751796) (xy 240.836389 -24.697359) (xy 240.856312 -24.645268) (xy 240.883608 -24.596633)
			(xy 240.917694 -24.55249) (xy 240.957843 -24.513781) (xy 241.003201 -24.48133) (xy 241.052801 -24.455829)
			(xy 241.105585 -24.437822) (xy 241.160428 -24.427692) (xy 241.216162 -24.425655) (xy 241.271599 -24.431755)
			(xy 241.325556 -24.445861) (xy 241.376885 -24.467673) (xy 241.424491 -24.496727) (xy 241.467359 -24.532402)
			(xy 241.504576 -24.573939) (xy 241.535349 -24.620452) (xy 241.559021 -24.670949) (xy 241.575089 -24.724356)
			(xy 241.583209 -24.779532) (xy 241.583718 -24.807418) (xy 241.583209 -24.835304) (xy 241.575089 -24.89048)
			(xy 241.559021 -24.943887) (xy 241.535349 -24.994384) (xy 241.504576 -25.040897) (xy 241.467359 -25.082434)
			(xy 241.424491 -25.118109) (xy 241.376885 -25.147163) (xy 241.325556 -25.168975) (xy 241.271599 -25.183081)
			(xy 241.216162 -25.189181) (xy 241.160428 -25.187144) (xy 241.105585 -25.177014) (xy 241.052801 -25.159007)
			(xy 241.003201 -25.133506) (xy 240.957843 -25.101055) (xy 240.917694 -25.062346) (xy 240.883608 -25.018203)
			(xy 240.856312 -24.969568) (xy 240.836389 -24.917477) (xy 240.824263 -24.86304) (xy 240.820192 -24.807418)
			(xy 240.618772 -24.807418) (xy 240.618772 -26.724102) (xy 240.621032 -26.727029) (xy 240.626259 -26.732257)
			(xy 240.629186 -26.734516) (xy 240.923826 -26.734516) (xy 240.926366 -26.734516) (xy 240.931725 -26.734084)
			(xy 240.942096 -26.731261) (xy 240.94694 -26.728928) (xy 240.970562 -26.716228) (xy 240.976404 -26.713434)
			(xy 240.976912 -26.71318) (xy 240.985802 -26.70556) (xy 240.989612 -26.700226) (xy 240.994996 -26.691797)
			(xy 240.999479 -26.672326) (xy 240.996231 -26.652611) (xy 240.985737 -26.635608) (xy 240.977928 -26.62936)
			(xy 240.972086 -26.625296) (xy 240.96599 -26.62301) (xy 240.939294 -26.612242) (xy 240.889224 -26.583844)
			(xy 240.843986 -26.548249) (xy 240.804606 -26.506265) (xy 240.771978 -26.458843) (xy 240.74684 -26.407059)
			(xy 240.729763 -26.352088) (xy 240.721135 -26.295175) (xy 240.720626 -26.266394) (xy 240.721112 -26.239143)
			(xy 240.728868 -26.185195) (xy 240.744223 -26.1329) (xy 240.766865 -26.083323) (xy 240.796331 -26.037473)
			(xy 240.832022 -25.996282) (xy 240.873213 -25.960591) (xy 240.919063 -25.931125) (xy 240.96864 -25.908483)
			(xy 241.020935 -25.893128) (xy 241.074883 -25.885372) (xy 241.129385 -25.885372) (xy 241.183333 -25.893128)
			(xy 241.235628 -25.908483) (xy 241.285205 -25.931125) (xy 241.331055 -25.960591) (xy 241.372246 -25.996282)
			(xy 241.407937 -26.037473) (xy 241.437403 -26.083323) (xy 241.460045 -26.1329) (xy 241.4754 -26.185195)
			(xy 241.483156 -26.239143) (xy 241.483642 -26.266394) (xy 241.483108 -26.29531) (xy 241.474381 -26.352481)
			(xy 241.457126 -26.407679) (xy 241.431738 -26.459641) (xy 241.398798 -26.507176) (xy 241.359062 -26.549196)
			(xy 241.336576 -26.567384) (xy 241.332004 -26.57094) (xy 241.322606 -26.58237) (xy 241.320313 -26.585227)
			(xy 241.316488 -26.591475) (xy 241.314986 -26.594816) (xy 241.314986 -26.595324) (xy 241.312875 -26.600591)
			(xy 241.310815 -26.611749) (xy 241.310922 -26.617422) (xy 241.312192 -26.643838) (xy 241.312192 -26.644346)
			(xy 241.314986 -26.690574) (xy 241.31778 -26.702766) (xy 241.323876 -26.713942) (xy 241.326863 -26.718654)
			(xy 241.334556 -26.72673) (xy 241.339116 -26.729944) (xy 241.340132 -26.730706) (xy 241.341656 -26.731468)
			(xy 241.366174 -26.746627) (xy 241.410864 -26.783031) (xy 241.449706 -26.825621) (xy 241.481851 -26.873468)
			(xy 241.506598 -26.925527) (xy 241.523407 -26.980663) (xy 241.531913 -27.037673) (xy 241.53241 -27.066494)
			(xy 241.531914 -27.094345) (xy 241.523988 -27.149479) (xy 241.508296 -27.202925) (xy 241.485158 -27.253593)
			(xy 241.455045 -27.300453) (xy 241.418569 -27.342551) (xy 241.376474 -27.379029) (xy 241.329616 -27.409145)
			(xy 241.278949 -27.432287) (xy 241.225505 -27.447982) (xy 241.170371 -27.455912) (xy 241.14252 -27.456384)
			(xy 241.142266 -27.456384) (xy 241.116945 -27.455981) (xy 241.066727 -27.449438) (xy 241.017774 -27.436466)
			(xy 240.970906 -27.417282) (xy 240.948718 -27.405076) (xy 240.942876 -27.401774) (xy 240.93678 -27.40025)
			(xy 240.923826 -27.398472) (xy 240.799112 -27.398472) (xy 240.789151 -27.398961) (xy 240.77073 -27.406551)
			(xy 240.763298 -27.413204) (xy 239.210088 -28.965906) (xy 239.053668 -29.12237) (xy 240.806732 -29.12237)
			(xy 240.806732 -28.25877) (xy 240.807222 -28.228786) (xy 240.81505 -28.16933) (xy 240.830571 -28.111405)
			(xy 240.85352 -28.056001) (xy 240.883504 -28.004067) (xy 240.92001 -27.956491) (xy 240.962415 -27.914086)
			(xy 241.009991 -27.87758) (xy 241.061925 -27.847596) (xy 241.117329 -27.824647) (xy 241.175254 -27.809126)
			(xy 241.23471 -27.801298) (xy 241.294678 -27.801298) (xy 241.354134 -27.809126) (xy 241.412059 -27.824647)
			(xy 241.467463 -27.847596) (xy 241.519397 -27.87758) (xy 241.566973 -27.914086) (xy 241.609378 -27.956491)
			(xy 241.645884 -28.004067) (xy 241.675868 -28.056001) (xy 241.698817 -28.111405) (xy 241.714338 -28.16933)
			(xy 241.722166 -28.228786) (xy 241.722656 -28.25877) (xy 241.722656 -29.114242) (xy 251.047504 -29.114242)
			(xy 251.047504 -28.250642) (xy 251.047994 -28.220674) (xy 251.055817 -28.161252) (xy 251.07133 -28.103359)
			(xy 251.094266 -28.047986) (xy 251.124233 -27.99608) (xy 251.16072 -27.94853) (xy 251.2031 -27.90615)
			(xy 251.25065 -27.869663) (xy 251.302556 -27.839696) (xy 251.357929 -27.81676) (xy 251.415822 -27.801247)
			(xy 251.475244 -27.793424) (xy 251.53518 -27.793424) (xy 251.594602 -27.801247) (xy 251.652495 -27.81676)
			(xy 251.707868 -27.839696) (xy 251.759774 -27.869663) (xy 251.807324 -27.90615) (xy 251.849704 -27.94853)
			(xy 251.886191 -27.99608) (xy 251.916158 -28.047986) (xy 251.939094 -28.103359) (xy 251.954607 -28.161252)
			(xy 251.96243 -28.220674) (xy 251.96292 -28.250642) (xy 251.96292 -29.114242) (xy 251.96243 -29.14421)
			(xy 251.954607 -29.203632) (xy 251.939094 -29.261525) (xy 251.916158 -29.316898) (xy 251.886191 -29.368804)
			(xy 251.849704 -29.416354) (xy 251.807324 -29.458734) (xy 251.759774 -29.495221) (xy 251.707868 -29.525188)
			(xy 251.652495 -29.548124) (xy 251.594602 -29.563637) (xy 251.53518 -29.57146) (xy 251.475244 -29.57146)
			(xy 251.415822 -29.563637) (xy 251.357929 -29.548124) (xy 251.302556 -29.525188) (xy 251.25065 -29.495221)
			(xy 251.2031 -29.458734) (xy 251.16072 -29.416354) (xy 251.124233 -29.368804) (xy 251.094266 -29.316898)
			(xy 251.07133 -29.261525) (xy 251.055817 -29.203632) (xy 251.047994 -29.14421) (xy 251.047504 -29.114242)
			(xy 241.722656 -29.114242) (xy 241.722656 -29.12237) (xy 241.722166 -29.152354) (xy 241.714338 -29.21181)
			(xy 241.698817 -29.269735) (xy 241.675868 -29.325139) (xy 241.645884 -29.377073) (xy 241.609378 -29.424649)
			(xy 241.566973 -29.467054) (xy 241.519397 -29.50356) (xy 241.467463 -29.533544) (xy 241.412059 -29.556493)
			(xy 241.354134 -29.572014) (xy 241.294678 -29.579842) (xy 241.23471 -29.579842) (xy 241.175254 -29.572014)
			(xy 241.117329 -29.556493) (xy 241.061925 -29.533544) (xy 241.009991 -29.50356) (xy 240.962415 -29.467054)
			(xy 240.92001 -29.424649) (xy 240.883504 -29.377073) (xy 240.85352 -29.325139) (xy 240.830571 -29.269735)
			(xy 240.81505 -29.21181) (xy 240.807222 -29.152354) (xy 240.806732 -29.12237) (xy 239.053668 -29.12237)
			(xy 238.300006 -29.876242) (xy 238.29518 -29.88183) (xy 238.29518 -30.922468) (xy 238.952532 -30.922468)
			(xy 238.952532 -30.058868) (xy 238.953022 -30.028884) (xy 238.96085 -29.969428) (xy 238.976371 -29.911503)
			(xy 238.99932 -29.856099) (xy 239.029304 -29.804165) (xy 239.06581 -29.756589) (xy 239.108215 -29.714184)
			(xy 239.155791 -29.677678) (xy 239.207725 -29.647694) (xy 239.263129 -29.624745) (xy 239.321054 -29.609224)
			(xy 239.38051 -29.601396) (xy 239.440478 -29.601396) (xy 239.499934 -29.609224) (xy 239.557859 -29.624745)
			(xy 239.613263 -29.647694) (xy 239.665197 -29.677678) (xy 239.712773 -29.714184) (xy 239.755178 -29.756589)
			(xy 239.791684 -29.804165) (xy 239.821668 -29.856099) (xy 239.844617 -29.911503) (xy 239.860138 -29.969428)
			(xy 239.867966 -30.028884) (xy 239.868456 -30.058868) (xy 239.868456 -30.92069) (xy 253.689612 -30.92069)
			(xy 253.689612 -30.05709) (xy 253.690102 -30.027122) (xy 253.697925 -29.9677) (xy 253.713438 -29.909807)
			(xy 253.736374 -29.854434) (xy 253.766341 -29.802528) (xy 253.802828 -29.754978) (xy 253.845208 -29.712598)
			(xy 253.892758 -29.676111) (xy 253.944664 -29.646144) (xy 254.000037 -29.623208) (xy 254.05793 -29.607695)
			(xy 254.117352 -29.599872) (xy 254.177288 -29.599872) (xy 254.23671 -29.607695) (xy 254.294603 -29.623208)
			(xy 254.349976 -29.646144) (xy 254.401882 -29.676111) (xy 254.449432 -29.712598) (xy 254.491812 -29.754978)
			(xy 254.528299 -29.802528) (xy 254.558266 -29.854434) (xy 254.581202 -29.909807) (xy 254.596715 -29.9677)
			(xy 254.604538 -30.027122) (xy 254.605028 -30.05709) (xy 254.605028 -30.92069) (xy 254.604538 -30.950658)
			(xy 254.596715 -31.01008) (xy 254.581202 -31.067973) (xy 254.558266 -31.123346) (xy 254.528299 -31.175252)
			(xy 254.491812 -31.222802) (xy 254.449432 -31.265182) (xy 254.401882 -31.301669) (xy 254.349976 -31.331636)
			(xy 254.294603 -31.354572) (xy 254.23671 -31.370085) (xy 254.177288 -31.377908) (xy 254.117352 -31.377908)
			(xy 254.05793 -31.370085) (xy 254.000037 -31.354572) (xy 253.944664 -31.331636) (xy 253.892758 -31.301669)
			(xy 253.845208 -31.265182) (xy 253.802828 -31.222802) (xy 253.766341 -31.175252) (xy 253.736374 -31.123346)
			(xy 253.713438 -31.067973) (xy 253.697925 -31.01008) (xy 253.690102 -30.950658) (xy 253.689612 -30.92069)
			(xy 239.868456 -30.92069) (xy 239.868456 -30.922468) (xy 239.867966 -30.952452) (xy 239.860138 -31.011908)
			(xy 239.844617 -31.069833) (xy 239.821668 -31.125237) (xy 239.791684 -31.177171) (xy 239.755178 -31.224747)
			(xy 239.712773 -31.267152) (xy 239.665197 -31.303658) (xy 239.613263 -31.333642) (xy 239.557859 -31.356591)
			(xy 239.499934 -31.372112) (xy 239.440478 -31.37994) (xy 239.38051 -31.37994) (xy 239.321054 -31.372112)
			(xy 239.263129 -31.356591) (xy 239.207725 -31.333642) (xy 239.155791 -31.303658) (xy 239.108215 -31.267152)
			(xy 239.06581 -31.224747) (xy 239.029304 -31.177171) (xy 238.99932 -31.125237) (xy 238.976371 -31.069833)
			(xy 238.96085 -31.011908) (xy 238.953022 -30.952452) (xy 238.952532 -30.922468) (xy 238.29518 -30.922468)
			(xy 238.29518 -32.722312) (xy 240.806732 -32.722312) (xy 240.806732 -31.858712) (xy 240.807222 -31.828728)
			(xy 240.81505 -31.769272) (xy 240.830571 -31.711347) (xy 240.85352 -31.655943) (xy 240.883504 -31.604009)
			(xy 240.92001 -31.556433) (xy 240.962415 -31.514028) (xy 241.009991 -31.477522) (xy 241.061925 -31.447538)
			(xy 241.117329 -31.424589) (xy 241.175254 -31.409068) (xy 241.23471 -31.40124) (xy 241.294678 -31.40124)
			(xy 241.354134 -31.409068) (xy 241.412059 -31.424589) (xy 241.467463 -31.447538) (xy 241.519397 -31.477522)
			(xy 241.566973 -31.514028) (xy 241.609378 -31.556433) (xy 241.645884 -31.604009) (xy 241.675868 -31.655943)
			(xy 241.698817 -31.711347) (xy 241.714338 -31.769272) (xy 241.722166 -31.828728) (xy 241.722656 -31.858712)
			(xy 241.722656 -32.714184) (xy 251.047504 -32.714184) (xy 251.047504 -31.850584) (xy 251.047994 -31.820616)
			(xy 251.055817 -31.761194) (xy 251.07133 -31.703301) (xy 251.094266 -31.647928) (xy 251.124233 -31.596022)
			(xy 251.16072 -31.548472) (xy 251.2031 -31.506092) (xy 251.25065 -31.469605) (xy 251.302556 -31.439638)
			(xy 251.357929 -31.416702) (xy 251.415822 -31.401189) (xy 251.475244 -31.393366) (xy 251.53518 -31.393366)
			(xy 251.594602 -31.401189) (xy 251.652495 -31.416702) (xy 251.707868 -31.439638) (xy 251.759774 -31.469605)
			(xy 251.807324 -31.506092) (xy 251.849704 -31.548472) (xy 251.886191 -31.596022) (xy 251.916158 -31.647928)
			(xy 251.939094 -31.703301) (xy 251.954607 -31.761194) (xy 251.96243 -31.820616) (xy 251.96292 -31.850584)
			(xy 251.96292 -32.714184) (xy 251.96243 -32.744152) (xy 251.954607 -32.803574) (xy 251.939094 -32.861467)
			(xy 251.916158 -32.91684) (xy 251.886191 -32.968746) (xy 251.849704 -33.016296) (xy 251.807324 -33.058676)
			(xy 251.759774 -33.095163) (xy 251.707868 -33.12513) (xy 251.652495 -33.148066) (xy 251.594602 -33.163579)
			(xy 251.53518 -33.171402) (xy 251.475244 -33.171402) (xy 251.415822 -33.163579) (xy 251.357929 -33.148066)
			(xy 251.302556 -33.12513) (xy 251.25065 -33.095163) (xy 251.2031 -33.058676) (xy 251.16072 -33.016296)
			(xy 251.124233 -32.968746) (xy 251.094266 -32.91684) (xy 251.07133 -32.861467) (xy 251.055817 -32.803574)
			(xy 251.047994 -32.744152) (xy 251.047504 -32.714184) (xy 241.722656 -32.714184) (xy 241.722656 -32.722312)
			(xy 241.722166 -32.752296) (xy 241.714338 -32.811752) (xy 241.698817 -32.869677) (xy 241.675868 -32.925081)
			(xy 241.645884 -32.977015) (xy 241.609378 -33.024591) (xy 241.566973 -33.066996) (xy 241.519397 -33.103502)
			(xy 241.467463 -33.133486) (xy 241.412059 -33.156435) (xy 241.354134 -33.171956) (xy 241.294678 -33.179784)
			(xy 241.23471 -33.179784) (xy 241.175254 -33.171956) (xy 241.117329 -33.156435) (xy 241.061925 -33.133486)
			(xy 241.009991 -33.103502) (xy 240.962415 -33.066996) (xy 240.92001 -33.024591) (xy 240.883504 -32.977015)
			(xy 240.85352 -32.925081) (xy 240.830571 -32.869677) (xy 240.81505 -32.811752) (xy 240.807222 -32.752296)
			(xy 240.806732 -32.722312) (xy 238.29518 -32.722312) (xy 238.29518 -34.52241) (xy 238.952532 -34.52241)
			(xy 238.952532 -33.65881) (xy 238.953022 -33.628826) (xy 238.96085 -33.56937) (xy 238.976371 -33.511445)
			(xy 238.99932 -33.456041) (xy 239.029304 -33.404107) (xy 239.06581 -33.356531) (xy 239.108215 -33.314126)
			(xy 239.155791 -33.27762) (xy 239.207725 -33.247636) (xy 239.263129 -33.224687) (xy 239.321054 -33.209166)
			(xy 239.38051 -33.201338) (xy 239.440478 -33.201338) (xy 239.499934 -33.209166) (xy 239.557859 -33.224687)
			(xy 239.613263 -33.247636) (xy 239.665197 -33.27762) (xy 239.712773 -33.314126) (xy 239.755178 -33.356531)
			(xy 239.791684 -33.404107) (xy 239.821668 -33.456041) (xy 239.844617 -33.511445) (xy 239.860138 -33.56937)
			(xy 239.867966 -33.628826) (xy 239.868456 -33.65881) (xy 239.868456 -34.520886) (xy 253.689612 -34.520886)
			(xy 253.689612 -33.657286) (xy 253.690102 -33.627318) (xy 253.697925 -33.567896) (xy 253.713438 -33.510003)
			(xy 253.736374 -33.45463) (xy 253.766341 -33.402724) (xy 253.802828 -33.355174) (xy 253.845208 -33.312794)
			(xy 253.892758 -33.276307) (xy 253.944664 -33.24634) (xy 254.000037 -33.223404) (xy 254.05793 -33.207891)
			(xy 254.117352 -33.200068) (xy 254.177288 -33.200068) (xy 254.23671 -33.207891) (xy 254.294603 -33.223404)
			(xy 254.349976 -33.24634) (xy 254.401882 -33.276307) (xy 254.449432 -33.312794) (xy 254.491812 -33.355174)
			(xy 254.528299 -33.402724) (xy 254.558266 -33.45463) (xy 254.581202 -33.510003) (xy 254.596715 -33.567896)
			(xy 254.604538 -33.627318) (xy 254.605028 -33.657286) (xy 254.605028 -34.520886) (xy 254.604538 -34.550854)
			(xy 254.596715 -34.610276) (xy 254.581202 -34.668169) (xy 254.558266 -34.723542) (xy 254.528299 -34.775448)
			(xy 254.491812 -34.822998) (xy 254.449432 -34.865378) (xy 254.401882 -34.901865) (xy 254.349976 -34.931832)
			(xy 254.294603 -34.954768) (xy 254.23671 -34.970281) (xy 254.177288 -34.978104) (xy 254.117352 -34.978104)
			(xy 254.05793 -34.970281) (xy 254.000037 -34.954768) (xy 253.944664 -34.931832) (xy 253.892758 -34.901865)
			(xy 253.845208 -34.865378) (xy 253.802828 -34.822998) (xy 253.766341 -34.775448) (xy 253.736374 -34.723542)
			(xy 253.713438 -34.668169) (xy 253.697925 -34.610276) (xy 253.690102 -34.550854) (xy 253.689612 -34.520886)
			(xy 239.868456 -34.520886) (xy 239.868456 -34.52241) (xy 239.867966 -34.552394) (xy 239.860138 -34.61185)
			(xy 239.844617 -34.669775) (xy 239.821668 -34.725179) (xy 239.791684 -34.777113) (xy 239.755178 -34.824689)
			(xy 239.712773 -34.867094) (xy 239.665197 -34.9036) (xy 239.613263 -34.933584) (xy 239.557859 -34.956533)
			(xy 239.499934 -34.972054) (xy 239.440478 -34.979882) (xy 239.38051 -34.979882) (xy 239.321054 -34.972054)
			(xy 239.263129 -34.956533) (xy 239.207725 -34.933584) (xy 239.155791 -34.9036) (xy 239.108215 -34.867094)
			(xy 239.06581 -34.824689) (xy 239.029304 -34.777113) (xy 238.99932 -34.725179) (xy 238.976371 -34.669775)
			(xy 238.96085 -34.61185) (xy 238.953022 -34.552394) (xy 238.952532 -34.52241) (xy 238.29518 -34.52241)
			(xy 238.29518 -34.72434) (xy 238.295688 -34.73196) (xy 238.297141 -34.739795) (xy 238.304255 -34.754044)
			(xy 238.309658 -34.7599) (xy 239.239806 -35.689794) (xy 239.692942 -36.14293) (xy 239.70361 -36.14928)
			(xy 239.709452 -36.151058) (xy 239.734535 -36.159321) (xy 239.782325 -36.181797) (xy 239.826559 -36.210648)
			(xy 239.866392 -36.245322) (xy 239.901064 -36.285157) (xy 239.929912 -36.329393) (xy 239.952386 -36.377183)
			(xy 239.960658 -36.402264) (xy 239.962436 -36.408106) (xy 239.968786 -36.418774) (xy 240.150142 -36.60013)
			(xy 244.198655 -36.60013) (xy 244.202659 -36.512245) (xy 244.214639 -36.425088) (xy 244.234494 -36.339381)
			(xy 244.262061 -36.255836) (xy 244.297111 -36.175143) (xy 244.339353 -36.097971) (xy 244.388438 -36.024961)
			(xy 244.443959 -35.956717) (xy 244.505456 -35.893804) (xy 244.572418 -35.836744) (xy 244.644292 -35.78601)
			(xy 244.720482 -35.742022) (xy 244.800356 -35.705144) (xy 244.883253 -35.675683) (xy 244.968485 -35.653881)
			(xy 245.055347 -35.639921) (xy 245.143118 -35.633917) (xy 245.231072 -35.63592) (xy 245.318479 -35.645912)
			(xy 245.404615 -35.663812) (xy 245.488767 -35.68947) (xy 245.570237 -35.722674) (xy 245.64835 -35.763148)
			(xy 245.722458 -35.810559) (xy 245.791949 -35.864512) (xy 245.80504 -35.876738) (xy 250.9172 -35.876738)
			(xy 250.921271 -35.821116) (xy 250.933397 -35.766679) (xy 250.95332 -35.714588) (xy 250.980616 -35.665953)
			(xy 251.014702 -35.62181) (xy 251.054851 -35.583101) (xy 251.100209 -35.55065) (xy 251.149809 -35.525149)
			(xy 251.202593 -35.507142) (xy 251.257436 -35.497012) (xy 251.31317 -35.494975) (xy 251.368607 -35.501075)
			(xy 251.422564 -35.515181) (xy 251.473893 -35.536993) (xy 251.521499 -35.566047) (xy 251.564367 -35.601722)
			(xy 251.601584 -35.643259) (xy 251.632357 -35.689772) (xy 251.656029 -35.740269) (xy 251.672097 -35.793676)
			(xy 251.680217 -35.848852) (xy 251.680726 -35.876738) (xy 251.680217 -35.904624) (xy 251.672097 -35.9598)
			(xy 251.656029 -36.013207) (xy 251.632357 -36.063704) (xy 251.601584 -36.110217) (xy 251.564367 -36.151754)
			(xy 251.521499 -36.187429) (xy 251.473893 -36.216483) (xy 251.422564 -36.238295) (xy 251.368607 -36.252401)
			(xy 251.31317 -36.258501) (xy 251.257436 -36.256464) (xy 251.202593 -36.246334) (xy 251.149809 -36.228327)
			(xy 251.100209 -36.202826) (xy 251.054851 -36.170375) (xy 251.014702 -36.131666) (xy 250.980616 -36.087523)
			(xy 250.95332 -36.038888) (xy 250.933397 -35.986797) (xy 250.921271 -35.93236) (xy 250.9172 -35.876738)
			(xy 245.80504 -35.876738) (xy 245.856245 -35.92456) (xy 245.914814 -35.990207) (xy 245.967171 -36.060907)
			(xy 246.012883 -36.136076) (xy 246.051569 -36.21509) (xy 246.08291 -36.297295) (xy 246.106645 -36.382009)
			(xy 246.122579 -36.46853) (xy 246.126362 -36.50996) (xy 252.813818 -36.50996) (xy 252.817889 -36.454338)
			(xy 252.830015 -36.399901) (xy 252.849938 -36.34781) (xy 252.877234 -36.299175) (xy 252.91132 -36.255032)
			(xy 252.951469 -36.216323) (xy 252.996827 -36.183872) (xy 253.046427 -36.158371) (xy 253.099211 -36.140364)
			(xy 253.154054 -36.130234) (xy 253.209788 -36.128197) (xy 253.265225 -36.134297) (xy 253.319182 -36.148403)
			(xy 253.370511 -36.170215) (xy 253.418117 -36.199269) (xy 253.460985 -36.234944) (xy 253.498202 -36.276481)
			(xy 253.528975 -36.322994) (xy 253.552647 -36.373491) (xy 253.568715 -36.426898) (xy 253.576835 -36.482074)
			(xy 253.577344 -36.50996) (xy 253.576835 -36.537846) (xy 253.568715 -36.593022) (xy 253.552647 -36.646429)
			(xy 253.528975 -36.696926) (xy 253.498202 -36.743439) (xy 253.460985 -36.784976) (xy 253.418117 -36.820651)
			(xy 253.370511 -36.849705) (xy 253.319182 -36.871517) (xy 253.265225 -36.885623) (xy 253.209788 -36.891723)
			(xy 253.154054 -36.889686) (xy 253.099211 -36.879556) (xy 253.046427 -36.861549) (xy 252.996827 -36.836048)
			(xy 252.951469 -36.803597) (xy 252.91132 -36.764888) (xy 252.877234 -36.720745) (xy 252.849938 -36.67211)
			(xy 252.830015 -36.620019) (xy 252.817889 -36.565582) (xy 252.813818 -36.50996) (xy 246.126362 -36.50996)
			(xy 246.130579 -36.556142) (xy 246.13108 -36.60013) (xy 246.130579 -36.644118) (xy 246.122579 -36.73173)
			(xy 246.106645 -36.818251) (xy 246.08291 -36.902965) (xy 246.051569 -36.98517) (xy 246.012883 -37.064184)
			(xy 245.967171 -37.139353) (xy 245.914814 -37.210053) (xy 245.856245 -37.2757) (xy 245.791949 -37.335748)
			(xy 245.722458 -37.389701) (xy 245.64835 -37.437112) (xy 245.574919 -37.47516) (xy 249.959112 -37.47516)
			(xy 249.963183 -37.419538) (xy 249.975309 -37.365101) (xy 249.995232 -37.31301) (xy 250.022528 -37.264375)
			(xy 250.056614 -37.220232) (xy 250.096763 -37.181523) (xy 250.142121 -37.149072) (xy 250.191721 -37.123571)
			(xy 250.244505 -37.105564) (xy 250.299348 -37.095434) (xy 250.355082 -37.093397) (xy 250.410519 -37.099497)
			(xy 250.464476 -37.113603) (xy 250.515805 -37.135415) (xy 250.563411 -37.164469) (xy 250.606279 -37.200144)
			(xy 250.643496 -37.241681) (xy 250.674269 -37.288194) (xy 250.697941 -37.338691) (xy 250.714009 -37.392098)
			(xy 250.722129 -37.447274) (xy 250.722638 -37.47516) (xy 250.722129 -37.503046) (xy 250.714009 -37.558222)
			(xy 250.697941 -37.611629) (xy 250.674269 -37.662126) (xy 250.674116 -37.662358) (xy 252.148338 -37.662358)
			(xy 252.152409 -37.606736) (xy 252.164535 -37.552299) (xy 252.184458 -37.500208) (xy 252.211754 -37.451573)
			(xy 252.24584 -37.40743) (xy 252.285989 -37.368721) (xy 252.331347 -37.33627) (xy 252.380947 -37.310769)
			(xy 252.433731 -37.292762) (xy 252.488574 -37.282632) (xy 252.544308 -37.280595) (xy 252.599745 -37.286695)
			(xy 252.653702 -37.300801) (xy 252.705031 -37.322613) (xy 252.752637 -37.351667) (xy 252.795505 -37.387342)
			(xy 252.832722 -37.428879) (xy 252.863495 -37.475392) (xy 252.887167 -37.525889) (xy 252.903235 -37.579296)
			(xy 252.911355 -37.634472) (xy 252.911864 -37.662358) (xy 252.911355 -37.690244) (xy 252.903235 -37.74542)
			(xy 252.887167 -37.798827) (xy 252.863495 -37.849324) (xy 252.832722 -37.895837) (xy 252.795505 -37.937374)
			(xy 252.752637 -37.973049) (xy 252.705031 -38.002103) (xy 252.653702 -38.023915) (xy 252.599745 -38.038021)
			(xy 252.544308 -38.044121) (xy 252.488574 -38.042084) (xy 252.433731 -38.031954) (xy 252.380947 -38.013947)
			(xy 252.331347 -37.988446) (xy 252.285989 -37.955995) (xy 252.24584 -37.917286) (xy 252.211754 -37.873143)
			(xy 252.184458 -37.824508) (xy 252.164535 -37.772417) (xy 252.152409 -37.71798) (xy 252.148338 -37.662358)
			(xy 250.674116 -37.662358) (xy 250.643496 -37.708639) (xy 250.606279 -37.750176) (xy 250.563411 -37.785851)
			(xy 250.515805 -37.814905) (xy 250.464476 -37.836717) (xy 250.410519 -37.850823) (xy 250.355082 -37.856923)
			(xy 250.299348 -37.854886) (xy 250.244505 -37.844756) (xy 250.191721 -37.826749) (xy 250.142121 -37.801248)
			(xy 250.096763 -37.768797) (xy 250.056614 -37.730088) (xy 250.022528 -37.685945) (xy 249.995232 -37.63731)
			(xy 249.975309 -37.585219) (xy 249.963183 -37.530782) (xy 249.959112 -37.47516) (xy 245.574919 -37.47516)
			(xy 245.570237 -37.477586) (xy 245.488767 -37.51079) (xy 245.404615 -37.536448) (xy 245.318479 -37.554348)
			(xy 245.231072 -37.56434) (xy 245.143118 -37.566343) (xy 245.055347 -37.560339) (xy 244.968485 -37.546379)
			(xy 244.883253 -37.524577) (xy 244.800356 -37.495116) (xy 244.720482 -37.458238) (xy 244.644292 -37.41425)
			(xy 244.572418 -37.363516) (xy 244.505456 -37.306456) (xy 244.443959 -37.243543) (xy 244.388438 -37.175299)
			(xy 244.339353 -37.102289) (xy 244.297111 -37.025117) (xy 244.262061 -36.944424) (xy 244.234494 -36.860879)
			(xy 244.214639 -36.775172) (xy 244.202659 -36.688015) (xy 244.198655 -36.60013) (xy 240.150142 -36.60013)
			(xy 242.279963 -38.729951) (xy 255.900897 -38.729951) (xy 255.900897 -38.675449) (xy 255.908654 -38.6215)
			(xy 255.924011 -38.569205) (xy 255.946653 -38.519628) (xy 255.976121 -38.473779) (xy 256.011815 -38.432589)
			(xy 256.053007 -38.3969) (xy 256.09886 -38.367436) (xy 256.148439 -38.344798) (xy 256.200736 -38.329447)
			(xy 256.254684 -38.321695) (xy 256.281936 -38.321234) (xy 256.310239 -38.321758) (xy 256.366227 -38.330102)
			(xy 256.420366 -38.34663) (xy 256.471467 -38.370979) (xy 256.518407 -38.402615) (xy 256.560156 -38.440842)
			(xy 256.595795 -38.48482) (xy 256.610612 -38.50894) (xy 256.618228 -38.520962) (xy 256.638843 -38.540563)
			(xy 256.664071 -38.553706) (xy 256.691948 -38.559367) (xy 256.720304 -38.557105) (xy 256.746932 -38.547097)
			(xy 256.769758 -38.530122) (xy 256.77876 -38.5191) (xy 256.796974 -38.496247) (xy 256.839131 -38.455782)
			(xy 256.886961 -38.422212) (xy 256.939348 -38.396321) (xy 256.995067 -38.378713) (xy 257.052819 -38.369801)
			(xy 257.082036 -38.36924) (xy 257.109289 -38.369632) (xy 257.16324 -38.377394) (xy 257.215537 -38.392754)
			(xy 257.265116 -38.4154) (xy 257.310967 -38.444871) (xy 257.352158 -38.480567) (xy 257.38785 -38.521762)
			(xy 257.417317 -38.567616) (xy 257.439958 -38.617197) (xy 257.455314 -38.669496) (xy 257.46307 -38.723447)
			(xy 257.46307 -38.777953) (xy 257.455314 -38.831904) (xy 257.439958 -38.884203) (xy 257.417317 -38.933784)
			(xy 257.38785 -38.979638) (xy 257.352158 -39.020833) (xy 257.310967 -39.056529) (xy 257.265116 -39.086)
			(xy 257.215537 -39.108646) (xy 257.16324 -39.124006) (xy 257.109289 -39.131768) (xy 257.082036 -39.132256)
			(xy 257.053732 -39.131759) (xy 256.997743 -39.123411) (xy 256.943603 -39.106879) (xy 256.892501 -39.082525)
			(xy 256.845561 -39.050885) (xy 256.803814 -39.012654) (xy 256.768177 -38.968672) (xy 256.75336 -38.94455)
			(xy 256.745781 -38.932503) (xy 256.725157 -38.912902) (xy 256.699922 -38.899761) (xy 256.672038 -38.894104)
			(xy 256.643676 -38.89637) (xy 256.617044 -38.906383) (xy 256.594215 -38.923365) (xy 256.585212 -38.93439)
			(xy 256.567011 -38.957254) (xy 256.524852 -38.997719) (xy 256.477019 -39.031288) (xy 256.42463 -39.057178)
			(xy 256.368908 -39.074782) (xy 256.311154 -39.083691) (xy 256.281936 -39.08425) (xy 256.254684 -39.083705)
			(xy 256.200736 -39.075953) (xy 256.148439 -39.060602) (xy 256.09886 -39.037964) (xy 256.053007 -39.0085)
			(xy 256.011815 -38.972811) (xy 255.976121 -38.931621) (xy 255.946653 -38.885772) (xy 255.924011 -38.836195)
			(xy 255.908654 -38.7839) (xy 255.900897 -38.729951) (xy 242.279963 -38.729951) (xy 244.818763 -41.268751)
			(xy 248.04395 -41.268751) (xy 248.04395 -41.214249) (xy 248.051706 -41.160301) (xy 248.06706 -41.108006)
			(xy 248.089699 -41.058428) (xy 248.119163 -41.012577) (xy 248.154852 -40.971385) (xy 248.19604 -40.935691)
			(xy 248.241888 -40.906221) (xy 248.291463 -40.883576) (xy 248.343756 -40.868215) (xy 248.397703 -40.860453)
			(xy 248.424954 -40.859964) (xy 248.453694 -40.860465) (xy 248.510522 -40.869094) (xy 248.565412 -40.88615)
			(xy 248.617124 -40.911247) (xy 248.664485 -40.943816) (xy 248.685812 -40.963088) (xy 248.69267 -40.969692)
			(xy 248.710704 -40.976804) (xy 248.799604 -40.976804) (xy 248.817638 -40.969692) (xy 248.824496 -40.963088)
			(xy 248.845808 -40.9438) (xy 248.893173 -40.911234) (xy 248.944889 -40.886144) (xy 248.999783 -40.869098)
			(xy 249.056614 -40.860481) (xy 249.085354 -40.859964) (xy 249.112607 -40.86048) (xy 249.166559 -40.868231)
			(xy 249.218858 -40.883582) (xy 249.268441 -40.90622) (xy 249.314296 -40.935685) (xy 249.355491 -40.971376)
			(xy 249.391187 -41.012567) (xy 249.420658 -41.058419) (xy 249.443302 -41.107998) (xy 249.458659 -41.160296)
			(xy 249.466417 -41.214247) (xy 249.466417 -41.268753) (xy 249.458659 -41.322704) (xy 249.443302 -41.375002)
			(xy 249.420658 -41.424581) (xy 249.391187 -41.470433) (xy 249.355491 -41.511624) (xy 249.314296 -41.547315)
			(xy 249.268441 -41.57678) (xy 249.218858 -41.599418) (xy 249.166559 -41.614769) (xy 249.112607 -41.62252)
			(xy 249.085354 -41.62298) (xy 249.056615 -41.622463) (xy 248.999788 -41.613835) (xy 248.944898 -41.596783)
			(xy 248.893187 -41.57169) (xy 248.845824 -41.539126) (xy 248.824496 -41.519856) (xy 248.817638 -41.513252)
			(xy 248.799604 -41.50614) (xy 248.710704 -41.50614) (xy 248.69267 -41.513252) (xy 248.685812 -41.519856)
			(xy 248.664503 -41.539148) (xy 248.617136 -41.571711) (xy 248.56542 -41.5968) (xy 248.510525 -41.613845)
			(xy 248.453694 -41.622462) (xy 248.424954 -41.62298) (xy 248.397703 -41.622547) (xy 248.343756 -41.614785)
			(xy 248.291463 -41.599424) (xy 248.241888 -41.576779) (xy 248.19604 -41.547309) (xy 248.154852 -41.511615)
			(xy 248.119163 -41.470423) (xy 248.089699 -41.424572) (xy 248.06706 -41.374994) (xy 248.051706 -41.322699)
			(xy 248.04395 -41.268751) (xy 244.818763 -41.268751) (xy 245.498874 -41.948862) (xy 245.516987 -41.967642)
			(xy 245.547672 -42.009839) (xy 245.571371 -42.05632) (xy 245.587499 -42.105939) (xy 245.59566 -42.157471)
			(xy 245.596156 -42.183558) (xy 245.596156 -43.305222) (xy 250.507246 -43.305222) (xy 250.507714 -43.277852)
			(xy 250.515529 -43.223672) (xy 250.531018 -43.171169) (xy 250.553859 -43.121422) (xy 250.583584 -43.075455)
			(xy 250.601226 -43.054524) (xy 250.60148 -43.05427) (xy 250.607053 -43.047174) (xy 250.613306 -43.030264)
			(xy 250.613672 -43.02125) (xy 250.613672 -42.954194) (xy 250.613324 -42.945176) (xy 250.607071 -42.928259)
			(xy 250.60148 -42.921174) (xy 250.601226 -42.921174) (xy 250.601226 -42.92092) (xy 250.583587 -42.899988)
			(xy 250.553874 -42.854015) (xy 250.531038 -42.804268) (xy 250.515547 -42.751767) (xy 250.507719 -42.697591)
			(xy 250.507246 -42.670222) (xy 250.507798 -42.641484) (xy 250.516416 -42.584659) (xy 250.53346 -42.529769)
			(xy 250.558545 -42.478057) (xy 250.591103 -42.430692) (xy 250.61037 -42.409364) (xy 250.616974 -42.402506)
			(xy 250.624086 -42.384472) (xy 250.624086 -42.295572) (xy 250.616974 -42.277538) (xy 250.61037 -42.27068)
			(xy 250.591123 -42.249333) (xy 250.558562 -42.201973) (xy 250.533473 -42.150264) (xy 250.516424 -42.095377)
			(xy 250.5078 -42.038553) (xy 250.507798 -41.981079) (xy 250.516417 -41.924255) (xy 250.533461 -41.869366)
			(xy 250.558546 -41.817655) (xy 250.591103 -41.770292) (xy 250.61037 -41.748964) (xy 250.616974 -41.742106)
			(xy 250.624086 -41.724072) (xy 250.624086 -41.635172) (xy 250.616974 -41.617138) (xy 250.61037 -41.61028)
			(xy 250.591115 -41.588939) (xy 250.558545 -41.541582) (xy 250.533449 -41.489873) (xy 250.516395 -41.434986)
			(xy 250.507769 -41.37816) (xy 250.507246 -41.349422) (xy 250.507732 -41.322171) (xy 250.515488 -41.268223)
			(xy 250.530843 -41.215928) (xy 250.553485 -41.166351) (xy 250.582951 -41.120501) (xy 250.618642 -41.07931)
			(xy 250.659833 -41.043619) (xy 250.705683 -41.014153) (xy 250.75526 -40.991511) (xy 250.807555 -40.976156)
			(xy 250.861503 -40.9684) (xy 250.916005 -40.9684) (xy 250.939126 -40.971724) (xy 258.793994 -40.971724)
			(xy 258.798065 -40.916102) (xy 258.810191 -40.861665) (xy 258.830114 -40.809574) (xy 258.85741 -40.760939)
			(xy 258.891496 -40.716796) (xy 258.931645 -40.678087) (xy 258.977003 -40.645636) (xy 259.026603 -40.620135)
			(xy 259.079387 -40.602128) (xy 259.13423 -40.591998) (xy 259.189964 -40.589961) (xy 259.245401 -40.596061)
			(xy 259.299358 -40.610167) (xy 259.350687 -40.631979) (xy 259.398293 -40.661033) (xy 259.441161 -40.696708)
			(xy 259.478378 -40.738245) (xy 259.509151 -40.784758) (xy 259.532823 -40.835255) (xy 259.548891 -40.888662)
			(xy 259.557011 -40.943838) (xy 259.55752 -40.971724) (xy 259.557011 -40.99961) (xy 259.548891 -41.054786)
			(xy 259.532823 -41.108193) (xy 259.509151 -41.15869) (xy 259.478378 -41.205203) (xy 259.441161 -41.24674)
			(xy 259.398293 -41.282415) (xy 259.350687 -41.311469) (xy 259.299358 -41.333281) (xy 259.245401 -41.347387)
			(xy 259.189964 -41.353487) (xy 259.13423 -41.35145) (xy 259.079387 -41.34132) (xy 259.026603 -41.323313)
			(xy 258.977003 -41.297812) (xy 258.931645 -41.265361) (xy 258.891496 -41.226652) (xy 258.85741 -41.182509)
			(xy 258.830114 -41.133874) (xy 258.810191 -41.081783) (xy 258.798065 -41.027346) (xy 258.793994 -40.971724)
			(xy 250.939126 -40.971724) (xy 250.969953 -40.976156) (xy 251.022248 -40.991511) (xy 251.071825 -41.014153)
			(xy 251.117675 -41.043619) (xy 251.158866 -41.07931) (xy 251.194557 -41.120501) (xy 251.224023 -41.166351)
			(xy 251.246665 -41.215928) (xy 251.26202 -41.268223) (xy 251.269776 -41.322171) (xy 251.270262 -41.349422)
			(xy 251.269735 -41.378161) (xy 251.261111 -41.434987) (xy 251.24406 -41.489877) (xy 251.21897 -41.541589)
			(xy 251.186407 -41.588952) (xy 251.167138 -41.61028) (xy 251.160534 -41.617138) (xy 251.153422 -41.635172)
			(xy 251.153422 -41.724072) (xy 251.160534 -41.742106) (xy 251.167138 -41.748964) (xy 251.186432 -41.770271)
			(xy 251.219 -41.817636) (xy 251.244093 -41.869351) (xy 251.261143 -41.924245) (xy 251.269765 -41.981075)
			(xy 251.269762 -42.038557) (xy 251.261136 -42.095387) (xy 251.244081 -42.150279) (xy 251.218984 -42.201992)
			(xy 251.186412 -42.249354) (xy 251.167138 -42.27068) (xy 251.160534 -42.277538) (xy 251.153422 -42.295572)
			(xy 251.153422 -42.384472) (xy 251.160534 -42.402506) (xy 251.167138 -42.409364) (xy 251.186415 -42.430686)
			(xy 251.218981 -42.478049) (xy 251.244073 -42.529762) (xy 251.261122 -42.584654) (xy 251.269743 -42.641483)
			(xy 251.270262 -42.670222) (xy 251.269818 -42.697593) (xy 251.261996 -42.751774) (xy 251.246503 -42.804277)
			(xy 251.225946 -42.849038) (xy 253.091948 -42.849038) (xy 253.096019 -42.793416) (xy 253.108145 -42.738979)
			(xy 253.128068 -42.686888) (xy 253.155364 -42.638253) (xy 253.18945 -42.59411) (xy 253.229599 -42.555401)
			(xy 253.274957 -42.52295) (xy 253.324557 -42.497449) (xy 253.377341 -42.479442) (xy 253.432184 -42.469312)
			(xy 253.487918 -42.467275) (xy 253.543355 -42.473375) (xy 253.597312 -42.487481) (xy 253.648641 -42.509293)
			(xy 253.696247 -42.538347) (xy 253.739115 -42.574022) (xy 253.776332 -42.615559) (xy 253.807105 -42.662072)
			(xy 253.830777 -42.712569) (xy 253.846845 -42.765976) (xy 253.854965 -42.821152) (xy 253.855326 -42.84091)
			(xy 259.133084 -42.84091) (xy 259.137155 -42.785288) (xy 259.149281 -42.730851) (xy 259.169204 -42.67876)
			(xy 259.1965 -42.630125) (xy 259.230586 -42.585982) (xy 259.270735 -42.547273) (xy 259.316093 -42.514822)
			(xy 259.365693 -42.489321) (xy 259.418477 -42.471314) (xy 259.47332 -42.461184) (xy 259.529054 -42.459147)
			(xy 259.584491 -42.465247) (xy 259.638448 -42.479353) (xy 259.689777 -42.501165) (xy 259.737383 -42.530219)
			(xy 259.780251 -42.565894) (xy 259.817468 -42.607431) (xy 259.848241 -42.653944) (xy 259.871913 -42.704441)
			(xy 259.887981 -42.757848) (xy 259.896101 -42.813024) (xy 259.89661 -42.84091) (xy 259.896101 -42.868796)
			(xy 259.887981 -42.923972) (xy 259.871913 -42.977379) (xy 259.848241 -43.027876) (xy 259.817468 -43.074389)
			(xy 259.780251 -43.115926) (xy 259.737383 -43.151601) (xy 259.689777 -43.180655) (xy 259.638448 -43.202467)
			(xy 259.584491 -43.216573) (xy 259.529054 -43.222673) (xy 259.47332 -43.220636) (xy 259.418477 -43.210506)
			(xy 259.365693 -43.192499) (xy 259.316093 -43.166998) (xy 259.270735 -43.134547) (xy 259.230586 -43.095838)
			(xy 259.1965 -43.051695) (xy 259.169204 -43.00306) (xy 259.149281 -42.950969) (xy 259.137155 -42.896532)
			(xy 259.133084 -42.84091) (xy 253.855326 -42.84091) (xy 253.855474 -42.849038) (xy 253.854965 -42.876924)
			(xy 253.846845 -42.9321) (xy 253.830777 -42.985507) (xy 253.807105 -43.036004) (xy 253.776332 -43.082517)
			(xy 253.739115 -43.124054) (xy 253.696247 -43.159729) (xy 253.648641 -43.188783) (xy 253.597312 -43.210595)
			(xy 253.543355 -43.224701) (xy 253.487918 -43.230801) (xy 253.432184 -43.228764) (xy 253.377341 -43.218634)
			(xy 253.324557 -43.200627) (xy 253.274957 -43.175126) (xy 253.229599 -43.142675) (xy 253.18945 -43.103966)
			(xy 253.155364 -43.059823) (xy 253.128068 -43.011188) (xy 253.108145 -42.959097) (xy 253.096019 -42.90466)
			(xy 253.091948 -42.849038) (xy 251.225946 -42.849038) (xy 251.223656 -42.854024) (xy 251.193926 -42.899989)
			(xy 251.176282 -42.92092) (xy 251.176028 -42.921174) (xy 251.170438 -42.928258) (xy 251.164195 -42.945177)
			(xy 251.163836 -42.954194) (xy 251.163836 -43.02125) (xy 251.164209 -43.030265) (xy 251.170445 -43.047183)
			(xy 251.176028 -43.05427) (xy 251.176282 -43.05427) (xy 251.176282 -43.054524) (xy 251.193896 -43.075476)
			(xy 251.223612 -43.121443) (xy 251.246453 -43.171186) (xy 251.26195 -43.223682) (xy 251.269785 -43.277854)
			(xy 251.270262 -43.305222) (xy 251.269776 -43.332473) (xy 251.26202 -43.386421) (xy 251.246665 -43.438716)
			(xy 251.224023 -43.488293) (xy 251.194557 -43.534143) (xy 251.158866 -43.575334) (xy 251.117675 -43.611025)
			(xy 251.071825 -43.640491) (xy 251.022248 -43.663133) (xy 250.969953 -43.678488) (xy 250.916005 -43.686244)
			(xy 250.861503 -43.686244) (xy 250.807555 -43.678488) (xy 250.75526 -43.663133) (xy 250.705683 -43.640491)
			(xy 250.659833 -43.611025) (xy 250.618642 -43.575334) (xy 250.582951 -43.534143) (xy 250.553485 -43.488293)
			(xy 250.530843 -43.438716) (xy 250.515488 -43.386421) (xy 250.507732 -43.332473) (xy 250.507246 -43.305222)
			(xy 245.596156 -43.305222) (xy 245.596156 -43.73626) (xy 252.413006 -43.73626) (xy 252.417077 -43.680638)
			(xy 252.429203 -43.626201) (xy 252.449126 -43.57411) (xy 252.476422 -43.525475) (xy 252.510508 -43.481332)
			(xy 252.550657 -43.442623) (xy 252.596015 -43.410172) (xy 252.645615 -43.384671) (xy 252.698399 -43.366664)
			(xy 252.753242 -43.356534) (xy 252.808976 -43.354497) (xy 252.864413 -43.360597) (xy 252.91837 -43.374703)
			(xy 252.969699 -43.396515) (xy 253.017305 -43.425569) (xy 253.060173 -43.461244) (xy 253.09739 -43.502781)
			(xy 253.128163 -43.549294) (xy 253.151835 -43.599791) (xy 253.167903 -43.653198) (xy 253.176023 -43.708374)
			(xy 253.176532 -43.73626) (xy 253.176023 -43.764146) (xy 253.167903 -43.819322) (xy 253.156597 -43.8569)
			(xy 256.715216 -43.8569) (xy 256.719182 -43.78881) (xy 256.731027 -43.721641) (xy 256.750589 -43.656301)
			(xy 256.777605 -43.593674) (xy 256.81171 -43.534608) (xy 256.852441 -43.4799) (xy 256.899248 -43.430291)
			(xy 256.951498 -43.386452) (xy 257.008485 -43.348975) (xy 257.069437 -43.318368) (xy 257.133531 -43.295044)
			(xy 257.199899 -43.279319) (xy 257.267643 -43.271406) (xy 257.301746 -43.270932) (xy 258.336034 -43.270932)
			(xy 258.368914 -43.271406) (xy 258.434261 -43.278766) (xy 258.498372 -43.293401) (xy 258.56044 -43.315128)
			(xy 258.619682 -43.343671) (xy 258.675354 -43.378673) (xy 258.726753 -43.419691) (xy 258.750308 -43.442636)
			(xy 258.906518 -43.598846) (xy 258.929437 -43.622392) (xy 258.970403 -43.67377) (xy 259.005359 -43.729413)
			(xy 259.033865 -43.78862) (xy 259.055562 -43.850646) (xy 259.070177 -43.914711) (xy 259.077528 -43.98001)
			(xy 259.077968 -44.012866) (xy 259.077968 -44.525438) (xy 259.078397 -44.535376) (xy 259.08599 -44.553748)
			(xy 259.099987 -44.567865) (xy 259.108956 -44.572174) (xy 259.209286 -44.614592) (xy 259.239258 -44.609004)
			(xy 259.25018 -44.598336) (xy 259.271629 -44.57837) (xy 259.319533 -44.544622) (xy 259.372032 -44.518592)
			(xy 259.427893 -44.500892) (xy 259.485803 -44.491936) (xy 259.515102 -44.491402) (xy 259.542354 -44.491868)
			(xy 259.596303 -44.499625) (xy 259.648599 -44.514981) (xy 259.698177 -44.537622) (xy 259.744028 -44.56709)
			(xy 259.785219 -44.602782) (xy 259.820912 -44.643973) (xy 259.850379 -44.689825) (xy 259.87302 -44.739403)
			(xy 259.888376 -44.791699) (xy 259.896132 -44.845648) (xy 259.896132 -44.900152) (xy 259.888376 -44.954101)
			(xy 259.87302 -45.006397) (xy 259.850379 -45.055975) (xy 259.820912 -45.101827) (xy 259.785219 -45.143018)
			(xy 259.744028 -45.17871) (xy 259.698177 -45.208178) (xy 259.648599 -45.230819) (xy 259.596303 -45.246175)
			(xy 259.542354 -45.253932) (xy 259.515102 -45.254418) (xy 259.485802 -45.253907) (xy 259.427888 -45.244957)
			(xy 259.372026 -45.227253) (xy 259.31953 -45.201212) (xy 259.271635 -45.167446) (xy 259.25018 -45.147484)
			(xy 259.239258 -45.136816) (xy 259.209286 -45.131228) (xy 259.108956 -45.173646) (xy 259.099956 -45.177895)
			(xy 259.085973 -45.192036) (xy 259.078429 -45.210437) (xy 259.077968 -45.220382) (xy 259.077968 -47.124112)
			(xy 259.078443 -47.134452) (xy 259.086546 -47.153476) (xy 259.101479 -47.167778) (xy 259.110988 -47.171864)
			(xy 259.215382 -47.210726) (xy 259.245608 -47.203106) (xy 259.256276 -47.190914) (xy 259.274499 -47.17078)
			(xy 259.315618 -47.13531) (xy 259.361354 -47.106032) (xy 259.41078 -47.08354) (xy 259.462898 -47.068287)
			(xy 259.516652 -47.060583) (xy 259.543804 -47.060104) (xy 259.571056 -47.060566) (xy 259.625005 -47.068323)
			(xy 259.677301 -47.083679) (xy 259.726879 -47.106321) (xy 259.77273 -47.135789) (xy 259.813922 -47.171481)
			(xy 259.849614 -47.212673) (xy 259.879081 -47.258524) (xy 259.901722 -47.308103) (xy 259.917078 -47.360399)
			(xy 259.924834 -47.414348) (xy 259.924834 -47.468852) (xy 259.917078 -47.522801) (xy 259.901722 -47.575097)
			(xy 259.879081 -47.624676) (xy 259.849614 -47.670527) (xy 259.813922 -47.711719) (xy 259.77273 -47.747411)
			(xy 259.726879 -47.776879) (xy 259.677301 -47.799521) (xy 259.625005 -47.814877) (xy 259.571056 -47.822634)
			(xy 259.543804 -47.82312) (xy 259.516533 -47.822617) (xy 259.462547 -47.814841) (xy 259.410217 -47.799462)
			(xy 259.360608 -47.776793) (xy 259.314731 -47.747295) (xy 259.273518 -47.711568) (xy 259.237808 -47.67034)
			(xy 259.208329 -47.624449) (xy 259.185681 -47.574831) (xy 259.177536 -47.5488) (xy 259.174207 -47.538914)
			(xy 259.160909 -47.522863) (xy 259.14233 -47.513413) (xy 259.121526 -47.512117) (xy 259.101918 -47.51919)
			(xy 259.086731 -47.533467) (xy 259.078463 -47.552602) (xy 259.077968 -47.563024) (xy 259.077968 -47.6504)
			(xy 259.078376 -47.660472) (xy 259.086107 -47.67907) (xy 259.092954 -47.686468) (xy 259.929376 -48.522636)
			(xy 259.952279 -48.546227) (xy 259.993275 -48.597636) (xy 260.028263 -48.653308) (xy 260.056804 -48.712543)
			(xy 260.078541 -48.7746) (xy 260.093201 -48.838698) (xy 260.100599 -48.904034) (xy 260.10108 -48.93691)
			(xy 260.100638 -48.970425) (xy 260.092954 -49.037015) (xy 260.077723 -49.102292) (xy 260.055143 -49.165406)
			(xy 260.025509 -49.225531) (xy 259.989209 -49.281882) (xy 259.946715 -49.333723) (xy 259.898585 -49.380377)
			(xy 259.845445 -49.421235) (xy 259.78799 -49.455762) (xy 259.757672 -49.470056) (xy 259.757418 -49.470056)
			(xy 259.749608 -49.474085) (xy 259.73712 -49.486434) (xy 259.729499 -49.502257) (xy 259.728208 -49.51095)
			(xy 259.719318 -49.59858) (xy 259.719118 -49.601953) (xy 264.312859 -49.601953) (xy 264.312859 -49.547447)
			(xy 264.320616 -49.493496) (xy 264.335973 -49.441198) (xy 264.358616 -49.391618) (xy 264.388084 -49.345765)
			(xy 264.423778 -49.304572) (xy 264.464971 -49.268879) (xy 264.510825 -49.239412) (xy 264.560406 -49.21677)
			(xy 264.612704 -49.201415) (xy 264.666655 -49.193659) (xy 264.693908 -49.193196) (xy 264.721278 -49.193658)
			(xy 264.775458 -49.201477) (xy 264.827961 -49.216967) (xy 264.877707 -49.23981) (xy 264.923674 -49.269535)
			(xy 264.944606 -49.287176) (xy 264.94486 -49.28743) (xy 264.951951 -49.293009) (xy 264.968865 -49.299259)
			(xy 264.97788 -49.299622) (xy 265.044936 -49.299622) (xy 265.053954 -49.299278) (xy 265.070871 -49.293021)
			(xy 265.077956 -49.28743) (xy 265.077956 -49.287176) (xy 265.07821 -49.287176) (xy 265.099143 -49.269535)
			(xy 265.145111 -49.239811) (xy 265.194857 -49.216965) (xy 265.247359 -49.201469) (xy 265.301537 -49.19364)
			(xy 265.356279 -49.19364) (xy 265.410457 -49.201469) (xy 265.462959 -49.216965) (xy 265.512705 -49.239811)
			(xy 265.558673 -49.269535) (xy 265.579606 -49.287176) (xy 265.57986 -49.28743) (xy 265.586951 -49.293009)
			(xy 265.603865 -49.299259) (xy 265.61288 -49.299622) (xy 265.679936 -49.299622) (xy 265.688954 -49.299278)
			(xy 265.705871 -49.293021) (xy 265.712956 -49.28743) (xy 265.712956 -49.287176) (xy 265.71321 -49.287176)
			(xy 265.734143 -49.269535) (xy 265.780111 -49.239811) (xy 265.829857 -49.216965) (xy 265.882359 -49.201469)
			(xy 265.936537 -49.19364) (xy 265.991279 -49.19364) (xy 266.045457 -49.201469) (xy 266.097959 -49.216965)
			(xy 266.147705 -49.239811) (xy 266.193673 -49.269535) (xy 266.214606 -49.287176) (xy 266.21486 -49.28743)
			(xy 266.221951 -49.293009) (xy 266.238865 -49.299259) (xy 266.24788 -49.299622) (xy 266.314936 -49.299622)
			(xy 266.323954 -49.299278) (xy 266.340871 -49.293021) (xy 266.347956 -49.28743) (xy 266.347956 -49.287176)
			(xy 266.34821 -49.287176) (xy 266.369124 -49.269515) (xy 266.415102 -49.239807) (xy 266.464854 -49.216976)
			(xy 266.517359 -49.20149) (xy 266.571538 -49.193667) (xy 266.598908 -49.193196) (xy 266.626159 -49.193674)
			(xy 266.680107 -49.201432) (xy 266.732401 -49.216788) (xy 266.781978 -49.23943) (xy 266.827828 -49.268896)
			(xy 266.869017 -49.304588) (xy 266.904708 -49.345779) (xy 266.934174 -49.391629) (xy 266.956815 -49.441207)
			(xy 266.97217 -49.493501) (xy 266.979926 -49.547449) (xy 266.979926 -49.601951) (xy 266.97217 -49.655899)
			(xy 266.956815 -49.708193) (xy 266.934174 -49.757771) (xy 266.904708 -49.803621) (xy 266.869017 -49.844812)
			(xy 266.827828 -49.880504) (xy 266.781978 -49.90997) (xy 266.732401 -49.932612) (xy 266.680107 -49.947968)
			(xy 266.626159 -49.955726) (xy 266.598908 -49.956212) (xy 266.571538 -49.955738) (xy 266.517359 -49.947922)
			(xy 266.464857 -49.932434) (xy 266.41511 -49.909594) (xy 266.369142 -49.879872) (xy 266.34821 -49.862232)
			(xy 266.347956 -49.861978) (xy 266.340859 -49.856406) (xy 266.32395 -49.850151) (xy 266.314936 -49.849786)
			(xy 266.24788 -49.849786) (xy 266.238863 -49.850137) (xy 266.221946 -49.856389) (xy 266.21486 -49.861978)
			(xy 266.214606 -49.862232) (xy 266.193673 -49.879873) (xy 266.147705 -49.909597) (xy 266.097959 -49.932443)
			(xy 266.045457 -49.947939) (xy 265.991279 -49.955768) (xy 265.936537 -49.955768) (xy 265.882359 -49.947939)
			(xy 265.829857 -49.932443) (xy 265.780111 -49.909597) (xy 265.734143 -49.879873) (xy 265.71321 -49.862232)
			(xy 265.712956 -49.861978) (xy 265.705859 -49.856406) (xy 265.68895 -49.850151) (xy 265.679936 -49.849786)
			(xy 265.61288 -49.849786) (xy 265.603863 -49.850137) (xy 265.586946 -49.856389) (xy 265.57986 -49.861978)
			(xy 265.57986 -49.862232) (xy 265.579606 -49.862232) (xy 265.558673 -49.879873) (xy 265.512705 -49.909597)
			(xy 265.462959 -49.932443) (xy 265.410457 -49.947939) (xy 265.356279 -49.955768) (xy 265.301537 -49.955768)
			(xy 265.247359 -49.947939) (xy 265.194857 -49.932443) (xy 265.145111 -49.909597) (xy 265.099143 -49.879873)
			(xy 265.07821 -49.862232) (xy 265.077956 -49.861978) (xy 265.070859 -49.856406) (xy 265.05395 -49.850151)
			(xy 265.044936 -49.849786) (xy 264.97788 -49.849786) (xy 264.968863 -49.850137) (xy 264.951946 -49.856389)
			(xy 264.94486 -49.861978) (xy 264.94486 -49.862232) (xy 264.944606 -49.862232) (xy 264.923687 -49.879887)
			(xy 264.87771 -49.909595) (xy 264.827959 -49.932428) (xy 264.775456 -49.947915) (xy 264.721278 -49.95574)
			(xy 264.693908 -49.956212) (xy 264.666655 -49.955741) (xy 264.612704 -49.947985) (xy 264.560406 -49.93263)
			(xy 264.510825 -49.909988) (xy 264.464971 -49.880521) (xy 264.423778 -49.844828) (xy 264.388084 -49.803635)
			(xy 264.358616 -49.757782) (xy 264.335973 -49.708202) (xy 264.320616 -49.655904) (xy 264.312859 -49.601953)
			(xy 259.719118 -49.601953) (xy 259.718794 -49.607419) (xy 259.723114 -49.624579) (xy 259.732984 -49.639267)
			(xy 259.739892 -49.644808) (xy 259.763727 -49.662892) (xy 259.805981 -49.705243) (xy 259.8411 -49.753676)
			(xy 259.868223 -49.807) (xy 259.886683 -49.863906) (xy 259.896027 -49.922997) (xy 259.89661 -49.95291)
			(xy 259.896124 -49.980161) (xy 259.888368 -50.034109) (xy 259.873013 -50.086404) (xy 259.850371 -50.135981)
			(xy 259.820905 -50.181831) (xy 259.785214 -50.223022) (xy 259.744023 -50.258713) (xy 259.698173 -50.288179)
			(xy 259.648596 -50.310821) (xy 259.596301 -50.326176) (xy 259.542353 -50.333932) (xy 259.487851 -50.333932)
			(xy 259.433903 -50.326176) (xy 259.381608 -50.310821) (xy 259.332031 -50.288179) (xy 259.286181 -50.258713)
			(xy 259.24499 -50.223022) (xy 259.209299 -50.181831) (xy 259.179833 -50.135981) (xy 259.157191 -50.086404)
			(xy 259.141836 -50.034109) (xy 259.13408 -49.980161) (xy 259.133594 -49.95291) (xy 259.134148 -49.922997)
			(xy 259.143505 -49.863907) (xy 259.161974 -49.807002) (xy 259.189103 -49.753681) (xy 259.224226 -49.705249)
			(xy 259.266481 -49.662897) (xy 259.290312 -49.644808) (xy 259.297307 -49.639347) (xy 259.307231 -49.624648)
			(xy 259.311499 -49.607433) (xy 259.310886 -49.59858) (xy 259.301996 -49.51095) (xy 259.300749 -49.502242)
			(xy 259.293152 -49.486389) (xy 259.280618 -49.474062) (xy 259.272786 -49.470056) (xy 259.272278 -49.470056)
			(xy 259.240653 -49.455123) (xy 259.180901 -49.418773) (xy 259.125911 -49.375556) (xy 259.100828 -49.351184)
			(xy 258.07797 -48.328326) (xy 258.055096 -48.304738) (xy 258.014128 -48.253367) (xy 257.97917 -48.197731)
			(xy 257.950661 -48.138532) (xy 257.928959 -48.076512) (xy 257.914338 -48.012453) (xy 257.906981 -47.947159)
			(xy 257.90652 -47.914306) (xy 257.90652 -47.785274) (xy 257.906122 -47.775776) (xy 257.899277 -47.758061)
			(xy 257.886433 -47.744073) (xy 257.878072 -47.739554) (xy 257.79603 -47.699422) (xy 257.787316 -47.695618)
			(xy 257.76838 -47.694059) (xy 257.750171 -47.699482) (xy 257.742436 -47.70501) (xy 257.722252 -47.720138)
			(xy 257.67869 -47.745568) (xy 257.632159 -47.765041) (xy 257.583469 -47.778216) (xy 257.533468 -47.784865)
			(xy 257.508248 -47.785274) (xy 257.480995 -47.7848) (xy 257.427042 -47.777049) (xy 257.374743 -47.761697)
			(xy 257.325161 -47.739058) (xy 257.279305 -47.709591) (xy 257.238111 -47.673899) (xy 257.202417 -47.632706)
			(xy 257.172949 -47.586852) (xy 257.150308 -47.53727) (xy 257.134954 -47.484971) (xy 257.127201 -47.431019)
			(xy 257.12674 -47.403766) (xy 257.127208 -47.377338) (xy 257.134518 -47.324991) (xy 257.148993 -47.274155)
			(xy 257.170354 -47.225809) (xy 257.18389 -47.203106) (xy 257.184144 -47.202852) (xy 257.189479 -47.192833)
			(xy 257.191738 -47.170284) (xy 257.188462 -47.159418) (xy 257.1623 -47.084742) (xy 257.157937 -47.074216)
			(xy 257.141834 -47.058131) (xy 257.131312 -47.053754) (xy 257.131058 -47.053754) (xy 257.106551 -47.04468)
			(xy 257.060098 -47.020739) (xy 257.017346 -46.990683) (xy 256.979094 -46.955077) (xy 256.946057 -46.914584)
			(xy 256.918854 -46.869964) (xy 256.897991 -46.822049) (xy 256.883861 -46.771736) (xy 256.876727 -46.719966)
			(xy 256.876296 -46.693836) (xy 256.876782 -46.666585) (xy 256.884538 -46.612637) (xy 256.899893 -46.560342)
			(xy 256.922535 -46.510765) (xy 256.952001 -46.464915) (xy 256.987692 -46.423724) (xy 257.028883 -46.388033)
			(xy 257.074733 -46.358567) (xy 257.12431 -46.335925) (xy 257.176605 -46.32057) (xy 257.230553 -46.312814)
			(xy 257.285055 -46.312814) (xy 257.339003 -46.32057) (xy 257.391298 -46.335925) (xy 257.440875 -46.358567)
			(xy 257.486725 -46.388033) (xy 257.527916 -46.423724) (xy 257.563607 -46.464915) (xy 257.593073 -46.510765)
			(xy 257.615715 -46.560342) (xy 257.63107 -46.612637) (xy 257.638826 -46.666585) (xy 257.639312 -46.693836)
			(xy 257.638838 -46.720263) (xy 257.631528 -46.772611) (xy 257.617056 -46.823446) (xy 257.595696 -46.871793)
			(xy 257.582162 -46.894496) (xy 257.581908 -46.89475) (xy 257.576571 -46.904768) (xy 257.574316 -46.927318)
			(xy 257.57759 -46.938184) (xy 257.603752 -47.01286) (xy 257.608136 -47.023375) (xy 257.624225 -47.039464)
			(xy 257.63474 -47.043848) (xy 257.634994 -47.043848) (xy 257.663792 -47.054657) (xy 257.717775 -47.084136)
			(xy 257.742436 -47.102522) (xy 257.750168 -47.108062) (xy 257.76838 -47.113504) (xy 257.787323 -47.111938)
			(xy 257.79603 -47.10811) (xy 257.878072 -47.067978) (xy 257.886427 -47.063456) (xy 257.899244 -47.049447)
			(xy 257.90613 -47.031751) (xy 257.90652 -47.022258) (xy 257.90652 -44.493688) (xy 257.906022 -44.483682)
			(xy 257.898362 -44.465194) (xy 257.884213 -44.451042) (xy 257.865726 -44.44338) (xy 257.85572 -44.442888)
			(xy 257.301746 -44.442888) (xy 257.267643 -44.442394) (xy 257.199899 -44.434481) (xy 257.133531 -44.418756)
			(xy 257.069437 -44.395432) (xy 257.008485 -44.364825) (xy 256.951498 -44.327348) (xy 256.899248 -44.283509)
			(xy 256.852441 -44.2339) (xy 256.81171 -44.179192) (xy 256.777605 -44.120126) (xy 256.750589 -44.057499)
			(xy 256.731027 -43.992159) (xy 256.719182 -43.92499) (xy 256.715216 -43.8569) (xy 253.156597 -43.8569)
			(xy 253.151835 -43.872729) (xy 253.128163 -43.923226) (xy 253.09739 -43.969739) (xy 253.060173 -44.011276)
			(xy 253.017305 -44.046951) (xy 252.969699 -44.076005) (xy 252.91837 -44.097817) (xy 252.864413 -44.111923)
			(xy 252.808976 -44.118023) (xy 252.753242 -44.115986) (xy 252.698399 -44.105856) (xy 252.645615 -44.087849)
			(xy 252.596015 -44.062348) (xy 252.550657 -44.029897) (xy 252.510508 -43.991188) (xy 252.476422 -43.947045)
			(xy 252.449126 -43.89841) (xy 252.429203 -43.846319) (xy 252.417077 -43.791882) (xy 252.413006 -43.73626)
			(xy 245.596156 -43.73626) (xy 245.596156 -45.114464) (xy 252.265432 -45.114464) (xy 252.269503 -45.058842)
			(xy 252.281629 -45.004405) (xy 252.301552 -44.952314) (xy 252.328848 -44.903679) (xy 252.362934 -44.859536)
			(xy 252.403083 -44.820827) (xy 252.448441 -44.788376) (xy 252.498041 -44.762875) (xy 252.550825 -44.744868)
			(xy 252.605668 -44.734738) (xy 252.661402 -44.732701) (xy 252.716839 -44.738801) (xy 252.770796 -44.752907)
			(xy 252.822125 -44.774719) (xy 252.869731 -44.803773) (xy 252.912599 -44.839448) (xy 252.949816 -44.880985)
			(xy 252.980589 -44.927498) (xy 253.004261 -44.977995) (xy 253.020329 -45.031402) (xy 253.028449 -45.086578)
			(xy 253.028958 -45.114464) (xy 253.028449 -45.14235) (xy 253.020329 -45.197526) (xy 253.004261 -45.250933)
			(xy 252.980589 -45.30143) (xy 252.949816 -45.347943) (xy 252.944174 -45.35424) (xy 256.903726 -45.35424)
			(xy 256.907797 -45.298618) (xy 256.919923 -45.244181) (xy 256.939846 -45.19209) (xy 256.967142 -45.143455)
			(xy 257.001228 -45.099312) (xy 257.041377 -45.060603) (xy 257.086735 -45.028152) (xy 257.136335 -45.002651)
			(xy 257.189119 -44.984644) (xy 257.243962 -44.974514) (xy 257.299696 -44.972477) (xy 257.355133 -44.978577)
			(xy 257.40909 -44.992683) (xy 257.460419 -45.014495) (xy 257.508025 -45.043549) (xy 257.550893 -45.079224)
			(xy 257.58811 -45.120761) (xy 257.618883 -45.167274) (xy 257.642555 -45.217771) (xy 257.658623 -45.271178)
			(xy 257.666743 -45.326354) (xy 257.667252 -45.35424) (xy 257.666743 -45.382126) (xy 257.658623 -45.437302)
			(xy 257.642555 -45.490709) (xy 257.618883 -45.541206) (xy 257.58811 -45.587719) (xy 257.550893 -45.629256)
			(xy 257.508025 -45.664931) (xy 257.460419 -45.693985) (xy 257.40909 -45.715797) (xy 257.355133 -45.729903)
			(xy 257.299696 -45.736003) (xy 257.243962 -45.733966) (xy 257.189119 -45.723836) (xy 257.136335 -45.705829)
			(xy 257.086735 -45.680328) (xy 257.041377 -45.647877) (xy 257.001228 -45.609168) (xy 256.967142 -45.565025)
			(xy 256.939846 -45.51639) (xy 256.919923 -45.464299) (xy 256.907797 -45.409862) (xy 256.903726 -45.35424)
			(xy 252.944174 -45.35424) (xy 252.912599 -45.38948) (xy 252.869731 -45.425155) (xy 252.822125 -45.454209)
			(xy 252.770796 -45.476021) (xy 252.716839 -45.490127) (xy 252.661402 -45.496227) (xy 252.605668 -45.49419)
			(xy 252.550825 -45.48406) (xy 252.498041 -45.466053) (xy 252.448441 -45.440552) (xy 252.403083 -45.408101)
			(xy 252.362934 -45.369392) (xy 252.328848 -45.325249) (xy 252.301552 -45.276614) (xy 252.281629 -45.224523)
			(xy 252.269503 -45.170086) (xy 252.265432 -45.114464) (xy 245.596156 -45.114464) (xy 245.596156 -46.082204)
			(xy 250.252484 -46.082204) (xy 250.252981 -46.054953) (xy 250.260737 -46.001006) (xy 250.276091 -45.948712)
			(xy 250.298732 -45.899136) (xy 250.328197 -45.853286) (xy 250.363887 -45.812095) (xy 250.405076 -45.776404)
			(xy 250.450925 -45.746937) (xy 250.500501 -45.724296) (xy 250.552795 -45.70894) (xy 250.606741 -45.701182)
			(xy 250.633992 -45.700696) (xy 250.660894 -45.701164) (xy 250.714164 -45.708735) (xy 250.765842 -45.723713)
			(xy 250.814904 -45.745802) (xy 250.860376 -45.774564) (xy 250.901358 -45.809428) (xy 250.937036 -45.849703)
			(xy 250.952254 -45.871892) (xy 250.959366 -45.882814) (xy 250.982226 -45.894752) (xy 251.094494 -45.89272)
			(xy 251.116846 -45.879766) (xy 251.123704 -45.86859) (xy 251.138636 -45.844996) (xy 251.174314 -45.802044)
			(xy 251.21587 -45.764751) (xy 251.262418 -45.733912) (xy 251.312964 -45.710188) (xy 251.366428 -45.694083)
			(xy 251.421668 -45.685943) (xy 251.449586 -45.685456) (xy 251.476579 -45.685925) (xy 251.530027 -45.693529)
			(xy 251.58187 -45.708588) (xy 251.631075 -45.7308) (xy 251.676659 -45.759723) (xy 251.69749 -45.776896)
			(xy 251.705618 -45.784008) (xy 251.726192 -45.790104) (xy 251.811536 -45.779182) (xy 251.822087 -45.777435)
			(xy 251.840367 -45.766361) (xy 251.846842 -45.757846) (xy 251.862176 -45.736601) (xy 251.897766 -45.698148)
			(xy 251.938287 -45.664931) (xy 251.982973 -45.637574) (xy 252.030984 -45.616593) (xy 252.081416 -45.602383)
			(xy 252.133318 -45.595211) (xy 252.159516 -45.594778) (xy 252.186765 -45.595293) (xy 252.240709 -45.603051)
			(xy 252.293 -45.618407) (xy 252.342574 -45.641049) (xy 252.38842 -45.670514) (xy 252.429607 -45.706204)
			(xy 252.465295 -45.747393) (xy 252.494759 -45.79324) (xy 252.517398 -45.842815) (xy 252.532752 -45.895106)
			(xy 252.540508 -45.949051) (xy 252.540508 -46.003549) (xy 252.532752 -46.057494) (xy 252.517398 -46.109785)
			(xy 252.494759 -46.15936) (xy 252.465295 -46.205207) (xy 252.429607 -46.246396) (xy 252.38842 -46.282086)
			(xy 252.342574 -46.311551) (xy 252.293 -46.334193) (xy 252.240709 -46.349549) (xy 252.186765 -46.357307)
			(xy 252.159516 -46.357794) (xy 252.132524 -46.357312) (xy 252.079077 -46.349709) (xy 252.027234 -46.334653)
			(xy 251.978029 -46.312444) (xy 251.932444 -46.283525) (xy 251.911612 -46.266354) (xy 251.903484 -46.259242)
			(xy 251.88291 -46.253146) (xy 251.797566 -46.264068) (xy 251.78702 -46.265833) (xy 251.768739 -46.276896)
			(xy 251.76226 -46.285404) (xy 251.744649 -46.309706) (xy 251.703052 -46.352965) (xy 251.679456 -46.37151)
			(xy 251.671582 -46.377352) (xy 251.661168 -46.394878) (xy 251.64796 -46.485302) (xy 251.652786 -46.504606)
			(xy 251.658628 -46.51248) (xy 251.658628 -46.512734) (xy 251.676125 -46.537482) (xy 251.703931 -46.591333)
			(xy 251.722869 -46.648904) (xy 251.732462 -46.708745) (xy 251.73305 -46.739048) (xy 251.732567 -46.766299)
			(xy 251.724805 -46.820244) (xy 251.709446 -46.872536) (xy 251.686802 -46.922111) (xy 251.657335 -46.967959)
			(xy 251.621643 -47.009148) (xy 251.580454 -47.044838) (xy 251.534606 -47.074305) (xy 251.485031 -47.096948)
			(xy 251.432738 -47.112306) (xy 251.378793 -47.120067) (xy 251.351542 -47.120556) (xy 251.325508 -47.120134)
			(xy 251.273924 -47.11304) (xy 251.223782 -47.099005) (xy 251.176011 -47.078288) (xy 251.131498 -47.051275)
			(xy 251.111004 -47.035212) (xy 251.103253 -47.029461) (xy 251.084838 -47.023726) (xy 251.07519 -47.024036)
			(xy 250.995434 -47.030386) (xy 250.977654 -47.039022) (xy 250.971304 -47.046388) (xy 250.953144 -47.066054)
			(xy 250.912232 -47.100574) (xy 250.866898 -47.129041) (xy 250.818033 -47.150895) (xy 250.766593 -47.165708)
			(xy 250.713589 -47.17319) (xy 250.686824 -47.173642) (xy 250.659575 -47.1731) (xy 250.605631 -47.165347)
			(xy 250.553339 -47.149997) (xy 250.503765 -47.127361) (xy 250.457916 -47.0979) (xy 250.416726 -47.062215)
			(xy 250.381034 -47.021031) (xy 250.351567 -46.975186) (xy 250.328923 -46.925615) (xy 250.313565 -46.873326)
			(xy 250.305805 -46.819383) (xy 250.305316 -46.792134) (xy 250.305836 -46.76336) (xy 250.314488 -46.706465)
			(xy 250.331585 -46.651515) (xy 250.356739 -46.599754) (xy 250.389381 -46.552359) (xy 250.408694 -46.531022)
			(xy 250.41606 -46.523148) (xy 250.423172 -46.503336) (xy 250.415806 -46.40707) (xy 250.4059 -46.388274)
			(xy 250.397518 -46.38167) (xy 250.375333 -46.363446) (xy 250.336123 -46.32151) (xy 250.303638 -46.274174)
			(xy 250.278609 -46.222506) (xy 250.261603 -46.167672) (xy 250.253002 -46.110909) (xy 250.252484 -46.082204)
			(xy 245.596156 -46.082204) (xy 245.596156 -48.30699) (xy 256.753866 -48.30699) (xy 256.757937 -48.251368)
			(xy 256.770063 -48.196931) (xy 256.789986 -48.14484) (xy 256.817282 -48.096205) (xy 256.851368 -48.052062)
			(xy 256.891517 -48.013353) (xy 256.936875 -47.980902) (xy 256.986475 -47.955401) (xy 257.039259 -47.937394)
			(xy 257.094102 -47.927264) (xy 257.149836 -47.925227) (xy 257.205273 -47.931327) (xy 257.25923 -47.945433)
			(xy 257.310559 -47.967245) (xy 257.358165 -47.996299) (xy 257.401033 -48.031974) (xy 257.43825 -48.073511)
			(xy 257.469023 -48.120024) (xy 257.492695 -48.170521) (xy 257.508763 -48.223928) (xy 257.516883 -48.279104)
			(xy 257.517392 -48.30699) (xy 257.516883 -48.334876) (xy 257.508763 -48.390052) (xy 257.492695 -48.443459)
			(xy 257.469023 -48.493956) (xy 257.43825 -48.540469) (xy 257.401033 -48.582006) (xy 257.358165 -48.617681)
			(xy 257.310559 -48.646735) (xy 257.25923 -48.668547) (xy 257.205273 -48.682653) (xy 257.149836 -48.688753)
			(xy 257.094102 -48.686716) (xy 257.039259 -48.676586) (xy 256.986475 -48.658579) (xy 256.936875 -48.633078)
			(xy 256.891517 -48.600627) (xy 256.851368 -48.561918) (xy 256.817282 -48.517775) (xy 256.789986 -48.46914)
			(xy 256.770063 -48.417049) (xy 256.757937 -48.362612) (xy 256.753866 -48.30699) (xy 245.596156 -48.30699)
			(xy 245.596156 -48.753014) (xy 253.3683 -48.753014) (xy 253.372371 -48.697392) (xy 253.384497 -48.642955)
			(xy 253.40442 -48.590864) (xy 253.431716 -48.542229) (xy 253.465802 -48.498086) (xy 253.505951 -48.459377)
			(xy 253.551309 -48.426926) (xy 253.600909 -48.401425) (xy 253.653693 -48.383418) (xy 253.708536 -48.373288)
			(xy 253.76427 -48.371251) (xy 253.819707 -48.377351) (xy 253.873664 -48.391457) (xy 253.924993 -48.413269)
			(xy 253.972599 -48.442323) (xy 254.015467 -48.477998) (xy 254.052684 -48.519535) (xy 254.083457 -48.566048)
			(xy 254.107129 -48.616545) (xy 254.123197 -48.669952) (xy 254.131317 -48.725128) (xy 254.131826 -48.753014)
			(xy 254.131317 -48.7809) (xy 254.123197 -48.836076) (xy 254.120753 -48.8442) (xy 254.387348 -48.8442)
			(xy 254.391419 -48.788578) (xy 254.403545 -48.734141) (xy 254.423468 -48.68205) (xy 254.450764 -48.633415)
			(xy 254.48485 -48.589272) (xy 254.524999 -48.550563) (xy 254.570357 -48.518112) (xy 254.619957 -48.492611)
			(xy 254.672741 -48.474604) (xy 254.727584 -48.464474) (xy 254.783318 -48.462437) (xy 254.838755 -48.468537)
			(xy 254.892712 -48.482643) (xy 254.944041 -48.504455) (xy 254.991647 -48.533509) (xy 255.034515 -48.569184)
			(xy 255.071732 -48.610721) (xy 255.102505 -48.657234) (xy 255.126177 -48.707731) (xy 255.142245 -48.761138)
			(xy 255.150365 -48.816314) (xy 255.150874 -48.8442) (xy 255.150365 -48.872086) (xy 255.147367 -48.89246)
			(xy 255.414016 -48.89246) (xy 255.418087 -48.836838) (xy 255.430213 -48.782401) (xy 255.450136 -48.73031)
			(xy 255.477432 -48.681675) (xy 255.511518 -48.637532) (xy 255.551667 -48.598823) (xy 255.597025 -48.566372)
			(xy 255.646625 -48.540871) (xy 255.699409 -48.522864) (xy 255.754252 -48.512734) (xy 255.809986 -48.510697)
			(xy 255.865423 -48.516797) (xy 255.91938 -48.530903) (xy 255.970709 -48.552715) (xy 256.018315 -48.581769)
			(xy 256.061183 -48.617444) (xy 256.0984 -48.658981) (xy 256.129173 -48.705494) (xy 256.152845 -48.755991)
			(xy 256.168913 -48.809398) (xy 256.177033 -48.864574) (xy 256.177542 -48.89246) (xy 256.177033 -48.920346)
			(xy 256.168913 -48.975522) (xy 256.152845 -49.028929) (xy 256.129173 -49.079426) (xy 256.0984 -49.125939)
			(xy 256.061183 -49.167476) (xy 256.018315 -49.203151) (xy 255.970709 -49.232205) (xy 255.91938 -49.254017)
			(xy 255.865423 -49.268123) (xy 255.809986 -49.274223) (xy 255.754252 -49.272186) (xy 255.699409 -49.262056)
			(xy 255.646625 -49.244049) (xy 255.597025 -49.218548) (xy 255.551667 -49.186097) (xy 255.511518 -49.147388)
			(xy 255.477432 -49.103245) (xy 255.450136 -49.05461) (xy 255.430213 -49.002519) (xy 255.418087 -48.948082)
			(xy 255.414016 -48.89246) (xy 255.147367 -48.89246) (xy 255.142245 -48.927262) (xy 255.126177 -48.980669)
			(xy 255.102505 -49.031166) (xy 255.071732 -49.077679) (xy 255.034515 -49.119216) (xy 254.991647 -49.154891)
			(xy 254.944041 -49.183945) (xy 254.892712 -49.205757) (xy 254.838755 -49.219863) (xy 254.783318 -49.225963)
			(xy 254.727584 -49.223926) (xy 254.672741 -49.213796) (xy 254.619957 -49.195789) (xy 254.570357 -49.170288)
			(xy 254.524999 -49.137837) (xy 254.48485 -49.099128) (xy 254.450764 -49.054985) (xy 254.423468 -49.00635)
			(xy 254.403545 -48.954259) (xy 254.391419 -48.899822) (xy 254.387348 -48.8442) (xy 254.120753 -48.8442)
			(xy 254.107129 -48.889483) (xy 254.083457 -48.93998) (xy 254.052684 -48.986493) (xy 254.015467 -49.02803)
			(xy 253.972599 -49.063705) (xy 253.924993 -49.092759) (xy 253.873664 -49.114571) (xy 253.819707 -49.128677)
			(xy 253.76427 -49.134777) (xy 253.708536 -49.13274) (xy 253.653693 -49.12261) (xy 253.600909 -49.104603)
			(xy 253.551309 -49.079102) (xy 253.505951 -49.046651) (xy 253.465802 -49.007942) (xy 253.431716 -48.963799)
			(xy 253.40442 -48.915164) (xy 253.384497 -48.863073) (xy 253.372371 -48.808636) (xy 253.3683 -48.753014)
			(xy 245.596156 -48.753014) (xy 245.596156 -50.721051) (xy 256.232883 -50.721051) (xy 256.232883 -50.666549)
			(xy 256.24064 -50.6126) (xy 256.255996 -50.560305) (xy 256.278638 -50.510728) (xy 256.308105 -50.464877)
			(xy 256.343797 -50.423687) (xy 256.384989 -50.387996) (xy 256.43084 -50.358531) (xy 256.480418 -50.335891)
			(xy 256.532714 -50.320537) (xy 256.586662 -50.312782) (xy 256.613914 -50.31232) (xy 256.640253 -50.312759)
			(xy 256.692432 -50.319983) (xy 256.74312 -50.33432) (xy 256.791353 -50.355496) (xy 256.836212 -50.383109)
			(xy 256.876844 -50.416633) (xy 256.912476 -50.45543) (xy 256.942429 -50.498762) (xy 256.966133 -50.545804)
			(xy 256.983138 -50.595661) (xy 256.988564 -50.621438) (xy 256.991588 -50.634981) (xy 257.003979 -50.6598)
			(xy 257.022604 -50.680357) (xy 257.046084 -50.695129) (xy 257.072678 -50.703021) (xy 257.100415 -50.703448)
			(xy 257.127239 -50.696378) (xy 257.13944 -50.689764) (xy 257.161399 -50.677474) (xy 257.207836 -50.658087)
			(xy 257.256419 -50.644971) (xy 257.306303 -50.638353) (xy 257.331464 -50.637948) (xy 257.358715 -50.638497)
			(xy 257.412664 -50.646249) (xy 257.46496 -50.6616) (xy 257.514539 -50.684238) (xy 257.560391 -50.713701)
			(xy 257.601584 -50.749391) (xy 257.637277 -50.79058) (xy 257.666745 -50.836429) (xy 257.689388 -50.886006)
			(xy 257.704744 -50.938301) (xy 257.712501 -50.992249) (xy 257.712501 -51.046751) (xy 257.704744 -51.100699)
			(xy 257.689388 -51.152994) (xy 257.666745 -51.202571) (xy 257.640123 -51.243992) (xy 265.332972 -51.243992)
			(xy 265.333416 -51.216621) (xy 265.341236 -51.16244) (xy 265.35673 -51.109936) (xy 265.379577 -51.060189)
			(xy 265.409308 -51.014224) (xy 265.426952 -50.993294) (xy 265.427206 -50.99304) (xy 265.432783 -50.985947)
			(xy 265.439035 -50.969035) (xy 265.439398 -50.96002) (xy 265.439398 -50.892964) (xy 265.439058 -50.883945)
			(xy 265.432799 -50.867029) (xy 265.427206 -50.859944) (xy 265.426952 -50.859944) (xy 265.426952 -50.85969)
			(xy 265.409303 -50.838766) (xy 265.379591 -50.792792) (xy 265.356756 -50.743042) (xy 265.341267 -50.69054)
			(xy 265.333443 -50.636362) (xy 265.332972 -50.608992) (xy 265.33347 -50.581741) (xy 265.341227 -50.527795)
			(xy 265.356582 -50.475502) (xy 265.379223 -50.425926) (xy 265.408688 -50.380077) (xy 265.444378 -50.338887)
			(xy 265.485567 -50.303196) (xy 265.531415 -50.273729) (xy 265.580991 -50.251087) (xy 265.633283 -50.23573)
			(xy 265.687229 -50.227971) (xy 265.71448 -50.227484) (xy 265.743398 -50.227985) (xy 265.800571 -50.236713)
			(xy 265.855772 -50.253972) (xy 265.907734 -50.279367) (xy 265.955268 -50.312315) (xy 265.997282 -50.352062)
			(xy 266.01547 -50.37455) (xy 266.023091 -50.383342) (xy 266.043982 -50.393532) (xy 266.055602 -50.394108)
			(xy 266.135358 -50.394108) (xy 266.146992 -50.393585) (xy 266.167901 -50.383384) (xy 266.17549 -50.37455)
			(xy 266.193674 -50.352061) (xy 266.235697 -50.312328) (xy 266.283234 -50.279391) (xy 266.335196 -50.254005)
			(xy 266.390394 -50.236749) (xy 266.447564 -50.22802) (xy 266.47648 -50.227484) (xy 266.503732 -50.227974)
			(xy 266.557682 -50.235728) (xy 266.609978 -50.251081) (xy 266.659558 -50.273721) (xy 266.705411 -50.303186)
			(xy 266.746603 -50.338877) (xy 266.782297 -50.380067) (xy 266.811766 -50.425917) (xy 266.834409 -50.475495)
			(xy 266.849766 -50.527791) (xy 266.857524 -50.58174) (xy 266.857988 -50.608992) (xy 266.857519 -50.635306)
			(xy 266.850285 -50.687435) (xy 266.835967 -50.738077) (xy 266.814834 -50.786276) (xy 266.787288 -50.83112)
			(xy 266.75385 -50.87176) (xy 266.734798 -50.889916) (xy 266.727387 -50.89743) (xy 266.718868 -50.916716)
			(xy 266.718288 -50.927254) (xy 266.718288 -51.00193) (xy 266.718845 -51.012476) (xy 266.727361 -51.031772)
			(xy 266.734798 -51.039268) (xy 266.753879 -51.057398) (xy 266.787334 -51.098033) (xy 266.81489 -51.142879)
			(xy 266.836024 -51.191085) (xy 266.850335 -51.241737) (xy 266.857553 -51.293874) (xy 266.857988 -51.320192)
			(xy 266.857537 -51.347446) (xy 266.849781 -51.401398) (xy 266.834425 -51.453697) (xy 266.811782 -51.503279)
			(xy 266.782313 -51.549133) (xy 266.746618 -51.590326) (xy 266.705423 -51.62602) (xy 266.659568 -51.655487)
			(xy 266.609986 -51.678129) (xy 266.557686 -51.693483) (xy 266.503734 -51.701238) (xy 266.47648 -51.7017)
			(xy 266.448814 -51.701203) (xy 266.394064 -51.693201) (xy 266.341042 -51.677382) (xy 266.290858 -51.654076)
			(xy 266.244563 -51.623773) (xy 266.203125 -51.587105) (xy 266.167413 -51.544842) (xy 266.152376 -51.521614)
			(xy 266.14576 -51.51192) (xy 266.125883 -51.499486) (xy 266.114276 -51.497738) (xy 266.034266 -51.489864)
			(xy 266.022627 -51.489215) (xy 266.000789 -51.497307) (xy 265.992356 -51.505358) (xy 265.992102 -51.505612)
			(xy 265.974005 -51.524177) (xy 265.933676 -51.556756) (xy 265.889305 -51.583571) (xy 265.84171 -51.604127)
			(xy 265.791769 -51.618044) (xy 265.740402 -51.625066) (xy 265.71448 -51.6255) (xy 265.687228 -51.625041)
			(xy 265.633279 -51.617281) (xy 265.580983 -51.601923) (xy 265.531405 -51.579279) (xy 265.485555 -51.54981)
			(xy 265.444364 -51.514116) (xy 265.408673 -51.472923) (xy 265.379207 -51.42707) (xy 265.356567 -51.377491)
			(xy 265.341213 -51.325194) (xy 265.333457 -51.271244) (xy 265.332972 -51.243992) (xy 257.640123 -51.243992)
			(xy 257.637277 -51.24842) (xy 257.601584 -51.289609) (xy 257.560391 -51.325299) (xy 257.514539 -51.354762)
			(xy 257.46496 -51.3774) (xy 257.412664 -51.392751) (xy 257.358715 -51.400503) (xy 257.331464 -51.400964)
			(xy 257.305128 -51.400478) (xy 257.252954 -51.393252) (xy 257.20227 -51.378917) (xy 257.154042 -51.357743)
			(xy 257.109185 -51.330135) (xy 257.068554 -51.296617) (xy 257.032922 -51.257827) (xy 257.002966 -51.214503)
			(xy 256.979257 -51.167469) (xy 256.962245 -51.11762) (xy 256.956814 -51.091846) (xy 256.953689 -51.078332)
			(xy 256.941309 -51.053527) (xy 256.922699 -51.032979) (xy 256.899239 -51.018209) (xy 256.872666 -51.010311)
			(xy 256.844947 -51.00987) (xy 256.818135 -51.016918) (xy 256.805938 -51.02352) (xy 256.783983 -51.035817)
			(xy 256.737544 -51.055203) (xy 256.688961 -51.068317) (xy 256.639075 -51.074933) (xy 256.613914 -51.075336)
			(xy 256.586662 -51.074818) (xy 256.532714 -51.067063) (xy 256.480418 -51.051709) (xy 256.43084 -51.029069)
			(xy 256.384989 -50.999604) (xy 256.343797 -50.963913) (xy 256.308105 -50.922723) (xy 256.278638 -50.876872)
			(xy 256.255996 -50.827295) (xy 256.24064 -50.775) (xy 256.232883 -50.721051) (xy 245.596156 -50.721051)
			(xy 245.596156 -52.035456) (xy 259.141212 -52.035456) (xy 259.145283 -51.979834) (xy 259.157409 -51.925397)
			(xy 259.177332 -51.873306) (xy 259.204628 -51.824671) (xy 259.238714 -51.780528) (xy 259.278863 -51.741819)
			(xy 259.324221 -51.709368) (xy 259.373821 -51.683867) (xy 259.426605 -51.66586) (xy 259.481448 -51.65573)
			(xy 259.537182 -51.653693) (xy 259.592619 -51.659793) (xy 259.646576 -51.673899) (xy 259.697905 -51.695711)
			(xy 259.745511 -51.724765) (xy 259.788379 -51.76044) (xy 259.825596 -51.801977) (xy 259.856369 -51.84849)
			(xy 259.880041 -51.898987) (xy 259.896109 -51.952394) (xy 259.904229 -52.00757) (xy 259.904738 -52.035456)
			(xy 259.904229 -52.063342) (xy 259.896109 -52.118518) (xy 259.880041 -52.171925) (xy 259.856369 -52.222422)
			(xy 259.825596 -52.268935) (xy 259.788379 -52.310472) (xy 259.745511 -52.346147) (xy 259.697905 -52.375201)
			(xy 259.646576 -52.397013) (xy 259.592619 -52.411119) (xy 259.537182 -52.417219) (xy 259.481448 -52.415182)
			(xy 259.426605 -52.405052) (xy 259.373821 -52.387045) (xy 259.324221 -52.361544) (xy 259.278863 -52.329093)
			(xy 259.238714 -52.290384) (xy 259.204628 -52.246241) (xy 259.177332 -52.197606) (xy 259.157409 -52.145515)
			(xy 259.145283 -52.091078) (xy 259.141212 -52.035456) (xy 245.596156 -52.035456) (xy 245.596156 -54.731412)
			(xy 245.720616 -54.731412) (xy 245.721085 -54.704042) (xy 245.728902 -54.649863) (xy 245.74439 -54.597359)
			(xy 245.767231 -54.547613) (xy 245.796955 -54.501646) (xy 245.814596 -54.480714) (xy 245.81485 -54.48046)
			(xy 245.820424 -54.473365) (xy 245.826677 -54.456454) (xy 245.827042 -54.44744) (xy 245.827042 -54.380384)
			(xy 245.826705 -54.371365) (xy 245.820445 -54.354447) (xy 245.81485 -54.347364) (xy 245.814596 -54.347364)
			(xy 245.814596 -54.34711) (xy 245.796968 -54.326167) (xy 245.767245 -54.2802) (xy 245.744401 -54.230456)
			(xy 245.728905 -54.177955) (xy 245.721076 -54.123779) (xy 245.721075 -54.069039) (xy 245.728902 -54.014862)
			(xy 245.744395 -53.962361) (xy 245.767237 -53.912616) (xy 245.796957 -53.866647) (xy 245.814596 -53.845714)
			(xy 245.81485 -53.84546) (xy 245.820424 -53.838365) (xy 245.826677 -53.821454) (xy 245.827042 -53.81244)
			(xy 245.827042 -53.745384) (xy 245.826705 -53.736365) (xy 245.820445 -53.719447) (xy 245.81485 -53.712364)
			(xy 245.814596 -53.712364) (xy 245.814596 -53.71211) (xy 245.796968 -53.691167) (xy 245.767245 -53.6452)
			(xy 245.744401 -53.595456) (xy 245.728905 -53.542955) (xy 245.721076 -53.488779) (xy 245.721075 -53.434039)
			(xy 245.728902 -53.379862) (xy 245.744395 -53.327361) (xy 245.767237 -53.277616) (xy 245.796957 -53.231647)
			(xy 245.814596 -53.210714) (xy 245.81485 -53.21046) (xy 245.820424 -53.203365) (xy 245.826677 -53.186454)
			(xy 245.827042 -53.17744) (xy 245.827042 -53.110384) (xy 245.826705 -53.101365) (xy 245.820445 -53.084447)
			(xy 245.81485 -53.077364) (xy 245.814596 -53.077364) (xy 245.814596 -53.07711) (xy 245.796948 -53.056186)
			(xy 245.767237 -53.010211) (xy 245.744403 -52.960461) (xy 245.728914 -52.907959) (xy 245.721089 -52.853782)
			(xy 245.720616 -52.826412) (xy 245.721102 -52.799161) (xy 245.728858 -52.745213) (xy 245.744213 -52.692918)
			(xy 245.766855 -52.643341) (xy 245.796321 -52.597491) (xy 245.832012 -52.5563) (xy 245.873203 -52.520609)
			(xy 245.919053 -52.491143) (xy 245.96863 -52.468501) (xy 246.020925 -52.453146) (xy 246.074873 -52.44539)
			(xy 246.129375 -52.44539) (xy 246.183323 -52.453146) (xy 246.235618 -52.468501) (xy 246.285195 -52.491143)
			(xy 246.331045 -52.520609) (xy 246.372236 -52.5563) (xy 246.407927 -52.597491) (xy 246.437393 -52.643341)
			(xy 246.460035 -52.692918) (xy 246.47539 -52.745213) (xy 246.483146 -52.799161) (xy 246.483632 -52.826412)
			(xy 246.48319 -52.853783) (xy 246.475369 -52.907964) (xy 246.459875 -52.960468) (xy 246.437027 -53.010215)
			(xy 246.407297 -53.05618) (xy 246.389652 -53.07711) (xy 246.389398 -53.077364) (xy 246.38382 -53.084457)
			(xy 246.377568 -53.101369) (xy 246.377206 -53.110384) (xy 246.377206 -53.17744) (xy 246.377543 -53.186459)
			(xy 246.383804 -53.203376) (xy 246.389398 -53.21046) (xy 246.389652 -53.21046) (xy 246.389652 -53.210714)
			(xy 246.407305 -53.231637) (xy 246.437031 -53.277606) (xy 246.459877 -53.327354) (xy 246.475373 -53.379857)
			(xy 246.483201 -53.434038) (xy 246.4832 -53.48878) (xy 246.47537 -53.54296) (xy 246.459871 -53.595463)
			(xy 246.437023 -53.64521) (xy 246.407294 -53.691178) (xy 246.389652 -53.71211) (xy 246.389398 -53.712364)
			(xy 246.38382 -53.719457) (xy 246.377568 -53.736369) (xy 246.377206 -53.745384) (xy 246.377206 -53.81244)
			(xy 246.377543 -53.821459) (xy 246.383804 -53.838376) (xy 246.389398 -53.84546) (xy 246.389652 -53.84546)
			(xy 246.389652 -53.845714) (xy 246.407305 -53.866637) (xy 246.437031 -53.912606) (xy 246.459877 -53.962354)
			(xy 246.475373 -54.014857) (xy 246.483201 -54.069038) (xy 246.4832 -54.12378) (xy 246.47537 -54.17796)
			(xy 246.459871 -54.230463) (xy 246.437023 -54.28021) (xy 246.407294 -54.326178) (xy 246.389652 -54.34711)
			(xy 246.389398 -54.347364) (xy 246.38382 -54.354457) (xy 246.377568 -54.371369) (xy 246.377206 -54.380384)
			(xy 246.377206 -54.44744) (xy 246.377543 -54.456459) (xy 246.383804 -54.473376) (xy 246.389398 -54.48046)
			(xy 246.389652 -54.48046) (xy 246.389652 -54.480714) (xy 246.407257 -54.501674) (xy 246.436975 -54.547638)
			(xy 246.459819 -54.597379) (xy 246.475318 -54.649873) (xy 246.483154 -54.704045) (xy 246.483632 -54.731412)
			(xy 246.483146 -54.758663) (xy 246.478482 -54.791102) (xy 248.37644 -54.791102) (xy 248.376897 -54.763731)
			(xy 248.384716 -54.709552) (xy 248.400206 -54.657048) (xy 248.42305 -54.607301) (xy 248.452777 -54.561335)
			(xy 248.47042 -54.540404) (xy 248.470674 -54.54015) (xy 248.476254 -54.53306) (xy 248.482503 -54.516145)
			(xy 248.482866 -54.50713) (xy 248.482866 -54.440074) (xy 248.482529 -54.431055) (xy 248.476268 -54.414138)
			(xy 248.470674 -54.407054) (xy 248.47042 -54.407054) (xy 248.47042 -54.4068) (xy 248.452782 -54.385866)
			(xy 248.423057 -54.339898) (xy 248.400212 -54.290152) (xy 248.384716 -54.23765) (xy 248.376887 -54.183472)
			(xy 248.376887 -54.128731) (xy 248.384715 -54.074553) (xy 248.400211 -54.022051) (xy 248.423056 -53.972305)
			(xy 248.45278 -53.926337) (xy 248.47042 -53.905404) (xy 248.470674 -53.90515) (xy 248.476254 -53.89806)
			(xy 248.482503 -53.881145) (xy 248.482866 -53.87213) (xy 248.482866 -53.805074) (xy 248.482529 -53.796055)
			(xy 248.476268 -53.779138) (xy 248.470674 -53.772054) (xy 248.47042 -53.772054) (xy 248.47042 -53.7718)
			(xy 248.452782 -53.750866) (xy 248.423057 -53.704898) (xy 248.400212 -53.655152) (xy 248.384716 -53.60265)
			(xy 248.376887 -53.548472) (xy 248.376887 -53.493731) (xy 248.384715 -53.439553) (xy 248.400211 -53.387051)
			(xy 248.423056 -53.337305) (xy 248.45278 -53.291337) (xy 248.47042 -53.270404) (xy 248.470674 -53.27015)
			(xy 248.476254 -53.26306) (xy 248.482503 -53.246145) (xy 248.482866 -53.23713) (xy 248.482866 -53.170074)
			(xy 248.482529 -53.161055) (xy 248.476268 -53.144138) (xy 248.470674 -53.137054) (xy 248.47042 -53.137054)
			(xy 248.47042 -53.1368) (xy 248.452771 -53.115876) (xy 248.42306 -53.069901) (xy 248.400225 -53.020152)
			(xy 248.384737 -52.967649) (xy 248.376912 -52.913472) (xy 248.37644 -52.886102) (xy 248.376926 -52.858851)
			(xy 248.384682 -52.804903) (xy 248.400037 -52.752608) (xy 248.422679 -52.703031) (xy 248.452145 -52.657181)
			(xy 248.487836 -52.61599) (xy 248.529027 -52.580299) (xy 248.574877 -52.550833) (xy 248.624454 -52.528191)
			(xy 248.676749 -52.512836) (xy 248.730697 -52.50508) (xy 248.785199 -52.50508) (xy 248.839147 -52.512836)
			(xy 248.891442 -52.528191) (xy 248.930551 -52.546052) (xy 253.879573 -52.546052) (xy 253.879573 -52.491548)
			(xy 253.88733 -52.4376) (xy 253.902686 -52.385304) (xy 253.925327 -52.335726) (xy 253.954794 -52.289875)
			(xy 253.990487 -52.248684) (xy 254.031678 -52.212992) (xy 254.077529 -52.183525) (xy 254.127108 -52.160884)
			(xy 254.179403 -52.145529) (xy 254.233352 -52.137773) (xy 254.260604 -52.13731) (xy 254.287974 -52.137771)
			(xy 254.342154 -52.14559) (xy 254.394657 -52.16108) (xy 254.444404 -52.183923) (xy 254.49037 -52.213648)
			(xy 254.511302 -52.23129) (xy 254.511556 -52.231544) (xy 254.518647 -52.237124) (xy 254.535561 -52.243373)
			(xy 254.544576 -52.243736) (xy 254.611632 -52.243736) (xy 254.620649 -52.243387) (xy 254.637566 -52.237133)
			(xy 254.644652 -52.231544) (xy 254.644652 -52.23129) (xy 254.644906 -52.23129) (xy 254.665839 -52.213649)
			(xy 254.711807 -52.183925) (xy 254.761553 -52.161079) (xy 254.814055 -52.145583) (xy 254.868233 -52.137754)
			(xy 254.922975 -52.137754) (xy 254.977153 -52.145583) (xy 255.029655 -52.161079) (xy 255.079401 -52.183925)
			(xy 255.125369 -52.213649) (xy 255.146302 -52.23129) (xy 255.146556 -52.231544) (xy 255.153647 -52.237124)
			(xy 255.170561 -52.243373) (xy 255.179576 -52.243736) (xy 255.246632 -52.243736) (xy 255.255649 -52.243387)
			(xy 255.272566 -52.237133) (xy 255.279652 -52.231544) (xy 255.279652 -52.23129) (xy 255.279906 -52.23129)
			(xy 255.300824 -52.213633) (xy 255.346801 -52.183924) (xy 255.396552 -52.161092) (xy 255.449056 -52.145605)
			(xy 255.503234 -52.137782) (xy 255.530604 -52.13731) (xy 255.557856 -52.13776) (xy 255.611806 -52.145517)
			(xy 255.664103 -52.160874) (xy 255.713682 -52.183516) (xy 255.759534 -52.212984) (xy 255.800726 -52.248677)
			(xy 255.836419 -52.289869) (xy 255.865886 -52.335722) (xy 255.888528 -52.385301) (xy 255.903883 -52.437598)
			(xy 255.91164 -52.491548) (xy 255.91164 -52.546052) (xy 255.905695 -52.587398) (xy 256.955288 -52.587398)
			(xy 256.959359 -52.531776) (xy 256.971485 -52.477339) (xy 256.991408 -52.425248) (xy 257.018704 -52.376613)
			(xy 257.05279 -52.33247) (xy 257.092939 -52.293761) (xy 257.138297 -52.26131) (xy 257.187897 -52.235809)
			(xy 257.240681 -52.217802) (xy 257.295524 -52.207672) (xy 257.351258 -52.205635) (xy 257.406695 -52.211735)
			(xy 257.460652 -52.225841) (xy 257.511981 -52.247653) (xy 257.559587 -52.276707) (xy 257.602455 -52.312382)
			(xy 257.639672 -52.353919) (xy 257.670445 -52.400432) (xy 257.694117 -52.450929) (xy 257.710185 -52.504336)
			(xy 257.717781 -52.555952) (xy 264.783779 -52.555952) (xy 264.783779 -52.501448) (xy 264.791536 -52.447498)
			(xy 264.806893 -52.395202) (xy 264.829536 -52.345623) (xy 264.859004 -52.299772) (xy 264.894698 -52.258581)
			(xy 264.935891 -52.22289) (xy 264.981744 -52.193424) (xy 265.031324 -52.170784) (xy 265.083622 -52.155431)
			(xy 265.137572 -52.147678) (xy 265.164824 -52.147216) (xy 265.192195 -52.147664) (xy 265.246375 -52.155486)
			(xy 265.298878 -52.170979) (xy 265.348625 -52.193825) (xy 265.394591 -52.223553) (xy 265.415522 -52.241196)
			(xy 265.415776 -52.24145) (xy 265.422861 -52.247039) (xy 265.439779 -52.253283) (xy 265.448796 -52.253642)
			(xy 265.515852 -52.253642) (xy 265.524868 -52.253275) (xy 265.541786 -52.247036) (xy 265.548872 -52.24145)
			(xy 265.548872 -52.241196) (xy 265.549126 -52.241196) (xy 265.570075 -52.223578) (xy 265.616043 -52.193863)
			(xy 265.665786 -52.171023) (xy 265.718283 -52.155527) (xy 265.772456 -52.147693) (xy 265.799824 -52.147216)
			(xy 265.827076 -52.147655) (xy 265.881024 -52.155415) (xy 265.93332 -52.170773) (xy 265.982897 -52.193417)
			(xy 266.028747 -52.222886) (xy 266.069937 -52.25858) (xy 266.105628 -52.299772) (xy 266.135094 -52.345624)
			(xy 266.157735 -52.395203) (xy 266.17309 -52.447499) (xy 266.180846 -52.501448) (xy 266.180846 -52.555952)
			(xy 266.17309 -52.609901) (xy 266.157735 -52.662197) (xy 266.135094 -52.711776) (xy 266.105628 -52.757628)
			(xy 266.069937 -52.79882) (xy 266.028747 -52.834514) (xy 265.982897 -52.863983) (xy 265.93332 -52.886627)
			(xy 265.881024 -52.901985) (xy 265.827076 -52.909745) (xy 265.799824 -52.910232) (xy 265.772453 -52.909768)
			(xy 265.718274 -52.901953) (xy 265.66577 -52.886464) (xy 265.616023 -52.863621) (xy 265.570057 -52.833895)
			(xy 265.549126 -52.816252) (xy 265.548872 -52.815998) (xy 265.541769 -52.810435) (xy 265.524865 -52.804174)
			(xy 265.515852 -52.803806) (xy 265.448796 -52.803806) (xy 265.439779 -52.80416) (xy 265.422862 -52.810409)
			(xy 265.415776 -52.815998) (xy 265.415776 -52.816252) (xy 265.415522 -52.816252) (xy 265.394586 -52.833887)
			(xy 265.348615 -52.863601) (xy 265.298869 -52.886438) (xy 265.246369 -52.90193) (xy 265.192193 -52.909758)
			(xy 265.164824 -52.910232) (xy 265.137572 -52.909722) (xy 265.083622 -52.901969) (xy 265.031324 -52.886616)
			(xy 264.981744 -52.863976) (xy 264.935891 -52.83451) (xy 264.894698 -52.798819) (xy 264.859004 -52.757628)
			(xy 264.829536 -52.711777) (xy 264.806893 -52.662198) (xy 264.791536 -52.609902) (xy 264.783779 -52.555952)
			(xy 257.717781 -52.555952) (xy 257.718305 -52.559512) (xy 257.718814 -52.587398) (xy 257.718305 -52.615284)
			(xy 257.710185 -52.67046) (xy 257.694117 -52.723867) (xy 257.670445 -52.774364) (xy 257.639672 -52.820877)
			(xy 257.602455 -52.862414) (xy 257.559587 -52.898089) (xy 257.511981 -52.927143) (xy 257.460652 -52.948955)
			(xy 257.406695 -52.963061) (xy 257.351258 -52.969161) (xy 257.295524 -52.967124) (xy 257.240681 -52.956994)
			(xy 257.187897 -52.938987) (xy 257.138297 -52.913486) (xy 257.092939 -52.881035) (xy 257.05279 -52.842326)
			(xy 257.018704 -52.798183) (xy 256.991408 -52.749548) (xy 256.971485 -52.697457) (xy 256.959359 -52.64302)
			(xy 256.955288 -52.587398) (xy 255.905695 -52.587398) (xy 255.903883 -52.600002) (xy 255.888528 -52.652299)
			(xy 255.865886 -52.701878) (xy 255.836419 -52.747731) (xy 255.800726 -52.788923) (xy 255.759534 -52.824616)
			(xy 255.713682 -52.854084) (xy 255.664103 -52.876726) (xy 255.611806 -52.892083) (xy 255.557856 -52.89984)
			(xy 255.530604 -52.900326) (xy 255.503233 -52.899876) (xy 255.449053 -52.892057) (xy 255.396549 -52.876565)
			(xy 255.346802 -52.853719) (xy 255.300836 -52.82399) (xy 255.279906 -52.806346) (xy 255.279652 -52.806092)
			(xy 255.272555 -52.80052) (xy 255.255646 -52.794265) (xy 255.246632 -52.7939) (xy 255.179576 -52.7939)
			(xy 255.170558 -52.794246) (xy 255.153641 -52.800501) (xy 255.146556 -52.806092) (xy 255.146302 -52.806346)
			(xy 255.125369 -52.823987) (xy 255.079401 -52.853711) (xy 255.029655 -52.876557) (xy 254.977153 -52.892053)
			(xy 254.922975 -52.899882) (xy 254.868233 -52.899882) (xy 254.814055 -52.892053) (xy 254.761553 -52.876557)
			(xy 254.711807 -52.853711) (xy 254.665839 -52.823987) (xy 254.644906 -52.806346) (xy 254.644652 -52.806092)
			(xy 254.637555 -52.80052) (xy 254.620646 -52.794265) (xy 254.611632 -52.7939) (xy 254.544576 -52.7939)
			(xy 254.535558 -52.794246) (xy 254.518641 -52.800501) (xy 254.511556 -52.806092) (xy 254.511556 -52.806346)
			(xy 254.511302 -52.806346) (xy 254.490373 -52.823989) (xy 254.4444 -52.853702) (xy 254.394652 -52.876538)
			(xy 254.34215 -52.892028) (xy 254.287974 -52.899854) (xy 254.260604 -52.900326) (xy 254.233352 -52.899827)
			(xy 254.179403 -52.892071) (xy 254.127108 -52.876716) (xy 254.077529 -52.854075) (xy 254.031678 -52.824608)
			(xy 253.990487 -52.788916) (xy 253.954794 -52.747725) (xy 253.925327 -52.701874) (xy 253.902686 -52.652296)
			(xy 253.88733 -52.6) (xy 253.879573 -52.546052) (xy 248.930551 -52.546052) (xy 248.941019 -52.550833)
			(xy 248.986869 -52.580299) (xy 249.02806 -52.61599) (xy 249.063751 -52.657181) (xy 249.093217 -52.703031)
			(xy 249.115859 -52.752608) (xy 249.131214 -52.804903) (xy 249.13897 -52.858851) (xy 249.139456 -52.886102)
			(xy 249.139002 -52.913473) (xy 249.131183 -52.967653) (xy 249.115692 -53.020156) (xy 249.092847 -53.069903)
			(xy 249.063119 -53.115869) (xy 249.045476 -53.1368) (xy 249.045222 -53.137054) (xy 249.039639 -53.144143)
			(xy 249.033392 -53.161058) (xy 249.03303 -53.170074) (xy 249.03303 -53.23713) (xy 249.033366 -53.246149)
			(xy 249.039627 -53.263066) (xy 249.045222 -53.27015) (xy 249.045476 -53.27015) (xy 249.045476 -53.270404)
			(xy 249.063119 -53.291335) (xy 249.092843 -53.337303) (xy 249.115688 -53.38705) (xy 249.131184 -53.439552)
			(xy 249.139012 -53.493731) (xy 249.139012 -53.548472) (xy 249.131183 -53.602651) (xy 249.115687 -53.655153)
			(xy 249.092842 -53.704899) (xy 249.063117 -53.750867) (xy 249.046546 -53.77053) (xy 249.410728 -53.77053)
			(xy 249.411257 -53.741613) (xy 249.419983 -53.684442) (xy 249.437238 -53.629243) (xy 249.462627 -53.577281)
			(xy 249.495569 -53.529747) (xy 249.535309 -53.48773) (xy 249.557794 -53.46954) (xy 249.566572 -53.461905)
			(xy 249.576772 -53.441025) (xy 249.577352 -53.429408) (xy 249.577352 -53.349652) (xy 249.576843 -53.338016)
			(xy 249.566635 -53.317106) (xy 249.557794 -53.30952) (xy 249.535319 -53.291319) (xy 249.495583 -53.249301)
			(xy 249.462644 -53.201768) (xy 249.437254 -53.149809) (xy 249.419996 -53.094613) (xy 249.411264 -53.037445)
			(xy 249.410728 -53.00853) (xy 249.411183 -52.981276) (xy 249.418937 -52.927323) (xy 249.434291 -52.875023)
			(xy 249.456933 -52.825441) (xy 249.486401 -52.779586) (xy 249.522096 -52.738392) (xy 249.56329 -52.702697)
			(xy 249.609146 -52.67323) (xy 249.658729 -52.650589) (xy 249.711029 -52.635236) (xy 249.764982 -52.627483)
			(xy 249.792236 -52.627022) (xy 249.818551 -52.627458) (xy 249.870681 -52.634699) (xy 249.921325 -52.649023)
			(xy 249.969524 -52.670162) (xy 250.014367 -52.697713) (xy 250.055005 -52.731158) (xy 250.07316 -52.750212)
			(xy 250.080693 -52.7576) (xy 250.099964 -52.766132) (xy 250.110498 -52.766722) (xy 250.185174 -52.766722)
			(xy 250.195723 -52.766186) (xy 250.215018 -52.757655) (xy 250.222512 -52.750212) (xy 250.240671 -52.73116)
			(xy 250.2813 -52.697702) (xy 250.326139 -52.670142) (xy 250.374339 -52.649003) (xy 250.424986 -52.634685)
			(xy 250.47712 -52.62746) (xy 250.503436 -52.627022) (xy 250.53069 -52.627444) (xy 250.584641 -52.635207)
			(xy 250.636939 -52.650568) (xy 250.686518 -52.673215) (xy 250.73237 -52.702688) (xy 250.77356 -52.738386)
			(xy 250.809251 -52.779583) (xy 250.838716 -52.82544) (xy 250.861355 -52.875023) (xy 250.876707 -52.927324)
			(xy 250.88446 -52.981276) (xy 250.884944 -53.00853) (xy 250.884481 -53.036197) (xy 250.876476 -53.09095)
			(xy 250.860653 -53.143974) (xy 250.837342 -53.194159) (xy 250.807033 -53.240454) (xy 250.770359 -53.28189)
			(xy 250.728089 -53.317599) (xy 250.704858 -53.332634) (xy 250.695169 -53.339256) (xy 250.68273 -53.359128)
			(xy 250.680982 -53.370734) (xy 250.673108 -53.450744) (xy 250.672469 -53.462382) (xy 250.680556 -53.484219)
			(xy 250.688602 -53.492654) (xy 250.688856 -53.492908) (xy 250.707415 -53.511011) (xy 250.739997 -53.551337)
			(xy 250.766814 -53.595707) (xy 250.787371 -53.643301) (xy 250.801289 -53.693242) (xy 250.80831 -53.744608)
			(xy 250.808744 -53.77053) (xy 250.80825 -53.79778) (xy 250.800491 -53.851726) (xy 250.785133 -53.904018)
			(xy 250.762491 -53.953593) (xy 250.733025 -53.999442) (xy 250.697335 -54.040631) (xy 250.656147 -54.076322)
			(xy 250.610299 -54.105789) (xy 250.560724 -54.128431) (xy 250.508432 -54.143789) (xy 250.454486 -54.15155)
			(xy 250.427236 -54.152038) (xy 250.399866 -54.151566) (xy 250.345686 -54.143752) (xy 250.293183 -54.128265)
			(xy 250.243436 -54.105424) (xy 250.197469 -54.0757) (xy 250.176538 -54.058058) (xy 250.176284 -54.057804)
			(xy 250.169206 -54.052205) (xy 250.152283 -54.045966) (xy 250.143264 -54.045612) (xy 250.076208 -54.045612)
			(xy 250.067191 -54.04597) (xy 250.050274 -54.052217) (xy 250.043188 -54.057804) (xy 250.043188 -54.058058)
			(xy 250.042934 -54.058058) (xy 250.021995 -54.075688) (xy 249.976024 -54.105403) (xy 249.926279 -54.128241)
			(xy 249.87378 -54.143734) (xy 249.819605 -54.151564) (xy 249.792236 -54.152038) (xy 249.764985 -54.151511)
			(xy 249.711038 -54.14376) (xy 249.658743 -54.12841) (xy 249.609165 -54.105774) (xy 249.563314 -54.076312)
			(xy 249.522121 -54.040625) (xy 249.486427 -53.999439) (xy 249.456958 -53.953593) (xy 249.434313 -53.904018)
			(xy 249.418954 -53.851726) (xy 249.411193 -53.797781) (xy 249.410728 -53.77053) (xy 249.046546 -53.77053)
			(xy 249.045476 -53.7718) (xy 249.045222 -53.772054) (xy 249.039639 -53.779143) (xy 249.033392 -53.796058)
			(xy 249.03303 -53.805074) (xy 249.03303 -53.87213) (xy 249.033366 -53.881149) (xy 249.039627 -53.898066)
			(xy 249.045222 -53.90515) (xy 249.045476 -53.90515) (xy 249.045476 -53.905404) (xy 249.063119 -53.926335)
			(xy 249.092843 -53.972303) (xy 249.115688 -54.02205) (xy 249.131184 -54.074552) (xy 249.139012 -54.128731)
			(xy 249.139012 -54.183472) (xy 249.131183 -54.237651) (xy 249.115687 -54.290153) (xy 249.101895 -54.320186)
			(xy 251.33046 -54.320186) (xy 251.330903 -54.292815) (xy 251.338724 -54.238634) (xy 251.354218 -54.18613)
			(xy 251.377065 -54.136384) (xy 251.406796 -54.090418) (xy 251.42444 -54.069488) (xy 251.424694 -54.069234)
			(xy 251.430272 -54.062141) (xy 251.436524 -54.045229) (xy 251.436886 -54.036214) (xy 251.436886 -53.969158)
			(xy 251.436504 -53.960144) (xy 251.430274 -53.943226) (xy 251.424694 -53.936138) (xy 251.42444 -53.936138)
			(xy 251.42444 -53.935884) (xy 251.406833 -53.914926) (xy 251.377115 -53.868961) (xy 251.354272 -53.81922)
			(xy 251.338774 -53.766725) (xy 251.330938 -53.712553) (xy 251.33046 -53.685186) (xy 251.330946 -53.657935)
			(xy 251.338702 -53.603987) (xy 251.354057 -53.551692) (xy 251.376699 -53.502115) (xy 251.406165 -53.456265)
			(xy 251.441856 -53.415074) (xy 251.483047 -53.379383) (xy 251.528897 -53.349917) (xy 251.578474 -53.327275)
			(xy 251.630769 -53.31192) (xy 251.684717 -53.304164) (xy 251.739219 -53.304164) (xy 251.793167 -53.31192)
			(xy 251.845462 -53.327275) (xy 251.895039 -53.349917) (xy 251.940889 -53.379383) (xy 251.98208 -53.415074)
			(xy 252.017771 -53.456265) (xy 252.047237 -53.502115) (xy 252.069879 -53.551692) (xy 252.085234 -53.603987)
			(xy 252.09299 -53.657935) (xy 252.093476 -53.685186) (xy 252.093008 -53.712556) (xy 252.085191 -53.766735)
			(xy 252.069703 -53.819239) (xy 252.046862 -53.868986) (xy 252.017137 -53.914952) (xy 251.999496 -53.935884)
			(xy 251.999242 -53.936138) (xy 251.993668 -53.943233) (xy 251.987415 -53.960144) (xy 251.98705 -53.969158)
			(xy 251.98705 -54.036214) (xy 251.98739 -54.045233) (xy 251.993648 -54.06215) (xy 251.999242 -54.069234)
			(xy 251.999496 -54.069234) (xy 251.999496 -54.069488) (xy 252.017142 -54.090414) (xy 252.046853 -54.136389)
			(xy 252.069688 -54.186138) (xy 252.085177 -54.23864) (xy 252.093003 -54.292816) (xy 252.093476 -54.320186)
			(xy 252.09299 -54.347437) (xy 252.085234 -54.401385) (xy 252.069879 -54.45368) (xy 252.047237 -54.503257)
			(xy 252.017771 -54.549107) (xy 251.98208 -54.590298) (xy 251.940889 -54.625989) (xy 251.895039 -54.655455)
			(xy 251.845462 -54.678097) (xy 251.793167 -54.693452) (xy 251.739219 -54.701208) (xy 251.684717 -54.701208)
			(xy 251.630769 -54.693452) (xy 251.578474 -54.678097) (xy 251.528897 -54.655455) (xy 251.483047 -54.625989)
			(xy 251.441856 -54.590298) (xy 251.406165 -54.549107) (xy 251.376699 -54.503257) (xy 251.354057 -54.45368)
			(xy 251.338702 -54.401385) (xy 251.330946 -54.347437) (xy 251.33046 -54.320186) (xy 249.101895 -54.320186)
			(xy 249.092842 -54.339899) (xy 249.063117 -54.385867) (xy 249.045476 -54.4068) (xy 249.045222 -54.407054)
			(xy 249.039639 -54.414143) (xy 249.033392 -54.431058) (xy 249.03303 -54.440074) (xy 249.03303 -54.50713)
			(xy 249.033366 -54.516149) (xy 249.039627 -54.533066) (xy 249.045222 -54.54015) (xy 249.045476 -54.54015)
			(xy 249.045476 -54.540404) (xy 249.063127 -54.561327) (xy 249.092838 -54.607302) (xy 249.115672 -54.657052)
			(xy 249.13116 -54.709554) (xy 249.138984 -54.763732) (xy 249.139101 -54.770528) (xy 252.271022 -54.770528)
			(xy 252.271499 -54.743158) (xy 252.279313 -54.688979) (xy 252.2948 -54.636476) (xy 252.317639 -54.586729)
			(xy 252.347362 -54.540762) (xy 252.365002 -54.51983) (xy 252.365256 -54.519576) (xy 252.370865 -54.512505)
			(xy 252.377097 -54.495576) (xy 252.377448 -54.486556) (xy 252.377448 -54.4195) (xy 252.377102 -54.410482)
			(xy 252.370848 -54.393564) (xy 252.365256 -54.38648) (xy 252.365002 -54.38648) (xy 252.365002 -54.386226)
			(xy 252.347362 -54.365295) (xy 252.31765 -54.319322) (xy 252.294814 -54.269574) (xy 252.279324 -54.217073)
			(xy 252.271496 -54.162897) (xy 252.271022 -54.135528) (xy 252.271508 -54.108277) (xy 252.279264 -54.054329)
			(xy 252.294619 -54.002034) (xy 252.317261 -53.952457) (xy 252.346727 -53.906607) (xy 252.382418 -53.865416)
			(xy 252.423609 -53.829725) (xy 252.469459 -53.800259) (xy 252.519036 -53.777617) (xy 252.571331 -53.762262)
			(xy 252.625279 -53.754506) (xy 252.679781 -53.754506) (xy 252.733729 -53.762262) (xy 252.786024 -53.777617)
			(xy 252.835601 -53.800259) (xy 252.881451 -53.829725) (xy 252.922642 -53.865416) (xy 252.958333 -53.906607)
			(xy 252.987799 -53.952457) (xy 253.010441 -54.002034) (xy 253.025796 -54.054329) (xy 253.033552 -54.108277)
			(xy 253.034038 -54.135528) (xy 253.033603 -54.1629) (xy 253.02578 -54.217081) (xy 253.010285 -54.269585)
			(xy 252.987436 -54.319331) (xy 252.957703 -54.365296) (xy 252.940058 -54.386226) (xy 252.939804 -54.38648)
			(xy 252.93422 -54.393568) (xy 252.927972 -54.410484) (xy 252.927612 -54.4195) (xy 252.927612 -54.486556)
			(xy 252.927988 -54.495571) (xy 252.934222 -54.512488) (xy 252.939804 -54.519576) (xy 252.940058 -54.519576)
			(xy 252.940058 -54.51983) (xy 252.957671 -54.540783) (xy 252.987388 -54.586749) (xy 253.01023 -54.636492)
			(xy 253.025727 -54.688988) (xy 253.033561 -54.74316) (xy 253.034038 -54.770528) (xy 253.033552 -54.797779)
			(xy 253.025796 -54.851727) (xy 253.010441 -54.904022) (xy 252.987799 -54.953599) (xy 252.958333 -54.999449)
			(xy 252.922642 -55.04064) (xy 252.881451 -55.076331) (xy 252.835601 -55.105797) (xy 252.786024 -55.128439)
			(xy 252.733729 -55.143794) (xy 252.679781 -55.15155) (xy 252.625279 -55.15155) (xy 252.571331 -55.143794)
			(xy 252.519036 -55.128439) (xy 252.469459 -55.105797) (xy 252.423609 -55.076331) (xy 252.382418 -55.04064)
			(xy 252.346727 -54.999449) (xy 252.317261 -54.953599) (xy 252.294619 -54.904022) (xy 252.279264 -54.851727)
			(xy 252.271508 -54.797779) (xy 252.271022 -54.770528) (xy 249.139101 -54.770528) (xy 249.139456 -54.791102)
			(xy 249.13897 -54.818353) (xy 249.131214 -54.872301) (xy 249.115859 -54.924596) (xy 249.093217 -54.974173)
			(xy 249.063751 -55.020023) (xy 249.02806 -55.061214) (xy 248.986869 -55.096905) (xy 248.941019 -55.126371)
			(xy 248.891442 -55.149013) (xy 248.839147 -55.164368) (xy 248.785199 -55.172124) (xy 248.730697 -55.172124)
			(xy 248.676749 -55.164368) (xy 248.624454 -55.149013) (xy 248.574877 -55.126371) (xy 248.529027 -55.096905)
			(xy 248.487836 -55.061214) (xy 248.452145 -55.020023) (xy 248.422679 -54.974173) (xy 248.400037 -54.924596)
			(xy 248.384682 -54.872301) (xy 248.376926 -54.818353) (xy 248.37644 -54.791102) (xy 246.478482 -54.791102)
			(xy 246.47539 -54.812611) (xy 246.460035 -54.864906) (xy 246.437393 -54.914483) (xy 246.407927 -54.960333)
			(xy 246.372236 -55.001524) (xy 246.331045 -55.037215) (xy 246.285195 -55.066681) (xy 246.235618 -55.089323)
			(xy 246.183323 -55.104678) (xy 246.129375 -55.112434) (xy 246.074873 -55.112434) (xy 246.020925 -55.104678)
			(xy 245.96863 -55.089323) (xy 245.919053 -55.066681) (xy 245.873203 -55.037215) (xy 245.832012 -55.001524)
			(xy 245.796321 -54.960333) (xy 245.766855 -54.914483) (xy 245.744213 -54.864906) (xy 245.728858 -54.812611)
			(xy 245.721102 -54.758663) (xy 245.720616 -54.731412) (xy 245.596156 -54.731412) (xy 245.596156 -57.002934)
			(xy 253.763526 -57.002934) (xy 253.764026 -56.974842) (xy 253.77225 -56.919265) (xy 253.788538 -56.865495)
			(xy 253.81254 -56.814696) (xy 253.843734 -56.767969) (xy 253.881447 -56.726325) (xy 253.924861 -56.690664)
			(xy 253.948692 -56.675782) (xy 253.957582 -56.670448) (xy 253.969774 -56.65343) (xy 253.990094 -56.560212)
			(xy 253.985776 -56.539638) (xy 253.979934 -56.531002) (xy 253.963937 -56.506936) (xy 253.938592 -56.455006)
			(xy 253.921366 -56.399848) (xy 253.91265 -56.342724) (xy 253.912116 -56.313832) (xy 253.912585 -56.286579)
			(xy 253.920338 -56.232627) (xy 253.935692 -56.180328) (xy 253.958332 -56.130746) (xy 253.987799 -56.084892)
			(xy 254.023492 -56.043698) (xy 254.064685 -56.008004) (xy 254.110539 -55.978536) (xy 254.16012 -55.955894)
			(xy 254.212419 -55.94054) (xy 254.266371 -55.932786) (xy 254.293624 -55.932324) (xy 254.320995 -55.93277)
			(xy 254.375175 -55.940592) (xy 254.427679 -55.956085) (xy 254.477425 -55.978932) (xy 254.523391 -56.008661)
			(xy 254.544322 -56.026304) (xy 254.544576 -56.026558) (xy 254.55166 -56.032148) (xy 254.568579 -56.038391)
			(xy 254.577596 -56.03875) (xy 254.644652 -56.03875) (xy 254.653668 -56.038381) (xy 254.670586 -56.032143)
			(xy 254.677672 -56.026558) (xy 254.677672 -56.026304) (xy 254.677926 -56.026304) (xy 254.698859 -56.008663)
			(xy 254.744827 -55.978939) (xy 254.794573 -55.956093) (xy 254.847075 -55.940597) (xy 254.901253 -55.932768)
			(xy 254.955995 -55.932768) (xy 255.010173 -55.940597) (xy 255.062675 -55.956093) (xy 255.112421 -55.978939)
			(xy 255.158389 -56.008663) (xy 255.179322 -56.026304) (xy 255.179576 -56.026558) (xy 255.18666 -56.032148)
			(xy 255.203579 -56.038391) (xy 255.212596 -56.03875) (xy 255.279652 -56.03875) (xy 255.288668 -56.038381)
			(xy 255.305586 -56.032143) (xy 255.312672 -56.026558) (xy 255.312672 -56.026304) (xy 255.312926 -56.026304)
			(xy 255.333876 -56.008687) (xy 255.379844 -55.978971) (xy 255.429587 -55.956131) (xy 255.482083 -55.940635)
			(xy 255.536256 -55.932801) (xy 255.563624 -55.932324) (xy 255.590876 -55.932747) (xy 255.644826 -55.940507)
			(xy 255.697122 -55.955866) (xy 255.746701 -55.97851) (xy 255.792552 -56.00798) (xy 255.833743 -56.043674)
			(xy 255.869435 -56.084867) (xy 255.898901 -56.13072) (xy 255.921542 -56.1803) (xy 255.936898 -56.232597)
			(xy 255.944654 -56.286548) (xy 255.944654 -56.341052) (xy 255.936898 -56.395003) (xy 255.921542 -56.4473)
			(xy 255.898901 -56.49688) (xy 255.869435 -56.542733) (xy 255.833743 -56.583926) (xy 255.792552 -56.61962)
			(xy 255.746701 -56.64909) (xy 255.697122 -56.671734) (xy 255.644826 -56.687093) (xy 255.590876 -56.694853)
			(xy 255.563624 -56.69534) (xy 255.536254 -56.694874) (xy 255.482074 -56.687059) (xy 255.42957 -56.67157)
			(xy 255.379823 -56.648728) (xy 255.333857 -56.619002) (xy 255.312926 -56.60136) (xy 255.312672 -56.601106)
			(xy 255.305568 -56.595544) (xy 255.288665 -56.589282) (xy 255.279652 -56.588914) (xy 255.212596 -56.588914)
			(xy 255.203579 -56.589266) (xy 255.186661 -56.595517) (xy 255.179576 -56.601106) (xy 255.179576 -56.60136)
			(xy 255.179322 -56.60136) (xy 255.158389 -56.619001) (xy 255.112421 -56.648725) (xy 255.062675 -56.671571)
			(xy 255.010173 -56.687067) (xy 254.955995 -56.694896) (xy 254.901253 -56.694896) (xy 254.847075 -56.687067)
			(xy 254.794573 -56.671571) (xy 254.744827 -56.648725) (xy 254.698859 -56.619001) (xy 254.677926 -56.60136)
			(xy 254.677672 -56.601106) (xy 254.670568 -56.595544) (xy 254.653665 -56.589282) (xy 254.644652 -56.588914)
			(xy 254.577596 -56.588914) (xy 254.568579 -56.589266) (xy 254.551661 -56.595517) (xy 254.544576 -56.601106)
			(xy 254.544068 -56.60136) (xy 254.531333 -56.612303) (xy 254.504242 -56.632145) (xy 254.489966 -56.640984)
			(xy 254.481076 -56.646318) (xy 254.468884 -56.663336) (xy 254.448564 -56.756554) (xy 254.452882 -56.777128)
			(xy 254.458724 -56.785764) (xy 254.474714 -56.809834) (xy 254.500058 -56.861764) (xy 254.517286 -56.91692)
			(xy 254.526005 -56.974042) (xy 254.526542 -57.002934) (xy 254.526056 -57.030185) (xy 254.5183 -57.084133)
			(xy 254.502945 -57.136428) (xy 254.480303 -57.186005) (xy 254.450837 -57.231855) (xy 254.415146 -57.273046)
			(xy 254.373955 -57.308737) (xy 254.328105 -57.338203) (xy 254.278528 -57.360845) (xy 254.226233 -57.3762)
			(xy 254.172285 -57.383956) (xy 254.117783 -57.383956) (xy 254.063835 -57.3762) (xy 254.01154 -57.360845)
			(xy 253.961963 -57.338203) (xy 253.916113 -57.308737) (xy 253.874922 -57.273046) (xy 253.839231 -57.231855)
			(xy 253.809765 -57.186005) (xy 253.787123 -57.136428) (xy 253.771768 -57.084133) (xy 253.764012 -57.030185)
			(xy 253.763526 -57.002934) (xy 245.596156 -57.002934) (xy 245.596156 -58.679334) (xy 254.195326 -58.679334)
			(xy 254.195741 -58.653018) (xy 254.202985 -58.600887) (xy 254.217314 -58.550243) (xy 254.238456 -58.502044)
			(xy 254.266012 -58.457202) (xy 254.29946 -58.416565) (xy 254.318516 -58.39841) (xy 254.325918 -58.390889)
			(xy 254.334442 -58.371608) (xy 254.335026 -58.361072) (xy 254.335026 -58.286396) (xy 254.334505 -58.275846)
			(xy 254.325963 -58.256551) (xy 254.318516 -58.249058) (xy 254.29945 -58.230913) (xy 254.265993 -58.190281)
			(xy 254.238435 -58.145439) (xy 254.217298 -58.097236) (xy 254.202984 -58.046587) (xy 254.195762 -57.994451)
			(xy 254.195326 -57.968134) (xy 254.195812 -57.940883) (xy 254.203568 -57.886935) (xy 254.218923 -57.83464)
			(xy 254.241565 -57.785063) (xy 254.271031 -57.739213) (xy 254.306722 -57.698022) (xy 254.347913 -57.662331)
			(xy 254.393763 -57.632865) (xy 254.44334 -57.610223) (xy 254.495635 -57.594868) (xy 254.549583 -57.587112)
			(xy 254.604085 -57.587112) (xy 254.658033 -57.594868) (xy 254.710328 -57.610223) (xy 254.759905 -57.632865)
			(xy 254.805755 -57.662331) (xy 254.846946 -57.698022) (xy 254.882637 -57.739213) (xy 254.912103 -57.785063)
			(xy 254.934745 -57.83464) (xy 254.9501 -57.886935) (xy 254.957856 -57.940883) (xy 254.958342 -57.968134)
			(xy 254.957916 -57.99445) (xy 254.950675 -58.046581) (xy 254.936349 -58.097225) (xy 254.915209 -58.145424)
			(xy 254.887655 -58.190266) (xy 254.854208 -58.230903) (xy 254.835152 -58.249058) (xy 254.827775 -58.2566)
			(xy 254.819235 -58.275864) (xy 254.818642 -58.286396) (xy 254.818642 -58.361072) (xy 254.819161 -58.371623)
			(xy 254.827702 -58.390919) (xy 254.835152 -58.39841) (xy 254.854215 -58.416558) (xy 254.88767 -58.45719)
			(xy 254.915226 -58.502032) (xy 254.936363 -58.550235) (xy 254.950679 -58.600883) (xy 254.957904 -58.653018)
			(xy 254.958342 -58.679334) (xy 254.957856 -58.706585) (xy 254.9501 -58.760533) (xy 254.934745 -58.812828)
			(xy 254.912103 -58.862405) (xy 254.882637 -58.908255) (xy 254.846946 -58.949446) (xy 254.805755 -58.985137)
			(xy 254.759905 -59.014603) (xy 254.710328 -59.037245) (xy 254.658033 -59.0526) (xy 254.604085 -59.060356)
			(xy 254.549583 -59.060356) (xy 254.495635 -59.0526) (xy 254.44334 -59.037245) (xy 254.393763 -59.014603)
			(xy 254.347913 -58.985137) (xy 254.306722 -58.949446) (xy 254.271031 -58.908255) (xy 254.241565 -58.862405)
			(xy 254.218923 -58.812828) (xy 254.203568 -58.760533) (xy 254.195812 -58.706585) (xy 254.195326 -58.679334)
			(xy 245.596156 -58.679334) (xy 245.596156 -60.01925) (xy 254.335784 -60.01925) (xy 254.335784 -59.96475)
			(xy 254.34354 -59.910804) (xy 254.358894 -59.858511) (xy 254.381534 -59.808935) (xy 254.410999 -59.763086)
			(xy 254.446688 -59.721897) (xy 254.487877 -59.686206) (xy 254.533725 -59.65674) (xy 254.5833 -59.634098)
			(xy 254.635592 -59.618742) (xy 254.689538 -59.610985) (xy 254.716788 -59.610498) (xy 254.744158 -59.610972)
			(xy 254.798337 -59.618788) (xy 254.85084 -59.634275) (xy 254.900587 -59.657115) (xy 254.946554 -59.686838)
			(xy 254.967486 -59.704478) (xy 254.96774 -59.704732) (xy 254.974837 -59.710303) (xy 254.991746 -59.716558)
			(xy 255.00076 -59.716924) (xy 255.067816 -59.716924) (xy 255.076833 -59.716569) (xy 255.09375 -59.710319)
			(xy 255.100836 -59.704732) (xy 255.100836 -59.704478) (xy 255.10109 -59.704478) (xy 255.122023 -59.686837)
			(xy 255.167991 -59.657113) (xy 255.217737 -59.634267) (xy 255.270239 -59.618771) (xy 255.324417 -59.610942)
			(xy 255.379159 -59.610942) (xy 255.433337 -59.618771) (xy 255.485839 -59.634267) (xy 255.535585 -59.657113)
			(xy 255.581553 -59.686837) (xy 255.602486 -59.704478) (xy 255.60274 -59.704732) (xy 255.609837 -59.710303)
			(xy 255.626746 -59.716558) (xy 255.63576 -59.716924) (xy 255.702816 -59.716924) (xy 255.711833 -59.716569)
			(xy 255.72875 -59.710319) (xy 255.735836 -59.704732) (xy 255.735836 -59.704478) (xy 255.73609 -59.704478)
			(xy 255.757012 -59.686827) (xy 255.802988 -59.657117) (xy 255.852738 -59.634284) (xy 255.905241 -59.618796)
			(xy 255.959418 -59.610971) (xy 255.986788 -59.610498) (xy 256.014042 -59.610949) (xy 256.067995 -59.618704)
			(xy 256.120295 -59.634059) (xy 256.169877 -59.656702) (xy 256.215733 -59.68617) (xy 256.256928 -59.721864)
			(xy 256.292623 -59.763058) (xy 256.322093 -59.808912) (xy 256.344736 -59.858494) (xy 256.360093 -59.910793)
			(xy 256.367851 -59.964746) (xy 256.367851 -60.019254) (xy 256.360093 -60.073207) (xy 256.344736 -60.125506)
			(xy 256.322093 -60.175088) (xy 256.292623 -60.220942) (xy 256.256928 -60.262136) (xy 256.215733 -60.29783)
			(xy 256.169877 -60.327298) (xy 256.120295 -60.349941) (xy 256.067995 -60.365296) (xy 256.014042 -60.373051)
			(xy 255.986788 -60.373514) (xy 255.959418 -60.373052) (xy 255.905239 -60.365232) (xy 255.852736 -60.349742)
			(xy 255.802989 -60.3269) (xy 255.757022 -60.297175) (xy 255.73609 -60.279534) (xy 255.735836 -60.27928)
			(xy 255.728745 -60.2737) (xy 255.711832 -60.26745) (xy 255.702816 -60.267088) (xy 255.63576 -60.267088)
			(xy 255.626741 -60.267428) (xy 255.609825 -60.273688) (xy 255.60274 -60.27928) (xy 255.602486 -60.279534)
			(xy 255.581553 -60.297175) (xy 255.535585 -60.326899) (xy 255.485839 -60.349745) (xy 255.433337 -60.365241)
			(xy 255.379159 -60.37307) (xy 255.324417 -60.37307) (xy 255.270239 -60.365241) (xy 255.217737 -60.349745)
			(xy 255.167991 -60.326899) (xy 255.122023 -60.297175) (xy 255.10109 -60.279534) (xy 255.100836 -60.27928)
			(xy 255.093745 -60.2737) (xy 255.076832 -60.26745) (xy 255.067816 -60.267088) (xy 255.00076 -60.267088)
			(xy 254.991741 -60.267428) (xy 254.974825 -60.273688) (xy 254.96774 -60.27928) (xy 254.96774 -60.279534)
			(xy 254.967486 -60.279534) (xy 254.946537 -60.297152) (xy 254.900568 -60.326865) (xy 254.850825 -60.349705)
			(xy 254.798328 -60.365201) (xy 254.744156 -60.373036) (xy 254.716788 -60.373514) (xy 254.689538 -60.373015)
			(xy 254.635592 -60.365258) (xy 254.5833 -60.349902) (xy 254.533725 -60.32726) (xy 254.487877 -60.297794)
			(xy 254.446688 -60.262103) (xy 254.410999 -60.220914) (xy 254.381534 -60.175065) (xy 254.358894 -60.125489)
			(xy 254.34354 -60.073196) (xy 254.335784 -60.01925) (xy 245.596156 -60.01925) (xy 245.596156 -67.100555)
			(xy 246.218627 -67.100555) (xy 246.218627 -67.046045) (xy 246.226385 -66.992089) (xy 246.241742 -66.939786)
			(xy 246.264387 -66.890202) (xy 246.293858 -66.844345) (xy 246.329556 -66.803149) (xy 246.370753 -66.767452)
			(xy 246.416611 -66.737983) (xy 246.466196 -66.715339) (xy 246.518499 -66.699983) (xy 246.572455 -66.692226)
			(xy 246.59971 -66.691764) (xy 246.627081 -66.692209) (xy 246.681262 -66.700029) (xy 246.733766 -66.715522)
			(xy 246.783512 -66.738369) (xy 246.829478 -66.7681) (xy 246.850408 -66.785744) (xy 246.850662 -66.785998)
			(xy 246.857755 -66.791575) (xy 246.874667 -66.797827) (xy 246.883682 -66.79819) (xy 246.950738 -66.79819)
			(xy 246.959757 -66.797853) (xy 246.976674 -66.791592) (xy 246.983758 -66.785998) (xy 246.983758 -66.785744)
			(xy 246.984012 -66.785744) (xy 247.004972 -66.76814) (xy 247.050937 -66.738421) (xy 247.100677 -66.715578)
			(xy 247.153172 -66.700079) (xy 247.207343 -66.692242) (xy 247.23471 -66.691764) (xy 247.261959 -66.692307)
			(xy 247.315901 -66.700064) (xy 247.368191 -66.715419) (xy 247.417763 -66.738059) (xy 247.463609 -66.767523)
			(xy 247.504795 -66.803212) (xy 247.540483 -66.844399) (xy 247.569946 -66.890245) (xy 247.592585 -66.939818)
			(xy 247.607938 -66.992108) (xy 247.615694 -67.046051) (xy 247.615694 -67.100549) (xy 247.607938 -67.154492)
			(xy 247.592585 -67.206782) (xy 247.569946 -67.256355) (xy 247.540483 -67.302201) (xy 247.504795 -67.343388)
			(xy 247.463609 -67.379077) (xy 247.417763 -67.408541) (xy 247.368191 -67.431181) (xy 247.315901 -67.446536)
			(xy 247.261959 -67.454293) (xy 247.23471 -67.45478) (xy 247.20734 -67.454313) (xy 247.153161 -67.446496)
			(xy 247.100657 -67.431008) (xy 247.05091 -67.408166) (xy 247.004944 -67.378441) (xy 246.984012 -67.3608)
			(xy 246.983758 -67.360546) (xy 246.976664 -67.354971) (xy 246.959753 -67.348719) (xy 246.950738 -67.348354)
			(xy 246.883682 -67.348354) (xy 246.874663 -67.348691) (xy 246.857746 -67.354951) (xy 246.850662 -67.360546)
			(xy 246.850662 -67.3608) (xy 246.850408 -67.3608) (xy 246.829484 -67.378449) (xy 246.783509 -67.408159)
			(xy 246.733759 -67.430993) (xy 246.681257 -67.446482) (xy 246.62708 -67.454307) (xy 246.59971 -67.45478)
			(xy 246.572455 -67.454374) (xy 246.518499 -67.446617) (xy 246.466196 -67.431261) (xy 246.416611 -67.408617)
			(xy 246.370753 -67.379148) (xy 246.329556 -67.343451) (xy 246.293858 -67.302255) (xy 246.264387 -67.256398)
			(xy 246.241742 -67.206814) (xy 246.226385 -67.154511) (xy 246.218627 -67.100555) (xy 245.596156 -67.100555)
			(xy 245.596156 -67.488054) (xy 250.979176 -67.488054) (xy 250.983247 -67.432432) (xy 250.995373 -67.377995)
			(xy 251.015296 -67.325904) (xy 251.042592 -67.277269) (xy 251.076678 -67.233126) (xy 251.116827 -67.194417)
			(xy 251.162185 -67.161966) (xy 251.211785 -67.136465) (xy 251.264569 -67.118458) (xy 251.319412 -67.108328)
			(xy 251.375146 -67.106291) (xy 251.430583 -67.112391) (xy 251.48454 -67.126497) (xy 251.535869 -67.148309)
			(xy 251.583475 -67.177363) (xy 251.626343 -67.213038) (xy 251.66356 -67.254575) (xy 251.694333 -67.301088)
			(xy 251.718005 -67.351585) (xy 251.734073 -67.404992) (xy 251.742193 -67.460168) (xy 251.742702 -67.488054)
			(xy 251.742193 -67.51594) (xy 251.739008 -67.537584) (xy 252.271274 -67.537584) (xy 252.275345 -67.481962)
			(xy 252.287471 -67.427525) (xy 252.307394 -67.375434) (xy 252.33469 -67.326799) (xy 252.368776 -67.282656)
			(xy 252.408925 -67.243947) (xy 252.454283 -67.211496) (xy 252.503883 -67.185995) (xy 252.556667 -67.167988)
			(xy 252.61151 -67.157858) (xy 252.667244 -67.155821) (xy 252.722681 -67.161921) (xy 252.776638 -67.176027)
			(xy 252.827967 -67.197839) (xy 252.875573 -67.226893) (xy 252.918441 -67.262568) (xy 252.955658 -67.304105)
			(xy 252.986431 -67.350618) (xy 253.010103 -67.401115) (xy 253.026171 -67.454522) (xy 253.034291 -67.509698)
			(xy 253.0348 -67.537584) (xy 253.034291 -67.56547) (xy 253.030246 -67.592956) (xy 253.545338 -67.592956)
			(xy 253.549409 -67.537334) (xy 253.561535 -67.482897) (xy 253.581458 -67.430806) (xy 253.608754 -67.382171)
			(xy 253.64284 -67.338028) (xy 253.682989 -67.299319) (xy 253.728347 -67.266868) (xy 253.777947 -67.241367)
			(xy 253.830731 -67.22336) (xy 253.885574 -67.21323) (xy 253.941308 -67.211193) (xy 253.996745 -67.217293)
			(xy 254.050702 -67.231399) (xy 254.102031 -67.253211) (xy 254.149637 -67.282265) (xy 254.192505 -67.31794)
			(xy 254.229722 -67.359477) (xy 254.260495 -67.40599) (xy 254.284167 -67.456487) (xy 254.300235 -67.509894)
			(xy 254.308355 -67.56507) (xy 254.308864 -67.592956) (xy 254.308355 -67.620842) (xy 254.300235 -67.676018)
			(xy 254.284167 -67.729425) (xy 254.260495 -67.779922) (xy 254.229722 -67.826435) (xy 254.192505 -67.867972)
			(xy 254.149637 -67.903647) (xy 254.102031 -67.932701) (xy 254.050702 -67.954513) (xy 253.996745 -67.968619)
			(xy 253.941308 -67.974719) (xy 253.885574 -67.972682) (xy 253.830731 -67.962552) (xy 253.777947 -67.944545)
			(xy 253.728347 -67.919044) (xy 253.682989 -67.886593) (xy 253.64284 -67.847884) (xy 253.608754 -67.803741)
			(xy 253.581458 -67.755106) (xy 253.561535 -67.703015) (xy 253.549409 -67.648578) (xy 253.545338 -67.592956)
			(xy 253.030246 -67.592956) (xy 253.026171 -67.620646) (xy 253.010103 -67.674053) (xy 252.986431 -67.72455)
			(xy 252.955658 -67.771063) (xy 252.918441 -67.8126) (xy 252.875573 -67.848275) (xy 252.827967 -67.877329)
			(xy 252.776638 -67.899141) (xy 252.722681 -67.913247) (xy 252.667244 -67.919347) (xy 252.61151 -67.91731)
			(xy 252.556667 -67.90718) (xy 252.503883 -67.889173) (xy 252.454283 -67.863672) (xy 252.408925 -67.831221)
			(xy 252.368776 -67.792512) (xy 252.33469 -67.748369) (xy 252.307394 -67.699734) (xy 252.287471 -67.647643)
			(xy 252.275345 -67.593206) (xy 252.271274 -67.537584) (xy 251.739008 -67.537584) (xy 251.734073 -67.571116)
			(xy 251.718005 -67.624523) (xy 251.694333 -67.67502) (xy 251.66356 -67.721533) (xy 251.626343 -67.76307)
			(xy 251.583475 -67.798745) (xy 251.535869 -67.827799) (xy 251.48454 -67.849611) (xy 251.430583 -67.863717)
			(xy 251.375146 -67.869817) (xy 251.319412 -67.86778) (xy 251.264569 -67.85765) (xy 251.211785 -67.839643)
			(xy 251.162185 -67.814142) (xy 251.116827 -67.781691) (xy 251.076678 -67.742982) (xy 251.042592 -67.698839)
			(xy 251.015296 -67.650204) (xy 250.995373 -67.598113) (xy 250.983247 -67.543676) (xy 250.979176 -67.488054)
			(xy 245.596156 -67.488054) (xy 245.596156 -68.586604) (xy 248.825258 -68.586604) (xy 248.825712 -68.559233)
			(xy 248.833531 -68.505053) (xy 248.849022 -68.452549) (xy 248.871867 -68.402803) (xy 248.901595 -68.356837)
			(xy 248.919238 -68.335906) (xy 248.919492 -68.335652) (xy 248.925062 -68.328554) (xy 248.931319 -68.311646)
			(xy 248.931684 -68.302632) (xy 248.931684 -68.235576) (xy 248.931342 -68.226558) (xy 248.925084 -68.209641)
			(xy 248.919492 -68.202556) (xy 248.919238 -68.202556) (xy 248.919238 -68.202302) (xy 248.901592 -68.181375)
			(xy 248.87188 -68.135401) (xy 248.849045 -68.085653) (xy 248.833555 -68.033151) (xy 248.82573 -67.978974)
			(xy 248.825258 -67.951604) (xy 248.825781 -67.924354) (xy 248.833536 -67.87041) (xy 248.848889 -67.818118)
			(xy 248.871528 -67.768543) (xy 248.90099 -67.722694) (xy 248.936678 -67.681505) (xy 248.977864 -67.645813)
			(xy 249.023709 -67.616346) (xy 249.073282 -67.593703) (xy 249.125573 -67.578345) (xy 249.179516 -67.570584)
			(xy 249.206766 -67.570096) (xy 249.233081 -67.570521) (xy 249.285212 -67.577764) (xy 249.335855 -67.592092)
			(xy 249.384054 -67.613233) (xy 249.428896 -67.640786) (xy 249.469534 -67.674231) (xy 249.48769 -67.693286)
			(xy 249.495215 -67.700683) (xy 249.514492 -67.709211) (xy 249.525028 -67.709796) (xy 249.599704 -67.709796)
			(xy 249.610256 -67.709284) (xy 249.629551 -67.700737) (xy 249.637042 -67.693286) (xy 249.655181 -67.674214)
			(xy 249.695815 -67.640759) (xy 249.740659 -67.613203) (xy 249.788863 -67.592067) (xy 249.839513 -67.577753)
			(xy 249.891649 -67.570532) (xy 249.917966 -67.570096) (xy 249.945335 -67.570583) (xy 249.999514 -67.578396)
			(xy 250.052016 -67.59388) (xy 250.101764 -67.616717) (xy 250.147732 -67.646437) (xy 250.168664 -67.664076)
			(xy 250.168918 -67.66433) (xy 250.175993 -67.669934) (xy 250.192919 -67.676169) (xy 250.201938 -67.676522)
			(xy 250.268994 -67.676522) (xy 250.27801 -67.676157) (xy 250.294927 -67.669914) (xy 250.302014 -67.66433)
			(xy 250.302014 -67.664076) (xy 250.302268 -67.664076) (xy 250.323198 -67.646435) (xy 250.369172 -67.616724)
			(xy 250.41892 -67.593889) (xy 250.471421 -67.578398) (xy 250.525597 -67.57057) (xy 250.552966 -67.570096)
			(xy 250.580218 -67.570587) (xy 250.634168 -67.578339) (xy 250.686466 -67.593691) (xy 250.736046 -67.61633)
			(xy 250.7819 -67.645795) (xy 250.823093 -67.681486) (xy 250.858787 -67.722676) (xy 250.888255 -67.768527)
			(xy 250.910898 -67.818106) (xy 250.926254 -67.870402) (xy 250.934011 -67.924352) (xy 250.934474 -67.951604)
			(xy 250.934017 -67.978975) (xy 250.926198 -68.033154) (xy 250.910707 -68.085658) (xy 250.887863 -68.135405)
			(xy 250.858136 -68.181371) (xy 250.840494 -68.202302) (xy 250.84024 -68.202556) (xy 250.834659 -68.209646)
			(xy 250.82841 -68.22656) (xy 250.828048 -68.235576) (xy 250.828048 -68.302632) (xy 250.828379 -68.311652)
			(xy 250.834643 -68.328569) (xy 250.84024 -68.335652) (xy 250.840494 -68.335652) (xy 250.840494 -68.335906)
			(xy 250.858148 -68.356826) (xy 250.887858 -68.402802) (xy 250.910691 -68.452552) (xy 250.926179 -68.505056)
			(xy 250.934002 -68.559234) (xy 250.934474 -68.586604) (xy 250.934048 -68.613858) (xy 250.92629 -68.667813)
			(xy 250.910932 -68.720113) (xy 250.894299 -68.75653) (xy 254.370332 -68.75653) (xy 254.370808 -68.72916)
			(xy 254.378622 -68.674981) (xy 254.394108 -68.622478) (xy 254.416948 -68.572731) (xy 254.446671 -68.526764)
			(xy 254.464312 -68.505832) (xy 254.464566 -68.505578) (xy 254.470176 -68.498508) (xy 254.476407 -68.481578)
			(xy 254.476758 -68.472558) (xy 254.476758 -68.405502) (xy 254.476409 -68.396484) (xy 254.470157 -68.379567)
			(xy 254.464566 -68.372482) (xy 254.464312 -68.372482) (xy 254.464312 -68.372228) (xy 254.446674 -68.351295)
			(xy 254.416962 -68.305322) (xy 254.394126 -68.255575) (xy 254.378634 -68.203075) (xy 254.370806 -68.148899)
			(xy 254.370332 -68.12153) (xy 254.370783 -68.094276) (xy 254.378537 -68.040323) (xy 254.393892 -67.988022)
			(xy 254.416533 -67.938439) (xy 254.446002 -67.892584) (xy 254.481697 -67.85139) (xy 254.522892 -67.815696)
			(xy 254.568748 -67.786229) (xy 254.618331 -67.763588) (xy 254.670632 -67.748235) (xy 254.724586 -67.740483)
			(xy 254.75184 -67.740022) (xy 254.779209 -67.740518) (xy 254.833387 -67.748328) (xy 254.88589 -67.76381)
			(xy 254.935638 -67.786645) (xy 254.981606 -67.816363) (xy 255.002538 -67.834002) (xy 255.002792 -67.834256)
			(xy 255.009872 -67.839852) (xy 255.026794 -67.846092) (xy 255.035812 -67.846448) (xy 255.102868 -67.846448)
			(xy 255.111885 -67.846087) (xy 255.128802 -67.839843) (xy 255.135888 -67.834256) (xy 255.135888 -67.834002)
			(xy 255.136142 -67.834002) (xy 255.157085 -67.816377) (xy 255.203055 -67.786663) (xy 255.2528 -67.763824)
			(xy 255.305298 -67.74833) (xy 255.359472 -67.740498) (xy 255.38684 -67.740022) (xy 255.413155 -67.740456)
			(xy 255.465285 -67.747696) (xy 255.515929 -67.762022) (xy 255.564128 -67.78316) (xy 255.608971 -67.810713)
			(xy 255.649609 -67.844158) (xy 255.667764 -67.863212) (xy 255.675295 -67.870602) (xy 255.694568 -67.879133)
			(xy 255.705102 -67.879722) (xy 255.779778 -67.879722) (xy 255.790327 -67.879188) (xy 255.809622 -67.870655)
			(xy 255.817116 -67.863212) (xy 255.835273 -67.844158) (xy 255.875902 -67.8107) (xy 255.920742 -67.783141)
			(xy 255.968943 -67.762002) (xy 256.01959 -67.747685) (xy 256.071724 -67.74046) (xy 256.09804 -67.740022)
			(xy 256.125294 -67.740441) (xy 256.179245 -67.748203) (xy 256.231543 -67.763565) (xy 256.281122 -67.786213)
			(xy 256.326974 -67.815686) (xy 256.368165 -67.851385) (xy 256.403856 -67.892582) (xy 256.43332 -67.938439)
			(xy 256.455959 -67.988023) (xy 256.471311 -68.040323) (xy 256.479064 -68.094276) (xy 256.479548 -68.12153)
			(xy 256.479112 -68.148901) (xy 256.471289 -68.203082) (xy 256.455794 -68.255586) (xy 256.432945 -68.305333)
			(xy 256.403213 -68.351298) (xy 256.385568 -68.372228) (xy 256.385314 -68.372482) (xy 256.37973 -68.379571)
			(xy 256.373481 -68.396486) (xy 256.373122 -68.405502) (xy 256.373122 -68.472558) (xy 256.373494 -68.481573)
			(xy 256.379731 -68.498491) (xy 256.385314 -68.505578) (xy 256.385568 -68.505578) (xy 256.385568 -68.505832)
			(xy 256.403184 -68.526783) (xy 256.4329 -68.57275) (xy 256.455741 -68.622493) (xy 256.471238 -68.674989)
			(xy 256.479071 -68.729162) (xy 256.479548 -68.75653) (xy 256.47905 -68.78378) (xy 256.471291 -68.837725)
			(xy 256.455934 -68.890017) (xy 256.433292 -68.939592) (xy 256.403826 -68.98544) (xy 256.368136 -69.026629)
			(xy 256.326948 -69.06232) (xy 256.281101 -69.091787) (xy 256.231527 -69.11443) (xy 256.179235 -69.129789)
			(xy 256.12529 -69.13755) (xy 256.09804 -69.138038) (xy 256.071724 -69.13763) (xy 256.019592 -69.130386)
			(xy 255.968947 -69.116057) (xy 255.920748 -69.094913) (xy 255.875906 -69.067355) (xy 255.83527 -69.033905)
			(xy 255.817116 -69.014848) (xy 255.809584 -69.007459) (xy 255.790312 -68.998926) (xy 255.779778 -68.998338)
			(xy 255.705102 -68.998338) (xy 255.694549 -68.998843) (xy 255.675253 -69.007394) (xy 255.667764 -69.014848)
			(xy 255.649628 -69.033923) (xy 255.608993 -69.067377) (xy 255.564148 -69.094932) (xy 255.515944 -69.116067)
			(xy 255.465294 -69.13038) (xy 255.413157 -69.137601) (xy 255.38684 -69.138038) (xy 255.35947 -69.137564)
			(xy 255.305291 -69.12975) (xy 255.252787 -69.114264) (xy 255.20304 -69.091424) (xy 255.157073 -69.061699)
			(xy 255.136142 -69.044058) (xy 255.135888 -69.043804) (xy 255.128809 -69.038207) (xy 255.111886 -69.031966)
			(xy 255.102868 -69.031612) (xy 255.035812 -69.031612) (xy 255.026795 -69.031972) (xy 255.009878 -69.038217)
			(xy 255.002792 -69.043804) (xy 255.002792 -69.044058) (xy 255.002538 -69.044058) (xy 254.981597 -69.061686)
			(xy 254.935627 -69.091401) (xy 254.885882 -69.11424) (xy 254.833383 -69.129733) (xy 254.779209 -69.137563)
			(xy 254.75184 -69.138038) (xy 254.724589 -69.137508) (xy 254.670643 -69.129757) (xy 254.618348 -69.114407)
			(xy 254.56877 -69.091772) (xy 254.522918 -69.062311) (xy 254.481726 -69.026624) (xy 254.446031 -68.985438)
			(xy 254.416562 -68.939592) (xy 254.393917 -68.890018) (xy 254.378558 -68.837726) (xy 254.370797 -68.78378)
			(xy 254.370332 -68.75653) (xy 250.894299 -68.75653) (xy 250.888286 -68.769696) (xy 250.858815 -68.81555)
			(xy 250.823117 -68.856744) (xy 250.78192 -68.892437) (xy 250.736062 -68.921904) (xy 250.686478 -68.944545)
			(xy 250.634175 -68.959898) (xy 250.580221 -68.967651) (xy 250.552966 -68.968112) (xy 250.525595 -68.967663)
			(xy 250.471416 -68.959841) (xy 250.418912 -68.944347) (xy 250.369166 -68.921502) (xy 250.323199 -68.891774)
			(xy 250.302268 -68.874132) (xy 250.302014 -68.873878) (xy 250.294929 -68.868289) (xy 250.278011 -68.862044)
			(xy 250.268994 -68.861686) (xy 250.201938 -68.861686) (xy 250.192923 -68.862064) (xy 250.176006 -68.868297)
			(xy 250.168918 -68.873878) (xy 250.168918 -68.874132) (xy 250.168664 -68.874132) (xy 250.147723 -68.89176)
			(xy 250.101752 -68.921472) (xy 250.052007 -68.94431) (xy 249.999508 -68.959804) (xy 249.945334 -68.967636)
			(xy 249.917966 -68.968112) (xy 249.891651 -68.967663) (xy 249.839522 -68.960424) (xy 249.788879 -68.946101)
			(xy 249.740681 -68.924965) (xy 249.695837 -68.897416) (xy 249.655198 -68.863975) (xy 249.637042 -68.844922)
			(xy 249.629504 -68.83754) (xy 249.610236 -68.829004) (xy 249.599704 -68.828412) (xy 249.525028 -68.828412)
			(xy 249.514478 -68.828939) (xy 249.495182 -68.837475) (xy 249.48769 -68.844922) (xy 249.469537 -68.86398)
			(xy 249.428906 -68.897436) (xy 249.384065 -68.924994) (xy 249.335864 -68.946132) (xy 249.285216 -68.960449)
			(xy 249.233082 -68.967673) (xy 249.206766 -68.968112) (xy 249.179514 -68.967654) (xy 249.125566 -68.959893)
			(xy 249.073271 -68.944534) (xy 249.023693 -68.921889) (xy 248.977843 -68.892419) (xy 248.936654 -68.856725)
			(xy 248.900963 -68.815532) (xy 248.871497 -68.76968) (xy 248.848856 -68.720101) (xy 248.833501 -68.667805)
			(xy 248.825744 -68.613856) (xy 248.825258 -68.586604) (xy 245.596156 -68.586604) (xy 245.596156 -71.555864)
			(xy 251.394466 -71.555864) (xy 251.398537 -71.500242) (xy 251.410663 -71.445805) (xy 251.430586 -71.393714)
			(xy 251.457882 -71.345079) (xy 251.491968 -71.300936) (xy 251.532117 -71.262227) (xy 251.577475 -71.229776)
			(xy 251.627075 -71.204275) (xy 251.679859 -71.186268) (xy 251.734702 -71.176138) (xy 251.790436 -71.174101)
			(xy 251.845873 -71.180201) (xy 251.89983 -71.194307) (xy 251.951159 -71.216119) (xy 251.998765 -71.245173)
			(xy 252.041633 -71.280848) (xy 252.07885 -71.322385) (xy 252.109623 -71.368898) (xy 252.133295 -71.419395)
			(xy 252.149363 -71.472802) (xy 252.157483 -71.527978) (xy 252.157992 -71.555864) (xy 252.157483 -71.58375)
			(xy 252.151644 -71.623428) (xy 252.90348 -71.623428) (xy 252.907551 -71.567806) (xy 252.919677 -71.513369)
			(xy 252.9396 -71.461278) (xy 252.966896 -71.412643) (xy 253.000982 -71.3685) (xy 253.041131 -71.329791)
			(xy 253.086489 -71.29734) (xy 253.136089 -71.271839) (xy 253.188873 -71.253832) (xy 253.243716 -71.243702)
			(xy 253.29945 -71.241665) (xy 253.354887 -71.247765) (xy 253.408844 -71.261871) (xy 253.460173 -71.283683)
			(xy 253.507779 -71.312737) (xy 253.550647 -71.348412) (xy 253.587864 -71.389949) (xy 253.618637 -71.436462)
			(xy 253.642309 -71.486959) (xy 253.658377 -71.540366) (xy 253.666497 -71.595542) (xy 253.667006 -71.623428)
			(xy 253.666497 -71.651314) (xy 253.658377 -71.70649) (xy 253.642309 -71.759897) (xy 253.618637 -71.810394)
			(xy 253.587864 -71.856907) (xy 253.550647 -71.898444) (xy 253.507779 -71.934119) (xy 253.460173 -71.963173)
			(xy 253.408844 -71.984985) (xy 253.354887 -71.999091) (xy 253.29945 -72.005191) (xy 253.243716 -72.003154)
			(xy 253.188873 -71.993024) (xy 253.136089 -71.975017) (xy 253.086489 -71.949516) (xy 253.041131 -71.917065)
			(xy 253.000982 -71.878356) (xy 252.966896 -71.834213) (xy 252.9396 -71.785578) (xy 252.919677 -71.733487)
			(xy 252.907551 -71.67905) (xy 252.90348 -71.623428) (xy 252.151644 -71.623428) (xy 252.149363 -71.638926)
			(xy 252.133295 -71.692333) (xy 252.109623 -71.74283) (xy 252.07885 -71.789343) (xy 252.041633 -71.83088)
			(xy 251.998765 -71.866555) (xy 251.951159 -71.895609) (xy 251.89983 -71.917421) (xy 251.845873 -71.931527)
			(xy 251.790436 -71.937627) (xy 251.734702 -71.93559) (xy 251.679859 -71.92546) (xy 251.627075 -71.907453)
			(xy 251.577475 -71.881952) (xy 251.532117 -71.849501) (xy 251.491968 -71.810792) (xy 251.457882 -71.766649)
			(xy 251.430586 -71.718014) (xy 251.410663 -71.665923) (xy 251.398537 -71.611486) (xy 251.394466 -71.555864)
			(xy 245.596156 -71.555864) (xy 245.596156 -73.726548) (xy 259.359398 -73.726548) (xy 259.363469 -73.670926)
			(xy 259.375595 -73.616489) (xy 259.395518 -73.564398) (xy 259.422814 -73.515763) (xy 259.4569 -73.47162)
			(xy 259.497049 -73.432911) (xy 259.542407 -73.40046) (xy 259.592007 -73.374959) (xy 259.644791 -73.356952)
			(xy 259.699634 -73.346822) (xy 259.755368 -73.344785) (xy 259.810805 -73.350885) (xy 259.864762 -73.364991)
			(xy 259.916091 -73.386803) (xy 259.963697 -73.415857) (xy 260.006565 -73.451532) (xy 260.043782 -73.493069)
			(xy 260.060118 -73.51776) (xy 260.530846 -73.51776) (xy 260.534917 -73.462138) (xy 260.547043 -73.407701)
			(xy 260.566966 -73.35561) (xy 260.594262 -73.306975) (xy 260.628348 -73.262832) (xy 260.668497 -73.224123)
			(xy 260.713855 -73.191672) (xy 260.763455 -73.166171) (xy 260.816239 -73.148164) (xy 260.871082 -73.138034)
			(xy 260.926816 -73.135997) (xy 260.982253 -73.142097) (xy 261.03621 -73.156203) (xy 261.087539 -73.178015)
			(xy 261.135145 -73.207069) (xy 261.178013 -73.242744) (xy 261.21523 -73.284281) (xy 261.246003 -73.330794)
			(xy 261.269675 -73.381291) (xy 261.285743 -73.434698) (xy 261.293863 -73.489874) (xy 261.294372 -73.51776)
			(xy 261.293863 -73.545646) (xy 261.285743 -73.600822) (xy 261.269675 -73.654229) (xy 261.246003 -73.704726)
			(xy 261.21523 -73.751239) (xy 261.178013 -73.792776) (xy 261.135145 -73.828451) (xy 261.087539 -73.857505)
			(xy 261.03621 -73.879317) (xy 260.982253 -73.893423) (xy 260.926816 -73.899523) (xy 260.871082 -73.897486)
			(xy 260.816239 -73.887356) (xy 260.763455 -73.869349) (xy 260.713855 -73.843848) (xy 260.668497 -73.811397)
			(xy 260.628348 -73.772688) (xy 260.594262 -73.728545) (xy 260.566966 -73.67991) (xy 260.547043 -73.627819)
			(xy 260.534917 -73.573382) (xy 260.530846 -73.51776) (xy 260.060118 -73.51776) (xy 260.074555 -73.539582)
			(xy 260.098227 -73.590079) (xy 260.114295 -73.643486) (xy 260.122415 -73.698662) (xy 260.122924 -73.726548)
			(xy 260.122415 -73.754434) (xy 260.114295 -73.80961) (xy 260.098227 -73.863017) (xy 260.074555 -73.913514)
			(xy 260.043782 -73.960027) (xy 260.006565 -74.001564) (xy 259.963697 -74.037239) (xy 259.916091 -74.066293)
			(xy 259.864762 -74.088105) (xy 259.810805 -74.102211) (xy 259.755368 -74.108311) (xy 259.699634 -74.106274)
			(xy 259.644791 -74.096144) (xy 259.592007 -74.078137) (xy 259.542407 -74.052636) (xy 259.497049 -74.020185)
			(xy 259.4569 -73.981476) (xy 259.422814 -73.937333) (xy 259.395518 -73.888698) (xy 259.375595 -73.836607)
			(xy 259.363469 -73.78217) (xy 259.359398 -73.726548) (xy 245.596156 -73.726548) (xy 245.596156 -75.288385)
			(xy 262.150829 -75.288385) (xy 262.150829 -75.228415) (xy 262.158657 -75.168959) (xy 262.174178 -75.111033)
			(xy 262.197128 -75.055628) (xy 262.227114 -75.003693) (xy 262.263621 -74.956116) (xy 262.306027 -74.913712)
			(xy 262.353605 -74.877206) (xy 262.405541 -74.847222) (xy 262.460946 -74.824274) (xy 262.518872 -74.808754)
			(xy 262.578329 -74.800928) (xy 262.608314 -74.80046) (xy 263.471914 -74.80046) (xy 263.501899 -74.800907)
			(xy 263.561356 -74.808736) (xy 263.619283 -74.824259) (xy 263.674687 -74.84721) (xy 263.726623 -74.877196)
			(xy 263.7742 -74.913705) (xy 263.816604 -74.956111) (xy 263.853111 -75.003689) (xy 263.883096 -75.055625)
			(xy 263.906045 -75.111031) (xy 263.921566 -75.168958) (xy 263.929394 -75.228415) (xy 263.929394 -75.288385)
			(xy 263.921566 -75.347842) (xy 263.906045 -75.405769) (xy 263.883096 -75.461175) (xy 263.853111 -75.513111)
			(xy 263.816604 -75.560689) (xy 263.7742 -75.603095) (xy 263.726623 -75.639604) (xy 263.674687 -75.66959)
			(xy 263.619283 -75.692541) (xy 263.561356 -75.708064) (xy 263.501899 -75.715893) (xy 263.471914 -75.716384)
			(xy 262.608314 -75.716384) (xy 262.578329 -75.715872) (xy 262.518872 -75.708046) (xy 262.460946 -75.692526)
			(xy 262.405541 -75.669578) (xy 262.353605 -75.639594) (xy 262.306027 -75.603088) (xy 262.263621 -75.560684)
			(xy 262.227114 -75.513107) (xy 262.197128 -75.461172) (xy 262.174178 -75.405767) (xy 262.158657 -75.347841)
			(xy 262.150829 -75.288385) (xy 245.596156 -75.288385) (xy 245.596156 -76.270104) (xy 253.795274 -76.270104)
			(xy 253.799345 -76.214482) (xy 253.811471 -76.160045) (xy 253.831394 -76.107954) (xy 253.85869 -76.059319)
			(xy 253.892776 -76.015176) (xy 253.932925 -75.976467) (xy 253.978283 -75.944016) (xy 254.027883 -75.918515)
			(xy 254.080667 -75.900508) (xy 254.13551 -75.890378) (xy 254.191244 -75.888341) (xy 254.246681 -75.894441)
			(xy 254.300638 -75.908547) (xy 254.351967 -75.930359) (xy 254.399573 -75.959413) (xy 254.442441 -75.995088)
			(xy 254.479658 -76.036625) (xy 254.510431 -76.083138) (xy 254.534103 -76.133635) (xy 254.550171 -76.187042)
			(xy 254.558291 -76.242218) (xy 254.5588 -76.270104) (xy 256.827272 -76.270104) (xy 256.831343 -76.214482)
			(xy 256.843469 -76.160045) (xy 256.863392 -76.107954) (xy 256.890688 -76.059319) (xy 256.924774 -76.015176)
			(xy 256.964923 -75.976467) (xy 257.010281 -75.944016) (xy 257.059881 -75.918515) (xy 257.112665 -75.900508)
			(xy 257.167508 -75.890378) (xy 257.223242 -75.888341) (xy 257.278679 -75.894441) (xy 257.332636 -75.908547)
			(xy 257.383965 -75.930359) (xy 257.431571 -75.959413) (xy 257.474439 -75.995088) (xy 257.511656 -76.036625)
			(xy 257.542429 -76.083138) (xy 257.566101 -76.133635) (xy 257.582169 -76.187042) (xy 257.590289 -76.242218)
			(xy 257.590798 -76.270104) (xy 257.843272 -76.270104) (xy 257.847343 -76.214482) (xy 257.859469 -76.160045)
			(xy 257.879392 -76.107954) (xy 257.906688 -76.059319) (xy 257.940774 -76.015176) (xy 257.980923 -75.976467)
			(xy 258.026281 -75.944016) (xy 258.075881 -75.918515) (xy 258.128665 -75.900508) (xy 258.183508 -75.890378)
			(xy 258.239242 -75.888341) (xy 258.294679 -75.894441) (xy 258.348636 -75.908547) (xy 258.399965 -75.930359)
			(xy 258.447571 -75.959413) (xy 258.490439 -75.995088) (xy 258.527656 -76.036625) (xy 258.558429 -76.083138)
			(xy 258.582101 -76.133635) (xy 258.598169 -76.187042) (xy 258.606289 -76.242218) (xy 258.606798 -76.270104)
			(xy 258.859272 -76.270104) (xy 258.863343 -76.214482) (xy 258.875469 -76.160045) (xy 258.895392 -76.107954)
			(xy 258.922688 -76.059319) (xy 258.956774 -76.015176) (xy 258.996923 -75.976467) (xy 259.042281 -75.944016)
			(xy 259.091881 -75.918515) (xy 259.144665 -75.900508) (xy 259.199508 -75.890378) (xy 259.255242 -75.888341)
			(xy 259.310679 -75.894441) (xy 259.364636 -75.908547) (xy 259.415965 -75.930359) (xy 259.463571 -75.959413)
			(xy 259.506439 -75.995088) (xy 259.543656 -76.036625) (xy 259.574429 -76.083138) (xy 259.598101 -76.133635)
			(xy 259.614169 -76.187042) (xy 259.622289 -76.242218) (xy 259.622798 -76.270104) (xy 260.158228 -76.270104)
			(xy 260.162299 -76.214482) (xy 260.174425 -76.160045) (xy 260.194348 -76.107954) (xy 260.221644 -76.059319)
			(xy 260.25573 -76.015176) (xy 260.295879 -75.976467) (xy 260.341237 -75.944016) (xy 260.390837 -75.918515)
			(xy 260.443621 -75.900508) (xy 260.498464 -75.890378) (xy 260.554198 -75.888341) (xy 260.609635 -75.894441)
			(xy 260.663592 -75.908547) (xy 260.714921 -75.930359) (xy 260.762527 -75.959413) (xy 260.805395 -75.995088)
			(xy 260.842612 -76.036625) (xy 260.873385 -76.083138) (xy 260.897057 -76.133635) (xy 260.913125 -76.187042)
			(xy 260.920303 -76.235814) (xy 261.146288 -76.235814) (xy 261.150359 -76.180192) (xy 261.162485 -76.125755)
			(xy 261.182408 -76.073664) (xy 261.209704 -76.025029) (xy 261.24379 -75.980886) (xy 261.283939 -75.942177)
			(xy 261.329297 -75.909726) (xy 261.378897 -75.884225) (xy 261.431681 -75.866218) (xy 261.486524 -75.856088)
			(xy 261.542258 -75.854051) (xy 261.597695 -75.860151) (xy 261.651652 -75.874257) (xy 261.702981 -75.896069)
			(xy 261.750587 -75.925123) (xy 261.793455 -75.960798) (xy 261.830672 -76.002335) (xy 261.861445 -76.048848)
			(xy 261.885117 -76.099345) (xy 261.901185 -76.152752) (xy 261.909305 -76.207928) (xy 261.909591 -76.223622)
			(xy 265.213082 -76.223622) (xy 265.217153 -76.168) (xy 265.229279 -76.113563) (xy 265.249202 -76.061472)
			(xy 265.276498 -76.012837) (xy 265.310584 -75.968694) (xy 265.350733 -75.929985) (xy 265.396091 -75.897534)
			(xy 265.445691 -75.872033) (xy 265.498475 -75.854026) (xy 265.553318 -75.843896) (xy 265.609052 -75.841859)
			(xy 265.664489 -75.847959) (xy 265.718446 -75.862065) (xy 265.769775 -75.883877) (xy 265.817381 -75.912931)
			(xy 265.860249 -75.948606) (xy 265.897466 -75.990143) (xy 265.928239 -76.036656) (xy 265.951911 -76.087153)
			(xy 265.967979 -76.14056) (xy 265.976099 -76.195736) (xy 265.976608 -76.223622) (xy 265.976099 -76.251508)
			(xy 265.967979 -76.306684) (xy 265.951911 -76.360091) (xy 265.928239 -76.410588) (xy 265.897466 -76.457101)
			(xy 265.860249 -76.498638) (xy 265.817381 -76.534313) (xy 265.769775 -76.563367) (xy 265.718446 -76.585179)
			(xy 265.664489 -76.599285) (xy 265.609052 -76.605385) (xy 265.553318 -76.603348) (xy 265.498475 -76.593218)
			(xy 265.445691 -76.575211) (xy 265.396091 -76.54971) (xy 265.350733 -76.517259) (xy 265.310584 -76.47855)
			(xy 265.276498 -76.434407) (xy 265.249202 -76.385772) (xy 265.229279 -76.333681) (xy 265.217153 -76.279244)
			(xy 265.213082 -76.223622) (xy 261.909591 -76.223622) (xy 261.909814 -76.235814) (xy 261.909305 -76.2637)
			(xy 261.901185 -76.318876) (xy 261.885117 -76.372283) (xy 261.861445 -76.42278) (xy 261.830672 -76.469293)
			(xy 261.793455 -76.51083) (xy 261.750587 -76.546505) (xy 261.702981 -76.575559) (xy 261.651652 -76.597371)
			(xy 261.597695 -76.611477) (xy 261.542258 -76.617577) (xy 261.486524 -76.61554) (xy 261.431681 -76.60541)
			(xy 261.378897 -76.587403) (xy 261.329297 -76.561902) (xy 261.283939 -76.529451) (xy 261.24379 -76.490742)
			(xy 261.209704 -76.446599) (xy 261.182408 -76.397964) (xy 261.162485 -76.345873) (xy 261.150359 -76.291436)
			(xy 261.146288 -76.235814) (xy 260.920303 -76.235814) (xy 260.921245 -76.242218) (xy 260.921754 -76.270104)
			(xy 260.921245 -76.29799) (xy 260.913125 -76.353166) (xy 260.897057 -76.406573) (xy 260.873385 -76.45707)
			(xy 260.842612 -76.503583) (xy 260.805395 -76.54512) (xy 260.762527 -76.580795) (xy 260.714921 -76.609849)
			(xy 260.663592 -76.631661) (xy 260.609635 -76.645767) (xy 260.554198 -76.651867) (xy 260.498464 -76.64983)
			(xy 260.443621 -76.6397) (xy 260.390837 -76.621693) (xy 260.341237 -76.596192) (xy 260.295879 -76.563741)
			(xy 260.25573 -76.525032) (xy 260.221644 -76.480889) (xy 260.194348 -76.432254) (xy 260.174425 -76.380163)
			(xy 260.162299 -76.325726) (xy 260.158228 -76.270104) (xy 259.622798 -76.270104) (xy 259.622289 -76.29799)
			(xy 259.614169 -76.353166) (xy 259.598101 -76.406573) (xy 259.574429 -76.45707) (xy 259.543656 -76.503583)
			(xy 259.506439 -76.54512) (xy 259.463571 -76.580795) (xy 259.415965 -76.609849) (xy 259.364636 -76.631661)
			(xy 259.310679 -76.645767) (xy 259.255242 -76.651867) (xy 259.199508 -76.64983) (xy 259.144665 -76.6397)
			(xy 259.091881 -76.621693) (xy 259.042281 -76.596192) (xy 258.996923 -76.563741) (xy 258.956774 -76.525032)
			(xy 258.922688 -76.480889) (xy 258.895392 -76.432254) (xy 258.875469 -76.380163) (xy 258.863343 -76.325726)
			(xy 258.859272 -76.270104) (xy 258.606798 -76.270104) (xy 258.606289 -76.29799) (xy 258.598169 -76.353166)
			(xy 258.582101 -76.406573) (xy 258.558429 -76.45707) (xy 258.527656 -76.503583) (xy 258.490439 -76.54512)
			(xy 258.447571 -76.580795) (xy 258.399965 -76.609849) (xy 258.348636 -76.631661) (xy 258.294679 -76.645767)
			(xy 258.239242 -76.651867) (xy 258.183508 -76.64983) (xy 258.128665 -76.6397) (xy 258.075881 -76.621693)
			(xy 258.026281 -76.596192) (xy 257.980923 -76.563741) (xy 257.940774 -76.525032) (xy 257.906688 -76.480889)
			(xy 257.879392 -76.432254) (xy 257.859469 -76.380163) (xy 257.847343 -76.325726) (xy 257.843272 -76.270104)
			(xy 257.590798 -76.270104) (xy 257.590289 -76.29799) (xy 257.582169 -76.353166) (xy 257.566101 -76.406573)
			(xy 257.542429 -76.45707) (xy 257.511656 -76.503583) (xy 257.474439 -76.54512) (xy 257.431571 -76.580795)
			(xy 257.383965 -76.609849) (xy 257.332636 -76.631661) (xy 257.278679 -76.645767) (xy 257.223242 -76.651867)
			(xy 257.167508 -76.64983) (xy 257.112665 -76.6397) (xy 257.059881 -76.621693) (xy 257.010281 -76.596192)
			(xy 256.964923 -76.563741) (xy 256.924774 -76.525032) (xy 256.890688 -76.480889) (xy 256.863392 -76.432254)
			(xy 256.843469 -76.380163) (xy 256.831343 -76.325726) (xy 256.827272 -76.270104) (xy 254.5588 -76.270104)
			(xy 254.558291 -76.29799) (xy 254.550171 -76.353166) (xy 254.534103 -76.406573) (xy 254.510431 -76.45707)
			(xy 254.479658 -76.503583) (xy 254.442441 -76.54512) (xy 254.399573 -76.580795) (xy 254.351967 -76.609849)
			(xy 254.300638 -76.631661) (xy 254.246681 -76.645767) (xy 254.191244 -76.651867) (xy 254.13551 -76.64983)
			(xy 254.080667 -76.6397) (xy 254.027883 -76.621693) (xy 253.978283 -76.596192) (xy 253.932925 -76.563741)
			(xy 253.892776 -76.525032) (xy 253.85869 -76.480889) (xy 253.831394 -76.432254) (xy 253.811471 -76.380163)
			(xy 253.799345 -76.325726) (xy 253.795274 -76.270104) (xy 245.596156 -76.270104) (xy 245.596156 -78.643226)
			(xy 254.273302 -78.643226) (xy 254.277373 -78.587604) (xy 254.289499 -78.533167) (xy 254.309422 -78.481076)
			(xy 254.336718 -78.432441) (xy 254.370804 -78.388298) (xy 254.410953 -78.349589) (xy 254.456311 -78.317138)
			(xy 254.505911 -78.291637) (xy 254.558695 -78.27363) (xy 254.613538 -78.2635) (xy 254.669272 -78.261463)
			(xy 254.724709 -78.267563) (xy 254.778666 -78.281669) (xy 254.829995 -78.303481) (xy 254.877601 -78.332535)
			(xy 254.920469 -78.36821) (xy 254.957686 -78.409747) (xy 254.988459 -78.45626) (xy 255.012131 -78.506757)
			(xy 255.028199 -78.560164) (xy 255.036319 -78.61534) (xy 255.036828 -78.643226) (xy 255.036319 -78.671112)
			(xy 255.028199 -78.726288) (xy 255.012131 -78.779695) (xy 254.988459 -78.830192) (xy 254.957686 -78.876705)
			(xy 254.920469 -78.918242) (xy 254.877601 -78.953917) (xy 254.829995 -78.982971) (xy 254.778666 -79.004783)
			(xy 254.724709 -79.018889) (xy 254.669272 -79.024989) (xy 254.613538 -79.022952) (xy 254.558695 -79.012822)
			(xy 254.505911 -78.994815) (xy 254.456311 -78.969314) (xy 254.410953 -78.936863) (xy 254.370804 -78.898154)
			(xy 254.336718 -78.854011) (xy 254.309422 -78.805376) (xy 254.289499 -78.753285) (xy 254.277373 -78.698848)
			(xy 254.273302 -78.643226) (xy 245.596156 -78.643226) (xy 245.596156 -79.779368) (xy 250.4473 -79.779368)
			(xy 250.451371 -79.723746) (xy 250.463497 -79.669309) (xy 250.48342 -79.617218) (xy 250.510716 -79.568583)
			(xy 250.544802 -79.52444) (xy 250.584951 -79.485731) (xy 250.630309 -79.45328) (xy 250.679909 -79.427779)
			(xy 250.732693 -79.409772) (xy 250.787536 -79.399642) (xy 250.84327 -79.397605) (xy 250.898707 -79.403705)
			(xy 250.952664 -79.417811) (xy 251.003993 -79.439623) (xy 251.051599 -79.468677) (xy 251.094467 -79.504352)
			(xy 251.131684 -79.545889) (xy 251.162457 -79.592402) (xy 251.186129 -79.642899) (xy 251.202197 -79.696306)
			(xy 251.210317 -79.751482) (xy 251.210826 -79.779368) (xy 251.210317 -79.807254) (xy 251.202197 -79.86243)
			(xy 251.186129 -79.915837) (xy 251.162457 -79.966334) (xy 251.131684 -80.012847) (xy 251.094467 -80.054384)
			(xy 251.051599 -80.090059) (xy 251.003993 -80.119113) (xy 250.952664 -80.140925) (xy 250.898707 -80.155031)
			(xy 250.84327 -80.161131) (xy 250.787536 -80.159094) (xy 250.732693 -80.148964) (xy 250.679909 -80.130957)
			(xy 250.630309 -80.105456) (xy 250.584951 -80.073005) (xy 250.544802 -80.034296) (xy 250.510716 -79.990153)
			(xy 250.48342 -79.941518) (xy 250.463497 -79.889427) (xy 250.451371 -79.83499) (xy 250.4473 -79.779368)
			(xy 245.596156 -79.779368) (xy 245.596156 -80.81645) (xy 251.98019 -80.81645) (xy 251.984261 -80.760828)
			(xy 251.996387 -80.706391) (xy 252.01631 -80.6543) (xy 252.043606 -80.605665) (xy 252.077692 -80.561522)
			(xy 252.117841 -80.522813) (xy 252.163199 -80.490362) (xy 252.212799 -80.464861) (xy 252.265583 -80.446854)
			(xy 252.320426 -80.436724) (xy 252.37616 -80.434687) (xy 252.431597 -80.440787) (xy 252.485554 -80.454893)
			(xy 252.536883 -80.476705) (xy 252.584489 -80.505759) (xy 252.627357 -80.541434) (xy 252.664574 -80.582971)
			(xy 252.695347 -80.629484) (xy 252.719019 -80.679981) (xy 252.735087 -80.733388) (xy 252.740994 -80.773524)
			(xy 253.898652 -80.773524) (xy 253.902723 -80.717902) (xy 253.914849 -80.663465) (xy 253.934772 -80.611374)
			(xy 253.962068 -80.562739) (xy 253.996154 -80.518596) (xy 254.036303 -80.479887) (xy 254.081661 -80.447436)
			(xy 254.131261 -80.421935) (xy 254.184045 -80.403928) (xy 254.238888 -80.393798) (xy 254.294622 -80.391761)
			(xy 254.350059 -80.397861) (xy 254.404016 -80.411967) (xy 254.455345 -80.433779) (xy 254.502951 -80.462833)
			(xy 254.545819 -80.498508) (xy 254.583036 -80.540045) (xy 254.613809 -80.586558) (xy 254.637481 -80.637055)
			(xy 254.653549 -80.690462) (xy 254.661669 -80.745638) (xy 254.662178 -80.773524) (xy 254.661669 -80.80141)
			(xy 254.653549 -80.856586) (xy 254.637481 -80.909993) (xy 254.613809 -80.96049) (xy 254.583036 -81.007003)
			(xy 254.545819 -81.04854) (xy 254.502951 -81.084215) (xy 254.455345 -81.113269) (xy 254.404016 -81.135081)
			(xy 254.350059 -81.149187) (xy 254.294622 -81.155287) (xy 254.238888 -81.15325) (xy 254.184045 -81.14312)
			(xy 254.131261 -81.125113) (xy 254.081661 -81.099612) (xy 254.036303 -81.067161) (xy 253.996154 -81.028452)
			(xy 253.962068 -80.984309) (xy 253.934772 -80.935674) (xy 253.914849 -80.883583) (xy 253.902723 -80.829146)
			(xy 253.898652 -80.773524) (xy 252.740994 -80.773524) (xy 252.743207 -80.788564) (xy 252.743716 -80.81645)
			(xy 252.743207 -80.844336) (xy 252.735087 -80.899512) (xy 252.719019 -80.952919) (xy 252.695347 -81.003416)
			(xy 252.664574 -81.049929) (xy 252.627357 -81.091466) (xy 252.584489 -81.127141) (xy 252.536883 -81.156195)
			(xy 252.485554 -81.178007) (xy 252.431597 -81.192113) (xy 252.37616 -81.198213) (xy 252.320426 -81.196176)
			(xy 252.265583 -81.186046) (xy 252.212799 -81.168039) (xy 252.163199 -81.142538) (xy 252.117841 -81.110087)
			(xy 252.077692 -81.071378) (xy 252.043606 -81.027235) (xy 252.01631 -80.9786) (xy 251.996387 -80.926509)
			(xy 251.984261 -80.872072) (xy 251.98019 -80.81645) (xy 245.596156 -80.81645) (xy 245.596156 -84.320888)
			(xy 247.814082 -84.320888) (xy 247.818153 -84.265266) (xy 247.830279 -84.210829) (xy 247.850202 -84.158738)
			(xy 247.877498 -84.110103) (xy 247.911584 -84.06596) (xy 247.951733 -84.027251) (xy 247.997091 -83.9948)
			(xy 248.046691 -83.969299) (xy 248.099475 -83.951292) (xy 248.154318 -83.941162) (xy 248.210052 -83.939125)
			(xy 248.265489 -83.945225) (xy 248.319446 -83.959331) (xy 248.370775 -83.981143) (xy 248.418381 -84.010197)
			(xy 248.461249 -84.045872) (xy 248.498466 -84.087409) (xy 248.529239 -84.133922) (xy 248.552911 -84.184419)
			(xy 248.568979 -84.237826) (xy 248.577099 -84.293002) (xy 248.577608 -84.320888) (xy 248.577099 -84.348774)
			(xy 248.568979 -84.40395) (xy 248.552911 -84.457357) (xy 248.529239 -84.507854) (xy 248.498466 -84.554367)
			(xy 248.461249 -84.595904) (xy 248.418381 -84.631579) (xy 248.370775 -84.660633) (xy 248.319446 -84.682445)
			(xy 248.265489 -84.696551) (xy 248.210052 -84.702651) (xy 248.154318 -84.700614) (xy 248.099475 -84.690484)
			(xy 248.046691 -84.672477) (xy 247.997091 -84.646976) (xy 247.951733 -84.614525) (xy 247.911584 -84.575816)
			(xy 247.877498 -84.531673) (xy 247.850202 -84.483038) (xy 247.830279 -84.430947) (xy 247.818153 -84.37651)
			(xy 247.814082 -84.320888) (xy 245.596156 -84.320888) (xy 245.596156 -87.045292) (xy 245.596581 -87.054385)
			(xy 245.603028 -87.071393) (xy 245.615006 -87.085082) (xy 245.622826 -87.089742) (xy 245.627906 -87.091774)
			(xy 245.634938 -87.094499) (xy 245.649931 -87.096058) (xy 245.65737 -87.094822) (xy 245.663974 -87.093552)
			(xy 245.677182 -87.08644) (xy 246.31142 -86.451948) (xy 246.334973 -86.428999) (xy 246.386371 -86.387974)
			(xy 246.442041 -86.352965) (xy 246.501283 -86.324414) (xy 246.563351 -86.302679) (xy 246.627463 -86.288036)
			(xy 246.692812 -86.280667) (xy 246.725694 -86.280244) (xy 247.526048 -86.280244) (xy 247.561653 -86.280784)
			(xy 247.632336 -86.289442) (xy 247.667018 -86.297516) (xy 247.70588 -86.308692) (xy 247.729502 -86.316312)
			(xy 247.73469 -86.314435) (xy 247.744174 -86.308801) (xy 247.748298 -86.305136) (xy 247.748552 -86.304882)
			(xy 247.767094 -86.287102) (xy 247.81383 -86.242652) (xy 247.818159 -86.23802) (xy 247.824586 -86.227097)
			(xy 247.82653 -86.221062) (xy 247.828308 -86.214966) (xy 247.828562 -86.20125) (xy 247.826784 -86.194392)
			(xy 247.821083 -86.170929) (xy 247.814971 -86.123031) (xy 247.814592 -86.098888) (xy 247.815078 -86.071637)
			(xy 247.822834 -86.017689) (xy 247.838189 -85.965394) (xy 247.860831 -85.915817) (xy 247.890297 -85.869967)
			(xy 247.925988 -85.828776) (xy 247.967179 -85.793085) (xy 248.013029 -85.763619) (xy 248.062606 -85.740977)
			(xy 248.114901 -85.725622) (xy 248.168849 -85.717866) (xy 248.223351 -85.717866) (xy 248.277299 -85.725622)
			(xy 248.329594 -85.740977) (xy 248.379171 -85.763619) (xy 248.425021 -85.793085) (xy 248.466212 -85.828776)
			(xy 248.501903 -85.869967) (xy 248.531369 -85.915817) (xy 248.554011 -85.965394) (xy 248.569366 -86.017689)
			(xy 248.577122 -86.071637) (xy 248.577608 -86.098888) (xy 248.577163 -86.125686) (xy 248.569679 -86.178756)
			(xy 248.554844 -86.230257) (xy 248.532948 -86.279175) (xy 248.504423 -86.324549) (xy 248.46983 -86.365485)
			(xy 248.42985 -86.401178) (xy 248.385268 -86.430925) (xy 248.336963 -86.454143) (xy 248.285885 -86.470373)
			(xy 248.233038 -86.479296) (xy 248.20626 -86.480396) (xy 248.206006 -86.480396) (xy 248.199148 -86.48065)
			(xy 248.188734 -86.483698) (xy 248.1834 -86.485222) (xy 248.175018 -86.489794) (xy 248.17451 -86.490048)
			(xy 248.167219 -86.494112) (xy 248.155554 -86.506038) (xy 248.15165 -86.513416) (xy 248.132092 -86.561168)
			(xy 248.132092 -86.561676) (xy 248.117106 -86.598252) (xy 248.117106 -86.598506) (xy 248.115074 -86.603332)
			(xy 248.11355 -86.606888) (xy 248.113296 -86.612984) (xy 248.117106 -86.622636) (xy 248.119133 -86.627507)
			(xy 248.124893 -86.636345) (xy 248.128536 -86.640162) (xy 248.224548 -86.73592) (xy 248.247497 -86.759473)
			(xy 248.266204 -86.78291) (xy 249.4821 -86.78291) (xy 249.486171 -86.727288) (xy 249.498297 -86.672851)
			(xy 249.51822 -86.62076) (xy 249.545516 -86.572125) (xy 249.579602 -86.527982) (xy 249.619751 -86.489273)
			(xy 249.665109 -86.456822) (xy 249.714709 -86.431321) (xy 249.767493 -86.413314) (xy 249.822336 -86.403184)
			(xy 249.87807 -86.401147) (xy 249.933507 -86.407247) (xy 249.987464 -86.421353) (xy 250.038793 -86.443165)
			(xy 250.086399 -86.472219) (xy 250.09012 -86.475316) (xy 251.185172 -86.475316) (xy 251.18563 -86.447945)
			(xy 251.193447 -86.393765) (xy 251.208937 -86.341261) (xy 251.231781 -86.291514) (xy 251.261509 -86.245549)
			(xy 251.279152 -86.224618) (xy 251.279406 -86.224364) (xy 251.284973 -86.217264) (xy 251.291231 -86.200357)
			(xy 251.291598 -86.191344) (xy 251.291598 -86.124288) (xy 251.291247 -86.115271) (xy 251.284995 -86.098354)
			(xy 251.279406 -86.091268) (xy 251.279152 -86.091268) (xy 251.279152 -86.091014) (xy 251.261514 -86.070081)
			(xy 251.2318 -86.024109) (xy 251.208963 -85.974362) (xy 251.193472 -85.921861) (xy 251.185645 -85.867685)
			(xy 251.185172 -85.840316) (xy 251.185658 -85.813065) (xy 251.193414 -85.759117) (xy 251.208769 -85.706822)
			(xy 251.231411 -85.657245) (xy 251.260877 -85.611395) (xy 251.296568 -85.570204) (xy 251.337759 -85.534513)
			(xy 251.383609 -85.505047) (xy 251.433186 -85.482405) (xy 251.485481 -85.46705) (xy 251.539429 -85.459294)
			(xy 251.593931 -85.459294) (xy 251.647879 -85.46705) (xy 251.700174 -85.482405) (xy 251.749751 -85.505047)
			(xy 251.795601 -85.534513) (xy 251.836792 -85.570204) (xy 251.872483 -85.611395) (xy 251.901949 -85.657245)
			(xy 251.924591 -85.706822) (xy 251.939946 -85.759117) (xy 251.947702 -85.813065) (xy 251.948188 -85.840316)
			(xy 251.947734 -85.867687) (xy 251.939914 -85.921866) (xy 251.924422 -85.97437) (xy 251.901578 -86.024116)
			(xy 251.87185 -86.070083) (xy 251.854208 -86.091014) (xy 251.853954 -86.091268) (xy 251.848369 -86.098356)
			(xy 251.842123 -86.115272) (xy 251.841762 -86.124288) (xy 251.841762 -86.191344) (xy 251.842154 -86.200357)
			(xy 251.848378 -86.217274) (xy 251.853954 -86.224364) (xy 251.854208 -86.224364) (xy 251.854208 -86.224618)
			(xy 251.871823 -86.245569) (xy 251.901538 -86.291537) (xy 251.924379 -86.34128) (xy 251.939876 -86.393776)
			(xy 251.94771 -86.447948) (xy 251.948188 -86.475316) (xy 251.947702 -86.502567) (xy 251.939946 -86.556515)
			(xy 251.924591 -86.60881) (xy 251.901949 -86.658387) (xy 251.872483 -86.704237) (xy 251.836792 -86.745428)
			(xy 251.795601 -86.781119) (xy 251.749751 -86.810585) (xy 251.700174 -86.833227) (xy 251.647879 -86.848582)
			(xy 251.593931 -86.856338) (xy 251.539429 -86.856338) (xy 251.485481 -86.848582) (xy 251.433186 -86.833227)
			(xy 251.383609 -86.810585) (xy 251.337759 -86.781119) (xy 251.296568 -86.745428) (xy 251.260877 -86.704237)
			(xy 251.231411 -86.658387) (xy 251.208769 -86.60881) (xy 251.193414 -86.556515) (xy 251.185658 -86.502567)
			(xy 251.185172 -86.475316) (xy 250.09012 -86.475316) (xy 250.129267 -86.507894) (xy 250.166484 -86.549431)
			(xy 250.197257 -86.595944) (xy 250.220929 -86.646441) (xy 250.236997 -86.699848) (xy 250.245117 -86.755024)
			(xy 250.245626 -86.78291) (xy 250.245117 -86.810796) (xy 250.236997 -86.865972) (xy 250.220929 -86.919379)
			(xy 250.197257 -86.969876) (xy 250.166484 -87.016389) (xy 250.129267 -87.057926) (xy 250.086399 -87.093601)
			(xy 250.038793 -87.122655) (xy 249.987464 -87.144467) (xy 249.933507 -87.158573) (xy 249.87807 -87.164673)
			(xy 249.822336 -87.162636) (xy 249.767493 -87.152506) (xy 249.714709 -87.134499) (xy 249.665109 -87.108998)
			(xy 249.619751 -87.076547) (xy 249.579602 -87.037838) (xy 249.545516 -86.993695) (xy 249.51822 -86.94506)
			(xy 249.498297 -86.892969) (xy 249.486171 -86.838532) (xy 249.4821 -86.78291) (xy 248.266204 -86.78291)
			(xy 248.288523 -86.810871) (xy 248.323532 -86.866541) (xy 248.352083 -86.925783) (xy 248.373818 -86.987851)
			(xy 248.388461 -87.051963) (xy 248.39583 -87.117312) (xy 248.396252 -87.150194) (xy 248.396252 -87.164672)
			(xy 248.395998 -87.170514) (xy 248.394222 -87.206482) (xy 248.382961 -87.27761) (xy 248.364746 -87.340948)
			(xy 250.984002 -87.340948) (xy 250.988073 -87.285326) (xy 251.000199 -87.230889) (xy 251.020122 -87.178798)
			(xy 251.047418 -87.130163) (xy 251.081504 -87.08602) (xy 251.121653 -87.047311) (xy 251.167011 -87.01486)
			(xy 251.216611 -86.989359) (xy 251.269395 -86.971352) (xy 251.324238 -86.961222) (xy 251.379972 -86.959185)
			(xy 251.435409 -86.965285) (xy 251.489366 -86.979391) (xy 251.540695 -87.001203) (xy 251.588301 -87.030257)
			(xy 251.631169 -87.065932) (xy 251.668386 -87.107469) (xy 251.699159 -87.153982) (xy 251.722831 -87.204479)
			(xy 251.738899 -87.257886) (xy 251.747019 -87.313062) (xy 251.747528 -87.340948) (xy 251.747019 -87.368834)
			(xy 251.738899 -87.42401) (xy 251.722831 -87.477417) (xy 251.699159 -87.527914) (xy 251.668386 -87.574427)
			(xy 251.631169 -87.615964) (xy 251.588301 -87.651639) (xy 251.540695 -87.680693) (xy 251.489366 -87.702505)
			(xy 251.435409 -87.716611) (xy 251.405373 -87.719916) (xy 252.861062 -87.719916) (xy 252.865133 -87.664294)
			(xy 252.877259 -87.609857) (xy 252.897182 -87.557766) (xy 252.924478 -87.509131) (xy 252.958564 -87.464988)
			(xy 252.998713 -87.426279) (xy 253.044071 -87.393828) (xy 253.093671 -87.368327) (xy 253.146455 -87.35032)
			(xy 253.201298 -87.34019) (xy 253.257032 -87.338153) (xy 253.312469 -87.344253) (xy 253.366426 -87.358359)
			(xy 253.417755 -87.380171) (xy 253.465361 -87.409225) (xy 253.508229 -87.4449) (xy 253.545446 -87.486437)
			(xy 253.576219 -87.53295) (xy 253.599891 -87.583447) (xy 253.615959 -87.636854) (xy 253.624079 -87.69203)
			(xy 253.624588 -87.719916) (xy 253.624079 -87.747802) (xy 253.615959 -87.802978) (xy 253.599891 -87.856385)
			(xy 253.576219 -87.906882) (xy 253.545446 -87.953395) (xy 253.508229 -87.994932) (xy 253.465361 -88.030607)
			(xy 253.417755 -88.059661) (xy 253.366426 -88.081473) (xy 253.312469 -88.095579) (xy 253.257032 -88.101679)
			(xy 253.201298 -88.099642) (xy 253.146455 -88.089512) (xy 253.093671 -88.071505) (xy 253.044071 -88.046004)
			(xy 252.998713 -88.013553) (xy 252.958564 -87.974844) (xy 252.924478 -87.930701) (xy 252.897182 -87.882066)
			(xy 252.877259 -87.829975) (xy 252.865133 -87.775538) (xy 252.861062 -87.719916) (xy 251.405373 -87.719916)
			(xy 251.379972 -87.722711) (xy 251.324238 -87.720674) (xy 251.269395 -87.710544) (xy 251.216611 -87.692537)
			(xy 251.167011 -87.667036) (xy 251.121653 -87.634585) (xy 251.081504 -87.595876) (xy 251.047418 -87.551733)
			(xy 251.020122 -87.503098) (xy 251.000199 -87.451007) (xy 250.988073 -87.39657) (xy 250.984002 -87.340948)
			(xy 248.364746 -87.340948) (xy 248.363058 -87.346819) (xy 248.334816 -87.413065) (xy 248.298659 -87.475344)
			(xy 248.255135 -87.532718) (xy 248.23039 -87.55888) (xy 248.223278 -87.566246) (xy 248.219722 -87.575136)
			(xy 248.217971 -87.579704) (xy 248.216059 -87.589296) (xy 248.215912 -87.594186) (xy 248.215912 -87.608918)
			(xy 248.216674 -87.617046) (xy 248.221754 -87.622126) (xy 248.245051 -87.645756) (xy 248.286726 -87.697397)
			(xy 248.322302 -87.753414) (xy 248.351323 -87.813091) (xy 248.37342 -87.875664) (xy 248.388308 -87.940332)
			(xy 248.395797 -88.006268) (xy 248.396252 -88.039448) (xy 248.396104 -88.049608) (xy 249.542806 -88.049608)
			(xy 249.546877 -87.993986) (xy 249.559003 -87.939549) (xy 249.578926 -87.887458) (xy 249.606222 -87.838823)
			(xy 249.640308 -87.79468) (xy 249.680457 -87.755971) (xy 249.725815 -87.72352) (xy 249.775415 -87.698019)
			(xy 249.828199 -87.680012) (xy 249.883042 -87.669882) (xy 249.938776 -87.667845) (xy 249.994213 -87.673945)
			(xy 250.04817 -87.688051) (xy 250.099499 -87.709863) (xy 250.147105 -87.738917) (xy 250.189973 -87.774592)
			(xy 250.22719 -87.816129) (xy 250.257963 -87.862642) (xy 250.281635 -87.913139) (xy 250.297703 -87.966546)
			(xy 250.305823 -88.021722) (xy 250.306332 -88.049608) (xy 250.305823 -88.077494) (xy 250.297703 -88.13267)
			(xy 250.281635 -88.186077) (xy 250.257963 -88.236574) (xy 250.22719 -88.283087) (xy 250.189973 -88.324624)
			(xy 250.147105 -88.360299) (xy 250.099499 -88.389353) (xy 250.04817 -88.411165) (xy 249.994213 -88.425271)
			(xy 249.938776 -88.431371) (xy 249.883042 -88.429334) (xy 249.828199 -88.419204) (xy 249.775415 -88.401197)
			(xy 249.725815 -88.375696) (xy 249.680457 -88.343245) (xy 249.640308 -88.304536) (xy 249.606222 -88.260393)
			(xy 249.578926 -88.211758) (xy 249.559003 -88.159667) (xy 249.546877 -88.10523) (xy 249.542806 -88.049608)
			(xy 248.396104 -88.049608) (xy 248.395773 -88.072325) (xy 248.388379 -88.137663) (xy 248.373723 -88.201763)
			(xy 248.351988 -88.263822) (xy 248.323449 -88.32306) (xy 248.288462 -88.378734) (xy 248.247466 -88.430145)
			(xy 248.224548 -88.453722) (xy 247.906286 -88.771984) (xy 250.730256 -88.771984) (xy 250.734327 -88.716362)
			(xy 250.746453 -88.661925) (xy 250.766376 -88.609834) (xy 250.793672 -88.561199) (xy 250.827758 -88.517056)
			(xy 250.867907 -88.478347) (xy 250.913265 -88.445896) (xy 250.962865 -88.420395) (xy 251.015649 -88.402388)
			(xy 251.070492 -88.392258) (xy 251.126226 -88.390221) (xy 251.181663 -88.396321) (xy 251.23562 -88.410427)
			(xy 251.286949 -88.432239) (xy 251.334555 -88.461293) (xy 251.377423 -88.496968) (xy 251.41464 -88.538505)
			(xy 251.445413 -88.585018) (xy 251.469085 -88.635515) (xy 251.485153 -88.688922) (xy 251.493273 -88.744098)
			(xy 251.493782 -88.771984) (xy 251.493273 -88.79987) (xy 251.485153 -88.855046) (xy 251.469085 -88.908453)
			(xy 251.445413 -88.95895) (xy 251.41464 -89.005463) (xy 251.377423 -89.047) (xy 251.334555 -89.082675)
			(xy 251.286949 -89.111729) (xy 251.23562 -89.133541) (xy 251.181663 -89.147647) (xy 251.126226 -89.153747)
			(xy 251.070492 -89.15171) (xy 251.015649 -89.14158) (xy 250.962865 -89.123573) (xy 250.913265 -89.098072)
			(xy 250.867907 -89.065621) (xy 250.827758 -89.026912) (xy 250.793672 -88.982769) (xy 250.766376 -88.934134)
			(xy 250.746453 -88.882043) (xy 250.734327 -88.827606) (xy 250.730256 -88.771984) (xy 247.906286 -88.771984)
			(xy 247.215152 -89.463118) (xy 248.974608 -89.463118) (xy 248.978679 -89.407496) (xy 248.990805 -89.353059)
			(xy 249.010728 -89.300968) (xy 249.038024 -89.252333) (xy 249.07211 -89.20819) (xy 249.112259 -89.169481)
			(xy 249.157617 -89.13703) (xy 249.207217 -89.111529) (xy 249.260001 -89.093522) (xy 249.314844 -89.083392)
			(xy 249.370578 -89.081355) (xy 249.426015 -89.087455) (xy 249.479972 -89.101561) (xy 249.531301 -89.123373)
			(xy 249.578907 -89.152427) (xy 249.621775 -89.188102) (xy 249.658992 -89.229639) (xy 249.689765 -89.276152)
			(xy 249.713437 -89.326649) (xy 249.729505 -89.380056) (xy 249.737625 -89.435232) (xy 249.73774 -89.441528)
			(xy 252.608078 -89.441528) (xy 252.612149 -89.385906) (xy 252.624275 -89.331469) (xy 252.644198 -89.279378)
			(xy 252.671494 -89.230743) (xy 252.70558 -89.1866) (xy 252.745729 -89.147891) (xy 252.791087 -89.11544)
			(xy 252.840687 -89.089939) (xy 252.893471 -89.071932) (xy 252.948314 -89.061802) (xy 253.004048 -89.059765)
			(xy 253.059485 -89.065865) (xy 253.113442 -89.079971) (xy 253.164771 -89.101783) (xy 253.212377 -89.130837)
			(xy 253.255245 -89.166512) (xy 253.292462 -89.208049) (xy 253.323235 -89.254562) (xy 253.346907 -89.305059)
			(xy 253.362975 -89.358466) (xy 253.371095 -89.413642) (xy 253.371604 -89.441528) (xy 253.371095 -89.469414)
			(xy 253.362975 -89.52459) (xy 253.346907 -89.577997) (xy 253.323235 -89.628494) (xy 253.292462 -89.675007)
			(xy 253.255245 -89.716544) (xy 253.212377 -89.752219) (xy 253.164771 -89.781273) (xy 253.113442 -89.803085)
			(xy 253.059485 -89.817191) (xy 253.004048 -89.823291) (xy 252.948314 -89.821254) (xy 252.893471 -89.811124)
			(xy 252.840687 -89.793117) (xy 252.791087 -89.767616) (xy 252.745729 -89.735165) (xy 252.70558 -89.696456)
			(xy 252.671494 -89.652313) (xy 252.644198 -89.603678) (xy 252.624275 -89.551587) (xy 252.612149 -89.49715)
			(xy 252.608078 -89.441528) (xy 249.73774 -89.441528) (xy 249.738134 -89.463118) (xy 249.737625 -89.491004)
			(xy 249.729505 -89.54618) (xy 249.713437 -89.599587) (xy 249.689765 -89.650084) (xy 249.658992 -89.696597)
			(xy 249.621775 -89.738134) (xy 249.578907 -89.773809) (xy 249.531301 -89.802863) (xy 249.479972 -89.824675)
			(xy 249.426015 -89.838781) (xy 249.370578 -89.844881) (xy 249.314844 -89.842844) (xy 249.260001 -89.832714)
			(xy 249.207217 -89.814707) (xy 249.157617 -89.789206) (xy 249.112259 -89.756755) (xy 249.07211 -89.718046)
			(xy 249.038024 -89.673903) (xy 249.010728 -89.625268) (xy 248.990805 -89.573177) (xy 248.978679 -89.51874)
			(xy 248.974608 -89.463118) (xy 247.215152 -89.463118) (xy 247.104408 -89.573862) (xy 247.101701 -89.576713)
			(xy 247.097106 -89.58309) (xy 247.095264 -89.586562) (xy 247.09268 -89.591989) (xy 247.089857 -89.603668)
			(xy 247.089676 -89.609676) (xy 247.089676 -89.868502) (xy 251.846586 -89.868502) (xy 251.850657 -89.81288)
			(xy 251.862783 -89.758443) (xy 251.882706 -89.706352) (xy 251.910002 -89.657717) (xy 251.944088 -89.613574)
			(xy 251.984237 -89.574865) (xy 252.029595 -89.542414) (xy 252.079195 -89.516913) (xy 252.131979 -89.498906)
			(xy 252.186822 -89.488776) (xy 252.242556 -89.486739) (xy 252.297993 -89.492839) (xy 252.35195 -89.506945)
			(xy 252.403279 -89.528757) (xy 252.450885 -89.557811) (xy 252.493753 -89.593486) (xy 252.53097 -89.635023)
			(xy 252.561743 -89.681536) (xy 252.585415 -89.732033) (xy 252.601483 -89.78544) (xy 252.609603 -89.840616)
			(xy 252.610112 -89.868502) (xy 252.609603 -89.896388) (xy 252.601483 -89.951564) (xy 252.585415 -90.004971)
			(xy 252.561743 -90.055468) (xy 252.53097 -90.101981) (xy 252.493753 -90.143518) (xy 252.450885 -90.179193)
			(xy 252.403279 -90.208247) (xy 252.35195 -90.230059) (xy 252.297993 -90.244165) (xy 252.242556 -90.250265)
			(xy 252.186822 -90.248228) (xy 252.131979 -90.238098) (xy 252.079195 -90.220091) (xy 252.029595 -90.19459)
			(xy 251.984237 -90.162139) (xy 251.944088 -90.12343) (xy 251.910002 -90.079287) (xy 251.882706 -90.030652)
			(xy 251.862783 -89.978561) (xy 251.850657 -89.924124) (xy 251.846586 -89.868502) (xy 247.089676 -89.868502)
			(xy 247.089676 -93.105986) (xy 248.549412 -93.105986) (xy 248.553483 -93.050364) (xy 248.565609 -92.995927)
			(xy 248.585532 -92.943836) (xy 248.612828 -92.895201) (xy 248.646914 -92.851058) (xy 248.687063 -92.812349)
			(xy 248.732421 -92.779898) (xy 248.782021 -92.754397) (xy 248.834805 -92.73639) (xy 248.889648 -92.72626)
			(xy 248.945382 -92.724223) (xy 249.000819 -92.730323) (xy 249.054776 -92.744429) (xy 249.106105 -92.766241)
			(xy 249.153711 -92.795295) (xy 249.196579 -92.83097) (xy 249.233796 -92.872507) (xy 249.264569 -92.91902)
			(xy 249.288241 -92.969517) (xy 249.304309 -93.022924) (xy 249.312429 -93.0781) (xy 249.312938 -93.105986)
			(xy 249.312429 -93.133872) (xy 249.304309 -93.189048) (xy 249.288241 -93.242455) (xy 249.264569 -93.292952)
			(xy 249.233796 -93.339465) (xy 249.196579 -93.381002) (xy 249.153711 -93.416677) (xy 249.106105 -93.445731)
			(xy 249.054776 -93.467543) (xy 249.000819 -93.481649) (xy 248.945382 -93.487749) (xy 248.889648 -93.485712)
			(xy 248.834805 -93.475582) (xy 248.782021 -93.457575) (xy 248.732421 -93.432074) (xy 248.687063 -93.399623)
			(xy 248.646914 -93.360914) (xy 248.612828 -93.316771) (xy 248.585532 -93.268136) (xy 248.565609 -93.216045)
			(xy 248.553483 -93.161608) (xy 248.549412 -93.105986) (xy 247.089676 -93.105986) (xy 247.089676 -94.098618)
			(xy 250.156724 -94.098618) (xy 250.160795 -94.042996) (xy 250.172921 -93.988559) (xy 250.192844 -93.936468)
			(xy 250.22014 -93.887833) (xy 250.254226 -93.84369) (xy 250.294375 -93.804981) (xy 250.339733 -93.77253)
			(xy 250.389333 -93.747029) (xy 250.442117 -93.729022) (xy 250.49696 -93.718892) (xy 250.552694 -93.716855)
			(xy 250.608131 -93.722955) (xy 250.662088 -93.737061) (xy 250.713417 -93.758873) (xy 250.761023 -93.787927)
			(xy 250.803891 -93.823602) (xy 250.841108 -93.865139) (xy 250.871881 -93.911652) (xy 250.895553 -93.962149)
			(xy 250.911621 -94.015556) (xy 250.919741 -94.070732) (xy 250.92025 -94.098618) (xy 250.919741 -94.126504)
			(xy 250.911621 -94.18168) (xy 250.895553 -94.235087) (xy 250.871881 -94.285584) (xy 250.841108 -94.332097)
			(xy 250.803891 -94.373634) (xy 250.761023 -94.409309) (xy 250.713417 -94.438363) (xy 250.662088 -94.460175)
			(xy 250.608131 -94.474281) (xy 250.552694 -94.480381) (xy 250.49696 -94.478344) (xy 250.442117 -94.468214)
			(xy 250.389333 -94.450207) (xy 250.339733 -94.424706) (xy 250.294375 -94.392255) (xy 250.254226 -94.353546)
			(xy 250.22014 -94.309403) (xy 250.192844 -94.260768) (xy 250.172921 -94.208677) (xy 250.160795 -94.15424)
			(xy 250.156724 -94.098618) (xy 247.089676 -94.098618) (xy 247.089676 -102.287832) (xy 247.090692 -102.297484)
			(xy 247.092322 -102.304727) (xy 247.099166 -102.317893) (xy 247.104154 -102.323392) (xy 247.231408 -102.450646)
			(xy 247.254354 -102.474201) (xy 247.295373 -102.5256) (xy 247.330376 -102.581272) (xy 247.358922 -102.640514)
			(xy 247.380651 -102.702581) (xy 247.395291 -102.766692) (xy 247.402656 -102.832039) (xy 247.403112 -102.86492)
			(xy 247.403112 -103.571548) (xy 247.402661 -103.604512) (xy 247.395258 -103.670022) (xy 247.38055 -103.734287)
			(xy 247.358724 -103.796497) (xy 247.330055 -103.855864) (xy 247.294905 -103.911639) (xy 247.268678 -103.94442)
			(xy 251.43206 -103.94442) (xy 251.432517 -103.91751) (xy 251.440103 -103.864226) (xy 251.4551 -103.812537)
			(xy 251.47721 -103.763467) (xy 251.505994 -103.717991) (xy 251.540882 -103.677009) (xy 251.581182 -103.641335)
			(xy 251.626093 -103.611676) (xy 251.674726 -103.588621) (xy 251.700284 -103.580184) (xy 251.700538 -103.580184)
			(xy 251.706228 -103.578197) (xy 251.716504 -103.571906) (xy 251.720858 -103.567738) (xy 252.40615 -102.882446)
			(xy 252.412955 -102.875018) (xy 252.420697 -102.85644) (xy 252.421136 -102.846378) (xy 252.421136 -95.810578)
			(xy 252.421584 -95.784489) (xy 252.429757 -95.732955) (xy 252.445897 -95.683336) (xy 252.469606 -95.636856)
			(xy 252.500301 -95.594661) (xy 252.518418 -95.575882) (xy 255.585722 -92.508832) (xy 255.592544 -92.501418)
			(xy 255.600274 -92.482829) (xy 255.600708 -92.472764) (xy 255.600708 -89.23655) (xy 255.58369 -89.210896)
			(xy 255.569212 -89.205054) (xy 255.559829 -89.201681) (xy 255.539909 -89.201693) (xy 255.521496 -89.209294)
			(xy 255.514094 -89.215976) (xy 254.46609 -90.263726) (xy 254.442208 -90.286922) (xy 254.389412 -90.327484)
			(xy 254.331772 -90.360804) (xy 254.270275 -90.386313) (xy 254.205974 -90.403574) (xy 254.139969 -90.412291)
			(xy 254.10668 -90.412824) (xy 254.075949 -90.412363) (xy 254.014936 -90.404952) (xy 253.955261 -90.390242)
			(xy 253.897794 -90.368446) (xy 253.843372 -90.339882) (xy 253.792791 -90.304968) (xy 253.746787 -90.264211)
			(xy 253.70603 -90.218206) (xy 253.671116 -90.167624) (xy 253.642552 -90.113203) (xy 253.620757 -90.055735)
			(xy 253.606047 -89.99606) (xy 253.598637 -89.935047) (xy 253.598172 -89.904316) (xy 253.598759 -89.871032)
			(xy 253.607492 -89.805038) (xy 253.624758 -89.740747) (xy 253.650263 -89.679258) (xy 253.683571 -89.62162)
			(xy 253.724113 -89.56882) (xy 253.74727 -89.544906) (xy 254.695706 -88.596216) (xy 254.702532 -88.588805)
			(xy 254.71026 -88.570214) (xy 254.710692 -88.560148) (xy 254.710692 -84.950554) (xy 254.710795 -84.936746)
			(xy 254.712321 -84.909171) (xy 254.71374 -84.895436) (xy 254.714342 -84.88677) (xy 254.710305 -84.869884)
			(xy 254.705866 -84.862416) (xy 254.68961 -84.837016) (xy 254.684557 -84.82998) (xy 254.670804 -84.819464)
			(xy 254.662686 -84.816442) (xy 254.637556 -84.807723) (xy 254.589785 -84.784331) (xy 254.545728 -84.754528)
			(xy 254.506239 -84.718892) (xy 254.472085 -84.678115) (xy 254.443929 -84.632988) (xy 254.422316 -84.584386)
			(xy 254.407666 -84.533252) (xy 254.400264 -84.480579) (xy 254.399796 -84.453984) (xy 254.400263 -84.426732)
			(xy 254.408022 -84.372784) (xy 254.423379 -84.320488) (xy 254.446022 -84.270911) (xy 254.475491 -84.22506)
			(xy 254.511184 -84.18387) (xy 254.552376 -84.148179) (xy 254.598228 -84.118713) (xy 254.647807 -84.096072)
			(xy 254.700103 -84.080717) (xy 254.754052 -84.072961) (xy 254.781304 -84.072476) (xy 254.799711 -84.072692)
			(xy 254.836352 -84.076255) (xy 254.854456 -84.079588) (xy 254.865632 -84.081874) (xy 254.887476 -84.076286)
			(xy 254.956818 -84.019136) (xy 254.965129 -84.01155) (xy 254.974769 -83.991255) (xy 254.97536 -83.98002)
			(xy 254.97536 -82.96402) (xy 254.974934 -82.953951) (xy 254.967215 -82.935352) (xy 254.960374 -82.927952)
			(xy 254.448564 -82.415888) (xy 254.425435 -82.391957) (xy 254.384928 -82.33915) (xy 254.351656 -82.281511)
			(xy 254.326189 -82.220023) (xy 254.308962 -82.155738) (xy 254.300268 -82.089755) (xy 254.29972 -82.056478)
			(xy 254.300189 -82.025763) (xy 254.307596 -81.964781) (xy 254.322299 -81.905136) (xy 254.344083 -81.847698)
			(xy 254.372632 -81.793305) (xy 254.407529 -81.742749) (xy 254.448265 -81.696768) (xy 254.494246 -81.656031)
			(xy 254.544801 -81.621134) (xy 254.599194 -81.592585) (xy 254.656632 -81.5708) (xy 254.716277 -81.556096)
			(xy 254.777259 -81.548689) (xy 254.807974 -81.548224) (xy 254.841254 -81.548746) (xy 254.907246 -81.557421)
			(xy 254.971541 -81.574638) (xy 255.033036 -81.600104) (xy 255.09068 -81.633382) (xy 255.143485 -81.673902)
			(xy 255.167384 -81.697068) (xy 255.64719 -82.17662) (xy 255.677162 -82.182462) (xy 255.691386 -82.17662)
			(xy 255.700403 -82.172281) (xy 255.714487 -82.158095) (xy 255.722127 -82.139623) (xy 255.722628 -82.12963)
			(xy 255.722628 -79.113888) (xy 255.723085 -79.087799) (xy 255.731256 -79.036266) (xy 255.747394 -78.986647)
			(xy 255.771101 -78.940167) (xy 255.801794 -78.897971) (xy 255.81991 -78.879192) (xy 256.290064 -78.409038)
			(xy 256.294182 -78.404646) (xy 256.300466 -78.394381) (xy 256.30251 -78.388718) (xy 256.30251 -78.38821)
			(xy 256.310984 -78.362676) (xy 256.334055 -78.314075) (xy 256.363723 -78.269196) (xy 256.399401 -78.22893)
			(xy 256.440381 -78.194075) (xy 256.485851 -78.165321) (xy 256.534909 -78.14324) (xy 256.586583 -78.128269)
			(xy 256.639847 -78.120704) (xy 256.666746 -78.12024) (xy 256.694002 -78.120612) (xy 256.747959 -78.128377)
			(xy 256.800261 -78.143741) (xy 256.849845 -78.166392) (xy 256.8957 -78.19587) (xy 256.936894 -78.231573)
			(xy 256.972587 -78.272775) (xy 257.002053 -78.318638) (xy 257.024692 -78.368227) (xy 257.040043 -78.420533)
			(xy 257.047794 -78.474492) (xy 257.048254 -78.501748) (xy 257.047759 -78.528657) (xy 257.040177 -78.581938)
			(xy 257.025185 -78.633626) (xy 257.00308 -78.682695) (xy 256.974301 -78.728172) (xy 256.939417 -78.769154)
			(xy 256.899122 -78.804829) (xy 256.854215 -78.834489) (xy 256.84136 -78.840584) (xy 259.167884 -78.840584)
			(xy 259.16837 -78.813333) (xy 259.176126 -78.759385) (xy 259.191481 -78.70709) (xy 259.214123 -78.657513)
			(xy 259.243589 -78.611663) (xy 259.27928 -78.570472) (xy 259.320471 -78.534781) (xy 259.366321 -78.505315)
			(xy 259.415898 -78.482673) (xy 259.468193 -78.467318) (xy 259.522141 -78.459562) (xy 259.576643 -78.459562)
			(xy 259.630591 -78.467318) (xy 259.682886 -78.482673) (xy 259.732463 -78.505315) (xy 259.778313 -78.534781)
			(xy 259.819504 -78.570472) (xy 259.855195 -78.611663) (xy 259.884661 -78.657513) (xy 259.907303 -78.70709)
			(xy 259.922658 -78.759385) (xy 259.930414 -78.813333) (xy 259.9309 -78.840584) (xy 259.930263 -78.872204)
			(xy 259.919821 -78.934576) (xy 259.89922 -78.994367) (xy 259.884672 -79.022448) (xy 259.880642 -79.030795)
			(xy 259.878307 -79.049168) (xy 259.8801 -79.058262) (xy 259.89788 -79.133446) (xy 259.908548 -79.149194)
			(xy 259.916168 -79.154274) (xy 259.937487 -79.169642) (xy 259.976117 -79.205275) (xy 260.009493 -79.24587)
			(xy 260.036983 -79.290661) (xy 260.058069 -79.338799) (xy 260.072352 -79.389376) (xy 260.07956 -79.441433)
			(xy 260.079998 -79.46771) (xy 260.079512 -79.494961) (xy 260.071756 -79.548909) (xy 260.056401 -79.601204)
			(xy 260.037442 -79.642716) (xy 261.293862 -79.642716) (xy 261.297933 -79.587094) (xy 261.310059 -79.532657)
			(xy 261.329982 -79.480566) (xy 261.357278 -79.431931) (xy 261.391364 -79.387788) (xy 261.431513 -79.349079)
			(xy 261.476871 -79.316628) (xy 261.526471 -79.291127) (xy 261.579255 -79.27312) (xy 261.634098 -79.26299)
			(xy 261.689832 -79.260953) (xy 261.745269 -79.267053) (xy 261.799226 -79.281159) (xy 261.850555 -79.302971)
			(xy 261.898161 -79.332025) (xy 261.941029 -79.3677) (xy 261.978246 -79.409237) (xy 262.009019 -79.45575)
			(xy 262.032691 -79.506247) (xy 262.048759 -79.559654) (xy 262.056879 -79.61483) (xy 262.057388 -79.642716)
			(xy 262.056879 -79.670602) (xy 262.048759 -79.725778) (xy 262.032691 -79.779185) (xy 262.009019 -79.829682)
			(xy 261.978246 -79.876195) (xy 261.941029 -79.917732) (xy 261.898161 -79.953407) (xy 261.850555 -79.982461)
			(xy 261.799226 -80.004273) (xy 261.745269 -80.018379) (xy 261.689832 -80.024479) (xy 261.634098 -80.022442)
			(xy 261.579255 -80.012312) (xy 261.526471 -79.994305) (xy 261.476871 -79.968804) (xy 261.431513 -79.936353)
			(xy 261.391364 -79.897644) (xy 261.357278 -79.853501) (xy 261.329982 -79.804866) (xy 261.310059 -79.752775)
			(xy 261.297933 -79.698338) (xy 261.293862 -79.642716) (xy 260.037442 -79.642716) (xy 260.033759 -79.650781)
			(xy 260.004293 -79.696631) (xy 259.968602 -79.737822) (xy 259.927411 -79.773513) (xy 259.881561 -79.802979)
			(xy 259.831984 -79.825621) (xy 259.779689 -79.840976) (xy 259.725741 -79.848732) (xy 259.671239 -79.848732)
			(xy 259.617291 -79.840976) (xy 259.564996 -79.825621) (xy 259.515419 -79.802979) (xy 259.469569 -79.773513)
			(xy 259.428378 -79.737822) (xy 259.392687 -79.696631) (xy 259.363221 -79.650781) (xy 259.340579 -79.601204)
			(xy 259.325224 -79.548909) (xy 259.317468 -79.494961) (xy 259.316982 -79.46771) (xy 259.317618 -79.43609)
			(xy 259.328061 -79.373718) (xy 259.348662 -79.313927) (xy 259.36321 -79.285846) (xy 259.367243 -79.2775)
			(xy 259.369576 -79.259127) (xy 259.367782 -79.250032) (xy 259.350002 -79.174848) (xy 259.339334 -79.1591)
			(xy 259.331714 -79.15402) (xy 259.310388 -79.138661) (xy 259.271759 -79.103026) (xy 259.238385 -79.062429)
			(xy 259.210895 -79.017637) (xy 259.18981 -78.969497) (xy 259.175529 -78.91892) (xy 259.168321 -78.866861)
			(xy 259.167884 -78.840584) (xy 256.84136 -78.840584) (xy 256.805586 -78.857546) (xy 256.78003 -78.865984)
			(xy 256.779776 -78.865984) (xy 256.774082 -78.867962) (xy 256.763807 -78.874259) (xy 256.759456 -78.87843)
			(xy 256.40157 -79.236316) (xy 256.394726 -79.243713) (xy 256.387009 -79.262315) (xy 256.386584 -79.272384)
			(xy 256.386584 -81.562956) (xy 264.230864 -81.562956) (xy 264.234935 -81.507334) (xy 264.247061 -81.452897)
			(xy 264.266984 -81.400806) (xy 264.29428 -81.352171) (xy 264.328366 -81.308028) (xy 264.368515 -81.269319)
			(xy 264.413873 -81.236868) (xy 264.463473 -81.211367) (xy 264.516257 -81.19336) (xy 264.5711 -81.18323)
			(xy 264.626834 -81.181193) (xy 264.682271 -81.187293) (xy 264.736228 -81.201399) (xy 264.787557 -81.223211)
			(xy 264.835163 -81.252265) (xy 264.878031 -81.28794) (xy 264.915248 -81.329477) (xy 264.946021 -81.37599)
			(xy 264.969693 -81.426487) (xy 264.985761 -81.479894) (xy 264.993881 -81.53507) (xy 264.99439 -81.562956)
			(xy 264.993881 -81.590842) (xy 264.985761 -81.646018) (xy 264.969693 -81.699425) (xy 264.946021 -81.749922)
			(xy 264.915248 -81.796435) (xy 264.878031 -81.837972) (xy 264.835163 -81.873647) (xy 264.787557 -81.902701)
			(xy 264.736228 -81.924513) (xy 264.682271 -81.938619) (xy 264.626834 -81.944719) (xy 264.5711 -81.942682)
			(xy 264.516257 -81.932552) (xy 264.463473 -81.914545) (xy 264.413873 -81.889044) (xy 264.368515 -81.856593)
			(xy 264.328366 -81.817884) (xy 264.29428 -81.773741) (xy 264.266984 -81.725106) (xy 264.247061 -81.673015)
			(xy 264.234935 -81.618578) (xy 264.230864 -81.562956) (xy 256.386584 -81.562956) (xy 256.386584 -84.758784)
			(xy 264.526774 -84.758784) (xy 264.530845 -84.703162) (xy 264.542971 -84.648725) (xy 264.562894 -84.596634)
			(xy 264.59019 -84.547999) (xy 264.624276 -84.503856) (xy 264.664425 -84.465147) (xy 264.709783 -84.432696)
			(xy 264.759383 -84.407195) (xy 264.812167 -84.389188) (xy 264.86701 -84.379058) (xy 264.922744 -84.377021)
			(xy 264.978181 -84.383121) (xy 265.032138 -84.397227) (xy 265.083467 -84.419039) (xy 265.131073 -84.448093)
			(xy 265.173941 -84.483768) (xy 265.211158 -84.525305) (xy 265.241931 -84.571818) (xy 265.265603 -84.622315)
			(xy 265.281671 -84.675722) (xy 265.289791 -84.730898) (xy 265.2903 -84.758784) (xy 265.289791 -84.78667)
			(xy 265.281671 -84.841846) (xy 265.265603 -84.895253) (xy 265.241931 -84.94575) (xy 265.211158 -84.992263)
			(xy 265.173941 -85.0338) (xy 265.131073 -85.069475) (xy 265.083467 -85.098529) (xy 265.032138 -85.120341)
			(xy 264.978181 -85.134447) (xy 264.922744 -85.140547) (xy 264.86701 -85.13851) (xy 264.812167 -85.12838)
			(xy 264.759383 -85.110373) (xy 264.709783 -85.084872) (xy 264.664425 -85.052421) (xy 264.624276 -85.013712)
			(xy 264.59019 -84.969569) (xy 264.562894 -84.920934) (xy 264.542971 -84.868843) (xy 264.530845 -84.814406)
			(xy 264.526774 -84.758784) (xy 256.386584 -84.758784) (xy 256.386584 -86.41842) (xy 264.566906 -86.41842)
			(xy 264.570977 -86.362798) (xy 264.583103 -86.308361) (xy 264.603026 -86.25627) (xy 264.630322 -86.207635)
			(xy 264.664408 -86.163492) (xy 264.704557 -86.124783) (xy 264.749915 -86.092332) (xy 264.799515 -86.066831)
			(xy 264.852299 -86.048824) (xy 264.907142 -86.038694) (xy 264.962876 -86.036657) (xy 265.018313 -86.042757)
			(xy 265.07227 -86.056863) (xy 265.123599 -86.078675) (xy 265.171205 -86.107729) (xy 265.214073 -86.143404)
			(xy 265.25129 -86.184941) (xy 265.282063 -86.231454) (xy 265.305735 -86.281951) (xy 265.321803 -86.335358)
			(xy 265.329923 -86.390534) (xy 265.330432 -86.41842) (xy 265.329923 -86.446306) (xy 265.321803 -86.501482)
			(xy 265.305735 -86.554889) (xy 265.282063 -86.605386) (xy 265.25129 -86.651899) (xy 265.214073 -86.693436)
			(xy 265.171205 -86.729111) (xy 265.123599 -86.758165) (xy 265.07227 -86.779977) (xy 265.018313 -86.794083)
			(xy 264.962876 -86.800183) (xy 264.907142 -86.798146) (xy 264.852299 -86.788016) (xy 264.799515 -86.770009)
			(xy 264.749915 -86.744508) (xy 264.704557 -86.712057) (xy 264.664408 -86.673348) (xy 264.630322 -86.629205)
			(xy 264.603026 -86.58057) (xy 264.583103 -86.528479) (xy 264.570977 -86.474042) (xy 264.566906 -86.41842)
			(xy 256.386584 -86.41842) (xy 256.386584 -86.99373) (xy 256.386076 -87.011002) (xy 256.385568 -87.021416)
			(xy 256.392426 -87.04072) (xy 256.456942 -87.109554) (xy 256.475738 -87.117936) (xy 256.486152 -87.117936)
			(xy 256.513187 -87.118741) (xy 256.566635 -87.12703) (xy 256.618376 -87.142784) (xy 256.667375 -87.165685)
			(xy 256.712649 -87.195276) (xy 256.75329 -87.230964) (xy 256.770706 -87.251286) (xy 269.21028 -87.251286)
			(xy 269.214351 -87.195664) (xy 269.226477 -87.141227) (xy 269.2464 -87.089136) (xy 269.273696 -87.040501)
			(xy 269.307782 -86.996358) (xy 269.347931 -86.957649) (xy 269.393289 -86.925198) (xy 269.442889 -86.899697)
			(xy 269.495673 -86.88169) (xy 269.550516 -86.87156) (xy 269.60625 -86.869523) (xy 269.661687 -86.875623)
			(xy 269.715644 -86.889729) (xy 269.766973 -86.911541) (xy 269.814579 -86.940595) (xy 269.857447 -86.97627)
			(xy 269.894664 -87.017807) (xy 269.925437 -87.06432) (xy 269.949109 -87.114817) (xy 269.965177 -87.168224)
			(xy 269.973297 -87.2234) (xy 269.973806 -87.251286) (xy 269.973297 -87.279172) (xy 269.965177 -87.334348)
			(xy 269.949109 -87.387755) (xy 269.925437 -87.438252) (xy 269.894664 -87.484765) (xy 269.857447 -87.526302)
			(xy 269.814579 -87.561977) (xy 269.766973 -87.591031) (xy 269.715644 -87.612843) (xy 269.661687 -87.626949)
			(xy 269.60625 -87.633049) (xy 269.550516 -87.631012) (xy 269.495673 -87.620882) (xy 269.442889 -87.602875)
			(xy 269.393289 -87.577374) (xy 269.347931 -87.544923) (xy 269.307782 -87.506214) (xy 269.273696 -87.462071)
			(xy 269.2464 -87.413436) (xy 269.226477 -87.361345) (xy 269.214351 -87.306908) (xy 269.21028 -87.251286)
			(xy 256.770706 -87.251286) (xy 256.788486 -87.272032) (xy 256.817529 -87.317659) (xy 256.839839 -87.36693)
			(xy 256.854968 -87.418857) (xy 256.862613 -87.472401) (xy 256.863088 -87.499444) (xy 256.862663 -87.526697)
			(xy 256.8549 -87.580648) (xy 256.839538 -87.632945) (xy 256.816891 -87.682524) (xy 256.787418 -87.728375)
			(xy 256.75172 -87.769565) (xy 256.710524 -87.805256) (xy 256.664668 -87.834721) (xy 256.615085 -87.857361)
			(xy 256.562786 -87.872714) (xy 256.508833 -87.880468) (xy 256.48158 -87.880952) (xy 256.458486 -87.88061)
			(xy 256.412638 -87.875002) (xy 256.39014 -87.869776) (xy 256.378964 -87.866982) (xy 256.356104 -87.871808)
			(xy 256.283714 -87.92845) (xy 256.274925 -87.936074) (xy 256.264735 -87.956962) (xy 256.264156 -87.968582)
			(xy 256.264156 -89.096088) (xy 258.801106 -89.096088) (xy 258.805177 -89.040466) (xy 258.817303 -88.986029)
			(xy 258.837226 -88.933938) (xy 258.864522 -88.885303) (xy 258.898608 -88.84116) (xy 258.938757 -88.802451)
			(xy 258.984115 -88.77) (xy 259.033715 -88.744499) (xy 259.086499 -88.726492) (xy 259.141342 -88.716362)
			(xy 259.197076 -88.714325) (xy 259.252513 -88.720425) (xy 259.30647 -88.734531) (xy 259.357799 -88.756343)
			(xy 259.405405 -88.785397) (xy 259.448273 -88.821072) (xy 259.48549 -88.862609) (xy 259.516263 -88.909122)
			(xy 259.539935 -88.959619) (xy 259.554629 -89.008458) (xy 261.557768 -89.008458) (xy 261.561839 -88.952836)
			(xy 261.573965 -88.898399) (xy 261.593888 -88.846308) (xy 261.621184 -88.797673) (xy 261.65527 -88.75353)
			(xy 261.695419 -88.714821) (xy 261.740777 -88.68237) (xy 261.790377 -88.656869) (xy 261.843161 -88.638862)
			(xy 261.898004 -88.628732) (xy 261.953738 -88.626695) (xy 262.009175 -88.632795) (xy 262.063132 -88.646901)
			(xy 262.114461 -88.668713) (xy 262.162067 -88.697767) (xy 262.204935 -88.733442) (xy 262.242152 -88.774979)
			(xy 262.272925 -88.821492) (xy 262.296597 -88.871989) (xy 262.312665 -88.925396) (xy 262.320785 -88.980572)
			(xy 262.321294 -89.008458) (xy 262.320785 -89.036344) (xy 262.312665 -89.09152) (xy 262.296597 -89.144927)
			(xy 262.272925 -89.195424) (xy 262.242152 -89.241937) (xy 262.204935 -89.283474) (xy 262.162067 -89.319149)
			(xy 262.114461 -89.348203) (xy 262.063132 -89.370015) (xy 262.009175 -89.384121) (xy 261.953738 -89.390221)
			(xy 261.898004 -89.388184) (xy 261.843161 -89.378054) (xy 261.790377 -89.360047) (xy 261.740777 -89.334546)
			(xy 261.695419 -89.302095) (xy 261.65527 -89.263386) (xy 261.621184 -89.219243) (xy 261.593888 -89.170608)
			(xy 261.573965 -89.118517) (xy 261.561839 -89.06408) (xy 261.557768 -89.008458) (xy 259.554629 -89.008458)
			(xy 259.556003 -89.013026) (xy 259.564123 -89.068202) (xy 259.564632 -89.096088) (xy 259.564123 -89.123974)
			(xy 259.556003 -89.17915) (xy 259.539935 -89.232557) (xy 259.516263 -89.283054) (xy 259.48549 -89.329567)
			(xy 259.448273 -89.371104) (xy 259.405405 -89.406779) (xy 259.357799 -89.435833) (xy 259.30647 -89.457645)
			(xy 259.252513 -89.471751) (xy 259.197076 -89.477851) (xy 259.141342 -89.475814) (xy 259.086499 -89.465684)
			(xy 259.033715 -89.447677) (xy 258.984115 -89.422176) (xy 258.938757 -89.389725) (xy 258.898608 -89.351016)
			(xy 258.864522 -89.306873) (xy 258.837226 -89.258238) (xy 258.817303 -89.206147) (xy 258.805177 -89.15171)
			(xy 258.801106 -89.096088) (xy 256.264156 -89.096088) (xy 256.264156 -90.462354) (xy 269.030448 -90.462354)
			(xy 269.034519 -90.406732) (xy 269.046645 -90.352295) (xy 269.066568 -90.300204) (xy 269.093864 -90.251569)
			(xy 269.12795 -90.207426) (xy 269.168099 -90.168717) (xy 269.213457 -90.136266) (xy 269.263057 -90.110765)
			(xy 269.315841 -90.092758) (xy 269.370684 -90.082628) (xy 269.426418 -90.080591) (xy 269.481855 -90.086691)
			(xy 269.535812 -90.100797) (xy 269.587141 -90.122609) (xy 269.634747 -90.151663) (xy 269.677615 -90.187338)
			(xy 269.714832 -90.228875) (xy 269.745605 -90.275388) (xy 269.769277 -90.325885) (xy 269.785345 -90.379292)
			(xy 269.793465 -90.434468) (xy 269.793974 -90.462354) (xy 269.793465 -90.49024) (xy 269.785345 -90.545416)
			(xy 269.769277 -90.598823) (xy 269.745605 -90.64932) (xy 269.714832 -90.695833) (xy 269.677615 -90.73737)
			(xy 269.634747 -90.773045) (xy 269.587141 -90.802099) (xy 269.535812 -90.823911) (xy 269.481855 -90.838017)
			(xy 269.426418 -90.844117) (xy 269.370684 -90.84208) (xy 269.315841 -90.83195) (xy 269.263057 -90.813943)
			(xy 269.213457 -90.788442) (xy 269.168099 -90.755991) (xy 269.12795 -90.717282) (xy 269.093864 -90.673139)
			(xy 269.066568 -90.624504) (xy 269.046645 -90.572413) (xy 269.034519 -90.517976) (xy 269.030448 -90.462354)
			(xy 256.264156 -90.462354) (xy 256.264156 -92.631768) (xy 256.263663 -92.657793) (xy 256.255491 -92.709199)
			(xy 256.23939 -92.758697) (xy 256.215754 -92.805073) (xy 256.185165 -92.847187) (xy 256.167128 -92.865956)
			(xy 255.49098 -93.542104) (xy 269.030448 -93.542104) (xy 269.034519 -93.486482) (xy 269.046645 -93.432045)
			(xy 269.066568 -93.379954) (xy 269.093864 -93.331319) (xy 269.12795 -93.287176) (xy 269.168099 -93.248467)
			(xy 269.213457 -93.216016) (xy 269.263057 -93.190515) (xy 269.315841 -93.172508) (xy 269.370684 -93.162378)
			(xy 269.426418 -93.160341) (xy 269.481855 -93.166441) (xy 269.535812 -93.180547) (xy 269.587141 -93.202359)
			(xy 269.634747 -93.231413) (xy 269.677615 -93.267088) (xy 269.714832 -93.308625) (xy 269.745605 -93.355138)
			(xy 269.769277 -93.405635) (xy 269.785345 -93.459042) (xy 269.793465 -93.514218) (xy 269.793974 -93.542104)
			(xy 269.793465 -93.56999) (xy 269.785345 -93.625166) (xy 269.769277 -93.678573) (xy 269.745605 -93.72907)
			(xy 269.714832 -93.775583) (xy 269.677615 -93.81712) (xy 269.634747 -93.852795) (xy 269.587141 -93.881849)
			(xy 269.535812 -93.903661) (xy 269.481855 -93.917767) (xy 269.426418 -93.923867) (xy 269.370684 -93.92183)
			(xy 269.315841 -93.9117) (xy 269.263057 -93.893693) (xy 269.213457 -93.868192) (xy 269.168099 -93.835741)
			(xy 269.12795 -93.797032) (xy 269.093864 -93.752889) (xy 269.066568 -93.704254) (xy 269.046645 -93.652163)
			(xy 269.034519 -93.597726) (xy 269.030448 -93.542104) (xy 255.49098 -93.542104) (xy 253.100078 -95.933006)
			(xy 253.09324 -95.940407) (xy 253.085519 -95.959006) (xy 253.085092 -95.969074) (xy 253.085092 -96.1644)
			(xy 269.425418 -96.1644) (xy 269.429489 -96.108778) (xy 269.441615 -96.054341) (xy 269.461538 -96.00225)
			(xy 269.488834 -95.953615) (xy 269.52292 -95.909472) (xy 269.563069 -95.870763) (xy 269.608427 -95.838312)
			(xy 269.658027 -95.812811) (xy 269.710811 -95.794804) (xy 269.765654 -95.784674) (xy 269.821388 -95.782637)
			(xy 269.876825 -95.788737) (xy 269.930782 -95.802843) (xy 269.982111 -95.824655) (xy 270.029717 -95.853709)
			(xy 270.072585 -95.889384) (xy 270.109802 -95.930921) (xy 270.140575 -95.977434) (xy 270.164247 -96.027931)
			(xy 270.180315 -96.081338) (xy 270.188435 -96.136514) (xy 270.188944 -96.1644) (xy 270.188435 -96.192286)
			(xy 270.180315 -96.247462) (xy 270.164247 -96.300869) (xy 270.140575 -96.351366) (xy 270.109802 -96.397879)
			(xy 270.072585 -96.439416) (xy 270.029717 -96.475091) (xy 269.982111 -96.504145) (xy 269.930782 -96.525957)
			(xy 269.876825 -96.540063) (xy 269.821388 -96.546163) (xy 269.765654 -96.544126) (xy 269.710811 -96.533996)
			(xy 269.658027 -96.515989) (xy 269.608427 -96.490488) (xy 269.563069 -96.458037) (xy 269.52292 -96.419328)
			(xy 269.488834 -96.375185) (xy 269.461538 -96.32655) (xy 269.441615 -96.274459) (xy 269.429489 -96.220022)
			(xy 269.425418 -96.1644) (xy 253.085092 -96.1644) (xy 253.085092 -98.766863) (xy 257.089906 -98.766863)
			(xy 257.089906 -98.633301) (xy 257.09797 -98.499983) (xy 257.11407 -98.367395) (xy 257.138145 -98.236021)
			(xy 257.170108 -98.10634) (xy 257.209843 -97.978826) (xy 257.257205 -97.853943) (xy 257.31202 -97.732148)
			(xy 257.37409 -97.613885) (xy 257.443186 -97.499586) (xy 257.519058 -97.389666) (xy 257.601428 -97.284529)
			(xy 257.689996 -97.184556) (xy 257.784438 -97.090114) (xy 257.884411 -97.001546) (xy 257.989548 -96.919176)
			(xy 258.099468 -96.843304) (xy 258.213767 -96.774208) (xy 258.33203 -96.712138) (xy 258.453825 -96.657323)
			(xy 258.578708 -96.609961) (xy 258.706222 -96.570226) (xy 258.835903 -96.538263) (xy 258.967277 -96.514188)
			(xy 259.099865 -96.498088) (xy 259.233183 -96.490024) (xy 259.366745 -96.490024) (xy 259.500063 -96.498088)
			(xy 259.632651 -96.514188) (xy 259.764025 -96.538263) (xy 259.893706 -96.570226) (xy 260.02122 -96.609961)
			(xy 260.146103 -96.657323) (xy 260.267898 -96.712138) (xy 260.386161 -96.774208) (xy 260.50046 -96.843304)
			(xy 260.61038 -96.919176) (xy 260.715517 -97.001546) (xy 260.81549 -97.090114) (xy 260.905776 -97.1804)
			(xy 269.425418 -97.1804) (xy 269.429489 -97.124778) (xy 269.441615 -97.070341) (xy 269.461538 -97.01825)
			(xy 269.488834 -96.969615) (xy 269.52292 -96.925472) (xy 269.563069 -96.886763) (xy 269.608427 -96.854312)
			(xy 269.658027 -96.828811) (xy 269.710811 -96.810804) (xy 269.765654 -96.800674) (xy 269.821388 -96.798637)
			(xy 269.876825 -96.804737) (xy 269.930782 -96.818843) (xy 269.982111 -96.840655) (xy 270.029717 -96.869709)
			(xy 270.072585 -96.905384) (xy 270.109802 -96.946921) (xy 270.140575 -96.993434) (xy 270.164247 -97.043931)
			(xy 270.180315 -97.097338) (xy 270.188435 -97.152514) (xy 270.188944 -97.1804) (xy 270.188435 -97.208286)
			(xy 270.180315 -97.263462) (xy 270.164247 -97.316869) (xy 270.140575 -97.367366) (xy 270.109802 -97.413879)
			(xy 270.072585 -97.455416) (xy 270.029717 -97.491091) (xy 269.982111 -97.520145) (xy 269.930782 -97.541957)
			(xy 269.876825 -97.556063) (xy 269.821388 -97.562163) (xy 269.765654 -97.560126) (xy 269.710811 -97.549996)
			(xy 269.658027 -97.531989) (xy 269.608427 -97.506488) (xy 269.563069 -97.474037) (xy 269.52292 -97.435328)
			(xy 269.488834 -97.391185) (xy 269.461538 -97.34255) (xy 269.441615 -97.290459) (xy 269.429489 -97.236022)
			(xy 269.425418 -97.1804) (xy 260.905776 -97.1804) (xy 260.909932 -97.184556) (xy 260.9985 -97.284529)
			(xy 261.08087 -97.389666) (xy 261.156742 -97.499586) (xy 261.225838 -97.613885) (xy 261.287908 -97.732148)
			(xy 261.342723 -97.853943) (xy 261.390085 -97.978826) (xy 261.42982 -98.10634) (xy 261.461783 -98.236021)
			(xy 261.485858 -98.367395) (xy 261.501958 -98.499983) (xy 261.510022 -98.633301) (xy 261.510526 -98.700082)
			(xy 261.510022 -98.766863) (xy 261.501958 -98.900181) (xy 261.485858 -99.032769) (xy 261.461783 -99.164143)
			(xy 261.42982 -99.293824) (xy 261.390085 -99.421338) (xy 261.342723 -99.546221) (xy 261.287908 -99.668016)
			(xy 261.225838 -99.786279) (xy 261.156742 -99.900578) (xy 261.08087 -100.010498) (xy 260.9985 -100.115635)
			(xy 260.909932 -100.215608) (xy 260.81549 -100.31005) (xy 260.715517 -100.398618) (xy 260.61038 -100.480988)
			(xy 260.50046 -100.55686) (xy 260.386161 -100.625956) (xy 260.267898 -100.688026) (xy 260.146103 -100.742841)
			(xy 260.02122 -100.790203) (xy 259.893706 -100.829938) (xy 259.764025 -100.861901) (xy 259.632651 -100.885976)
			(xy 259.500063 -100.902076) (xy 259.366745 -100.91014) (xy 259.233183 -100.91014) (xy 259.099865 -100.902076)
			(xy 258.967277 -100.885976) (xy 258.835903 -100.861901) (xy 258.706222 -100.829938) (xy 258.578708 -100.790203)
			(xy 258.453825 -100.742841) (xy 258.33203 -100.688026) (xy 258.213767 -100.625956) (xy 258.099468 -100.55686)
			(xy 257.989548 -100.480988) (xy 257.884411 -100.398618) (xy 257.784438 -100.31005) (xy 257.689996 -100.215608)
			(xy 257.601428 -100.115635) (xy 257.519058 -100.010498) (xy 257.443186 -99.900578) (xy 257.37409 -99.786279)
			(xy 257.31202 -99.668016) (xy 257.257205 -99.546221) (xy 257.209843 -99.421338) (xy 257.170108 -99.293824)
			(xy 257.138145 -99.164143) (xy 257.11407 -99.032769) (xy 257.09797 -98.900181) (xy 257.089906 -98.766863)
			(xy 253.085092 -98.766863) (xy 253.085092 -103.004874) (xy 253.084605 -103.030961) (xy 253.076441 -103.082493)
			(xy 253.060309 -103.132112) (xy 253.036609 -103.178593) (xy 253.005923 -103.22079) (xy 252.98781 -103.23957)
			(xy 252.19025 -104.03713) (xy 252.186142 -104.04153) (xy 252.179851 -104.051789) (xy 252.177804 -104.05745)
			(xy 252.177804 -104.057958) (xy 252.169386 -104.083513) (xy 252.146313 -104.132118) (xy 252.11664 -104.177)
			(xy 252.080955 -104.217268) (xy 252.039967 -104.252123) (xy 251.994489 -104.280874) (xy 251.945423 -104.302951)
			(xy 251.893741 -104.317915) (xy 251.84047 -104.325469) (xy 251.813568 -104.325928) (xy 251.786317 -104.325452)
			(xy 251.73237 -104.317692) (xy 251.680076 -104.302333) (xy 251.6305 -104.27969) (xy 251.584651 -104.250222)
			(xy 251.543462 -104.21453) (xy 251.50777 -104.17334) (xy 251.478304 -104.127489) (xy 251.455662 -104.077913)
			(xy 251.440306 -104.025618) (xy 251.432547 -103.971671) (xy 251.43206 -103.94442) (xy 247.268678 -103.94442)
			(xy 247.253719 -103.963118) (xy 247.207016 -104.00965) (xy 247.155387 -104.050648) (xy 247.099483 -104.085593)
			(xy 247.040011 -104.114044) (xy 246.977722 -104.135643) (xy 246.945658 -104.143302) (xy 246.94515 -104.143302)
			(xy 246.921274 -104.14889) (xy 246.918293 -104.152415) (xy 246.913561 -104.16034) (xy 246.911876 -104.164638)
			(xy 246.905272 -104.187244) (xy 246.905272 -104.187752) (xy 246.888 -104.248458) (xy 246.887746 -104.24922)
			(xy 246.885206 -104.255824) (xy 246.88419 -104.269794) (xy 246.885714 -104.27716) (xy 246.887442 -104.284349)
			(xy 246.894416 -104.297379) (xy 246.89943 -104.302814) (xy 256.016252 -113.419636) (xy 256.022934 -113.425762)
			(xy 256.039425 -113.433257) (xy 256.057495 -113.434531) (xy 256.06629 -113.432336) (xy 256.071624 -113.43005)
			(xy 256.078437 -113.426959) (xy 256.090049 -113.417534) (xy 256.094484 -113.411508) (xy 256.098294 -113.40592)
			(xy 256.102612 -113.391442) (xy 256.102612 -111.055658) (xy 256.103101 -111.029572) (xy 256.111273 -110.978043)
			(xy 256.127409 -110.928428) (xy 256.151111 -110.881951) (xy 256.181795 -110.839755) (xy 256.199894 -110.820962)
			(xy 269.046198 -97.974658) (xy 269.064979 -97.956545) (xy 269.107176 -97.925858) (xy 269.153656 -97.902155)
			(xy 269.203274 -97.88602) (xy 269.254806 -97.877852) (xy 269.280894 -97.877376) (xy 269.839694 -97.877376)
			(xy 269.849854 -97.87636) (xy 269.856952 -97.874642) (xy 269.86985 -97.867809) (xy 269.875254 -97.862898)
			(xy 277.471378 -90.267028) (xy 277.472005 -90.262465) (xy 277.471756 -90.253259) (xy 277.47087 -90.24874)
			(xy 277.469854 -90.244168) (xy 277.468584 -90.23985) (xy 277.46833 -90.239088) (xy 277.461218 -90.212672)
			(xy 277.447248 -90.160856) (xy 277.443692 -90.151712) (xy 277.441895 -90.148317) (xy 277.437429 -90.142069)
			(xy 277.434802 -90.139266) (xy 277.43023 -90.13444) (xy 277.424134 -90.130884) (xy 277.412958 -90.126058)
			(xy 277.405084 -90.123772) (xy 277.403814 -90.123518) (xy 277.385366 -90.117947) (xy 277.349611 -90.103565)
			(xy 277.33244 -90.094816) (xy 277.326852 -90.091768) (xy 277.314914 -90.08872) (xy 277.109174 -90.08872)
			(xy 277.08315 -90.088194) (xy 277.031745 -90.08003) (xy 276.982246 -90.063938) (xy 276.935868 -90.040312)
			(xy 276.893749 -90.009732) (xy 276.874986 -89.991692) (xy 275.51253 -88.629236) (xy 275.499576 -88.628982)
			(xy 275.47697 -88.633046) (xy 275.476462 -88.633046) (xy 275.426424 -88.642444) (xy 275.415502 -88.644476)
			(xy 275.405342 -88.651588) (xy 275.40331 -88.653112) (xy 275.385784 -88.666828) (xy 275.377656 -88.674702)
			(xy 275.374608 -88.678512) (xy 275.371814 -88.684354) (xy 275.359807 -88.70831) (xy 275.33008 -88.752892)
			(xy 275.294408 -88.792876) (xy 275.253491 -88.827475) (xy 275.208135 -88.856009) (xy 275.159233 -88.877915)
			(xy 275.107747 -88.892763) (xy 275.05469 -88.900261) (xy 275.027898 -88.900762) (xy 275.027136 -88.900762)
			(xy 274.995954 -88.900124) (xy 274.934424 -88.889958) (xy 274.875359 -88.869939) (xy 274.847558 -88.855804)
			(xy 274.844256 -88.85428) (xy 274.838414 -88.851232) (xy 273.860006 -88.851232) (xy 273.833919 -88.850746)
			(xy 273.782387 -88.84258) (xy 273.732769 -88.826447) (xy 273.686289 -88.802747) (xy 273.644091 -88.772062)
			(xy 273.62531 -88.75395) (xy 268.453362 -83.582002) (xy 268.435248 -83.563222) (xy 268.404561 -83.521025)
			(xy 268.380858 -83.474544) (xy 268.364723 -83.424926) (xy 268.356555 -83.373394) (xy 268.35608 -83.347306)
			(xy 268.35608 -78.313534) (xy 268.355911 -78.307525) (xy 268.353083 -78.295845) (xy 268.350492 -78.29042)
			(xy 268.348654 -78.286944) (xy 268.344064 -78.280563) (xy 268.341348 -78.27772) (xy 267.168884 -77.105256)
			(xy 267.16101 -77.104748) (xy 267.125704 -77.10678) (xy 267.125196 -77.10678) (xy 267.090398 -77.109066)
			(xy 267.081762 -77.109574) (xy 267.074142 -77.112622) (xy 267.070357 -77.114347) (xy 267.063342 -77.118818)
			(xy 267.060172 -77.121512) (xy 267.050266 -77.130148) (xy 267.04671 -77.134466) (xy 267.038328 -77.145388)
			(xy 267.03782 -77.145896) (xy 267.03655 -77.14742) (xy 267.01242 -77.173582) (xy 266.997942 -77.187044)
			(xy 266.9921 -77.192886) (xy 266.986393 -77.19916) (xy 266.979118 -77.214469) (xy 266.977876 -77.222858)
			(xy 266.976098 -77.269848) (xy 266.975082 -77.294486) (xy 266.975396 -77.303448) (xy 266.981374 -77.32034)
			(xy 266.986766 -77.327506) (xy 266.988544 -77.329538) (xy 266.989814 -77.330808) (xy 266.99083 -77.331824)
			(xy 267.010192 -77.352169) (xy 267.043336 -77.397508) (xy 267.069472 -77.447218) (xy 267.079222 -77.473556)
			(xy 267.088595 -77.501827) (xy 267.099444 -77.560389) (xy 267.100812 -77.590142) (xy 267.100812 -77.600302)
			(xy 267.100812 -77.604112) (xy 267.100812 -77.606144) (xy 267.100558 -77.616304) (xy 267.100304 -77.62113)
			(xy 267.098175 -77.649986) (xy 267.086298 -77.706612) (xy 267.066006 -77.760796) (xy 267.037765 -77.811294)
			(xy 267.002221 -77.856948) (xy 266.960192 -77.896711) (xy 266.912639 -77.929672) (xy 266.860655 -77.955073)
			(xy 266.805431 -77.972333) (xy 266.748233 -77.981056) (xy 266.719304 -77.981556) (xy 266.691569 -77.981052)
			(xy 266.636684 -77.973008) (xy 266.583542 -77.957103) (xy 266.533262 -77.933672) (xy 266.486904 -77.90321)
			(xy 266.445444 -77.866357) (xy 266.409756 -77.82389) (xy 266.380591 -77.776705) (xy 266.358565 -77.725794)
			(xy 266.344141 -77.672231) (xy 266.340336 -77.644752) (xy 266.338812 -77.630274) (xy 266.337542 -77.600048)
			(xy 266.337542 -77.578966) (xy 266.338558 -77.570076) (xy 266.338812 -77.56906) (xy 266.339066 -77.56525)
			(xy 266.3422 -77.536572) (xy 266.356001 -77.48056) (xy 266.378068 -77.42726) (xy 266.407901 -77.377886)
			(xy 266.444821 -77.33356) (xy 266.466066 -77.314044) (xy 266.470638 -77.30998) (xy 266.474194 -77.3049)
			(xy 266.478183 -77.298801) (xy 266.482824 -77.284992) (xy 266.483338 -77.277722) (xy 266.485116 -77.229208)
			(xy 266.485116 -77.2287) (xy 266.485624 -77.210666) (xy 266.485624 -77.206856) (xy 266.483846 -77.195934)
			(xy 266.48283 -77.192886) (xy 266.478258 -77.182726) (xy 266.476226 -77.179678) (xy 266.470638 -77.173074)
			(xy 266.470384 -77.17282) (xy 266.452509 -77.154629) (xy 266.421213 -77.114359) (xy 266.395494 -77.070319)
			(xy 266.375799 -77.023275) (xy 266.36247 -76.974047) (xy 266.355742 -76.923492) (xy 266.355322 -76.897992)
			(xy 266.355882 -76.868492) (xy 266.364863 -76.810178) (xy 266.382613 -76.753911) (xy 266.408721 -76.701001)
			(xy 266.442576 -76.65268) (xy 266.483391 -76.610075) (xy 266.506452 -76.591668) (xy 266.5095 -76.589382)
			(xy 266.51585 -76.583032) (xy 266.520457 -76.578176) (xy 266.527146 -76.566587) (xy 266.529058 -76.560172)
			(xy 266.530582 -76.550774) (xy 266.533122 -76.514452) (xy 266.535154 -76.486512) (xy 266.535154 -76.47813)
			(xy 266.534646 -76.471018) (xy 258.656074 -68.592446) (xy 258.64279 -68.578819) (xy 258.61911 -68.549026)
			(xy 258.60883 -68.53301) (xy 258.605782 -68.52793) (xy 258.132834 -68.054982) (xy 258.115277 -68.036768)
			(xy 258.085537 -67.995845) (xy 258.062569 -67.950772) (xy 258.046941 -67.902659) (xy 258.039037 -67.852692)
			(xy 258.0386 -67.827398) (xy 258.0386 -67.822826) (xy 258.038185 -67.812801) (xy 258.03052 -67.794275)
			(xy 258.016346 -67.780095) (xy 257.997825 -67.77242) (xy 257.9878 -67.772026) (xy 257.980434 -67.772026)
			(xy 257.969004 -67.775582) (xy 257.965194 -67.77736) (xy 257.946792 -67.799766) (xy 257.904408 -67.839328)
			(xy 257.85658 -67.8721) (xy 257.804384 -67.897343) (xy 257.748998 -67.914488) (xy 257.69167 -67.923149)
			(xy 257.66268 -67.923664) (xy 257.648532 -67.923555) (xy 257.620309 -67.921521) (xy 257.606292 -67.9196)
			(xy 257.57632 -67.92341) (xy 257.549396 -67.907916) (xy 257.539998 -67.903598) (xy 257.515826 -67.895065)
			(xy 257.469803 -67.872494) (xy 257.427181 -67.844016) (xy 257.407664 -67.827398) (xy 257.393694 -67.825366)
			(xy 257.376676 -67.825366) (xy 257.369184 -67.825066) (xy 257.354849 -67.820689) (xy 257.348482 -67.81673)
			(xy 257.339846 -67.811396) (xy 257.326384 -67.809872) (xy 257.321421 -67.80967) (xy 257.311573 -67.810951)
			(xy 257.306826 -67.812412) (xy 257.283966 -67.82054) (xy 257.276854 -67.826636) (xy 257.255977 -67.844029)
			(xy 257.210227 -67.873347) (xy 257.160779 -67.895873) (xy 257.108634 -67.911153) (xy 257.054849 -67.918877)
			(xy 257.02768 -67.919346) (xy 257.000427 -67.918859) (xy 256.946476 -67.911099) (xy 256.894178 -67.895741)
			(xy 256.844599 -67.873096) (xy 256.798746 -67.843626) (xy 256.757554 -67.807931) (xy 256.721862 -67.766738)
			(xy 256.692394 -67.720884) (xy 256.669752 -67.671303) (xy 256.654397 -67.619004) (xy 256.64664 -67.565053)
			(xy 256.64664 -67.510547) (xy 256.654397 -67.456596) (xy 256.669752 -67.404297) (xy 256.692394 -67.354716)
			(xy 256.721862 -67.308862) (xy 256.757554 -67.267669) (xy 256.798746 -67.231974) (xy 256.844599 -67.202504)
			(xy 256.894178 -67.179859) (xy 256.946476 -67.164501) (xy 257.000427 -67.156741) (xy 257.02768 -67.15633)
			(xy 257.028442 -67.15633) (xy 257.058796 -67.15696) (xy 257.118727 -67.166658) (xy 257.176366 -67.185724)
			(xy 257.230259 -67.213677) (xy 257.25501 -67.23126) (xy 257.267456 -67.240912) (xy 257.267964 -67.24142)
			(xy 257.27279 -67.244214) (xy 257.27836 -67.247013) (xy 257.290436 -67.250091) (xy 257.296666 -67.25031)
			(xy 257.313684 -67.25031) (xy 257.321173 -67.25062) (xy 257.335495 -67.255016) (xy 257.341878 -67.258946)
			(xy 257.350514 -67.26428) (xy 257.363976 -67.265804) (xy 257.368664 -67.266049) (xy 257.377995 -67.265029)
			(xy 257.382518 -67.263772) (xy 257.386836 -67.262248) (xy 257.391294 -67.260399) (xy 257.399477 -67.255285)
			(xy 257.403092 -67.252088) (xy 257.424527 -67.233334) (xy 257.471876 -67.201683) (xy 257.52336 -67.177331)
			(xy 257.577864 -67.160806) (xy 257.634203 -67.152467) (xy 257.66268 -67.152012) (xy 257.662934 -67.152012)
			(xy 257.691923 -67.152529) (xy 257.74925 -67.161195) (xy 257.804635 -67.178342) (xy 257.85683 -67.203584)
			(xy 257.90466 -67.236352) (xy 257.947048 -67.275909) (xy 257.965448 -67.298316) (xy 257.970782 -67.300856)
			(xy 257.980942 -67.30365) (xy 257.9878 -67.30365) (xy 257.997811 -67.303163) (xy 258.016312 -67.295505)
			(xy 258.030477 -67.281354) (xy 258.038153 -67.262861) (xy 258.0386 -67.25285) (xy 258.0386 -67.204844)
			(xy 258.038533 -67.201239) (xy 258.037506 -67.194102) (xy 258.036568 -67.19062) (xy 258.035044 -67.186048)
			(xy 258.031234 -67.176904) (xy 258.023614 -67.169284) (xy 257.703066 -66.848482) (xy 257.387344 -66.53276)
			(xy 257.384763 -66.530311) (xy 257.379025 -66.526105) (xy 257.375914 -66.524378) (xy 257.364484 -66.52006)
			(xy 257.352292 -66.518536) (xy 253.810516 -66.518536) (xy 253.783062 -66.518115) (xy 253.728911 -66.509055)
			(xy 253.70282 -66.500502) (xy 253.702566 -66.500248) (xy 253.701804 -66.499994) (xy 253.700026 -66.499232)
			(xy 253.699264 -66.498978) (xy 253.696978 -66.497962) (xy 253.678944 -66.490596) (xy 253.58344 -66.424048)
			(xy 253.576582 -66.418206) (xy 253.096776 -65.938146) (xy 253.092966 -65.93586) (xy 253.091442 -65.934844)
			(xy 253.075738 -65.924819) (xy 253.046463 -65.901772) (xy 253.033022 -65.88887) (xy 253.032006 -65.887854)
			(xy 252.617732 -65.47358) (xy 252.607064 -65.46723) (xy 252.601222 -65.465452) (xy 252.573912 -65.456424)
			(xy 252.522163 -65.431316) (xy 252.474769 -65.398725) (xy 252.432802 -65.359391) (xy 252.397214 -65.314205)
			(xy 252.36881 -65.264189) (xy 252.348233 -65.210477) (xy 252.33595 -65.154286) (xy 252.33224 -65.096887)
			(xy 252.334268 -65.068196) (xy 252.334522 -65.066164) (xy 252.334522 -65.065402) (xy 252.335792 -65.052956)
			(xy 252.332998 -65.041526) (xy 252.331351 -65.036453) (xy 252.326231 -65.027099) (xy 252.322838 -65.022984)
			(xy 252.278642 -64.9732) (xy 252.271022 -64.964564) (xy 252.266747 -64.960344) (xy 252.256602 -64.953914)
			(xy 252.250956 -64.951864) (xy 252.240288 -64.948816) (xy 251.71527 -64.948816) (xy 251.711664 -64.948881)
			(xy 251.704526 -64.949903) (xy 251.701046 -64.950848) (xy 251.696474 -64.952372) (xy 251.68733 -64.956182)
			(xy 250.660408 -65.983104) (xy 250.6435 -65.999393) (xy 250.605822 -66.027401) (xy 250.564482 -66.049652)
			(xy 250.542552 -66.058034) (xy 250.541282 -66.058034) (xy 250.524772 -66.064384) (xy 250.52274 -66.065146)
			(xy 250.519184 -66.066162) (xy 250.513088 -66.067432) (xy 250.512326 -66.067432) (xy 250.507754 -66.068194)
			(xy 250.506484 -66.068448) (xy 250.505722 -66.068702) (xy 250.505214 -66.068702) (xy 250.495909 -66.070842)
			(xy 250.4771 -66.074144) (xy 250.467622 -66.075306) (xy 250.467368 -66.075306) (xy 250.464828 -66.07556)
			(xy 250.432824 -66.077084) (xy 247.154446 -66.077084) (xy 247.141238 -66.078862) (xy 247.13057 -66.081656)
			(xy 247.11914 -66.086482) (xy 247.1166 -66.088006) (xy 247.095056 -66.099671) (xy 247.049633 -66.118028)
			(xy 247.002237 -66.130429) (xy 246.953644 -66.136671) (xy 246.929148 -66.137028) (xy 246.92864 -66.137028)
			(xy 246.901385 -66.136568) (xy 246.847428 -66.128816) (xy 246.795124 -66.113463) (xy 246.745538 -66.090823)
			(xy 246.699678 -66.061357) (xy 246.658479 -66.025663) (xy 246.622779 -65.98447) (xy 246.593305 -65.938615)
			(xy 246.570658 -65.889032) (xy 246.555297 -65.83673) (xy 246.547536 -65.782775) (xy 246.547132 -65.75552)
			(xy 246.546878 -65.75552) (xy 246.54734 -65.728586) (xy 246.554912 -65.675252) (xy 246.56991 -65.623513)
			(xy 246.592034 -65.574397) (xy 246.620845 -65.528881) (xy 246.655771 -65.487868) (xy 246.696117 -65.452175)
			(xy 246.741082 -65.42251) (xy 246.789772 -65.399463) (xy 246.815356 -65.39103) (xy 246.81561 -65.39103)
			(xy 246.821442 -65.389014) (xy 246.831968 -65.382584) (xy 246.836438 -65.37833) (xy 246.938038 -65.27673)
			(xy 246.956818 -65.258615) (xy 246.999014 -65.227927) (xy 247.045495 -65.204225) (xy 247.095113 -65.188092)
			(xy 247.146646 -65.179928) (xy 247.172734 -65.179448) (xy 250.074684 -65.179448) (xy 250.084336 -65.178432)
			(xy 250.09158 -65.176805) (xy 250.104749 -65.169963) (xy 250.110244 -65.16497) (xy 250.966478 -64.308736)
			(xy 250.985248 -64.290703) (xy 251.027365 -64.260121) (xy 251.073741 -64.236493) (xy 251.123238 -64.220398)
			(xy 251.174642 -64.212232) (xy 251.200666 -64.211708) (xy 251.50064 -64.211708) (xy 251.50699 -64.2112)
			(xy 251.515334 -64.209871) (xy 251.530514 -64.20247) (xy 251.536708 -64.196722) (xy 251.996702 -63.736474)
			(xy 251.997464 -63.735458) (xy 252.017623 -63.715279) (xy 252.063696 -63.681661) (xy 252.114969 -63.656681)
			(xy 252.142244 -63.648336) (xy 252.145038 -63.647828) (xy 252.147832 -63.647066) (xy 252.167911 -63.642056)
			(xy 252.20893 -63.636584) (xy 252.22962 -63.636144) (xy 254.3683 -63.636144) (xy 254.37545 -63.635756)
			(xy 254.389113 -63.631494) (xy 254.395224 -63.627762) (xy 254.402082 -63.622936) (xy 254.406654 -63.618872)
			(xy 254.411174 -63.614056) (xy 254.417738 -63.602601) (xy 254.419608 -63.596266) (xy 254.423164 -63.583312)
			(xy 254.427482 -63.572898) (xy 254.432054 -63.56096) (xy 254.433818 -63.556818) (xy 254.438547 -63.549159)
			(xy 254.441452 -63.54572) (xy 254.442468 -63.54445) (xy 254.446777 -63.539) (xy 254.452568 -63.526378)
			(xy 254.453898 -63.519558) (xy 254.454914 -63.5127) (xy 254.454152 -63.505842) (xy 254.453602 -63.502169)
			(xy 254.451555 -63.49503) (xy 254.450088 -63.491618) (xy 254.441452 -63.472314) (xy 254.441452 -63.471806)
			(xy 254.43688 -63.461392) (xy 254.430276 -63.454534) (xy 254.430022 -63.45428) (xy 254.429514 -63.453772)
			(xy 254.409283 -63.432375) (xy 254.374987 -63.384508) (xy 254.348451 -63.331942) (xy 254.330305 -63.275923)
			(xy 254.320979 -63.217781) (xy 254.320294 -63.188342) (xy 254.320294 -63.180214) (xy 254.321294 -63.151263)
			(xy 254.330965 -63.094148) (xy 254.349161 -63.039153) (xy 254.375462 -62.987541) (xy 254.409265 -62.940499)
			(xy 254.449792 -62.899109) (xy 254.496112 -62.864322) (xy 254.547158 -62.836939) (xy 254.601758 -62.817589)
			(xy 254.658656 -62.806717) (xy 254.687578 -62.805056) (xy 254.687832 -62.805056) (xy 254.701802 -62.804802)
			(xy 254.70231 -62.804802) (xy 254.727936 -62.805233) (xy 254.778721 -62.812134) (xy 254.828122 -62.825782)
			(xy 254.875246 -62.845931) (xy 254.919244 -62.872218) (xy 254.939546 -62.88786) (xy 254.94615 -62.89294)
			(xy 254.957326 -62.89675) (xy 254.970788 -62.898782) (xy 254.992632 -62.898782) (xy 254.996237 -62.898847)
			(xy 255.003375 -62.899871) (xy 255.006856 -62.900814) (xy 255.010412 -62.901576) (xy 255.06426 -62.901576)
			(xy 255.072864 -62.901241) (xy 255.089094 -62.895529) (xy 255.09601 -62.8904) (xy 255.096264 -62.890146)
			(xy 255.097026 -62.889638) (xy 255.101598 -62.886082) (xy 255.104138 -62.88405) (xy 255.1049 -62.883288)
			(xy 255.126998 -62.86754) (xy 255.128014 -62.867032) (xy 255.135888 -62.861698) (xy 255.139444 -62.859666)
			(xy 255.156082 -62.849894) (xy 255.190948 -62.833357) (xy 255.20904 -62.826646) (xy 255.209802 -62.826392)
			(xy 255.213612 -62.825122) (xy 255.238636 -62.817069) (xy 255.290257 -62.80713) (xy 255.316482 -62.80531)
			(xy 255.33604 -62.804802) (xy 255.336802 -62.804802) (xy 255.352804 -62.805056) (xy 255.357122 -62.80531)
			(xy 255.38653 -62.807454) (xy 255.444216 -62.819656) (xy 255.499343 -62.840574) (xy 255.550603 -62.86971)
			(xy 255.574038 -62.887606) (xy 255.574292 -62.88786) (xy 255.57734 -62.8904) (xy 255.583449 -62.894137)
			(xy 255.597114 -62.898399) (xy 255.604264 -62.898782) (xy 255.627632 -62.898782) (xy 255.633072 -62.898925)
			(xy 255.643704 -62.901232) (xy 255.648714 -62.903354) (xy 255.66243 -62.909704) (xy 255.667133 -62.911773)
			(xy 255.677114 -62.914214) (xy 255.682242 -62.91453) (xy 255.690878 -62.914022) (xy 255.698164 -62.91274)
			(xy 255.71159 -62.906542) (xy 255.717294 -62.90183) (xy 255.717548 -62.901576) (xy 255.738617 -62.883466)
			(xy 255.78501 -62.852901) (xy 255.835343 -62.829381) (xy 255.888553 -62.813405) (xy 255.943516 -62.805309)
			(xy 255.971294 -62.804802) (xy 255.971802 -62.804802) (xy 255.999054 -62.805265) (xy 256.053005 -62.813023)
			(xy 256.105302 -62.828379) (xy 256.154881 -62.851022) (xy 256.200733 -62.88049) (xy 256.241925 -62.916184)
			(xy 256.277617 -62.957377) (xy 256.307084 -63.00323) (xy 256.329725 -63.05281) (xy 256.34508 -63.105107)
			(xy 256.352835 -63.159057) (xy 256.35331 -63.18631) (xy 256.35274 -63.216037) (xy 256.343514 -63.27477)
			(xy 256.325285 -63.331361) (xy 256.298496 -63.384437) (xy 256.263796 -63.432714) (xy 256.243328 -63.45428)
			(xy 256.243074 -63.454534) (xy 256.236978 -63.460884) (xy 256.232914 -63.46952) (xy 256.229104 -63.477648)
			(xy 256.227072 -63.483744) (xy 256.224024 -63.497968) (xy 256.223157 -63.504155) (xy 256.224044 -63.516612)
			(xy 256.225802 -63.522606) (xy 256.244852 -63.569342) (xy 256.244852 -63.56985) (xy 256.260346 -63.606934)
			(xy 256.267204 -63.617856) (xy 256.274812 -63.626102) (xy 256.295113 -63.635587) (xy 256.30632 -63.636144)
			(xy 257.501136 -63.636144) (xy 257.509209 -63.634851) (xy 257.523974 -63.627852) (xy 257.530092 -63.622428)
			(xy 257.607308 -63.545212) (xy 257.61188 -63.539878) (xy 257.61188 -58.181494) (xy 257.611718 -58.175483)
			(xy 257.608902 -58.163797) (xy 257.606292 -58.15838) (xy 257.604452 -58.154906) (xy 257.599858 -58.148528)
			(xy 257.597148 -58.14568) (xy 257.275076 -57.823608) (xy 257.259603 -57.807607) (xy 257.232767 -57.772096)
			(xy 257.211088 -57.733222) (xy 257.202686 -57.71261) (xy 257.20167 -57.709816) (xy 257.195828 -57.700418)
			(xy 257.195574 -57.69991) (xy 257.180169 -57.678515) (xy 257.155619 -57.631861) (xy 257.138759 -57.581911)
			(xy 257.130015 -57.529922) (xy 257.12928 -57.503568) (xy 257.12928 -56.577992) (xy 257.125206 -56.572854)
			(xy 257.114911 -56.564741) (xy 257.10896 -56.56199) (xy 257.016504 -56.528208) (xy 257.00913 -56.525742)
			(xy 256.993608 -56.524968) (xy 256.986024 -56.526684) (xy 256.978658 -56.528716) (xy 256.96545 -56.537098)
			(xy 256.96037 -56.543194) (xy 256.942115 -56.564014) (xy 256.900631 -56.600686) (xy 256.854291 -56.630991)
			(xy 256.804063 -56.654293) (xy 256.750999 -56.670105) (xy 256.696209 -56.678096) (xy 256.668524 -56.678576)
			(xy 256.641272 -56.678114) (xy 256.587323 -56.670361) (xy 256.535027 -56.655008) (xy 256.485448 -56.632369)
			(xy 256.439596 -56.602904) (xy 256.398404 -56.567213) (xy 256.36271 -56.526024) (xy 256.333243 -56.480173)
			(xy 256.3106 -56.430596) (xy 256.295244 -56.3783) (xy 256.287487 -56.324352) (xy 256.287487 -56.269848)
			(xy 256.295244 -56.2159) (xy 256.3106 -56.163604) (xy 256.333243 -56.114027) (xy 256.36271 -56.068176)
			(xy 256.398404 -56.026987) (xy 256.439596 -55.991296) (xy 256.485448 -55.961831) (xy 256.535027 -55.939192)
			(xy 256.587323 -55.923839) (xy 256.641272 -55.916086) (xy 256.668524 -55.91556) (xy 256.6955 -55.916026)
			(xy 256.748916 -55.92362) (xy 256.800732 -55.938654) (xy 256.849917 -55.960828) (xy 256.895493 -55.989701)
			(xy 256.936554 -56.0247) (xy 256.954782 -56.044592) (xy 256.960624 -56.051196) (xy 256.976372 -56.06161)
			(xy 256.985614 -56.066299) (xy 257.006185 -56.068654) (xy 257.01625 -56.066182) (xy 257.072892 -56.045608)
			(xy 257.106166 -56.033416) (xy 257.112965 -56.030663) (xy 257.124705 -56.021878) (xy 257.12928 -56.016144)
			(xy 257.12928 -54.68112) (xy 257.129765 -54.655032) (xy 257.137929 -54.6035) (xy 257.154061 -54.553881)
			(xy 257.177761 -54.507399) (xy 257.208445 -54.465201) (xy 257.226562 -54.446424) (xy 257.265932 -54.407054)
			(xy 257.26771 -54.40045) (xy 257.264408 -54.387496) (xy 257.255264 -54.351428) (xy 257.25374 -54.348634)
			(xy 257.251962 -54.34584) (xy 257.24739 -54.337712) (xy 257.233674 -54.325774) (xy 257.231896 -54.325012)
			(xy 257.23088 -54.324758) (xy 257.22453 -54.322472) (xy 257.197241 -54.312032) (xy 257.145953 -54.284051)
			(xy 257.099532 -54.248576) (xy 257.059064 -54.206436) (xy 257.025495 -54.158618) (xy 256.999612 -54.106239)
			(xy 256.98202 -54.050527) (xy 256.97313 -53.992782) (xy 256.972562 -53.96357) (xy 256.97305 -53.936319)
			(xy 256.98081 -53.882373) (xy 256.996167 -53.83008) (xy 257.018809 -53.780505) (xy 257.048276 -53.734656)
			(xy 257.083967 -53.693467) (xy 257.125156 -53.657776) (xy 257.171005 -53.628309) (xy 257.22058 -53.605667)
			(xy 257.272873 -53.59031) (xy 257.326819 -53.58255) (xy 257.35407 -53.582062) (xy 257.380152 -53.58251)
			(xy 257.431829 -53.589615) (xy 257.482059 -53.603684) (xy 257.529909 -53.624454) (xy 257.574488 -53.651541)
			(xy 257.614969 -53.684439) (xy 257.650599 -53.722539) (xy 257.680714 -53.76513) (xy 257.69316 -53.788056)
			(xy 257.693414 -53.788564) (xy 257.694938 -53.791358) (xy 257.697237 -53.794993) (xy 257.702859 -53.8015)
			(xy 257.706114 -53.804312) (xy 257.734816 -53.826156) (xy 257.747262 -53.828188) (xy 257.816096 -53.84038)
			(xy 257.820131 -53.841013) (xy 257.828298 -53.841139) (xy 257.832352 -53.840634) (xy 258.856226 -52.81676)
			(xy 258.874997 -52.798729) (xy 258.917114 -52.768151) (xy 258.96349 -52.744527) (xy 259.012988 -52.728439)
			(xy 259.064391 -52.72028) (xy 259.090414 -52.719732) (xy 259.327904 -52.719732) (xy 259.339334 -52.716684)
			(xy 259.345176 -52.713636) (xy 259.370792 -52.700736) (xy 259.424968 -52.681915) (xy 259.48135 -52.67141)
			(xy 259.53867 -52.669456) (xy 259.595636 -52.676098) (xy 259.650968 -52.691185) (xy 259.703422 -52.714379)
			(xy 259.751816 -52.745157) (xy 259.795062 -52.782827) (xy 259.832188 -52.826542) (xy 259.862357 -52.875318)
			(xy 259.884891 -52.928058) (xy 259.892546 -52.955698) (xy 259.894324 -52.962556) (xy 259.898388 -52.969414)
			(xy 259.905754 -52.979066) (xy 260.42344 -53.496551) (xy 264.333464 -53.496551) (xy 264.333464 -53.442049)
			(xy 264.34122 -53.3881) (xy 264.356575 -53.335805) (xy 264.379216 -53.286227) (xy 264.408681 -53.240376)
			(xy 264.444372 -53.199185) (xy 264.485562 -53.163492) (xy 264.531412 -53.134024) (xy 264.580988 -53.111381)
			(xy 264.633283 -53.096024) (xy 264.687231 -53.088265) (xy 264.714482 -53.087778) (xy 264.741853 -53.088236)
			(xy 264.796033 -53.096053) (xy 264.848537 -53.111543) (xy 264.898284 -53.134387) (xy 264.944249 -53.164115)
			(xy 264.96518 -53.181758) (xy 264.965434 -53.182012) (xy 264.972534 -53.187578) (xy 264.989441 -53.193837)
			(xy 264.998454 -53.194204) (xy 265.06551 -53.194204) (xy 265.074527 -53.193851) (xy 265.091444 -53.1876)
			(xy 265.09853 -53.182012) (xy 265.09853 -53.181758) (xy 265.098784 -53.181758) (xy 265.119706 -53.164106)
			(xy 265.165682 -53.134397) (xy 265.215432 -53.111565) (xy 265.267935 -53.096076) (xy 265.322112 -53.08825)
			(xy 265.349482 -53.087778) (xy 265.376735 -53.088268) (xy 265.430686 -53.096023) (xy 265.482984 -53.111377)
			(xy 265.532564 -53.134017) (xy 265.578418 -53.163484) (xy 265.619611 -53.199176) (xy 265.655306 -53.240368)
			(xy 265.684774 -53.28622) (xy 265.707417 -53.335799) (xy 265.722773 -53.388097) (xy 265.730531 -53.442047)
			(xy 265.730531 -53.496553) (xy 265.722773 -53.550503) (xy 265.707417 -53.602801) (xy 265.684774 -53.65238)
			(xy 265.655306 -53.698232) (xy 265.619611 -53.739424) (xy 265.578418 -53.775116) (xy 265.532564 -53.804583)
			(xy 265.482984 -53.827223) (xy 265.430686 -53.842577) (xy 265.376735 -53.850332) (xy 265.349482 -53.850794)
			(xy 265.322111 -53.85034) (xy 265.267932 -53.842519) (xy 265.215428 -53.827028) (xy 265.165682 -53.804183)
			(xy 265.119715 -53.774456) (xy 265.098784 -53.756814) (xy 265.09853 -53.75656) (xy 265.091443 -53.750975)
			(xy 265.074526 -53.744728) (xy 265.06551 -53.744368) (xy 264.998454 -53.744368) (xy 264.989441 -53.744758)
			(xy 264.972524 -53.750983) (xy 264.965434 -53.75656) (xy 264.965434 -53.756814) (xy 264.96518 -53.756814)
			(xy 264.94423 -53.774431) (xy 264.898262 -53.804146) (xy 264.848519 -53.826986) (xy 264.796022 -53.842482)
			(xy 264.74185 -53.850316) (xy 264.714482 -53.850794) (xy 264.687231 -53.850335) (xy 264.633283 -53.842576)
			(xy 264.580988 -53.827219) (xy 264.531412 -53.804576) (xy 264.485562 -53.775108) (xy 264.444372 -53.739415)
			(xy 264.408681 -53.698224) (xy 264.379216 -53.652373) (xy 264.356575 -53.602795) (xy 264.34122 -53.5505)
			(xy 264.333464 -53.496551) (xy 260.42344 -53.496551) (xy 260.55955 -53.632608) (xy 260.577108 -53.650822)
			(xy 260.606851 -53.691743) (xy 260.629821 -53.736817) (xy 260.645452 -53.78493) (xy 260.653358 -53.834897)
			(xy 260.653784 -53.860192) (xy 260.653784 -54.912768) (xy 260.654242 -54.922405) (xy 260.661409 -54.9403)
			(xy 260.667754 -54.947566) (xy 260.67004 -54.949852) (xy 260.713334 -54.989051) (xy 262.101068 -54.989051)
			(xy 262.101068 -54.934549) (xy 262.108824 -54.880602) (xy 262.124178 -54.828308) (xy 262.146818 -54.778731)
			(xy 262.176283 -54.732881) (xy 262.211973 -54.69169) (xy 262.253161 -54.655997) (xy 262.29901 -54.62653)
			(xy 262.348585 -54.603887) (xy 262.400879 -54.588529) (xy 262.454825 -54.580769) (xy 262.482076 -54.580282)
			(xy 262.510167 -54.580796) (xy 262.565743 -54.58902) (xy 262.619512 -54.605307) (xy 262.670309 -54.629307)
			(xy 262.717036 -54.660499) (xy 262.758682 -54.698208) (xy 262.794345 -54.741619) (xy 262.809228 -54.765448)
			(xy 262.814562 -54.774338) (xy 262.83158 -54.78653) (xy 262.924798 -54.80685) (xy 262.945372 -54.802532)
			(xy 262.954008 -54.79669) (xy 262.978068 -54.780683) (xy 263.030001 -54.755342) (xy 263.08516 -54.738119)
			(xy 263.142285 -54.729406) (xy 263.171178 -54.728872) (xy 263.198429 -54.729376) (xy 263.252378 -54.737129)
			(xy 263.304674 -54.752481) (xy 263.354252 -54.77512) (xy 263.400105 -54.804584) (xy 263.441297 -54.840273)
			(xy 263.476991 -54.881462) (xy 263.50646 -54.927311) (xy 263.529104 -54.976887) (xy 263.544462 -55.029181)
			(xy 263.552221 -55.083129) (xy 263.552686 -55.11038) (xy 263.552212 -55.13775) (xy 263.544396 -55.191929)
			(xy 263.528909 -55.244432) (xy 263.506069 -55.294179) (xy 263.476346 -55.340146) (xy 263.458706 -55.361078)
			(xy 263.458452 -55.361332) (xy 263.452882 -55.36843) (xy 263.446627 -55.385338) (xy 263.44626 -55.394352)
			(xy 263.44626 -55.461408) (xy 263.4466 -55.470427) (xy 263.452858 -55.487344) (xy 263.458452 -55.494428)
			(xy 263.458706 -55.494428) (xy 263.458706 -55.494682) (xy 263.476326 -55.515631) (xy 263.506049 -55.561597)
			(xy 263.528893 -55.611341) (xy 263.54439 -55.66384) (xy 263.552219 -55.718016) (xy 263.552222 -55.772754)
			(xy 263.544396 -55.826931) (xy 263.528904 -55.879431) (xy 263.506063 -55.929177) (xy 263.476344 -55.975145)
			(xy 263.458706 -55.996078) (xy 263.458452 -55.996332) (xy 263.452882 -56.00343) (xy 263.446627 -56.020338)
			(xy 263.44626 -56.029352) (xy 263.44626 -56.096408) (xy 263.4466 -56.105427) (xy 263.452858 -56.122344)
			(xy 263.458452 -56.129428) (xy 263.458706 -56.129428) (xy 263.458706 -56.129682) (xy 263.476351 -56.150609)
			(xy 263.506062 -56.196583) (xy 263.528896 -56.246332) (xy 263.544386 -56.298834) (xy 263.552213 -56.353011)
			(xy 263.552686 -56.38038) (xy 263.5522 -56.407631) (xy 263.544444 -56.461579) (xy 263.529089 -56.513874)
			(xy 263.506447 -56.563451) (xy 263.476981 -56.609301) (xy 263.44129 -56.650492) (xy 263.400099 -56.686183)
			(xy 263.354249 -56.715649) (xy 263.304672 -56.738291) (xy 263.252377 -56.753646) (xy 263.198429 -56.761402)
			(xy 263.143927 -56.761402) (xy 263.089979 -56.753646) (xy 263.037684 -56.738291) (xy 262.988107 -56.715649)
			(xy 262.942257 -56.686183) (xy 262.901066 -56.650492) (xy 262.865375 -56.609301) (xy 262.835909 -56.563451)
			(xy 262.813267 -56.513874) (xy 262.797912 -56.461579) (xy 262.790156 -56.407631) (xy 262.78967 -56.38038)
			(xy 262.790107 -56.353009) (xy 262.797929 -56.298828) (xy 262.813424 -56.246323) (xy 262.836273 -56.196577)
			(xy 262.866005 -56.150612) (xy 262.88365 -56.129682) (xy 262.883904 -56.129428) (xy 262.889485 -56.122338)
			(xy 262.895735 -56.105424) (xy 262.896096 -56.096408) (xy 262.896096 -56.029352) (xy 262.895715 -56.020338)
			(xy 262.889484 -56.00342) (xy 262.883904 -55.996332) (xy 262.88365 -55.996332) (xy 262.88365 -55.996078)
			(xy 262.865989 -55.975162) (xy 262.836263 -55.929192) (xy 262.813417 -55.879443) (xy 262.797922 -55.826938)
			(xy 262.790094 -55.772757) (xy 262.790097 -55.718013) (xy 262.797928 -55.663833) (xy 262.813428 -55.611329)
			(xy 262.836278 -55.561582) (xy 262.866007 -55.515614) (xy 262.88365 -55.494682) (xy 262.883904 -55.494428)
			(xy 262.889485 -55.487338) (xy 262.895735 -55.470424) (xy 262.896096 -55.461408) (xy 262.896096 -55.394352)
			(xy 262.895715 -55.385338) (xy 262.889484 -55.36842) (xy 262.883904 -55.361332) (xy 262.88365 -55.360824)
			(xy 262.872704 -55.348092) (xy 262.852864 -55.320999) (xy 262.844026 -55.306722) (xy 262.838692 -55.297832)
			(xy 262.821674 -55.28564) (xy 262.728456 -55.26532) (xy 262.707882 -55.269638) (xy 262.699246 -55.27548)
			(xy 262.67517 -55.29146) (xy 262.623243 -55.316808) (xy 262.568089 -55.334039) (xy 262.510967 -55.34276)
			(xy 262.482076 -55.343298) (xy 262.454825 -55.342831) (xy 262.400879 -55.335071) (xy 262.348585 -55.319713)
			(xy 262.29901 -55.29707) (xy 262.253161 -55.267603) (xy 262.211973 -55.23191) (xy 262.176283 -55.190719)
			(xy 262.146818 -55.144869) (xy 262.124178 -55.095292) (xy 262.108824 -55.042998) (xy 262.101068 -54.989051)
			(xy 260.713334 -54.989051) (xy 260.726428 -55.000906) (xy 260.733794 -55.006494) (xy 260.73991 -55.009971)
			(xy 260.753434 -55.013827) (xy 260.760464 -55.014114) (xy 260.76529 -55.014114) (xy 260.767576 -55.01386)
			(xy 260.80466 -55.012082) (xy 260.805168 -55.012082) (xy 260.81228 -55.012082) (xy 260.842198 -55.013184)
			(xy 260.901159 -55.023556) (xy 260.957775 -55.043014) (xy 261.010654 -55.07108) (xy 261.0585 -55.107063)
			(xy 261.079742 -55.12816) (xy 261.086854 -55.135526) (xy 261.116064 -55.148226) (xy 261.120219 -55.149779)
			(xy 261.128906 -55.151559) (xy 261.133336 -55.151782) (xy 261.187946 -55.151782) (xy 261.197852 -55.150004)
			(xy 261.207504 -55.147972) (xy 261.235698 -55.135526) (xy 261.242556 -55.128414) (xy 261.260584 -55.110344)
			(xy 261.300632 -55.078696) (xy 261.344544 -55.052672) (xy 261.391535 -55.032739) (xy 261.440765 -55.019253)
			(xy 261.491354 -55.012454) (xy 261.516876 -55.012082) (xy 261.544131 -55.012543) (xy 261.598086 -55.020298)
			(xy 261.650388 -55.035652) (xy 261.699972 -55.058294) (xy 261.74583 -55.087762) (xy 261.787026 -55.123457)
			(xy 261.822724 -55.164651) (xy 261.852195 -55.210507) (xy 261.87484 -55.26009) (xy 261.890197 -55.312391)
			(xy 261.897955 -55.366345) (xy 261.897955 -55.420855) (xy 261.890197 -55.474809) (xy 261.87484 -55.52711)
			(xy 261.852195 -55.576693) (xy 261.822724 -55.622549) (xy 261.787026 -55.663743) (xy 261.74583 -55.699438)
			(xy 261.699972 -55.728906) (xy 261.650388 -55.751548) (xy 261.598086 -55.766902) (xy 261.544131 -55.774657)
			(xy 261.516876 -55.775098) (xy 261.491388 -55.774672) (xy 261.440866 -55.767882) (xy 261.391698 -55.754426)
			(xy 261.344759 -55.734543) (xy 261.300885 -55.708588) (xy 261.260858 -55.677023) (xy 261.24281 -55.65902)
			(xy 261.235698 -55.651654) (xy 261.206488 -55.638954) (xy 261.202334 -55.637397) (xy 261.193647 -55.635608)
			(xy 261.189216 -55.635398) (xy 261.140194 -55.635398) (xy 261.130034 -55.636414) (xy 261.119112 -55.6387)
			(xy 261.113524 -55.639716) (xy 261.086854 -55.651654) (xy 261.079996 -55.65902) (xy 261.062335 -55.676676)
			(xy 261.023188 -55.707686) (xy 260.980326 -55.733317) (xy 260.957568 -55.743602) (xy 260.949694 -55.747158)
			(xy 260.943852 -55.752238) (xy 260.935216 -55.762398) (xy 260.922262 -55.785004) (xy 260.922262 -55.785258)
			(xy 260.919468 -55.790084) (xy 260.915827 -55.79693) (xy 260.912464 -55.812059) (xy 260.912864 -55.819802)
			(xy 260.913118 -55.824374) (xy 260.91388 -55.84825) (xy 260.91388 -57.48528) (xy 262.805924 -57.48528)
			(xy 262.809995 -57.429658) (xy 262.822121 -57.375221) (xy 262.842044 -57.32313) (xy 262.86934 -57.274495)
			(xy 262.903426 -57.230352) (xy 262.943575 -57.191643) (xy 262.988933 -57.159192) (xy 263.038533 -57.133691)
			(xy 263.091317 -57.115684) (xy 263.14616 -57.105554) (xy 263.201894 -57.103517) (xy 263.257331 -57.109617)
			(xy 263.311288 -57.123723) (xy 263.362617 -57.145535) (xy 263.410223 -57.174589) (xy 263.453091 -57.210264)
			(xy 263.490308 -57.251801) (xy 263.521081 -57.298314) (xy 263.544753 -57.348811) (xy 263.560821 -57.402218)
			(xy 263.568941 -57.457394) (xy 263.56945 -57.48528) (xy 263.568941 -57.513166) (xy 263.560821 -57.568342)
			(xy 263.544753 -57.621749) (xy 263.521081 -57.672246) (xy 263.490308 -57.718759) (xy 263.453091 -57.760296)
			(xy 263.410223 -57.795971) (xy 263.362617 -57.825025) (xy 263.311288 -57.846837) (xy 263.257331 -57.860943)
			(xy 263.201894 -57.867043) (xy 263.14616 -57.865006) (xy 263.091317 -57.854876) (xy 263.038533 -57.836869)
			(xy 262.988933 -57.811368) (xy 262.943575 -57.778917) (xy 262.903426 -57.740208) (xy 262.86934 -57.696065)
			(xy 262.842044 -57.64743) (xy 262.822121 -57.595339) (xy 262.809995 -57.540902) (xy 262.805924 -57.48528)
			(xy 260.91388 -57.48528) (xy 260.91388 -58.561224) (xy 264.762232 -58.561224) (xy 264.766303 -58.505602)
			(xy 264.778429 -58.451165) (xy 264.798352 -58.399074) (xy 264.825648 -58.350439) (xy 264.859734 -58.306296)
			(xy 264.899883 -58.267587) (xy 264.945241 -58.235136) (xy 264.994841 -58.209635) (xy 265.047625 -58.191628)
			(xy 265.102468 -58.181498) (xy 265.158202 -58.179461) (xy 265.213639 -58.185561) (xy 265.267596 -58.199667)
			(xy 265.318925 -58.221479) (xy 265.366531 -58.250533) (xy 265.409399 -58.286208) (xy 265.446616 -58.327745)
			(xy 265.477389 -58.374258) (xy 265.501061 -58.424755) (xy 265.517129 -58.478162) (xy 265.525249 -58.533338)
			(xy 265.525758 -58.561224) (xy 265.525249 -58.58911) (xy 265.517129 -58.644286) (xy 265.501061 -58.697693)
			(xy 265.477389 -58.74819) (xy 265.446616 -58.794703) (xy 265.409399 -58.83624) (xy 265.366531 -58.871915)
			(xy 265.318925 -58.900969) (xy 265.267596 -58.922781) (xy 265.213639 -58.936887) (xy 265.158202 -58.942987)
			(xy 265.102468 -58.94095) (xy 265.047625 -58.93082) (xy 264.994841 -58.912813) (xy 264.945241 -58.887312)
			(xy 264.899883 -58.854861) (xy 264.859734 -58.816152) (xy 264.825648 -58.772009) (xy 264.798352 -58.723374)
			(xy 264.778429 -58.671283) (xy 264.766303 -58.616846) (xy 264.762232 -58.561224) (xy 260.91388 -58.561224)
			(xy 260.91388 -59.174634) (xy 263.293096 -59.174634) (xy 263.297167 -59.119012) (xy 263.309293 -59.064575)
			(xy 263.329216 -59.012484) (xy 263.356512 -58.963849) (xy 263.390598 -58.919706) (xy 263.430747 -58.880997)
			(xy 263.476105 -58.848546) (xy 263.525705 -58.823045) (xy 263.578489 -58.805038) (xy 263.633332 -58.794908)
			(xy 263.689066 -58.792871) (xy 263.744503 -58.798971) (xy 263.79846 -58.813077) (xy 263.849789 -58.834889)
			(xy 263.897395 -58.863943) (xy 263.940263 -58.899618) (xy 263.97748 -58.941155) (xy 264.008253 -58.987668)
			(xy 264.031925 -59.038165) (xy 264.047993 -59.091572) (xy 264.056113 -59.146748) (xy 264.056622 -59.174634)
			(xy 264.056113 -59.20252) (xy 264.047993 -59.257696) (xy 264.031925 -59.311103) (xy 264.008253 -59.3616)
			(xy 263.97748 -59.408113) (xy 263.940263 -59.44965) (xy 263.897395 -59.485325) (xy 263.849789 -59.514379)
			(xy 263.79846 -59.536191) (xy 263.744503 -59.550297) (xy 263.689066 -59.556397) (xy 263.633332 -59.55436)
			(xy 263.578489 -59.54423) (xy 263.525705 -59.526223) (xy 263.476105 -59.500722) (xy 263.430747 -59.468271)
			(xy 263.390598 -59.429562) (xy 263.356512 -59.385419) (xy 263.329216 -59.336784) (xy 263.309293 -59.284693)
			(xy 263.297167 -59.230256) (xy 263.293096 -59.174634) (xy 260.91388 -59.174634) (xy 260.91388 -60.633356)
			(xy 265.996926 -60.633356) (xy 266.000997 -60.577734) (xy 266.013123 -60.523297) (xy 266.033046 -60.471206)
			(xy 266.060342 -60.422571) (xy 266.094428 -60.378428) (xy 266.134577 -60.339719) (xy 266.179935 -60.307268)
			(xy 266.229535 -60.281767) (xy 266.282319 -60.26376) (xy 266.337162 -60.25363) (xy 266.392896 -60.251593)
			(xy 266.448333 -60.257693) (xy 266.50229 -60.271799) (xy 266.553619 -60.293611) (xy 266.601225 -60.322665)
			(xy 266.644093 -60.35834) (xy 266.68131 -60.399877) (xy 266.712083 -60.44639) (xy 266.735755 -60.496887)
			(xy 266.751823 -60.550294) (xy 266.759943 -60.60547) (xy 266.760452 -60.633356) (xy 266.759943 -60.661242)
			(xy 266.751823 -60.716418) (xy 266.735755 -60.769825) (xy 266.712083 -60.820322) (xy 266.68131 -60.866835)
			(xy 266.644093 -60.908372) (xy 266.601225 -60.944047) (xy 266.553619 -60.973101) (xy 266.50229 -60.994913)
			(xy 266.448333 -61.009019) (xy 266.392896 -61.015119) (xy 266.337162 -61.013082) (xy 266.282319 -61.002952)
			(xy 266.229535 -60.984945) (xy 266.179935 -60.959444) (xy 266.134577 -60.926993) (xy 266.094428 -60.888284)
			(xy 266.060342 -60.844141) (xy 266.033046 -60.795506) (xy 266.013123 -60.743415) (xy 266.000997 -60.688978)
			(xy 265.996926 -60.633356) (xy 260.91388 -60.633356) (xy 260.91388 -61.487812) (xy 264.504422 -61.487812)
			(xy 264.508493 -61.43219) (xy 264.520619 -61.377753) (xy 264.540542 -61.325662) (xy 264.567838 -61.277027)
			(xy 264.601924 -61.232884) (xy 264.642073 -61.194175) (xy 264.687431 -61.161724) (xy 264.737031 -61.136223)
			(xy 264.789815 -61.118216) (xy 264.844658 -61.108086) (xy 264.900392 -61.106049) (xy 264.955829 -61.112149)
			(xy 265.009786 -61.126255) (xy 265.061115 -61.148067) (xy 265.108721 -61.177121) (xy 265.151589 -61.212796)
			(xy 265.188806 -61.254333) (xy 265.219579 -61.300846) (xy 265.243251 -61.351343) (xy 265.259319 -61.40475)
			(xy 265.267439 -61.459926) (xy 265.267948 -61.487812) (xy 265.267439 -61.515698) (xy 265.259319 -61.570874)
			(xy 265.243251 -61.624281) (xy 265.219579 -61.674778) (xy 265.188806 -61.721291) (xy 265.151589 -61.762828)
			(xy 265.108721 -61.798503) (xy 265.061115 -61.827557) (xy 265.009786 -61.849369) (xy 264.955829 -61.863475)
			(xy 264.900392 -61.869575) (xy 264.844658 -61.867538) (xy 264.789815 -61.857408) (xy 264.737031 -61.839401)
			(xy 264.687431 -61.8139) (xy 264.642073 -61.781449) (xy 264.601924 -61.74274) (xy 264.567838 -61.698597)
			(xy 264.540542 -61.649962) (xy 264.520619 -61.597871) (xy 264.508493 -61.543434) (xy 264.504422 -61.487812)
			(xy 260.91388 -61.487812) (xy 260.91388 -62.121034) (xy 262.442196 -62.121034) (xy 262.446267 -62.065412)
			(xy 262.458393 -62.010975) (xy 262.478316 -61.958884) (xy 262.505612 -61.910249) (xy 262.539698 -61.866106)
			(xy 262.579847 -61.827397) (xy 262.625205 -61.794946) (xy 262.674805 -61.769445) (xy 262.727589 -61.751438)
			(xy 262.782432 -61.741308) (xy 262.838166 -61.739271) (xy 262.893603 -61.745371) (xy 262.94756 -61.759477)
			(xy 262.998889 -61.781289) (xy 263.046495 -61.810343) (xy 263.089363 -61.846018) (xy 263.12658 -61.887555)
			(xy 263.157353 -61.934068) (xy 263.181025 -61.984565) (xy 263.197093 -62.037972) (xy 263.205213 -62.093148)
			(xy 263.205722 -62.121034) (xy 263.205213 -62.14892) (xy 263.197093 -62.204096) (xy 263.181025 -62.257503)
			(xy 263.157353 -62.308) (xy 263.12658 -62.354513) (xy 263.089363 -62.39605) (xy 263.046495 -62.431725)
			(xy 262.998889 -62.460779) (xy 262.94756 -62.482591) (xy 262.893603 -62.496697) (xy 262.838166 -62.502797)
			(xy 262.782432 -62.50076) (xy 262.727589 -62.49063) (xy 262.674805 -62.472623) (xy 262.625205 -62.447122)
			(xy 262.579847 -62.414671) (xy 262.539698 -62.375962) (xy 262.505612 -62.331819) (xy 262.478316 -62.283184)
			(xy 262.458393 -62.231093) (xy 262.446267 -62.176656) (xy 262.442196 -62.121034) (xy 260.91388 -62.121034)
			(xy 260.91388 -63.273432) (xy 261.776716 -63.273432) (xy 261.780787 -63.21781) (xy 261.792913 -63.163373)
			(xy 261.812836 -63.111282) (xy 261.840132 -63.062647) (xy 261.874218 -63.018504) (xy 261.914367 -62.979795)
			(xy 261.959725 -62.947344) (xy 262.009325 -62.921843) (xy 262.062109 -62.903836) (xy 262.116952 -62.893706)
			(xy 262.172686 -62.891669) (xy 262.228123 -62.897769) (xy 262.28208 -62.911875) (xy 262.333409 -62.933687)
			(xy 262.381015 -62.962741) (xy 262.423883 -62.998416) (xy 262.4611 -63.039953) (xy 262.491873 -63.086466)
			(xy 262.515545 -63.136963) (xy 262.531613 -63.19037) (xy 262.539733 -63.245546) (xy 262.540242 -63.273432)
			(xy 262.539733 -63.301318) (xy 262.531613 -63.356494) (xy 262.515545 -63.409901) (xy 262.491873 -63.460398)
			(xy 262.4611 -63.506911) (xy 262.423883 -63.548448) (xy 262.381015 -63.584123) (xy 262.333409 -63.613177)
			(xy 262.28208 -63.634989) (xy 262.228123 -63.649095) (xy 262.172686 -63.655195) (xy 262.116952 -63.653158)
			(xy 262.062109 -63.643028) (xy 262.009325 -63.625021) (xy 261.959725 -63.59952) (xy 261.914367 -63.567069)
			(xy 261.874218 -63.52836) (xy 261.840132 -63.484217) (xy 261.812836 -63.435582) (xy 261.792913 -63.383491)
			(xy 261.780787 -63.329054) (xy 261.776716 -63.273432) (xy 260.91388 -63.273432) (xy 260.91388 -65.124076)
			(xy 264.307318 -65.124076) (xy 264.311389 -65.068454) (xy 264.323515 -65.014017) (xy 264.343438 -64.961926)
			(xy 264.370734 -64.913291) (xy 264.40482 -64.869148) (xy 264.444969 -64.830439) (xy 264.490327 -64.797988)
			(xy 264.539927 -64.772487) (xy 264.592711 -64.75448) (xy 264.647554 -64.74435) (xy 264.703288 -64.742313)
			(xy 264.758725 -64.748413) (xy 264.812682 -64.762519) (xy 264.864011 -64.784331) (xy 264.911617 -64.813385)
			(xy 264.954485 -64.84906) (xy 264.991702 -64.890597) (xy 265.022475 -64.93711) (xy 265.046147 -64.987607)
			(xy 265.062215 -65.041014) (xy 265.070335 -65.09619) (xy 265.070844 -65.124076) (xy 265.070335 -65.151962)
			(xy 265.062215 -65.207138) (xy 265.046147 -65.260545) (xy 265.022475 -65.311042) (xy 264.991702 -65.357555)
			(xy 264.954485 -65.399092) (xy 264.911617 -65.434767) (xy 264.864011 -65.463821) (xy 264.812682 -65.485633)
			(xy 264.758725 -65.499739) (xy 264.703288 -65.505839) (xy 264.647554 -65.503802) (xy 264.592711 -65.493672)
			(xy 264.539927 -65.475665) (xy 264.490327 -65.450164) (xy 264.444969 -65.417713) (xy 264.40482 -65.379004)
			(xy 264.370734 -65.334861) (xy 264.343438 -65.286226) (xy 264.323515 -65.234135) (xy 264.311389 -65.179698)
			(xy 264.307318 -65.124076) (xy 260.91388 -65.124076) (xy 260.91388 -69.28358) (xy 260.914388 -69.290438)
			(xy 263.255252 -71.631302) (xy 263.258808 -71.634604) (xy 263.268242 -71.641578) (xy 263.291066 -71.646893)
			(xy 263.31389 -71.641578) (xy 263.323324 -71.634604) (xy 263.327388 -71.63054) (xy 263.331558 -71.626188)
			(xy 263.337851 -71.615912) (xy 263.339834 -71.61022) (xy 263.343136 -71.599806) (xy 263.342374 -71.595742)
			(xy 263.341104 -71.58736) (xy 263.339223 -71.57468) (xy 263.337187 -71.549124) (xy 263.33704 -71.536306)
			(xy 263.33704 -70.315582) (xy 263.337527 -70.289495) (xy 263.345697 -70.237965) (xy 263.361831 -70.188349)
			(xy 263.385532 -70.14187) (xy 263.416216 -70.099673) (xy 263.434322 -70.080886) (xy 267.658596 -65.856866)
			(xy 267.6628 -65.852394) (xy 267.669092 -65.841858) (xy 267.671042 -65.836038) (xy 267.672095 -65.832381)
			(xy 267.673243 -65.824857) (xy 267.673328 -65.821052) (xy 267.673328 -63.403988) (xy 267.67282 -63.396876)
			(xy 267.671398 -63.38892) (xy 267.664272 -63.374422) (xy 267.65885 -63.368428) (xy 267.02258 -62.732412)
			(xy 266.714224 -62.424056) (xy 266.703556 -62.417706) (xy 266.697968 -62.415928) (xy 266.693904 -62.414658)
			(xy 266.684281 -62.411476) (xy 266.665349 -62.404231) (xy 266.656058 -62.40018) (xy 266.627102 -62.385702)
			(xy 266.626594 -62.385702) (xy 266.621768 -62.382654) (xy 266.62126 -62.382654) (xy 266.592558 -62.364366)
			(xy 266.587986 -62.361318) (xy 266.579537 -62.356835) (xy 266.560654 -62.353882) (xy 266.542 -62.358039)
			(xy 266.533884 -62.363096) (xy 266.533884 -62.36335) (xy 266.525857 -62.369312) (xy 266.514753 -62.385915)
			(xy 266.512294 -62.395608) (xy 266.511278 -62.404244) (xy 266.510955 -62.408387) (xy 266.511473 -62.41668)
			(xy 266.512294 -62.420754) (xy 266.513818 -62.427358) (xy 266.520168 -62.439042) (xy 266.52474 -62.443868)
			(xy 266.544133 -62.465225) (xy 266.57692 -62.512689) (xy 266.602191 -62.564547) (xy 266.619371 -62.619617)
			(xy 266.628068 -62.676645) (xy 266.628626 -62.705488) (xy 266.628626 -62.71514) (xy 266.628372 -62.722506)
			(xy 266.626777 -62.748969) (xy 266.617184 -62.801108) (xy 266.600462 -62.851416) (xy 266.576936 -62.898923)
			(xy 266.547056 -62.942715) (xy 266.5114 -62.981947) (xy 266.470655 -63.015863) (xy 266.425605 -63.043809)
			(xy 266.377119 -63.065248) (xy 266.326132 -63.079765) (xy 266.273625 -63.087082) (xy 266.247118 -63.087504)
			(xy 266.219865 -63.087042) (xy 266.165912 -63.079287) (xy 266.113613 -63.063933) (xy 266.064031 -63.041292)
			(xy 266.018176 -63.011824) (xy 265.976982 -62.976131) (xy 265.941286 -62.934938) (xy 265.911817 -62.889085)
			(xy 265.889174 -62.839504) (xy 265.873817 -62.787205) (xy 265.866059 -62.733253) (xy 265.866059 -62.678747)
			(xy 265.873817 -62.624795) (xy 265.889174 -62.572496) (xy 265.911817 -62.522915) (xy 265.941286 -62.477062)
			(xy 265.976982 -62.435869) (xy 266.018176 -62.400176) (xy 266.064031 -62.370708) (xy 266.113613 -62.348067)
			(xy 266.165912 -62.332713) (xy 266.219865 -62.324958) (xy 266.247118 -62.324488) (xy 266.24788 -62.324488)
			(xy 266.270252 -62.324808) (xy 266.31469 -62.330024) (xy 266.336526 -62.334902) (xy 266.337796 -62.33541)
			(xy 266.344146 -62.336426) (xy 266.351258 -62.336934) (xy 266.361629 -62.336762) (xy 266.380908 -62.329164)
			(xy 266.388596 -62.322202) (xy 266.39139 -62.319408) (xy 266.446254 -62.256162) (xy 266.451929 -62.249038)
			(xy 266.458299 -62.231988) (xy 266.4587 -62.222888) (xy 266.4587 -62.208918) (xy 266.455144 -62.190122)
			(xy 266.45362 -62.186058) (xy 266.442224 -62.153709) (xy 266.429952 -62.086236) (xy 266.429236 -62.051946)
			(xy 266.429236 -62.051438) (xy 266.42949 -62.039246) (xy 266.429998 -62.032642) (xy 266.429998 -62.031626)
			(xy 266.431836 -62.00493) (xy 266.442052 -61.952405) (xy 266.459509 -61.901823) (xy 266.483864 -61.854177)
			(xy 266.51464 -61.810403) (xy 266.532614 -61.79058) (xy 266.553352 -61.769283) (xy 266.600232 -61.732737)
			(xy 266.652208 -61.703897) (xy 266.708026 -61.683461) (xy 266.766337 -61.671921) (xy 266.796012 -61.670184)
			(xy 266.807696 -61.66993) (xy 266.812522 -61.66993) (xy 266.843358 -61.670476) (xy 266.90424 -61.680307)
			(xy 266.962747 -61.699806) (xy 266.990322 -61.713618) (xy 266.995854 -61.716309) (xy 267.007795 -61.719253)
			(xy 267.013944 -61.71946) (xy 267.161518 -61.71946) (xy 267.171396 -61.719001) (xy 267.1897 -61.711565)
			(xy 267.197078 -61.704982) (xy 267.364718 -61.537342) (xy 267.704062 -61.198252) (xy 267.71074 -61.190973)
			(xy 267.718444 -61.172806) (xy 267.719048 -61.162946) (xy 267.719048 -58.840624) (xy 267.715921 -58.836625)
			(xy 267.708374 -58.829839) (xy 267.704062 -58.827162) (xy 267.673582 -58.809382) (xy 267.629132 -58.783474)
			(xy 267.620977 -58.779488) (xy 267.603009 -58.777014) (xy 267.59408 -58.778648) (xy 267.578078 -58.782458)
			(xy 267.57249 -58.785506) (xy 267.544488 -58.799879) (xy 267.484941 -58.820261) (xy 267.422857 -58.830591)
			(xy 267.391388 -58.831226) (xy 267.39088 -58.831226) (xy 267.363628 -58.830739) (xy 267.30968 -58.82298)
			(xy 267.257385 -58.807622) (xy 267.207808 -58.784979) (xy 267.161958 -58.75551) (xy 267.120769 -58.719817)
			(xy 267.085078 -58.678626) (xy 267.055612 -58.632774) (xy 267.032971 -58.583196) (xy 267.017616 -58.5309)
			(xy 267.00986 -58.476952) (xy 267.00986 -58.422448) (xy 267.017616 -58.3685) (xy 267.032971 -58.316204)
			(xy 267.055612 -58.266626) (xy 267.085078 -58.220774) (xy 267.120769 -58.179583) (xy 267.161958 -58.14389)
			(xy 267.207808 -58.114421) (xy 267.257385 -58.091778) (xy 267.30968 -58.07642) (xy 267.363628 -58.068661)
			(xy 267.39088 -58.06821) (xy 267.391642 -58.06821) (xy 267.423548 -58.068853) (xy 267.486469 -58.079474)
			(xy 267.546741 -58.10043) (xy 267.57503 -58.1152) (xy 267.576808 -58.116216) (xy 267.586206 -58.121804)
			(xy 267.596874 -58.123074) (xy 267.597382 -58.123074) (xy 267.602301 -58.12352) (xy 267.612147 -58.122747)
			(xy 267.61694 -58.12155) (xy 267.625068 -58.11901) (xy 267.631672 -58.114692) (xy 267.704062 -58.072274)
			(xy 267.70838 -58.069602) (xy 267.715938 -58.062825) (xy 267.719048 -58.058812) (xy 267.719048 -54.889146)
			(xy 267.71866 -54.879619) (xy 267.711715 -54.861875) (xy 267.698767 -54.847896) (xy 267.690346 -54.843426)
			(xy 267.687298 -54.842156) (xy 267.680128 -54.839442) (xy 267.664871 -54.838007) (xy 267.657326 -54.839362)
			(xy 267.650722 -54.840632) (xy 267.638022 -54.84749) (xy 264.618216 -57.867296) (xy 265.843002 -57.867296)
			(xy 265.847073 -57.811674) (xy 265.859199 -57.757237) (xy 265.879122 -57.705146) (xy 265.906418 -57.656511)
			(xy 265.940504 -57.612368) (xy 265.980653 -57.573659) (xy 266.026011 -57.541208) (xy 266.075611 -57.515707)
			(xy 266.128395 -57.4977) (xy 266.183238 -57.48757) (xy 266.238972 -57.485533) (xy 266.294409 -57.491633)
			(xy 266.348366 -57.505739) (xy 266.399695 -57.527551) (xy 266.447301 -57.556605) (xy 266.490169 -57.59228)
			(xy 266.527386 -57.633817) (xy 266.558159 -57.68033) (xy 266.581831 -57.730827) (xy 266.597899 -57.784234)
			(xy 266.606019 -57.83941) (xy 266.606528 -57.867296) (xy 266.606019 -57.895182) (xy 266.597899 -57.950358)
			(xy 266.581831 -58.003765) (xy 266.558159 -58.054262) (xy 266.527386 -58.100775) (xy 266.490169 -58.142312)
			(xy 266.447301 -58.177987) (xy 266.399695 -58.207041) (xy 266.348366 -58.228853) (xy 266.294409 -58.242959)
			(xy 266.238972 -58.249059) (xy 266.183238 -58.247022) (xy 266.128395 -58.236892) (xy 266.075611 -58.218885)
			(xy 266.026011 -58.193384) (xy 265.980653 -58.160933) (xy 265.940504 -58.122224) (xy 265.906418 -58.078081)
			(xy 265.879122 -58.029446) (xy 265.859199 -57.977355) (xy 265.847073 -57.922918) (xy 265.843002 -57.867296)
			(xy 264.618216 -57.867296) (xy 264.312654 -58.172858) (xy 264.306304 -58.183526) (xy 264.304526 -58.189368)
			(xy 264.296077 -58.214935) (xy 264.272997 -58.263583) (xy 264.243311 -58.308506) (xy 264.207607 -58.348812)
			(xy 264.166595 -58.383703) (xy 264.121088 -58.412485) (xy 264.071988 -58.434588) (xy 264.020269 -58.449573)
			(xy 263.966959 -58.457143) (xy 263.940036 -58.457592) (xy 263.912782 -58.457131) (xy 263.858828 -58.449378)
			(xy 263.806527 -58.434025) (xy 263.756943 -58.411384) (xy 263.711087 -58.381917) (xy 263.669891 -58.346223)
			(xy 263.634195 -58.305029) (xy 263.604725 -58.259175) (xy 263.582082 -58.209592) (xy 263.566726 -58.157292)
			(xy 263.55897 -58.103338) (xy 263.558528 -58.076084) (xy 263.558274 -58.076084) (xy 263.558731 -58.049149)
			(xy 263.566297 -57.995812) (xy 263.581291 -57.944071) (xy 263.603413 -57.894952) (xy 263.632225 -57.849434)
			(xy 263.667153 -57.808422) (xy 263.707503 -57.77273) (xy 263.752473 -57.743069) (xy 263.801167 -57.720029)
			(xy 263.826752 -57.711594) (xy 263.827006 -57.711594) (xy 263.832839 -57.709581) (xy 263.843372 -57.703157)
			(xy 263.847834 -57.698894) (xy 267.346176 -54.200806) (xy 267.350519 -54.196185) (xy 267.356945 -54.185256)
			(xy 267.358876 -54.179216) (xy 267.359824 -54.175737) (xy 267.360843 -54.168598) (xy 267.360908 -54.164992)
			(xy 267.360908 -46.17212) (xy 267.360737 -46.166111) (xy 267.357908 -46.154432) (xy 267.35532 -46.149006)
			(xy 267.353482 -46.14553) (xy 267.348892 -46.139148) (xy 267.346176 -46.136306) (xy 261.528306 -40.318436)
			(xy 261.525455 -40.31573) (xy 261.519077 -40.311136) (xy 261.515606 -40.309292) (xy 261.510178 -40.306715)
			(xy 261.498498 -40.303903) (xy 261.492492 -40.303704) (xy 258.666996 -40.303704) (xy 258.662678 -40.30599)
			(xy 258.634251 -40.320901) (xy 258.573649 -40.342053) (xy 258.510367 -40.352794) (xy 258.478274 -40.353488)
			(xy 258.477766 -40.353488) (xy 258.450518 -40.352999) (xy 258.396577 -40.345239) (xy 258.344289 -40.329882)
			(xy 258.294718 -40.30724) (xy 258.248875 -40.277775) (xy 258.207691 -40.242085) (xy 258.172005 -40.200898)
			(xy 258.142543 -40.155052) (xy 258.119906 -40.105479) (xy 258.104553 -40.05319) (xy 258.096798 -39.999248)
			(xy 258.096798 -39.944752) (xy 258.104553 -39.89081) (xy 258.119906 -39.838521) (xy 258.142543 -39.788948)
			(xy 258.172005 -39.743102) (xy 258.207691 -39.701915) (xy 258.248875 -39.666225) (xy 258.294718 -39.63676)
			(xy 258.344289 -39.614118) (xy 258.396577 -39.598761) (xy 258.450518 -39.591001) (xy 258.477766 -39.590472)
			(xy 258.47802 -39.590472) (xy 258.502267 -39.590867) (xy 258.550369 -39.597036) (xy 258.597305 -39.609236)
			(xy 258.642323 -39.627271) (xy 258.663694 -39.638732) (xy 258.666488 -39.640256) (xy 261.23392 -39.640256)
			(xy 261.243962 -39.639827) (xy 261.262504 -39.632113) (xy 261.276667 -39.617873) (xy 261.28091 -39.60876)
			(xy 261.282434 -39.605458) (xy 261.283958 -39.601648) (xy 261.285482 -39.586662) (xy 261.283958 -39.57955)
			(xy 261.282231 -39.572361) (xy 261.275255 -39.559331) (xy 261.270242 -39.553896) (xy 257.939794 -36.223448)
			(xy 257.936943 -36.220742) (xy 257.930565 -36.216148) (xy 257.927094 -36.214304) (xy 257.921668 -36.211717)
			(xy 257.909988 -36.208884) (xy 257.90398 -36.208716) (xy 256.938526 -36.208716) (xy 256.929636 -36.216844)
			(xy 256.897124 -36.261802) (xy 256.880614 -36.284916) (xy 256.876873 -36.291024) (xy 256.872603 -36.304688)
			(xy 256.872232 -36.31184) (xy 256.872232 -36.331906) (xy 256.874518 -36.339526) (xy 256.882682 -36.367329)
			(xy 256.891477 -36.424601) (xy 256.892044 -36.453572) (xy 256.89156 -36.480825) (xy 256.883807 -36.534778)
			(xy 256.868455 -36.587078) (xy 256.845816 -36.636661) (xy 256.816351 -36.682518) (xy 256.78066 -36.723714)
			(xy 256.739469 -36.759412) (xy 256.693618 -36.788885) (xy 256.644038 -36.811532) (xy 256.591741 -36.826893)
			(xy 256.537789 -36.834656) (xy 256.510536 -36.83508) (xy 256.483411 -36.834605) (xy 256.429707 -36.826925)
			(xy 256.377632 -36.811713) (xy 256.328238 -36.789278) (xy 256.282521 -36.760071) (xy 256.241402 -36.724682)
			(xy 256.205712 -36.683824) (xy 256.17617 -36.638322) (xy 256.153373 -36.589095) (xy 256.137779 -36.537133)
			(xy 256.129704 -36.483487) (xy 256.129028 -36.456366) (xy 256.129028 -36.45281) (xy 256.129589 -36.423839)
			(xy 256.138395 -36.366569) (xy 256.146554 -36.338764) (xy 256.147316 -36.336224) (xy 256.14884 -36.331398)
			(xy 256.150364 -36.318444) (xy 256.150635 -36.31029) (xy 256.146633 -36.294483) (xy 256.14249 -36.287456)
			(xy 256.12344 -36.260786) (xy 256.092452 -36.21786) (xy 256.083054 -36.208716) (xy 255.560322 -36.208716)
			(xy 255.55448 -36.211764) (xy 255.551178 -36.213288) (xy 255.523377 -36.227426) (xy 255.464316 -36.247462)
			(xy 255.402783 -36.257631) (xy 255.3716 -36.258246) (xy 255.370838 -36.258246) (xy 255.343581 -36.257786)
			(xy 255.28962 -36.250032) (xy 255.237312 -36.234678) (xy 255.187723 -36.212035) (xy 255.14186 -36.182565)
			(xy 255.100659 -36.146868) (xy 255.064957 -36.10567) (xy 255.035483 -36.059811) (xy 255.012835 -36.010223)
			(xy 254.997476 -35.957917) (xy 254.989717 -35.903957) (xy 254.989717 -35.849443) (xy 254.997476 -35.795483)
			(xy 255.012835 -35.743177) (xy 255.035483 -35.693589) (xy 255.064957 -35.64773) (xy 255.100659 -35.606532)
			(xy 255.14186 -35.570835) (xy 255.187723 -35.541365) (xy 255.237312 -35.518722) (xy 255.28962 -35.503368)
			(xy 255.343581 -35.495614) (xy 255.370838 -35.49523) (xy 255.3716 -35.49523) (xy 255.402781 -35.495871)
			(xy 255.464309 -35.506042) (xy 255.523371 -35.526066) (xy 255.551178 -35.540188) (xy 255.55448 -35.541712)
			(xy 255.560322 -35.54476) (xy 257.645662 -35.54476) (xy 257.654754 -35.544338) (xy 257.671763 -35.537892)
			(xy 257.685444 -35.525905) (xy 257.690112 -35.51809) (xy 257.692144 -35.51301) (xy 257.694872 -35.505978)
			(xy 257.696437 -35.490984) (xy 257.695192 -35.483546) (xy 257.693922 -35.476942) (xy 257.68681 -35.463734)
			(xy 255.350264 -33.127188) (xy 255.332232 -33.108418) (xy 255.301652 -33.066301) (xy 255.278026 -33.019925)
			(xy 255.261935 -32.970427) (xy 255.253774 -32.919023) (xy 255.253236 -32.893) (xy 255.253236 -29.624528)
			(xy 255.253765 -29.598505) (xy 255.261935 -29.547103) (xy 255.278031 -29.497608) (xy 255.301658 -29.451233)
			(xy 255.332238 -29.409116) (xy 255.350264 -29.39034) (xy 255.853184 -28.88742) (xy 255.8593 -28.880735)
			(xy 255.866779 -28.864246) (xy 255.868043 -28.846184) (xy 255.865884 -28.837382) (xy 255.863598 -28.832048)
			(xy 255.860511 -28.825231) (xy 255.85109 -28.813614) (xy 255.845056 -28.809188) (xy 255.839468 -28.805378)
			(xy 255.82499 -28.80106) (xy 253.27356 -28.80106) (xy 253.247474 -28.800571) (xy 253.195946 -28.792399)
			(xy 253.146332 -28.776262) (xy 253.099855 -28.752559) (xy 253.057661 -28.721873) (xy 253.038864 -28.703778)
			(xy 252.01499 -27.67965) (xy 252.00901 -27.674212) (xy 251.9945 -27.667107) (xy 251.986542 -27.66568)
			(xy 251.97943 -27.665172) (xy 250.933458 -27.665172) (xy 250.907434 -27.664645) (xy 250.856029 -27.65648)
			(xy 250.806531 -27.640388) (xy 250.760152 -27.616763) (xy 250.718032 -27.586186) (xy 250.69927 -27.568144)
			(xy 249.747024 -26.615644) (xy 249.740416 -26.609708) (xy 249.724257 -26.602366) (xy 249.706562 -26.600989)
			(xy 249.689461 -26.605741) (xy 249.682 -26.610564) (xy 249.669186 -26.620383) (xy 249.650023 -26.646342)
			(xy 249.639907 -26.676982) (xy 249.639328 -26.693114) (xy 249.639328 -27.342846) (xy 249.638838 -27.37283)
			(xy 249.63101 -27.432286) (xy 249.615489 -27.490211) (xy 249.59254 -27.545615) (xy 249.562556 -27.597549)
			(xy 249.52605 -27.645125) (xy 249.483645 -27.68753) (xy 249.436069 -27.724036) (xy 249.384135 -27.75402)
			(xy 249.328731 -27.776969) (xy 249.270806 -27.79249) (xy 249.21135 -27.800318) (xy 249.151382 -27.800318)
			(xy 249.091926 -27.79249) (xy 249.034001 -27.776969) (xy 248.978597 -27.75402) (xy 248.926663 -27.724036)
			(xy 248.879087 -27.68753) (xy 248.836682 -27.645125) (xy 248.800176 -27.597549) (xy 248.770192 -27.545615)
			(xy 248.747243 -27.490211) (xy 248.731722 -27.432286) (xy 248.723894 -27.37283) (xy 248.723404 -27.342846)
			(xy 248.723404 -26.479246) (xy 248.723935 -26.448026) (xy 248.732418 -26.386164) (xy 248.74922 -26.326026)
			(xy 248.77403 -26.268725) (xy 248.806388 -26.215323) (xy 248.845696 -26.166807) (xy 248.891225 -26.124076)
			(xy 248.942133 -26.08792) (xy 248.997478 -26.05901) (xy 249.02668 -26.047954) (xy 249.037094 -26.044144)
			(xy 249.052334 -26.029412) (xy 249.055636 -26.025602) (xy 249.058714 -26.021651) (xy 249.063452 -26.012828)
			(xy 249.065034 -26.008076) (xy 249.067828 -25.99563) (xy 249.067828 -25.995122) (xy 249.084084 -25.923494)
			(xy 249.08517 -25.915003) (xy 249.082322 -25.898132) (xy 249.078496 -25.890474) (xy 249.073416 -25.8826)
			(xy 248.678192 -25.487376) (xy 248.673112 -25.483058) (xy 248.630694 -25.453086) (xy 248.520966 -25.37587)
			(xy 248.514438 -25.371572) (xy 248.499566 -25.366792) (xy 248.491756 -25.366472) (xy 246.905018 -25.366472)
			(xy 246.901716 -25.366472) (xy 246.892698 -25.367424) (xy 246.876168 -25.374849) (xy 246.869458 -25.38095)
			(xy 246.795544 -25.455118) (xy 246.763794 -25.486868) (xy 246.757444 -25.497536) (xy 246.755666 -25.503378)
			(xy 246.747216 -25.528942) (xy 246.724133 -25.577585) (xy 246.694445 -25.622502) (xy 246.658741 -25.662802)
			(xy 246.617728 -25.697685) (xy 246.57222 -25.726459) (xy 246.523121 -25.748554) (xy 246.471405 -25.763531)
			(xy 246.418097 -25.771093) (xy 246.391176 -25.771602) (xy 246.363926 -25.771115) (xy 246.309981 -25.763355)
			(xy 246.25769 -25.747998) (xy 246.208116 -25.725355) (xy 246.162269 -25.695888) (xy 246.121082 -25.660197)
			(xy 246.085394 -25.619007) (xy 246.05593 -25.573158) (xy 246.033292 -25.523582) (xy 246.017938 -25.471289)
			(xy 246.010183 -25.417344) (xy 246.009668 -25.390094) (xy 246.009414 -25.390094) (xy 246.009871 -25.363157)
			(xy 246.017435 -25.309818) (xy 246.032426 -25.258072) (xy 246.054546 -25.20895) (xy 246.083356 -25.163427)
			(xy 246.118282 -25.122409) (xy 246.15863 -25.086711) (xy 246.203598 -25.057043) (xy 246.252292 -25.033994)
			(xy 246.277892 -25.025604) (xy 246.278146 -25.025604) (xy 246.283983 -25.023597) (xy 246.294526 -25.017183)
			(xy 246.298974 -25.012904) (xy 246.341392 -24.970486) (xy 246.341834 -24.96688) (xy 246.341841 -24.959614)
			(xy 246.341392 -24.956008) (xy 245.989602 -24.604218) (xy 245.964456 -24.578276) (xy 245.92004 -24.52129)
			(xy 245.88296 -24.45928) (xy 245.853775 -24.393186) (xy 245.832929 -24.324008) (xy 245.82628 -24.288496)
			(xy 245.822216 -24.263858) (xy 245.818165 -24.260143) (xy 245.808817 -24.254366) (xy 245.803674 -24.252428)
			(xy 245.736618 -24.231092) (xy 245.73611 -24.231092) (xy 245.723918 -24.227282) (xy 245.715282 -24.225504)
			(xy 245.708678 -24.224996) (xy 245.70309 -24.224996) (xy 245.693946 -24.228806) (xy 245.689382 -24.230812)
			(xy 245.681064 -24.236309) (xy 245.677436 -24.239728) (xy 245.492524 -24.42464) (xy 245.473754 -24.442674)
			(xy 245.431639 -24.473259) (xy 245.385263 -24.496889) (xy 245.335765 -24.512985) (xy 245.28436 -24.521152)
			(xy 245.258336 -24.521668) (xy 244.070124 -24.521668) (xy 244.065806 -24.523954) (xy 244.03738 -24.538868)
			(xy 243.976779 -24.560026) (xy 243.913496 -24.570773) (xy 243.881402 -24.571452) (xy 243.880894 -24.571452)
			(xy 243.85364 -24.570966) (xy 243.799687 -24.563208) (xy 243.747387 -24.54785) (xy 243.697804 -24.525206)
			(xy 243.651949 -24.495736) (xy 243.610755 -24.460041) (xy 243.57506 -24.418846) (xy 243.545591 -24.37299)
			(xy 243.522948 -24.323408) (xy 243.507591 -24.271108) (xy 243.499834 -24.217154) (xy 243.499834 -24.162646)
			(xy 243.507591 -24.108692) (xy 243.522948 -24.056392) (xy 243.545591 -24.00681) (xy 243.57506 -23.960954)
			(xy 243.610755 -23.919759) (xy 243.651949 -23.884064) (xy 243.697804 -23.854594) (xy 243.747387 -23.83195)
			(xy 243.799687 -23.816592) (xy 243.85364 -23.808834) (xy 243.880894 -23.808436) (xy 243.881148 -23.808436)
			(xy 243.905395 -23.808832) (xy 243.953496 -23.815005) (xy 244.00043 -23.827207) (xy 244.045447 -23.845242)
			(xy 244.066822 -23.856696) (xy 244.069616 -23.85822) (xy 245.099332 -23.85822) (xy 245.102634 -23.85822)
			(xy 245.111656 -23.857276) (xy 245.128197 -23.849862) (xy 245.134892 -23.843742) (xy 245.214902 -23.763478)
			(xy 245.254018 -23.724362) (xy 245.254272 -23.710646) (xy 245.25224 -23.701756) (xy 245.242842 -23.673562)
			(xy 245.242842 -23.673054) (xy 245.221506 -23.603712) (xy 245.21414 -23.597108) (xy 245.189502 -23.59279)
			(xy 245.156654 -23.586395) (xy 245.092578 -23.567079) (xy 245.031122 -23.540585) (xy 244.973088 -23.507257)
			(xy 244.91923 -23.467531) (xy 244.870253 -23.421924) (xy 244.826794 -23.371032) (xy 244.78942 -23.315516)
			(xy 244.758619 -23.256102) (xy 244.746272 -23.224998) (xy 244.73789 -23.203154) (xy 244.733857 -23.200571)
			(xy 244.725033 -23.196852) (xy 244.720364 -23.195788) (xy 244.671088 -23.185374) (xy 244.67058 -23.185374)
			(xy 244.634766 -23.177754) (xy 244.620542 -23.178008) (xy 244.358922 -23.439628) (xy 244.335346 -23.462576)
			(xy 244.283906 -23.503597) (xy 244.228196 -23.538601) (xy 244.168918 -23.567148) (xy 244.106816 -23.588877)
			(xy 244.042671 -23.603517) (xy 243.977291 -23.610883) (xy 243.944394 -23.611332) (xy 243.908966 -23.610797)
			(xy 243.838627 -23.602256) (xy 243.76983 -23.585298) (xy 243.703579 -23.560172) (xy 243.640839 -23.527243)
			(xy 243.582526 -23.486992) (xy 243.52949 -23.440006) (xy 243.482504 -23.386969) (xy 243.442254 -23.328655)
			(xy 243.409326 -23.265916) (xy 243.3842 -23.199664) (xy 243.367243 -23.130867) (xy 243.358703 -23.060528)
			(xy 243.358162 -23.0251) (xy 243.358623 -22.992204) (xy 243.365989 -22.926825) (xy 243.380629 -22.862682)
			(xy 243.402359 -22.800582) (xy 243.430905 -22.741305) (xy 243.465909 -22.685596) (xy 243.506929 -22.634157)
			(xy 243.529866 -22.610572) (xy 244.022626 -22.117812) (xy 244.0462 -22.094861) (xy 244.097638 -22.053832)
			(xy 244.153347 -22.018821) (xy 244.212625 -21.990267) (xy 244.274727 -21.96853) (xy 244.338873 -21.953884)
			(xy 244.404256 -21.946511) (xy 244.437154 -21.946108) (xy 244.45849 -21.946616) (xy 248.268998 -21.946616)
			(xy 248.270522 -21.94433) (xy 248.271538 -21.942806) (xy 248.302018 -21.892514) (xy 248.302018 -21.892006)
			(xy 248.317512 -21.866098) (xy 248.322338 -21.85416) (xy 248.323862 -21.842476) (xy 248.324116 -21.830792)
			(xy 248.318528 -21.818854) (xy 248.31802 -21.817838) (xy 248.30412 -21.790283) (xy 248.284434 -21.731793)
			(xy 248.274433 -21.670894) (xy 248.273824 -21.640038) (xy 248.273824 -21.63572) (xy 248.274592 -21.607317)
			(xy 248.283503 -21.551204) (xy 248.300641 -21.497034) (xy 248.325625 -21.446006) (xy 248.357903 -21.399249)
			(xy 248.376948 -21.378164) (xy 248.383806 -21.371052) (xy 248.387362 -21.362162) (xy 248.389902 -21.353018)
			(xy 248.390664 -21.344128) (xy 248.390664 -21.27377) (xy 248.3906 -21.269636) (xy 248.38933 -21.261468)
			(xy 248.388124 -21.257514) (xy 248.387362 -21.255736) (xy 248.38406 -21.2471) (xy 248.376948 -21.23948)
			(xy 248.357674 -21.218154) (xy 248.325104 -21.170791) (xy 248.300008 -21.119079) (xy 248.282953 -21.064186)
			(xy 248.274328 -21.007356) (xy 248.274325 -20.949876) (xy 248.282946 -20.893045) (xy 248.299996 -20.838151)
			(xy 248.325088 -20.786436) (xy 248.357654 -20.739071) (xy 248.376948 -20.717764) (xy 248.38406 -20.710144)
			(xy 248.387362 -20.701508) (xy 248.388124 -20.69973) (xy 248.389356 -20.695781) (xy 248.390633 -20.68761)
			(xy 248.390664 -20.683474) (xy 248.390664 -20.61337) (xy 248.3906 -20.609236) (xy 248.38933 -20.601068)
			(xy 248.388124 -20.597114) (xy 248.387362 -20.595336) (xy 248.38406 -20.5867) (xy 248.376948 -20.57908)
			(xy 248.357674 -20.557754) (xy 248.325104 -20.510391) (xy 248.300008 -20.458679) (xy 248.282953 -20.403786)
			(xy 248.274328 -20.346956) (xy 248.274325 -20.289476) (xy 248.282946 -20.232645) (xy 248.299996 -20.177751)
			(xy 248.325088 -20.126036) (xy 248.357654 -20.078671) (xy 248.376948 -20.057364) (xy 248.38406 -20.049744)
			(xy 248.387362 -20.041108) (xy 248.388124 -20.03933) (xy 248.389356 -20.035381) (xy 248.390633 -20.02721)
			(xy 248.390664 -20.023074) (xy 248.390664 -19.95297) (xy 248.3906 -19.948836) (xy 248.38933 -19.940668)
			(xy 248.388124 -19.936714) (xy 248.387362 -19.934936) (xy 248.38406 -19.9263) (xy 248.376948 -19.91868)
			(xy 248.357674 -19.897354) (xy 248.325104 -19.849991) (xy 248.300008 -19.798279) (xy 248.282953 -19.743386)
			(xy 248.274328 -19.686556) (xy 248.274325 -19.629076) (xy 248.282946 -19.572245) (xy 248.299996 -19.517351)
			(xy 248.325088 -19.465636) (xy 248.357654 -19.418271) (xy 248.376948 -19.396964) (xy 248.38406 -19.389344)
			(xy 248.387362 -19.380708) (xy 248.388124 -19.37893) (xy 248.389356 -19.374981) (xy 248.390633 -19.36681)
			(xy 248.390664 -19.362674) (xy 248.390664 -19.29257) (xy 248.3906 -19.288436) (xy 248.38933 -19.280268)
			(xy 248.388124 -19.276314) (xy 248.387362 -19.274536) (xy 248.38406 -19.2659) (xy 248.376948 -19.25828)
			(xy 248.357679 -19.236952) (xy 248.325118 -19.189588) (xy 248.300028 -19.137876) (xy 248.282979 -19.082987)
			(xy 248.274355 -19.02616) (xy 248.273824 -18.997422) (xy 248.27431 -18.970171) (xy 248.282066 -18.916223)
			(xy 248.297421 -18.863928) (xy 248.320063 -18.814351) (xy 248.349529 -18.768501) (xy 248.38522 -18.72731)
			(xy 248.426411 -18.691619) (xy 248.472261 -18.662153) (xy 248.521838 -18.639511) (xy 248.574133 -18.624156)
			(xy 248.628081 -18.6164) (xy 248.682583 -18.6164) (xy 248.736531 -18.624156) (xy 248.788826 -18.639511)
			(xy 248.838403 -18.662153) (xy 248.884253 -18.691619) (xy 248.925444 -18.72731) (xy 248.961135 -18.768501)
			(xy 248.990601 -18.814351) (xy 249.013243 -18.863928) (xy 249.028598 -18.916223) (xy 249.036354 -18.970171)
			(xy 249.03684 -18.997422) (xy 249.036317 -19.02616) (xy 249.027691 -19.082985) (xy 249.010636 -19.137873)
			(xy 248.985539 -19.18958) (xy 248.952969 -19.236937) (xy 248.933716 -19.25828) (xy 248.926604 -19.2659)
			(xy 248.923302 -19.274536) (xy 248.92254 -19.276314) (xy 248.92131 -19.280263) (xy 248.920039 -19.288434)
			(xy 248.92 -19.29257) (xy 248.92 -19.362674) (xy 248.920067 -19.366807) (xy 248.921343 -19.374974)
			(xy 248.92254 -19.37893) (xy 248.923302 -19.380708) (xy 248.926604 -19.389344) (xy 248.933716 -19.396964)
			(xy 248.952983 -19.418292) (xy 248.985542 -19.465655) (xy 249.010628 -19.517366) (xy 249.027673 -19.572254)
			(xy 249.036292 -19.629079) (xy 249.036289 -19.686553) (xy 249.027666 -19.743377) (xy 249.010616 -19.798264)
			(xy 248.985526 -19.849973) (xy 248.952963 -19.897333) (xy 248.933716 -19.91868) (xy 248.926604 -19.9263)
			(xy 248.923302 -19.934936) (xy 248.92254 -19.936714) (xy 248.92131 -19.940663) (xy 248.920039 -19.948834)
			(xy 248.92 -19.95297) (xy 248.92 -20.023074) (xy 248.920067 -20.027207) (xy 248.921343 -20.035374)
			(xy 248.92254 -20.03933) (xy 248.923302 -20.041108) (xy 248.926604 -20.049744) (xy 248.933716 -20.057364)
			(xy 248.952983 -20.078692) (xy 248.985542 -20.126055) (xy 249.010628 -20.177766) (xy 249.027673 -20.232654)
			(xy 249.036292 -20.289479) (xy 249.036289 -20.346953) (xy 249.027666 -20.403777) (xy 249.010616 -20.458664)
			(xy 248.985526 -20.510373) (xy 248.952963 -20.557733) (xy 248.933716 -20.57908) (xy 248.926604 -20.5867)
			(xy 248.923302 -20.595336) (xy 248.92254 -20.597114) (xy 248.92131 -20.601063) (xy 248.920039 -20.609234)
			(xy 248.92 -20.61337) (xy 248.92 -20.683474) (xy 248.920067 -20.687607) (xy 248.921343 -20.695774)
			(xy 248.92254 -20.69973) (xy 248.923302 -20.701508) (xy 248.926604 -20.710144) (xy 248.933716 -20.717764)
			(xy 248.952983 -20.739092) (xy 248.985542 -20.786455) (xy 249.010628 -20.838166) (xy 249.027673 -20.893054)
			(xy 249.036292 -20.949879) (xy 249.036289 -21.007353) (xy 249.027666 -21.064177) (xy 249.010616 -21.119064)
			(xy 248.985526 -21.170773) (xy 248.952963 -21.218133) (xy 248.933716 -21.23948) (xy 248.926604 -21.2471)
			(xy 248.923302 -21.255736) (xy 248.92254 -21.257514) (xy 248.92131 -21.261463) (xy 248.920039 -21.269634)
			(xy 248.92 -21.27377) (xy 248.92 -21.344128) (xy 248.920762 -21.353018) (xy 248.923302 -21.362162)
			(xy 248.926858 -21.371052) (xy 248.934224 -21.378672) (xy 248.953164 -21.39972) (xy 248.985256 -21.446369)
			(xy 249.010102 -21.497249) (xy 249.027155 -21.551241) (xy 249.036042 -21.607161) (xy 249.03684 -21.635466)
			(xy 249.03684 -21.63953) (xy 249.036239 -21.67047) (xy 249.026262 -21.73154) (xy 249.006572 -21.790204)
			(xy 248.992644 -21.817838) (xy 248.99112 -21.820632) (xy 248.988999 -21.825769) (xy 248.986814 -21.836664)
			(xy 248.986802 -21.842222) (xy 248.987056 -21.855684) (xy 249.008646 -21.892006) (xy 249.008646 -21.892514)
			(xy 249.039126 -21.942552) (xy 249.04192 -21.946616) (xy 253.45263 -21.946616) (xy 253.460339 -21.946388)
			(xy 253.475076 -21.941862) (xy 253.481586 -21.937726) (xy 253.48565 -21.934424) (xy 253.828804 -21.59127)
			(xy 253.829312 -21.583904) (xy 253.829312 -21.567902) (xy 253.826264 -21.556218) (xy 253.821946 -21.547836)
			(xy 253.808414 -21.520574) (xy 253.78922 -21.462819) (xy 253.779434 -21.402751) (xy 253.778766 -21.372322)
			(xy 253.778766 -21.36394) (xy 253.779761 -21.337046) (xy 253.788381 -21.283923) (xy 253.804383 -21.232539)
			(xy 253.827449 -21.183915) (xy 253.857122 -21.139016) (xy 253.892811 -21.098735) (xy 253.933808 -21.06387)
			(xy 253.979299 -21.035114) (xy 254.028381 -21.013039) (xy 254.080078 -20.998082) (xy 254.133365 -20.990541)
			(xy 254.160274 -20.990052) (xy 254.160528 -20.990052) (xy 254.17653 -20.990306) (xy 254.187198 -20.990814)
			(xy 254.196342 -20.987258) (xy 254.200707 -20.985507) (xy 254.208761 -20.980652) (xy 254.212344 -20.977606)
			(xy 254.22606 -20.964652) (xy 254.226568 -20.964144) (xy 254.268478 -20.923758) (xy 254.272288 -20.919186)
			(xy 254.272288 -19.452844) (xy 254.272853 -19.417134) (xy 254.281601 -19.346249) (xy 254.298898 -19.276954)
			(xy 254.32449 -19.210274) (xy 254.357996 -19.147199) (xy 254.398919 -19.088664) (xy 254.446653 -19.035536)
			(xy 254.473202 -19.011646) (xy 254.48387 -19.002248) (xy 254.485902 -18.99793) (xy 254.48791 -18.993217)
			(xy 254.490211 -18.983235) (xy 254.490474 -18.978118) (xy 254.491998 -18.922238) (xy 254.491998 -18.921476)
			(xy 254.492506 -18.906998) (xy 254.443992 -18.858738) (xy 254.417285 -18.831161) (xy 254.370577 -18.770235)
			(xy 254.332229 -18.703729) (xy 254.316992 -18.668492) (xy 254.302962 -18.633086) (xy 254.283142 -18.55955)
			(xy 254.273023 -18.484066) (xy 254.272288 -18.445988) (xy 254.272288 -18.44421) (xy 254.272822 -18.408796)
			(xy 254.281358 -18.338484) (xy 254.298307 -18.269714) (xy 254.323421 -18.203488) (xy 254.356334 -18.140772)
			(xy 254.396567 -18.082481) (xy 254.443533 -18.029464) (xy 254.496546 -17.982494) (xy 254.554835 -17.942257)
			(xy 254.617548 -17.909339) (xy 254.683772 -17.88422) (xy 254.752541 -17.867266) (xy 254.822852 -17.858725)
			(xy 254.858266 -17.858232) (xy 254.867664 -17.858232) (xy 254.904459 -17.85943) (xy 254.977335 -17.869874)
			(xy 255.048333 -17.889348) (xy 255.082548 -17.902936) (xy 255.117777 -17.918188) (xy 255.184279 -17.956538)
			(xy 255.245209 -18.003239) (xy 255.272794 -18.029936) (xy 255.603502 -18.360898) (xy 255.841246 -18.598642)
			(xy 255.864144 -18.622206) (xy 255.905098 -18.673589) (xy 255.940047 -18.729232) (xy 255.968551 -18.788435)
			(xy 255.990252 -18.850456) (xy 256.004877 -18.914515) (xy 256.012244 -18.979808) (xy 256.012696 -19.012662)
			(xy 256.012696 -21.474684) (xy 256.015628 -21.478426) (xy 256.022665 -21.484815) (xy 256.026666 -21.487384)
			(xy 256.032508 -21.49094) (xy 256.119884 -21.527516) (xy 256.1265 -21.530024) (xy 256.140547 -21.531688)
			(xy 256.14757 -21.530818) (xy 256.73685 -20.941538) (xy 256.737357 -20.937744) (xy 256.737359 -20.930091)
			(xy 256.73685 -20.926298) (xy 256.73685 -20.925536) (xy 256.731516 -20.892516) (xy 256.723642 -20.842986)
			(xy 256.720805 -20.83192) (xy 256.706917 -20.813809) (xy 256.696972 -20.808188) (xy 256.690114 -20.804632)
			(xy 256.664339 -20.79026) (xy 256.617162 -20.754808) (xy 256.575999 -20.712523) (xy 256.541828 -20.66441)
			(xy 256.515464 -20.611614) (xy 256.497532 -20.555391) (xy 256.488461 -20.49708) (xy 256.48793 -20.467574)
			(xy 256.488395 -20.440323) (xy 256.496155 -20.386377) (xy 256.511514 -20.334085) (xy 256.534158 -20.28451)
			(xy 256.563628 -20.238663) (xy 256.599322 -20.197477) (xy 256.640514 -20.161789) (xy 256.686367 -20.132328)
			(xy 256.735945 -20.109692) (xy 256.78824 -20.094342) (xy 256.842187 -20.086591) (xy 256.869438 -20.086066)
			(xy 256.896584 -20.086547) (xy 256.950328 -20.094249) (xy 257.002437 -20.109492) (xy 257.051859 -20.131968)
			(xy 257.097596 -20.161223) (xy 257.138724 -20.196666) (xy 257.174412 -20.237582) (xy 257.203939 -20.283144)
			(xy 257.226709 -20.332431) (xy 257.242262 -20.384448) (xy 257.250284 -20.438145) (xy 257.250946 -20.465288)
			(xy 257.250946 -20.467828) (xy 257.250349 -20.498333) (xy 257.240656 -20.558568) (xy 257.231642 -20.587716)
			(xy 257.230118 -20.592288) (xy 257.228848 -20.601432) (xy 257.228848 -20.601686) (xy 257.227324 -20.611338)
			(xy 257.229864 -20.622006) (xy 257.231151 -20.626485) (xy 257.235116 -20.634917) (xy 257.237738 -20.63877)
			(xy 257.248406 -20.653502) (xy 257.248914 -20.65401) (xy 257.259074 -20.668488) (xy 257.261275 -20.671402)
			(xy 257.266377 -20.676627) (xy 257.269234 -20.678902) (xy 257.275492 -20.683483) (xy 257.289967 -20.689028)
			(xy 257.297682 -20.689824) (xy 258.840986 -20.689824) (xy 258.873862 -20.690305) (xy 258.939198 -20.697703)
			(xy 259.003297 -20.712362) (xy 259.039748 -20.72513) (xy 263.380486 -20.72513) (xy 263.384456 -20.594996)
			(xy 263.396352 -20.465346) (xy 263.416131 -20.336663) (xy 263.443717 -20.209424) (xy 263.47901 -20.084105)
			(xy 263.521876 -19.961169) (xy 263.572158 -19.841076) (xy 263.629667 -19.724272) (xy 263.694191 -19.61119)
			(xy 263.765488 -19.502253) (xy 263.843293 -19.397865) (xy 263.927318 -19.298414) (xy 264.01725 -19.204271)
			(xy 264.112754 -19.115786) (xy 264.213474 -19.033287) (xy 264.319036 -18.957082) (xy 264.429048 -18.887455)
			(xy 264.5431 -18.824664) (xy 264.660768 -18.768942) (xy 264.781614 -18.720498) (xy 264.905189 -18.679511)
			(xy 265.031032 -18.646134) (xy 265.158677 -18.620491) (xy 265.287647 -18.602677) (xy 265.417463 -18.592759)
			(xy 265.547642 -18.590774) (xy 265.677701 -18.596728) (xy 265.807154 -18.610601) (xy 265.935521 -18.632339)
			(xy 266.062324 -18.661863) (xy 266.187091 -18.699062) (xy 266.309358 -18.743798) (xy 266.428671 -18.795906)
			(xy 266.544584 -18.855189) (xy 266.656669 -18.92143) (xy 266.764506 -18.99438) (xy 266.867695 -19.073768)
			(xy 266.965853 -19.1593) (xy 267.058614 -19.250657) (xy 267.145633 -19.347499) (xy 267.226586 -19.449466)
			(xy 267.301172 -19.556178) (xy 267.369113 -19.667239) (xy 267.430158 -19.782235) (xy 267.484079 -19.900739)
			(xy 267.530674 -20.02231) (xy 267.569772 -20.146495) (xy 267.601226 -20.272833) (xy 267.62492 -20.400854)
			(xy 267.640764 -20.53008) (xy 267.648702 -20.660033) (xy 267.649198 -20.72513) (xy 267.648702 -20.790227)
			(xy 267.640764 -20.92018) (xy 267.62492 -21.049406) (xy 267.601226 -21.177427) (xy 267.569772 -21.303765)
			(xy 267.530674 -21.42795) (xy 267.484079 -21.549521) (xy 267.430158 -21.668025) (xy 267.369113 -21.783021)
			(xy 267.301172 -21.894082) (xy 267.226586 -22.000794) (xy 267.145633 -22.102761) (xy 267.058614 -22.199603)
			(xy 266.965853 -22.29096) (xy 266.867695 -22.376492) (xy 266.764506 -22.45588) (xy 266.656669 -22.52883)
			(xy 266.544584 -22.595071) (xy 266.428671 -22.654354) (xy 266.309358 -22.706462) (xy 266.187091 -22.751198)
			(xy 266.062324 -22.788397) (xy 265.935521 -22.817921) (xy 265.807154 -22.839659) (xy 265.677701 -22.853532)
			(xy 265.547642 -22.859486) (xy 265.417463 -22.857501) (xy 265.287647 -22.847583) (xy 265.158677 -22.829769)
			(xy 265.031032 -22.804126) (xy 264.905189 -22.770749) (xy 264.781614 -22.729762) (xy 264.660768 -22.681318)
			(xy 264.5431 -22.625596) (xy 264.429048 -22.562805) (xy 264.319036 -22.493178) (xy 264.213474 -22.416973)
			(xy 264.112754 -22.334474) (xy 264.01725 -22.245989) (xy 263.927318 -22.151846) (xy 263.843293 -22.052395)
			(xy 263.765488 -21.948007) (xy 263.694191 -21.83907) (xy 263.629667 -21.725988) (xy 263.572158 -21.609184)
			(xy 263.521876 -21.489091) (xy 263.47901 -21.366155) (xy 263.443717 -21.240836) (xy 263.416131 -21.113597)
			(xy 263.396352 -20.984914) (xy 263.384456 -20.855264) (xy 263.380486 -20.72513) (xy 259.039748 -20.72513)
			(xy 259.065353 -20.734099) (xy 259.124589 -20.76264) (xy 259.180261 -20.797628) (xy 259.23167 -20.838624)
			(xy 259.25526 -20.861528) (xy 259.834888 -21.441156) (xy 259.857834 -21.464711) (xy 259.898854 -21.51611)
			(xy 259.933857 -21.571781) (xy 259.962403 -21.631023) (xy 259.984132 -21.693091) (xy 259.998771 -21.757202)
			(xy 260.006135 -21.822549) (xy 260.006476 -21.847048) (xy 260.272782 -21.847048) (xy 260.276853 -21.791426)
			(xy 260.288979 -21.736989) (xy 260.308902 -21.684898) (xy 260.336198 -21.636263) (xy 260.370284 -21.59212)
			(xy 260.410433 -21.553411) (xy 260.455791 -21.52096) (xy 260.505391 -21.495459) (xy 260.558175 -21.477452)
			(xy 260.613018 -21.467322) (xy 260.668752 -21.465285) (xy 260.724189 -21.471385) (xy 260.778146 -21.485491)
			(xy 260.829475 -21.507303) (xy 260.877081 -21.536357) (xy 260.919949 -21.572032) (xy 260.957166 -21.613569)
			(xy 260.987939 -21.660082) (xy 261.011611 -21.710579) (xy 261.027679 -21.763986) (xy 261.035799 -21.819162)
			(xy 261.036308 -21.847048) (xy 261.035799 -21.874934) (xy 261.027679 -21.93011) (xy 261.011611 -21.983517)
			(xy 260.987939 -22.034014) (xy 260.957166 -22.080527) (xy 260.919949 -22.122064) (xy 260.877081 -22.157739)
			(xy 260.829475 -22.186793) (xy 260.778146 -22.208605) (xy 260.724189 -22.222711) (xy 260.668752 -22.228811)
			(xy 260.613018 -22.226774) (xy 260.558175 -22.216644) (xy 260.505391 -22.198637) (xy 260.455791 -22.173136)
			(xy 260.410433 -22.140685) (xy 260.370284 -22.101976) (xy 260.336198 -22.057833) (xy 260.308902 -22.009198)
			(xy 260.288979 -21.957107) (xy 260.276853 -21.90267) (xy 260.272782 -21.847048) (xy 260.006476 -21.847048)
			(xy 260.006592 -21.85543) (xy 260.006592 -21.869908) (xy 260.006338 -21.87575) (xy 260.004649 -21.910354)
			(xy 259.994136 -21.978835) (xy 259.975616 -22.045597) (xy 259.949349 -22.109708) (xy 259.915702 -22.170271)
			(xy 259.875144 -22.226442) (xy 259.828241 -22.277436) (xy 259.77565 -22.322539) (xy 259.718105 -22.361122)
			(xy 259.656409 -22.392647) (xy 259.591425 -22.416672) (xy 259.52406 -22.432862) (xy 259.455256 -22.440991)
			(xy 259.420614 -22.441408) (xy 259.38774 -22.440981) (xy 259.322402 -22.43365) (xy 259.258296 -22.419047)
			(xy 259.19623 -22.397354) (xy 259.136985 -22.368845) (xy 259.081306 -22.333878) (xy 259.029895 -22.292894)
			(xy 259.00634 -22.269958) (xy 258.947666 -22.211284) (xy 258.941824 -22.210776) (xy 258.929378 -22.210776)
			(xy 258.920363 -22.211139) (xy 258.90345 -22.217389) (xy 258.896358 -22.222968) (xy 258.894834 -22.224238)
			(xy 258.868398 -22.245838) (xy 258.81139 -22.283398) (xy 258.750403 -22.314075) (xy 258.686262 -22.337455)
			(xy 258.619838 -22.35322) (xy 258.552032 -22.361157) (xy 258.517898 -22.361652) (xy 258.360164 -22.361652)
			(xy 258.35102 -22.370542) (xy 258.332478 -22.393656) (xy 258.299458 -22.43455) (xy 258.296918 -22.438614)
			(xy 258.293108 -22.447758) (xy 258.289044 -22.463506) (xy 258.291584 -22.474936) (xy 258.295431 -22.494203)
			(xy 258.299632 -22.533269) (xy 258.299966 -22.552914) (xy 258.299966 -22.553422) (xy 258.299966 -22.559264)
			(xy 258.299203 -22.586807) (xy 258.29073 -22.641249) (xy 258.274516 -22.693907) (xy 258.250899 -22.743686)
			(xy 258.22037 -22.789553) (xy 258.183563 -22.830553) (xy 258.141244 -22.865835) (xy 258.094291 -22.894665)
			(xy 258.043681 -22.916445) (xy 257.990465 -22.930721) (xy 257.963162 -22.934422) (xy 257.948938 -22.935946)
			(xy 257.915664 -22.937216) (xy 257.913632 -22.937216) (xy 257.8886 -22.936489) (xy 257.839042 -22.929276)
			(xy 257.790855 -22.915641) (xy 257.744866 -22.895817) (xy 257.701867 -22.870146) (xy 257.681984 -22.85492)
			(xy 257.66522 -22.84095) (xy 257.663696 -22.83968) (xy 257.661918 -22.838156) (xy 257.65379 -22.832822)
			(xy 257.643371 -22.827185) (xy 257.619796 -22.825205) (xy 257.608578 -22.829012) (xy 257.584702 -22.839426)
			(xy 257.584194 -22.839426) (xy 257.523234 -22.866604) (xy 257.521202 -22.86762) (xy 257.507486 -22.874478)
			(xy 257.50266 -22.882352) (xy 257.50266 -23.965154) (xy 258.277358 -23.965154) (xy 258.281429 -23.909532)
			(xy 258.293555 -23.855095) (xy 258.313478 -23.803004) (xy 258.340774 -23.754369) (xy 258.37486 -23.710226)
			(xy 258.415009 -23.671517) (xy 258.460367 -23.639066) (xy 258.509967 -23.613565) (xy 258.562751 -23.595558)
			(xy 258.617594 -23.585428) (xy 258.673328 -23.583391) (xy 258.728765 -23.589491) (xy 258.782722 -23.603597)
			(xy 258.834051 -23.625409) (xy 258.881657 -23.654463) (xy 258.924525 -23.690138) (xy 258.961742 -23.731675)
			(xy 258.992515 -23.778188) (xy 259.016187 -23.828685) (xy 259.032255 -23.882092) (xy 259.040375 -23.937268)
			(xy 259.04055 -23.946866) (xy 259.280404 -23.946866) (xy 259.284475 -23.891244) (xy 259.296601 -23.836807)
			(xy 259.316524 -23.784716) (xy 259.34382 -23.736081) (xy 259.377906 -23.691938) (xy 259.418055 -23.653229)
			(xy 259.463413 -23.620778) (xy 259.513013 -23.595277) (xy 259.565797 -23.57727) (xy 259.62064 -23.56714)
			(xy 259.676374 -23.565103) (xy 259.731811 -23.571203) (xy 259.785768 -23.585309) (xy 259.837097 -23.607121)
			(xy 259.884703 -23.636175) (xy 259.927571 -23.67185) (xy 259.964788 -23.713387) (xy 259.995561 -23.7599)
			(xy 260.019233 -23.810397) (xy 260.035301 -23.863804) (xy 260.043421 -23.91898) (xy 260.04393 -23.946866)
			(xy 260.04349 -23.970996) (xy 260.272782 -23.970996) (xy 260.276853 -23.915374) (xy 260.288979 -23.860937)
			(xy 260.308902 -23.808846) (xy 260.336198 -23.760211) (xy 260.370284 -23.716068) (xy 260.410433 -23.677359)
			(xy 260.455791 -23.644908) (xy 260.505391 -23.619407) (xy 260.558175 -23.6014) (xy 260.613018 -23.59127)
			(xy 260.668752 -23.589233) (xy 260.724189 -23.595333) (xy 260.778146 -23.609439) (xy 260.829475 -23.631251)
			(xy 260.877081 -23.660305) (xy 260.919949 -23.69598) (xy 260.957166 -23.737517) (xy 260.987939 -23.78403)
			(xy 261.011611 -23.834527) (xy 261.027679 -23.887934) (xy 261.035799 -23.94311) (xy 261.036308 -23.970996)
			(xy 261.035799 -23.998882) (xy 261.027679 -24.054058) (xy 261.011611 -24.107465) (xy 260.987939 -24.157962)
			(xy 260.957166 -24.204475) (xy 260.919949 -24.246012) (xy 260.877081 -24.281687) (xy 260.829475 -24.310741)
			(xy 260.778146 -24.332553) (xy 260.724189 -24.346659) (xy 260.668752 -24.352759) (xy 260.613018 -24.350722)
			(xy 260.558175 -24.340592) (xy 260.505391 -24.322585) (xy 260.455791 -24.297084) (xy 260.410433 -24.264633)
			(xy 260.370284 -24.225924) (xy 260.336198 -24.181781) (xy 260.308902 -24.133146) (xy 260.288979 -24.081055)
			(xy 260.276853 -24.026618) (xy 260.272782 -23.970996) (xy 260.04349 -23.970996) (xy 260.043421 -23.974752)
			(xy 260.035301 -24.029928) (xy 260.019233 -24.083335) (xy 259.995561 -24.133832) (xy 259.964788 -24.180345)
			(xy 259.927571 -24.221882) (xy 259.884703 -24.257557) (xy 259.837097 -24.286611) (xy 259.785768 -24.308423)
			(xy 259.731811 -24.322529) (xy 259.676374 -24.328629) (xy 259.62064 -24.326592) (xy 259.565797 -24.316462)
			(xy 259.513013 -24.298455) (xy 259.463413 -24.272954) (xy 259.418055 -24.240503) (xy 259.377906 -24.201794)
			(xy 259.34382 -24.157651) (xy 259.316524 -24.109016) (xy 259.296601 -24.056925) (xy 259.284475 -24.002488)
			(xy 259.280404 -23.946866) (xy 259.04055 -23.946866) (xy 259.040884 -23.965154) (xy 259.040375 -23.99304)
			(xy 259.032255 -24.048216) (xy 259.016187 -24.101623) (xy 258.992515 -24.15212) (xy 258.961742 -24.198633)
			(xy 258.924525 -24.24017) (xy 258.881657 -24.275845) (xy 258.834051 -24.304899) (xy 258.782722 -24.326711)
			(xy 258.728765 -24.340817) (xy 258.673328 -24.346917) (xy 258.617594 -24.34488) (xy 258.562751 -24.33475)
			(xy 258.509967 -24.316743) (xy 258.460367 -24.291242) (xy 258.415009 -24.258791) (xy 258.37486 -24.220082)
			(xy 258.340774 -24.175939) (xy 258.313478 -24.127304) (xy 258.293555 -24.075213) (xy 258.281429 -24.020776)
			(xy 258.277358 -23.965154) (xy 257.50266 -23.965154) (xy 257.50266 -24.807418) (xy 264.571224 -24.807418)
			(xy 264.575295 -24.751796) (xy 264.587421 -24.697359) (xy 264.607344 -24.645268) (xy 264.63464 -24.596633)
			(xy 264.668726 -24.55249) (xy 264.708875 -24.513781) (xy 264.754233 -24.48133) (xy 264.803833 -24.455829)
			(xy 264.856617 -24.437822) (xy 264.91146 -24.427692) (xy 264.967194 -24.425655) (xy 265.022631 -24.431755)
			(xy 265.076588 -24.445861) (xy 265.127917 -24.467673) (xy 265.175523 -24.496727) (xy 265.218391 -24.532402)
			(xy 265.255608 -24.573939) (xy 265.286381 -24.620452) (xy 265.310053 -24.670949) (xy 265.326121 -24.724356)
			(xy 265.334241 -24.779532) (xy 265.33475 -24.807418) (xy 265.334241 -24.835304) (xy 265.326121 -24.89048)
			(xy 265.310053 -24.943887) (xy 265.286381 -24.994384) (xy 265.255608 -25.040897) (xy 265.218391 -25.082434)
			(xy 265.175523 -25.118109) (xy 265.127917 -25.147163) (xy 265.076588 -25.168975) (xy 265.022631 -25.183081)
			(xy 264.967194 -25.189181) (xy 264.91146 -25.187144) (xy 264.856617 -25.177014) (xy 264.803833 -25.159007)
			(xy 264.754233 -25.133506) (xy 264.708875 -25.101055) (xy 264.668726 -25.062346) (xy 264.63464 -25.018203)
			(xy 264.607344 -24.969568) (xy 264.587421 -24.917477) (xy 264.575295 -24.86304) (xy 264.571224 -24.807418)
			(xy 257.50266 -24.807418) (xy 257.50266 -25.912572) (xy 257.502733 -25.916782) (xy 257.504135 -25.925084)
			(xy 257.505454 -25.929082) (xy 257.507994 -25.936448) (xy 257.512566 -25.942544) (xy 257.538474 -25.950418)
			(xy 257.562039 -25.958149) (xy 257.60712 -25.978823) (xy 257.649185 -26.005096) (xy 257.684118 -26.03373)
			(xy 263.467848 -26.03373) (xy 263.471919 -25.978108) (xy 263.484045 -25.923671) (xy 263.503968 -25.87158)
			(xy 263.531264 -25.822945) (xy 263.56535 -25.778802) (xy 263.605499 -25.740093) (xy 263.650857 -25.707642)
			(xy 263.700457 -25.682141) (xy 263.753241 -25.664134) (xy 263.808084 -25.654004) (xy 263.863818 -25.651967)
			(xy 263.919255 -25.658067) (xy 263.973212 -25.672173) (xy 264.024541 -25.693985) (xy 264.072147 -25.723039)
			(xy 264.115015 -25.758714) (xy 264.152232 -25.800251) (xy 264.183005 -25.846764) (xy 264.206677 -25.897261)
			(xy 264.222745 -25.950668) (xy 264.230865 -26.005844) (xy 264.231374 -26.03373) (xy 264.230865 -26.061616)
			(xy 264.222745 -26.116792) (xy 264.206677 -26.170199) (xy 264.183005 -26.220696) (xy 264.152232 -26.267209)
			(xy 264.115015 -26.308746) (xy 264.072147 -26.344421) (xy 264.024541 -26.373475) (xy 263.973212 -26.395287)
			(xy 263.919255 -26.409393) (xy 263.863818 -26.415493) (xy 263.808084 -26.413456) (xy 263.753241 -26.403326)
			(xy 263.700457 -26.385319) (xy 263.650857 -26.359818) (xy 263.605499 -26.327367) (xy 263.56535 -26.288658)
			(xy 263.531264 -26.244515) (xy 263.503968 -26.19588) (xy 263.484045 -26.143789) (xy 263.471919 -26.089352)
			(xy 263.467848 -26.03373) (xy 257.684118 -26.03373) (xy 257.687541 -26.036536) (xy 257.704844 -26.054304)
			(xy 257.726066 -26.077634) (xy 257.761409 -26.129866) (xy 257.787807 -26.18714) (xy 257.796792 -26.217372)
			(xy 257.799078 -26.2255) (xy 258.736084 -27.162506) (xy 258.754114 -27.181277) (xy 258.784691 -27.223395)
			(xy 258.808314 -27.269772) (xy 258.824403 -27.319269) (xy 258.832564 -27.370671) (xy 258.833112 -27.396694)
			(xy 258.833112 -28.139136) (xy 260.597902 -28.139136) (xy 260.601973 -28.083514) (xy 260.614099 -28.029077)
			(xy 260.634022 -27.976986) (xy 260.661318 -27.928351) (xy 260.695404 -27.884208) (xy 260.735553 -27.845499)
			(xy 260.780911 -27.813048) (xy 260.830511 -27.787547) (xy 260.883295 -27.76954) (xy 260.938138 -27.75941)
			(xy 260.993872 -27.757373) (xy 261.049309 -27.763473) (xy 261.103266 -27.777579) (xy 261.154595 -27.799391)
			(xy 261.202201 -27.828445) (xy 261.245069 -27.86412) (xy 261.282286 -27.905657) (xy 261.313059 -27.95217)
			(xy 261.336731 -28.002667) (xy 261.352799 -28.056074) (xy 261.360919 -28.11125) (xy 261.361428 -28.139136)
			(xy 261.867902 -28.139136) (xy 261.871973 -28.083514) (xy 261.884099 -28.029077) (xy 261.904022 -27.976986)
			(xy 261.931318 -27.928351) (xy 261.965404 -27.884208) (xy 262.005553 -27.845499) (xy 262.050911 -27.813048)
			(xy 262.100511 -27.787547) (xy 262.153295 -27.76954) (xy 262.208138 -27.75941) (xy 262.263872 -27.757373)
			(xy 262.319309 -27.763473) (xy 262.373266 -27.777579) (xy 262.424595 -27.799391) (xy 262.472201 -27.828445)
			(xy 262.515069 -27.86412) (xy 262.552286 -27.905657) (xy 262.583059 -27.95217) (xy 262.606731 -28.002667)
			(xy 262.622799 -28.056074) (xy 262.630919 -28.11125) (xy 262.631428 -28.139136) (xy 262.630919 -28.167022)
			(xy 262.622799 -28.222198) (xy 262.606731 -28.275605) (xy 262.583059 -28.326102) (xy 262.552286 -28.372615)
			(xy 262.515069 -28.414152) (xy 262.472201 -28.449827) (xy 262.424595 -28.478881) (xy 262.373266 -28.500693)
			(xy 262.319309 -28.514799) (xy 262.263872 -28.520899) (xy 262.208138 -28.518862) (xy 262.153295 -28.508732)
			(xy 262.100511 -28.490725) (xy 262.050911 -28.465224) (xy 262.005553 -28.432773) (xy 261.965404 -28.394064)
			(xy 261.931318 -28.349921) (xy 261.904022 -28.301286) (xy 261.884099 -28.249195) (xy 261.871973 -28.194758)
			(xy 261.867902 -28.139136) (xy 261.361428 -28.139136) (xy 261.360919 -28.167022) (xy 261.352799 -28.222198)
			(xy 261.336731 -28.275605) (xy 261.313059 -28.326102) (xy 261.282286 -28.372615) (xy 261.245069 -28.414152)
			(xy 261.202201 -28.449827) (xy 261.154595 -28.478881) (xy 261.103266 -28.500693) (xy 261.049309 -28.514799)
			(xy 260.993872 -28.520899) (xy 260.938138 -28.518862) (xy 260.883295 -28.508732) (xy 260.830511 -28.490725)
			(xy 260.780911 -28.465224) (xy 260.735553 -28.432773) (xy 260.695404 -28.394064) (xy 260.661318 -28.349921)
			(xy 260.634022 -28.301286) (xy 260.614099 -28.249195) (xy 260.601973 -28.194758) (xy 260.597902 -28.139136)
			(xy 258.833112 -28.139136) (xy 258.833112 -30.209236) (xy 258.832586 -30.235261) (xy 258.824422 -30.286666)
			(xy 258.808332 -30.336167) (xy 258.787599 -30.376876) (xy 259.08889 -30.376876) (xy 259.089429 -30.347959)
			(xy 259.098149 -30.290788) (xy 259.1154 -30.235588) (xy 259.140788 -30.183625) (xy 259.17373 -30.136091)
			(xy 259.213471 -30.094075) (xy 259.235956 -30.075886) (xy 259.244769 -30.068285) (xy 259.254947 -30.047379)
			(xy 259.255514 -30.035754) (xy 259.255514 -29.955998) (xy 259.254957 -29.944369) (xy 259.24478 -29.923459)
			(xy 259.235956 -29.915866) (xy 259.213447 -29.897705) (xy 259.173715 -29.855678) (xy 259.140781 -29.808136)
			(xy 259.115397 -29.756169) (xy 259.098146 -29.700967) (xy 259.089422 -29.643794) (xy 259.08889 -29.614876)
			(xy 259.089376 -29.587625) (xy 259.097132 -29.533677) (xy 259.112487 -29.481382) (xy 259.135129 -29.431805)
			(xy 259.164595 -29.385955) (xy 259.200286 -29.344764) (xy 259.241477 -29.309073) (xy 259.287327 -29.279607)
			(xy 259.336904 -29.256965) (xy 259.389199 -29.24161) (xy 259.443147 -29.233854) (xy 259.497649 -29.233854)
			(xy 259.551597 -29.24161) (xy 259.603892 -29.256965) (xy 259.653469 -29.279607) (xy 259.699319 -29.309073)
			(xy 259.74051 -29.344764) (xy 259.776201 -29.385955) (xy 259.805667 -29.431805) (xy 259.828309 -29.481382)
			(xy 259.843664 -29.533677) (xy 259.85142 -29.587625) (xy 259.851906 -29.614876) (xy 259.851406 -29.643794)
			(xy 259.842678 -29.700968) (xy 259.825419 -29.756168) (xy 259.800024 -29.808131) (xy 259.767076 -29.855664)
			(xy 259.727329 -29.897678) (xy 259.70484 -29.915866) (xy 259.696048 -29.923487) (xy 259.685858 -29.944378)
			(xy 259.685282 -29.955998) (xy 259.685282 -30.035754) (xy 259.685811 -30.047387) (xy 259.696008 -30.068296)
			(xy 259.70484 -30.075886) (xy 259.727325 -30.094075) (xy 259.767058 -30.136096) (xy 259.799996 -30.183632)
			(xy 259.825384 -30.235593) (xy 259.84264 -30.290791) (xy 259.85137 -30.34796) (xy 259.851906 -30.376876)
			(xy 259.85142 -30.404127) (xy 259.843664 -30.458075) (xy 259.828309 -30.51037) (xy 259.805667 -30.559947)
			(xy 259.776201 -30.605797) (xy 259.74051 -30.646988) (xy 259.699319 -30.682679) (xy 259.653469 -30.712145)
			(xy 259.603892 -30.734787) (xy 259.551597 -30.750142) (xy 259.497649 -30.757898) (xy 259.443147 -30.757898)
			(xy 259.389199 -30.750142) (xy 259.336904 -30.734787) (xy 259.287327 -30.712145) (xy 259.241477 -30.682679)
			(xy 259.200286 -30.646988) (xy 259.164595 -30.605797) (xy 259.135129 -30.559947) (xy 259.112487 -30.51037)
			(xy 259.097132 -30.458075) (xy 259.089376 -30.404127) (xy 259.08889 -30.376876) (xy 258.787599 -30.376876)
			(xy 258.78471 -30.382548) (xy 258.754136 -30.424671) (xy 258.736084 -30.443424) (xy 257.770376 -31.408878)
			(xy 257.765135 -31.414548) (xy 257.758039 -31.428254) (xy 257.756406 -31.435802) (xy 257.755644 -31.444692)
			(xy 257.755644 -31.567882) (xy 259.198616 -31.567882) (xy 259.202687 -31.51226) (xy 259.214813 -31.457823)
			(xy 259.234736 -31.405732) (xy 259.262032 -31.357097) (xy 259.296118 -31.312954) (xy 259.336267 -31.274245)
			(xy 259.381625 -31.241794) (xy 259.431225 -31.216293) (xy 259.484009 -31.198286) (xy 259.538852 -31.188156)
			(xy 259.594586 -31.186119) (xy 259.650023 -31.192219) (xy 259.70398 -31.206325) (xy 259.755309 -31.228137)
			(xy 259.802915 -31.257191) (xy 259.845783 -31.292866) (xy 259.883 -31.334403) (xy 259.913773 -31.380916)
			(xy 259.937445 -31.431413) (xy 259.953513 -31.48482) (xy 259.961633 -31.539996) (xy 259.962142 -31.567882)
			(xy 259.961633 -31.595768) (xy 259.953513 -31.650944) (xy 259.937445 -31.704351) (xy 259.930453 -31.719266)
			(xy 260.48538 -31.719266) (xy 260.489451 -31.663644) (xy 260.501577 -31.609207) (xy 260.5215 -31.557116)
			(xy 260.548796 -31.508481) (xy 260.582882 -31.464338) (xy 260.623031 -31.425629) (xy 260.668389 -31.393178)
			(xy 260.717989 -31.367677) (xy 260.770773 -31.34967) (xy 260.825616 -31.33954) (xy 260.88135 -31.337503)
			(xy 260.936787 -31.343603) (xy 260.990744 -31.357709) (xy 261.042073 -31.379521) (xy 261.089679 -31.408575)
			(xy 261.132547 -31.44425) (xy 261.169764 -31.485787) (xy 261.200537 -31.5323) (xy 261.224209 -31.582797)
			(xy 261.240277 -31.636204) (xy 261.244427 -31.664402) (xy 261.760968 -31.664402) (xy 261.765039 -31.60878)
			(xy 261.777165 -31.554343) (xy 261.797088 -31.502252) (xy 261.824384 -31.453617) (xy 261.85847 -31.409474)
			(xy 261.898619 -31.370765) (xy 261.943977 -31.338314) (xy 261.993577 -31.312813) (xy 262.046361 -31.294806)
			(xy 262.101204 -31.284676) (xy 262.156938 -31.282639) (xy 262.212375 -31.288739) (xy 262.266332 -31.302845)
			(xy 262.317661 -31.324657) (xy 262.365267 -31.353711) (xy 262.408135 -31.389386) (xy 262.445352 -31.430923)
			(xy 262.476125 -31.477436) (xy 262.499797 -31.527933) (xy 262.515865 -31.58134) (xy 262.523985 -31.636516)
			(xy 262.524494 -31.664402) (xy 262.523985 -31.692288) (xy 262.515865 -31.747464) (xy 262.499797 -31.800871)
			(xy 262.476125 -31.851368) (xy 262.445352 -31.897881) (xy 262.408135 -31.939418) (xy 262.365267 -31.975093)
			(xy 262.317661 -32.004147) (xy 262.266332 -32.025959) (xy 262.212375 -32.040065) (xy 262.156938 -32.046165)
			(xy 262.101204 -32.044128) (xy 262.046361 -32.033998) (xy 261.993577 -32.015991) (xy 261.943977 -31.99049)
			(xy 261.898619 -31.958039) (xy 261.85847 -31.91933) (xy 261.824384 -31.875187) (xy 261.797088 -31.826552)
			(xy 261.777165 -31.774461) (xy 261.765039 -31.720024) (xy 261.760968 -31.664402) (xy 261.244427 -31.664402)
			(xy 261.248397 -31.69138) (xy 261.248906 -31.719266) (xy 261.248397 -31.747152) (xy 261.240277 -31.802328)
			(xy 261.224209 -31.855735) (xy 261.200537 -31.906232) (xy 261.169764 -31.952745) (xy 261.132547 -31.994282)
			(xy 261.089679 -32.029957) (xy 261.042073 -32.059011) (xy 260.990744 -32.080823) (xy 260.936787 -32.094929)
			(xy 260.88135 -32.101029) (xy 260.825616 -32.098992) (xy 260.770773 -32.088862) (xy 260.717989 -32.070855)
			(xy 260.668389 -32.045354) (xy 260.623031 -32.012903) (xy 260.582882 -31.974194) (xy 260.548796 -31.930051)
			(xy 260.5215 -31.881416) (xy 260.501577 -31.829325) (xy 260.489451 -31.774888) (xy 260.48538 -31.719266)
			(xy 259.930453 -31.719266) (xy 259.913773 -31.754848) (xy 259.883 -31.801361) (xy 259.845783 -31.842898)
			(xy 259.802915 -31.878573) (xy 259.755309 -31.907627) (xy 259.70398 -31.929439) (xy 259.650023 -31.943545)
			(xy 259.594586 -31.949645) (xy 259.538852 -31.947608) (xy 259.484009 -31.937478) (xy 259.431225 -31.919471)
			(xy 259.381625 -31.89397) (xy 259.336267 -31.861519) (xy 259.296118 -31.82281) (xy 259.262032 -31.778667)
			(xy 259.234736 -31.730032) (xy 259.214813 -31.677941) (xy 259.202687 -31.623504) (xy 259.198616 -31.567882)
			(xy 257.755644 -31.567882) (xy 257.755644 -31.971996) (xy 257.755953 -31.980189) (xy 257.761138 -31.995734)
			(xy 257.765804 -32.002476) (xy 261.028036 -35.264852) (xy 262.102344 -35.264852) (xy 262.106415 -35.20923)
			(xy 262.118541 -35.154793) (xy 262.138464 -35.102702) (xy 262.16576 -35.054067) (xy 262.199846 -35.009924)
			(xy 262.239995 -34.971215) (xy 262.285353 -34.938764) (xy 262.334953 -34.913263) (xy 262.387737 -34.895256)
			(xy 262.44258 -34.885126) (xy 262.498314 -34.883089) (xy 262.553751 -34.889189) (xy 262.607708 -34.903295)
			(xy 262.659037 -34.925107) (xy 262.706643 -34.954161) (xy 262.749511 -34.989836) (xy 262.786728 -35.031373)
			(xy 262.817501 -35.077886) (xy 262.841173 -35.128383) (xy 262.857241 -35.18179) (xy 262.865361 -35.236966)
			(xy 262.86587 -35.264852) (xy 262.865361 -35.292738) (xy 262.857241 -35.347914) (xy 262.841173 -35.401321)
			(xy 262.817501 -35.451818) (xy 262.786728 -35.498331) (xy 262.749511 -35.539868) (xy 262.706643 -35.575543)
			(xy 262.659037 -35.604597) (xy 262.607708 -35.626409) (xy 262.553751 -35.640515) (xy 262.498314 -35.646615)
			(xy 262.44258 -35.644578) (xy 262.387737 -35.634448) (xy 262.334953 -35.616441) (xy 262.285353 -35.59094)
			(xy 262.239995 -35.558489) (xy 262.199846 -35.51978) (xy 262.16576 -35.475637) (xy 262.138464 -35.427002)
			(xy 262.118541 -35.374911) (xy 262.106415 -35.320474) (xy 262.102344 -35.264852) (xy 261.028036 -35.264852)
			(xy 262.050087 -36.286948) (xy 263.400284 -36.286948) (xy 263.404355 -36.231326) (xy 263.416481 -36.176889)
			(xy 263.436404 -36.124798) (xy 263.4637 -36.076163) (xy 263.497786 -36.03202) (xy 263.537935 -35.993311)
			(xy 263.583293 -35.96086) (xy 263.632893 -35.935359) (xy 263.685677 -35.917352) (xy 263.74052 -35.907222)
			(xy 263.796254 -35.905185) (xy 263.851691 -35.911285) (xy 263.905648 -35.925391) (xy 263.956977 -35.947203)
			(xy 264.004583 -35.976257) (xy 264.047451 -36.011932) (xy 264.084668 -36.053469) (xy 264.115441 -36.099982)
			(xy 264.139113 -36.150479) (xy 264.155181 -36.203886) (xy 264.163301 -36.259062) (xy 264.16381 -36.286948)
			(xy 264.163301 -36.314834) (xy 264.155181 -36.37001) (xy 264.139113 -36.423417) (xy 264.115441 -36.473914)
			(xy 264.084668 -36.520427) (xy 264.047451 -36.561964) (xy 264.004583 -36.597639) (xy 263.956977 -36.626693)
			(xy 263.905648 -36.648505) (xy 263.851691 -36.662611) (xy 263.796254 -36.668711) (xy 263.74052 -36.666674)
			(xy 263.685677 -36.656544) (xy 263.632893 -36.638537) (xy 263.583293 -36.613036) (xy 263.537935 -36.580585)
			(xy 263.497786 -36.541876) (xy 263.4637 -36.497733) (xy 263.436404 -36.449098) (xy 263.416481 -36.397007)
			(xy 263.404355 -36.34257) (xy 263.400284 -36.286948) (xy 262.050087 -36.286948) (xy 263.53008 -37.767006)
			(xy 263.534727 -37.767521) (xy 263.544061 -37.767017) (xy 263.548622 -37.76599) (xy 263.578848 -37.756846)
			(xy 263.579356 -37.756846) (xy 263.627616 -37.74186) (xy 263.632583 -37.739736) (xy 263.641548 -37.733713)
			(xy 263.645396 -37.729922) (xy 263.655302 -37.719) (xy 263.65581 -37.718492) (xy 263.663938 -37.709602)
			(xy 263.670288 -37.69995) (xy 263.67359 -37.6936) (xy 263.674606 -37.689536) (xy 263.675114 -37.686996)
			(xy 263.682131 -37.65944) (xy 263.703211 -37.606632) (xy 263.73189 -37.557534) (xy 263.767533 -37.513232)
			(xy 263.809351 -37.474705) (xy 263.856421 -37.442805) (xy 263.9077 -37.418239) (xy 263.962056 -37.401549)
			(xy 264.018286 -37.393105) (xy 264.046716 -37.39261) (xy 264.073968 -37.393074) (xy 264.127916 -37.400833)
			(xy 264.180211 -37.416191) (xy 264.229788 -37.438835) (xy 264.275638 -37.468303) (xy 264.316827 -37.503997)
			(xy 264.352517 -37.54519) (xy 264.381982 -37.591042) (xy 264.404621 -37.640621) (xy 264.419974 -37.692917)
			(xy 264.427728 -37.746866) (xy 264.428224 -37.774118) (xy 264.427699 -37.802547) (xy 264.419263 -37.858776)
			(xy 264.402579 -37.913131) (xy 264.378017 -37.964411) (xy 264.346121 -38.011479) (xy 264.307596 -38.053296)
			(xy 264.263295 -38.088936) (xy 264.214197 -38.117611) (xy 264.161388 -38.138686) (xy 264.133838 -38.14572)
			(xy 264.133584 -38.14572) (xy 264.126472 -38.147498) (xy 264.116058 -38.152832) (xy 264.1092 -38.158928)
			(xy 264.108946 -38.159182) (xy 264.102342 -38.165024) (xy 264.101834 -38.165532) (xy 264.090912 -38.175438)
			(xy 264.087127 -38.17929) (xy 264.081117 -38.18826) (xy 264.078974 -38.193218) (xy 264.063988 -38.241478)
			(xy 264.063988 -38.241986) (xy 264.054844 -38.272212) (xy 264.053854 -38.276778) (xy 264.053351 -38.286106)
			(xy 264.053828 -38.290754) (xy 270.122142 -44.359068) (xy 270.127747 -44.363476) (xy 270.140772 -44.369264)
			(xy 270.147796 -44.370498) (xy 270.162215 -44.372018) (xy 270.190891 -44.367846) (xy 270.217242 -44.355787)
			(xy 270.239144 -44.336811) (xy 270.254833 -44.312446) (xy 270.263047 -44.284656) (xy 270.26362 -44.270168)
			(xy 270.26362 -41.658794) (xy 270.263112 -41.651936) (xy 265.499342 -36.888166) (xy 265.488674 -36.881816)
			(xy 265.482832 -36.880038) (xy 265.45775 -36.871774) (xy 265.409962 -36.849296) (xy 265.36573 -36.820445)
			(xy 265.325898 -36.78577) (xy 265.291228 -36.745934) (xy 265.262382 -36.701699) (xy 265.23991 -36.653908)
			(xy 265.231626 -36.628832) (xy 265.229848 -36.62299) (xy 265.223498 -36.612322) (xy 263.728708 -35.117532)
			(xy 263.710676 -35.098761) (xy 263.680095 -35.056644) (xy 263.656468 -35.010268) (xy 263.640373 -34.960771)
			(xy 263.632206 -34.909368) (xy 263.63168 -34.883344) (xy 263.63168 -32.411162) (xy 263.623298 -32.402272)
			(xy 263.587484 -32.372808) (xy 263.586976 -32.3723) (xy 263.563608 -32.35325) (xy 263.560749 -32.350961)
			(xy 263.554499 -32.347142) (xy 263.551162 -32.34563) (xy 263.529826 -32.350202) (xy 263.499768 -32.356212)
			(xy 263.43881 -32.362699) (xy 263.40816 -32.363156) (xy 263.361424 -32.363156) (xy 263.361424 -32.361378)
			(xy 263.327977 -32.358235) (xy 263.262061 -32.345252) (xy 263.198063 -32.324812) (xy 263.136825 -32.297183)
			(xy 263.079151 -32.262728) (xy 263.025798 -32.221899) (xy 262.977468 -32.175234) (xy 262.934795 -32.123344)
			(xy 262.89834 -32.066913) (xy 262.868583 -32.00668) (xy 262.845913 -31.943438) (xy 262.830629 -31.878017)
			(xy 262.822931 -31.811277) (xy 262.822436 -31.777686) (xy 262.822436 -30.776164) (xy 262.819642 -30.772862)
			(xy 262.815578 -30.76829) (xy 262.738108 -30.720284) (xy 262.730534 -30.716167) (xy 262.713642 -30.712794)
			(xy 262.696594 -30.715269) (xy 262.688832 -30.719014) (xy 262.686292 -30.720284) (xy 262.67791 -30.724348)
			(xy 262.670036 -30.727904) (xy 262.644876 -30.738838) (xy 262.592242 -30.754296) (xy 262.537952 -30.762162)
			(xy 262.510524 -30.762702) (xy 262.482962 -30.762235) (xy 262.428399 -30.754393) (xy 262.375508 -30.738865)
			(xy 262.325365 -30.715967) (xy 262.278992 -30.686166) (xy 262.237332 -30.650068) (xy 262.201234 -30.608408)
			(xy 262.171433 -30.562035) (xy 262.148535 -30.511892) (xy 262.133007 -30.459001) (xy 262.125165 -30.404438)
			(xy 262.124698 -30.376876) (xy 262.125208 -30.348467) (xy 262.133562 -30.292267) (xy 262.150085 -30.237905)
			(xy 262.174418 -30.186561) (xy 262.206033 -30.139352) (xy 262.244244 -30.097301) (xy 262.265922 -30.078934)
			(xy 262.26643 -30.078426) (xy 262.272018 -30.0736) (xy 262.276082 -30.070298) (xy 262.279638 -30.066234)
			(xy 262.28548 -30.057344) (xy 262.292084 -30.04312) (xy 262.293751 -30.038668) (xy 262.29554 -30.029331)
			(xy 262.29564 -30.024578) (xy 262.29564 -29.967682) (xy 262.295498 -29.962242) (xy 262.29319 -29.951611)
			(xy 262.291068 -29.9466) (xy 262.287766 -29.939742) (xy 262.287766 -29.939234) (xy 262.280908 -29.925518)
			(xy 262.272526 -29.914088) (xy 262.2677 -29.909262) (xy 262.265922 -29.907738) (xy 262.244897 -29.889499)
			(xy 262.207836 -29.847972) (xy 262.177196 -29.801506) (xy 262.153627 -29.751083) (xy 262.137627 -29.697773)
			(xy 262.129536 -29.642705) (xy 262.129016 -29.614876) (xy 262.129504 -29.587627) (xy 262.137263 -29.533683)
			(xy 262.152621 -29.481392) (xy 262.175264 -29.43182) (xy 262.204731 -29.385974) (xy 262.240423 -29.344789)
			(xy 262.281613 -29.309102) (xy 262.327462 -29.279641) (xy 262.377037 -29.257004) (xy 262.42933 -29.241653)
			(xy 262.483274 -29.233901) (xy 262.510524 -29.233368) (xy 262.535892 -29.233786) (xy 262.58618 -29.240514)
			(xy 262.635133 -29.253847) (xy 262.681887 -29.273551) (xy 262.725616 -29.299277) (xy 262.765551 -29.330573)
			(xy 262.783574 -29.34843) (xy 262.785606 -29.350462) (xy 262.796528 -29.358082) (xy 262.82777 -29.372052)
			(xy 262.839454 -29.37129) (xy 262.839708 -29.37129) (xy 262.85317 -29.370528) (xy 262.8646 -29.362908)
			(xy 262.870168 -29.35901) (xy 262.879174 -29.348836) (xy 262.88238 -29.342842) (xy 262.896916 -29.314212)
			(xy 262.931343 -29.260009) (xy 262.971495 -29.209899) (xy 262.993886 -29.186886) (xy 265.432286 -26.748486)
			(xy 265.437276 -26.742988) (xy 265.444125 -26.729823) (xy 265.445748 -26.722578) (xy 265.446764 -26.712926)
			(xy 265.446764 -24.158194) (xy 265.44726 -24.124094) (xy 265.455177 -24.056354) (xy 265.470906 -23.989991)
			(xy 265.494232 -23.925903) (xy 265.52484 -23.864957) (xy 265.562317 -23.807976) (xy 265.606156 -23.755731)
			(xy 265.655763 -23.708928) (xy 265.710469 -23.668202) (xy 265.769533 -23.634101) (xy 265.832156 -23.607088)
			(xy 265.897492 -23.587528) (xy 265.964656 -23.575685) (xy 266.032742 -23.57172) (xy 266.100828 -23.575685)
			(xy 266.167992 -23.587528) (xy 266.233328 -23.607088) (xy 266.295951 -23.634101) (xy 266.355015 -23.668202)
			(xy 266.409721 -23.708928) (xy 266.459328 -23.755731) (xy 266.503167 -23.807976) (xy 266.540644 -23.864957)
			(xy 266.571252 -23.925903) (xy 266.594578 -23.989991) (xy 266.610307 -24.056354) (xy 266.618224 -24.124094)
			(xy 266.61872 -24.158194) (xy 266.61872 -24.807418) (xy 266.82014 -24.807418) (xy 266.824211 -24.751796)
			(xy 266.836337 -24.697359) (xy 266.85626 -24.645268) (xy 266.883556 -24.596633) (xy 266.917642 -24.55249)
			(xy 266.957791 -24.513781) (xy 267.003149 -24.48133) (xy 267.052749 -24.455829) (xy 267.105533 -24.437822)
			(xy 267.160376 -24.427692) (xy 267.21611 -24.425655) (xy 267.271547 -24.431755) (xy 267.325504 -24.445861)
			(xy 267.376833 -24.467673) (xy 267.424439 -24.496727) (xy 267.467307 -24.532402) (xy 267.504524 -24.573939)
			(xy 267.535297 -24.620452) (xy 267.558969 -24.670949) (xy 267.575037 -24.724356) (xy 267.583157 -24.779532)
			(xy 267.583666 -24.807418) (xy 267.583157 -24.835304) (xy 267.575037 -24.89048) (xy 267.558969 -24.943887)
			(xy 267.535297 -24.994384) (xy 267.504524 -25.040897) (xy 267.467307 -25.082434) (xy 267.424439 -25.118109)
			(xy 267.376833 -25.147163) (xy 267.325504 -25.168975) (xy 267.271547 -25.183081) (xy 267.21611 -25.189181)
			(xy 267.160376 -25.187144) (xy 267.105533 -25.177014) (xy 267.052749 -25.159007) (xy 267.003149 -25.133506)
			(xy 266.957791 -25.101055) (xy 266.917642 -25.062346) (xy 266.883556 -25.018203) (xy 266.85626 -24.969568)
			(xy 266.836337 -24.917477) (xy 266.824211 -24.86304) (xy 266.82014 -24.807418) (xy 266.61872 -24.807418)
			(xy 266.61872 -26.724102) (xy 266.620981 -26.727027) (xy 266.626211 -26.732252) (xy 266.629134 -26.734516)
			(xy 266.923774 -26.734516) (xy 266.926314 -26.734516) (xy 266.931674 -26.73409) (xy 266.942051 -26.731276)
			(xy 266.946888 -26.728928) (xy 266.97051 -26.716228) (xy 266.976352 -26.713434) (xy 266.97686 -26.71318)
			(xy 266.98575 -26.70556) (xy 266.98956 -26.700226) (xy 266.994948 -26.691799) (xy 266.999436 -26.672328)
			(xy 266.996185 -26.652612) (xy 266.985683 -26.635613) (xy 266.977876 -26.62936) (xy 266.972034 -26.625296)
			(xy 266.965938 -26.62301) (xy 266.939239 -26.612245) (xy 266.889164 -26.58385) (xy 266.84392 -26.548257)
			(xy 266.804535 -26.506274) (xy 266.771902 -26.458851) (xy 266.746761 -26.407066) (xy 266.729682 -26.352092)
			(xy 266.721053 -26.295177) (xy 266.720574 -26.266394) (xy 266.72106 -26.239143) (xy 266.728816 -26.185195)
			(xy 266.744171 -26.1329) (xy 266.766813 -26.083323) (xy 266.796279 -26.037473) (xy 266.83197 -25.996282)
			(xy 266.873161 -25.960591) (xy 266.919011 -25.931125) (xy 266.968588 -25.908483) (xy 267.020883 -25.893128)
			(xy 267.074831 -25.885372) (xy 267.129333 -25.885372) (xy 267.183281 -25.893128) (xy 267.235576 -25.908483)
			(xy 267.285153 -25.931125) (xy 267.331003 -25.960591) (xy 267.372194 -25.996282) (xy 267.407885 -26.037473)
			(xy 267.437351 -26.083323) (xy 267.459993 -26.1329) (xy 267.475348 -26.185195) (xy 267.483104 -26.239143)
			(xy 267.48359 -26.266394) (xy 267.483056 -26.295311) (xy 267.47433 -26.352482) (xy 267.457076 -26.407682)
			(xy 267.43169 -26.459646) (xy 267.398753 -26.507184) (xy 267.35902 -26.549208) (xy 267.336524 -26.567384)
			(xy 267.331952 -26.57094) (xy 267.322554 -26.58237) (xy 267.320263 -26.585228) (xy 267.316442 -26.591478)
			(xy 267.314934 -26.594816) (xy 267.314934 -26.595324) (xy 267.312824 -26.600592) (xy 267.310767 -26.611749)
			(xy 267.31087 -26.617422) (xy 267.31214 -26.643838) (xy 267.31214 -26.644346) (xy 267.314934 -26.690574)
			(xy 267.317982 -26.702004) (xy 267.325094 -26.714958) (xy 267.331444 -26.72334) (xy 267.335762 -26.727912)
			(xy 267.337794 -26.729182) (xy 267.342112 -26.731722) (xy 267.36658 -26.746891) (xy 267.411174 -26.783298)
			(xy 267.449925 -26.825872) (xy 267.48199 -26.873684) (xy 267.50667 -26.925693) (xy 267.523428 -26.980768)
			(xy 267.5319 -27.03771) (xy 267.532358 -27.066494) (xy 267.531885 -27.094345) (xy 267.523958 -27.14948)
			(xy 267.508265 -27.202926) (xy 267.485125 -27.253594) (xy 267.455009 -27.300453) (xy 267.418531 -27.342549)
			(xy 267.376433 -27.379025) (xy 267.329571 -27.409137) (xy 267.278902 -27.432274) (xy 267.225455 -27.447964)
			(xy 267.170319 -27.455887) (xy 267.142468 -27.456384) (xy 267.142214 -27.456384) (xy 267.116894 -27.455978)
			(xy 267.066678 -27.449429) (xy 267.017729 -27.436451) (xy 266.970865 -27.417262) (xy 266.948666 -27.405076)
			(xy 266.942824 -27.401774) (xy 266.936728 -27.40025) (xy 266.923774 -27.398472) (xy 266.79906 -27.398472)
			(xy 266.789095 -27.398953) (xy 266.770661 -27.406531) (xy 266.763246 -27.413204) (xy 265.210036 -28.965906)
			(xy 265.053616 -29.12237) (xy 266.80668 -29.12237) (xy 266.80668 -28.25877) (xy 266.80717 -28.228786)
			(xy 266.814998 -28.16933) (xy 266.830519 -28.111405) (xy 266.853468 -28.056001) (xy 266.883452 -28.004067)
			(xy 266.919958 -27.956491) (xy 266.962363 -27.914086) (xy 267.009939 -27.87758) (xy 267.061873 -27.847596)
			(xy 267.117277 -27.824647) (xy 267.175202 -27.809126) (xy 267.234658 -27.801298) (xy 267.294626 -27.801298)
			(xy 267.354082 -27.809126) (xy 267.412007 -27.824647) (xy 267.467411 -27.847596) (xy 267.519345 -27.87758)
			(xy 267.566921 -27.914086) (xy 267.609326 -27.956491) (xy 267.645832 -28.004067) (xy 267.675816 -28.056001)
			(xy 267.698765 -28.111405) (xy 267.714286 -28.16933) (xy 267.722114 -28.228786) (xy 267.722604 -28.25877)
			(xy 267.722604 -29.114242) (xy 277.047452 -29.114242) (xy 277.047452 -28.250642) (xy 277.047942 -28.220674)
			(xy 277.055765 -28.161252) (xy 277.071278 -28.103359) (xy 277.094214 -28.047986) (xy 277.124181 -27.99608)
			(xy 277.160668 -27.94853) (xy 277.203048 -27.90615) (xy 277.250598 -27.869663) (xy 277.302504 -27.839696)
			(xy 277.357877 -27.81676) (xy 277.41577 -27.801247) (xy 277.475192 -27.793424) (xy 277.535128 -27.793424)
			(xy 277.59455 -27.801247) (xy 277.652443 -27.81676) (xy 277.707816 -27.839696) (xy 277.759722 -27.869663)
			(xy 277.807272 -27.90615) (xy 277.849652 -27.94853) (xy 277.886139 -27.99608) (xy 277.916106 -28.047986)
			(xy 277.939042 -28.103359) (xy 277.954555 -28.161252) (xy 277.962378 -28.220674) (xy 277.962868 -28.250642)
			(xy 277.962868 -29.114242) (xy 277.962378 -29.14421) (xy 277.954555 -29.203632) (xy 277.939042 -29.261525)
			(xy 277.916106 -29.316898) (xy 277.886139 -29.368804) (xy 277.849652 -29.416354) (xy 277.807272 -29.458734)
			(xy 277.759722 -29.495221) (xy 277.707816 -29.525188) (xy 277.652443 -29.548124) (xy 277.59455 -29.563637)
			(xy 277.535128 -29.57146) (xy 277.475192 -29.57146) (xy 277.41577 -29.563637) (xy 277.357877 -29.548124)
			(xy 277.302504 -29.525188) (xy 277.250598 -29.495221) (xy 277.203048 -29.458734) (xy 277.160668 -29.416354)
			(xy 277.124181 -29.368804) (xy 277.094214 -29.316898) (xy 277.071278 -29.261525) (xy 277.055765 -29.203632)
			(xy 277.047942 -29.14421) (xy 277.047452 -29.114242) (xy 267.722604 -29.114242) (xy 267.722604 -29.12237)
			(xy 267.722114 -29.152354) (xy 267.714286 -29.21181) (xy 267.698765 -29.269735) (xy 267.675816 -29.325139)
			(xy 267.645832 -29.377073) (xy 267.609326 -29.424649) (xy 267.566921 -29.467054) (xy 267.519345 -29.50356)
			(xy 267.467411 -29.533544) (xy 267.412007 -29.556493) (xy 267.354082 -29.572014) (xy 267.294626 -29.579842)
			(xy 267.234658 -29.579842) (xy 267.175202 -29.572014) (xy 267.117277 -29.556493) (xy 267.061873 -29.533544)
			(xy 267.009939 -29.50356) (xy 266.962363 -29.467054) (xy 266.919958 -29.424649) (xy 266.883452 -29.377073)
			(xy 266.853468 -29.325139) (xy 266.830519 -29.269735) (xy 266.814998 -29.21181) (xy 266.80717 -29.152354)
			(xy 266.80668 -29.12237) (xy 265.053616 -29.12237) (xy 264.299954 -29.876242) (xy 264.295128 -29.88183)
			(xy 264.295128 -30.922468) (xy 264.95248 -30.922468) (xy 264.95248 -30.058868) (xy 264.95297 -30.028884)
			(xy 264.960798 -29.969428) (xy 264.976319 -29.911503) (xy 264.999268 -29.856099) (xy 265.029252 -29.804165)
			(xy 265.065758 -29.756589) (xy 265.108163 -29.714184) (xy 265.155739 -29.677678) (xy 265.207673 -29.647694)
			(xy 265.263077 -29.624745) (xy 265.321002 -29.609224) (xy 265.380458 -29.601396) (xy 265.440426 -29.601396)
			(xy 265.499882 -29.609224) (xy 265.557807 -29.624745) (xy 265.613211 -29.647694) (xy 265.665145 -29.677678)
			(xy 265.712721 -29.714184) (xy 265.755126 -29.756589) (xy 265.791632 -29.804165) (xy 265.821616 -29.856099)
			(xy 265.844565 -29.911503) (xy 265.860086 -29.969428) (xy 265.867914 -30.028884) (xy 265.868404 -30.058868)
			(xy 265.868404 -30.92069) (xy 279.68956 -30.92069) (xy 279.68956 -30.05709) (xy 279.69005 -30.027122)
			(xy 279.697873 -29.9677) (xy 279.713386 -29.909807) (xy 279.736322 -29.854434) (xy 279.766289 -29.802528)
			(xy 279.802776 -29.754978) (xy 279.845156 -29.712598) (xy 279.892706 -29.676111) (xy 279.944612 -29.646144)
			(xy 279.999985 -29.623208) (xy 280.057878 -29.607695) (xy 280.1173 -29.599872) (xy 280.177236 -29.599872)
			(xy 280.236658 -29.607695) (xy 280.294551 -29.623208) (xy 280.349924 -29.646144) (xy 280.40183 -29.676111)
			(xy 280.44938 -29.712598) (xy 280.49176 -29.754978) (xy 280.528247 -29.802528) (xy 280.558214 -29.854434)
			(xy 280.58115 -29.909807) (xy 280.596663 -29.9677) (xy 280.604486 -30.027122) (xy 280.604976 -30.05709)
			(xy 280.604976 -30.92069) (xy 280.604486 -30.950658) (xy 280.596663 -31.01008) (xy 280.58115 -31.067973)
			(xy 280.558214 -31.123346) (xy 280.528247 -31.175252) (xy 280.49176 -31.222802) (xy 280.44938 -31.265182)
			(xy 280.40183 -31.301669) (xy 280.349924 -31.331636) (xy 280.294551 -31.354572) (xy 280.236658 -31.370085)
			(xy 280.177236 -31.377908) (xy 280.1173 -31.377908) (xy 280.057878 -31.370085) (xy 279.999985 -31.354572)
			(xy 279.944612 -31.331636) (xy 279.892706 -31.301669) (xy 279.845156 -31.265182) (xy 279.802776 -31.222802)
			(xy 279.766289 -31.175252) (xy 279.736322 -31.123346) (xy 279.713386 -31.067973) (xy 279.697873 -31.01008)
			(xy 279.69005 -30.950658) (xy 279.68956 -30.92069) (xy 265.868404 -30.92069) (xy 265.868404 -30.922468)
			(xy 265.867914 -30.952452) (xy 265.860086 -31.011908) (xy 265.844565 -31.069833) (xy 265.821616 -31.125237)
			(xy 265.791632 -31.177171) (xy 265.755126 -31.224747) (xy 265.712721 -31.267152) (xy 265.665145 -31.303658)
			(xy 265.613211 -31.333642) (xy 265.557807 -31.356591) (xy 265.499882 -31.372112) (xy 265.440426 -31.37994)
			(xy 265.380458 -31.37994) (xy 265.321002 -31.372112) (xy 265.263077 -31.356591) (xy 265.207673 -31.333642)
			(xy 265.155739 -31.303658) (xy 265.108163 -31.267152) (xy 265.065758 -31.224747) (xy 265.029252 -31.177171)
			(xy 264.999268 -31.125237) (xy 264.976319 -31.069833) (xy 264.960798 -31.011908) (xy 264.95297 -30.952452)
			(xy 264.95248 -30.922468) (xy 264.295128 -30.922468) (xy 264.295128 -32.722312) (xy 266.80668 -32.722312)
			(xy 266.80668 -31.858712) (xy 266.80717 -31.828728) (xy 266.814998 -31.769272) (xy 266.830519 -31.711347)
			(xy 266.853468 -31.655943) (xy 266.883452 -31.604009) (xy 266.919958 -31.556433) (xy 266.962363 -31.514028)
			(xy 267.009939 -31.477522) (xy 267.061873 -31.447538) (xy 267.117277 -31.424589) (xy 267.175202 -31.409068)
			(xy 267.234658 -31.40124) (xy 267.294626 -31.40124) (xy 267.354082 -31.409068) (xy 267.412007 -31.424589)
			(xy 267.467411 -31.447538) (xy 267.519345 -31.477522) (xy 267.566921 -31.514028) (xy 267.609326 -31.556433)
			(xy 267.645832 -31.604009) (xy 267.675816 -31.655943) (xy 267.698765 -31.711347) (xy 267.714286 -31.769272)
			(xy 267.722114 -31.828728) (xy 267.722604 -31.858712) (xy 267.722604 -32.714184) (xy 277.047452 -32.714184)
			(xy 277.047452 -31.850584) (xy 277.047942 -31.820616) (xy 277.055765 -31.761194) (xy 277.071278 -31.703301)
			(xy 277.094214 -31.647928) (xy 277.124181 -31.596022) (xy 277.160668 -31.548472) (xy 277.203048 -31.506092)
			(xy 277.250598 -31.469605) (xy 277.302504 -31.439638) (xy 277.357877 -31.416702) (xy 277.41577 -31.401189)
			(xy 277.475192 -31.393366) (xy 277.535128 -31.393366) (xy 277.59455 -31.401189) (xy 277.652443 -31.416702)
			(xy 277.707816 -31.439638) (xy 277.759722 -31.469605) (xy 277.807272 -31.506092) (xy 277.849652 -31.548472)
			(xy 277.886139 -31.596022) (xy 277.916106 -31.647928) (xy 277.939042 -31.703301) (xy 277.954555 -31.761194)
			(xy 277.962378 -31.820616) (xy 277.962868 -31.850584) (xy 277.962868 -32.714184) (xy 277.962378 -32.744152)
			(xy 277.954555 -32.803574) (xy 277.939042 -32.861467) (xy 277.916106 -32.91684) (xy 277.886139 -32.968746)
			(xy 277.849652 -33.016296) (xy 277.807272 -33.058676) (xy 277.759722 -33.095163) (xy 277.707816 -33.12513)
			(xy 277.652443 -33.148066) (xy 277.59455 -33.163579) (xy 277.535128 -33.171402) (xy 277.475192 -33.171402)
			(xy 277.41577 -33.163579) (xy 277.357877 -33.148066) (xy 277.302504 -33.12513) (xy 277.250598 -33.095163)
			(xy 277.203048 -33.058676) (xy 277.160668 -33.016296) (xy 277.124181 -32.968746) (xy 277.094214 -32.91684)
			(xy 277.071278 -32.861467) (xy 277.055765 -32.803574) (xy 277.047942 -32.744152) (xy 277.047452 -32.714184)
			(xy 267.722604 -32.714184) (xy 267.722604 -32.722312) (xy 267.722114 -32.752296) (xy 267.714286 -32.811752)
			(xy 267.698765 -32.869677) (xy 267.675816 -32.925081) (xy 267.645832 -32.977015) (xy 267.609326 -33.024591)
			(xy 267.566921 -33.066996) (xy 267.519345 -33.103502) (xy 267.467411 -33.133486) (xy 267.412007 -33.156435)
			(xy 267.354082 -33.171956) (xy 267.294626 -33.179784) (xy 267.234658 -33.179784) (xy 267.175202 -33.171956)
			(xy 267.117277 -33.156435) (xy 267.061873 -33.133486) (xy 267.009939 -33.103502) (xy 266.962363 -33.066996)
			(xy 266.919958 -33.024591) (xy 266.883452 -32.977015) (xy 266.853468 -32.925081) (xy 266.830519 -32.869677)
			(xy 266.814998 -32.811752) (xy 266.80717 -32.752296) (xy 266.80668 -32.722312) (xy 264.295128 -32.722312)
			(xy 264.295128 -34.52241) (xy 264.95248 -34.52241) (xy 264.95248 -33.65881) (xy 264.95297 -33.628826)
			(xy 264.960798 -33.56937) (xy 264.976319 -33.511445) (xy 264.999268 -33.456041) (xy 265.029252 -33.404107)
			(xy 265.065758 -33.356531) (xy 265.108163 -33.314126) (xy 265.155739 -33.27762) (xy 265.207673 -33.247636)
			(xy 265.263077 -33.224687) (xy 265.321002 -33.209166) (xy 265.380458 -33.201338) (xy 265.440426 -33.201338)
			(xy 265.499882 -33.209166) (xy 265.557807 -33.224687) (xy 265.613211 -33.247636) (xy 265.665145 -33.27762)
			(xy 265.712721 -33.314126) (xy 265.755126 -33.356531) (xy 265.791632 -33.404107) (xy 265.821616 -33.456041)
			(xy 265.844565 -33.511445) (xy 265.860086 -33.56937) (xy 265.867914 -33.628826) (xy 265.868404 -33.65881)
			(xy 265.868404 -34.520886) (xy 279.68956 -34.520886) (xy 279.68956 -33.657286) (xy 279.69005 -33.627318)
			(xy 279.697873 -33.567896) (xy 279.713386 -33.510003) (xy 279.736322 -33.45463) (xy 279.766289 -33.402724)
			(xy 279.802776 -33.355174) (xy 279.845156 -33.312794) (xy 279.892706 -33.276307) (xy 279.944612 -33.24634)
			(xy 279.999985 -33.223404) (xy 280.057878 -33.207891) (xy 280.1173 -33.200068) (xy 280.177236 -33.200068)
			(xy 280.236658 -33.207891) (xy 280.294551 -33.223404) (xy 280.349924 -33.24634) (xy 280.40183 -33.276307)
			(xy 280.44938 -33.312794) (xy 280.49176 -33.355174) (xy 280.528247 -33.402724) (xy 280.558214 -33.45463)
			(xy 280.58115 -33.510003) (xy 280.596663 -33.567896) (xy 280.604486 -33.627318) (xy 280.604976 -33.657286)
			(xy 280.604976 -34.520886) (xy 280.604486 -34.550854) (xy 280.596663 -34.610276) (xy 280.58115 -34.668169)
			(xy 280.558214 -34.723542) (xy 280.528247 -34.775448) (xy 280.49176 -34.822998) (xy 280.44938 -34.865378)
			(xy 280.40183 -34.901865) (xy 280.349924 -34.931832) (xy 280.294551 -34.954768) (xy 280.236658 -34.970281)
			(xy 280.177236 -34.978104) (xy 280.1173 -34.978104) (xy 280.057878 -34.970281) (xy 279.999985 -34.954768)
			(xy 279.944612 -34.931832) (xy 279.892706 -34.901865) (xy 279.845156 -34.865378) (xy 279.802776 -34.822998)
			(xy 279.766289 -34.775448) (xy 279.736322 -34.723542) (xy 279.713386 -34.668169) (xy 279.697873 -34.610276)
			(xy 279.69005 -34.550854) (xy 279.68956 -34.520886) (xy 265.868404 -34.520886) (xy 265.868404 -34.52241)
			(xy 265.867914 -34.552394) (xy 265.860086 -34.61185) (xy 265.844565 -34.669775) (xy 265.821616 -34.725179)
			(xy 265.791632 -34.777113) (xy 265.755126 -34.824689) (xy 265.712721 -34.867094) (xy 265.665145 -34.9036)
			(xy 265.613211 -34.933584) (xy 265.557807 -34.956533) (xy 265.499882 -34.972054) (xy 265.440426 -34.979882)
			(xy 265.380458 -34.979882) (xy 265.321002 -34.972054) (xy 265.263077 -34.956533) (xy 265.207673 -34.933584)
			(xy 265.155739 -34.9036) (xy 265.108163 -34.867094) (xy 265.065758 -34.824689) (xy 265.029252 -34.777113)
			(xy 264.999268 -34.725179) (xy 264.976319 -34.669775) (xy 264.960798 -34.61185) (xy 264.95297 -34.552394)
			(xy 264.95248 -34.52241) (xy 264.295128 -34.52241) (xy 264.295128 -34.72434) (xy 264.295636 -34.73196)
			(xy 264.297087 -34.739796) (xy 264.304196 -34.75405) (xy 264.309606 -34.7599) (xy 265.239754 -35.689794)
			(xy 265.69289 -36.14293) (xy 265.703558 -36.14928) (xy 265.7094 -36.151058) (xy 265.734481 -36.159324)
			(xy 265.782266 -36.181804) (xy 265.826495 -36.210657) (xy 265.866323 -36.245333) (xy 265.900991 -36.285169)
			(xy 265.929835 -36.329404) (xy 265.952305 -36.377194) (xy 265.960606 -36.402264) (xy 265.962384 -36.408106)
			(xy 265.968734 -36.418774) (xy 266.15009 -36.60013) (xy 270.198603 -36.60013) (xy 270.202607 -36.512245)
			(xy 270.214587 -36.425088) (xy 270.234442 -36.339381) (xy 270.262009 -36.255836) (xy 270.297059 -36.175143)
			(xy 270.339301 -36.097971) (xy 270.388386 -36.024961) (xy 270.443907 -35.956717) (xy 270.505404 -35.893804)
			(xy 270.572366 -35.836744) (xy 270.64424 -35.78601) (xy 270.72043 -35.742022) (xy 270.800304 -35.705144)
			(xy 270.883201 -35.675683) (xy 270.968433 -35.653881) (xy 271.055295 -35.639921) (xy 271.143066 -35.633917)
			(xy 271.23102 -35.63592) (xy 271.318427 -35.645912) (xy 271.404563 -35.663812) (xy 271.488715 -35.68947)
			(xy 271.570185 -35.722674) (xy 271.648298 -35.763148) (xy 271.722406 -35.810559) (xy 271.791897 -35.864512)
			(xy 271.804988 -35.876738) (xy 276.917148 -35.876738) (xy 276.921219 -35.821116) (xy 276.933345 -35.766679)
			(xy 276.953268 -35.714588) (xy 276.980564 -35.665953) (xy 277.01465 -35.62181) (xy 277.054799 -35.583101)
			(xy 277.100157 -35.55065) (xy 277.149757 -35.525149) (xy 277.202541 -35.507142) (xy 277.257384 -35.497012)
			(xy 277.313118 -35.494975) (xy 277.368555 -35.501075) (xy 277.422512 -35.515181) (xy 277.473841 -35.536993)
			(xy 277.521447 -35.566047) (xy 277.564315 -35.601722) (xy 277.601532 -35.643259) (xy 277.632305 -35.689772)
			(xy 277.655977 -35.740269) (xy 277.672045 -35.793676) (xy 277.680165 -35.848852) (xy 277.680674 -35.876738)
			(xy 277.680165 -35.904624) (xy 277.672045 -35.9598) (xy 277.655977 -36.013207) (xy 277.632305 -36.063704)
			(xy 277.601532 -36.110217) (xy 277.564315 -36.151754) (xy 277.521447 -36.187429) (xy 277.473841 -36.216483)
			(xy 277.422512 -36.238295) (xy 277.368555 -36.252401) (xy 277.313118 -36.258501) (xy 277.257384 -36.256464)
			(xy 277.202541 -36.246334) (xy 277.149757 -36.228327) (xy 277.100157 -36.202826) (xy 277.054799 -36.170375)
			(xy 277.01465 -36.131666) (xy 276.980564 -36.087523) (xy 276.953268 -36.038888) (xy 276.933345 -35.986797)
			(xy 276.921219 -35.93236) (xy 276.917148 -35.876738) (xy 271.804988 -35.876738) (xy 271.856193 -35.92456)
			(xy 271.914762 -35.990207) (xy 271.967119 -36.060907) (xy 272.012831 -36.136076) (xy 272.051517 -36.21509)
			(xy 272.082858 -36.297295) (xy 272.106593 -36.382009) (xy 272.122527 -36.46853) (xy 272.12631 -36.50996)
			(xy 278.813766 -36.50996) (xy 278.817837 -36.454338) (xy 278.829963 -36.399901) (xy 278.849886 -36.34781)
			(xy 278.877182 -36.299175) (xy 278.911268 -36.255032) (xy 278.951417 -36.216323) (xy 278.996775 -36.183872)
			(xy 279.046375 -36.158371) (xy 279.099159 -36.140364) (xy 279.154002 -36.130234) (xy 279.209736 -36.128197)
			(xy 279.265173 -36.134297) (xy 279.31913 -36.148403) (xy 279.370459 -36.170215) (xy 279.418065 -36.199269)
			(xy 279.460933 -36.234944) (xy 279.49815 -36.276481) (xy 279.528923 -36.322994) (xy 279.552595 -36.373491)
			(xy 279.568663 -36.426898) (xy 279.576783 -36.482074) (xy 279.577292 -36.50996) (xy 279.576783 -36.537846)
			(xy 279.568663 -36.593022) (xy 279.552595 -36.646429) (xy 279.528923 -36.696926) (xy 279.49815 -36.743439)
			(xy 279.460933 -36.784976) (xy 279.418065 -36.820651) (xy 279.370459 -36.849705) (xy 279.31913 -36.871517)
			(xy 279.265173 -36.885623) (xy 279.209736 -36.891723) (xy 279.154002 -36.889686) (xy 279.099159 -36.879556)
			(xy 279.046375 -36.861549) (xy 278.996775 -36.836048) (xy 278.951417 -36.803597) (xy 278.911268 -36.764888)
			(xy 278.877182 -36.720745) (xy 278.849886 -36.67211) (xy 278.829963 -36.620019) (xy 278.817837 -36.565582)
			(xy 278.813766 -36.50996) (xy 272.12631 -36.50996) (xy 272.130527 -36.556142) (xy 272.131028 -36.60013)
			(xy 272.130527 -36.644118) (xy 272.122527 -36.73173) (xy 272.106593 -36.818251) (xy 272.082858 -36.902965)
			(xy 272.051517 -36.98517) (xy 272.012831 -37.064184) (xy 271.967119 -37.139353) (xy 271.914762 -37.210053)
			(xy 271.856193 -37.2757) (xy 271.791897 -37.335748) (xy 271.722406 -37.389701) (xy 271.648298 -37.437112)
			(xy 271.574867 -37.47516) (xy 275.95906 -37.47516) (xy 275.963131 -37.419538) (xy 275.975257 -37.365101)
			(xy 275.99518 -37.31301) (xy 276.022476 -37.264375) (xy 276.056562 -37.220232) (xy 276.096711 -37.181523)
			(xy 276.142069 -37.149072) (xy 276.191669 -37.123571) (xy 276.244453 -37.105564) (xy 276.299296 -37.095434)
			(xy 276.35503 -37.093397) (xy 276.410467 -37.099497) (xy 276.464424 -37.113603) (xy 276.515753 -37.135415)
			(xy 276.563359 -37.164469) (xy 276.606227 -37.200144) (xy 276.643444 -37.241681) (xy 276.674217 -37.288194)
			(xy 276.697889 -37.338691) (xy 276.713957 -37.392098) (xy 276.722077 -37.447274) (xy 276.722586 -37.47516)
			(xy 276.722077 -37.503046) (xy 276.713957 -37.558222) (xy 276.697889 -37.611629) (xy 276.674217 -37.662126)
			(xy 276.674064 -37.662358) (xy 278.148286 -37.662358) (xy 278.152357 -37.606736) (xy 278.164483 -37.552299)
			(xy 278.184406 -37.500208) (xy 278.211702 -37.451573) (xy 278.245788 -37.40743) (xy 278.285937 -37.368721)
			(xy 278.331295 -37.33627) (xy 278.380895 -37.310769) (xy 278.433679 -37.292762) (xy 278.488522 -37.282632)
			(xy 278.544256 -37.280595) (xy 278.599693 -37.286695) (xy 278.65365 -37.300801) (xy 278.704979 -37.322613)
			(xy 278.752585 -37.351667) (xy 278.795453 -37.387342) (xy 278.83267 -37.428879) (xy 278.863443 -37.475392)
			(xy 278.887115 -37.525889) (xy 278.903183 -37.579296) (xy 278.911303 -37.634472) (xy 278.911812 -37.662358)
			(xy 278.911303 -37.690244) (xy 278.903183 -37.74542) (xy 278.887115 -37.798827) (xy 278.863443 -37.849324)
			(xy 278.83267 -37.895837) (xy 278.795453 -37.937374) (xy 278.752585 -37.973049) (xy 278.704979 -38.002103)
			(xy 278.65365 -38.023915) (xy 278.599693 -38.038021) (xy 278.544256 -38.044121) (xy 278.488522 -38.042084)
			(xy 278.433679 -38.031954) (xy 278.380895 -38.013947) (xy 278.331295 -37.988446) (xy 278.285937 -37.955995)
			(xy 278.245788 -37.917286) (xy 278.211702 -37.873143) (xy 278.184406 -37.824508) (xy 278.164483 -37.772417)
			(xy 278.152357 -37.71798) (xy 278.148286 -37.662358) (xy 276.674064 -37.662358) (xy 276.643444 -37.708639)
			(xy 276.606227 -37.750176) (xy 276.563359 -37.785851) (xy 276.515753 -37.814905) (xy 276.464424 -37.836717)
			(xy 276.410467 -37.850823) (xy 276.35503 -37.856923) (xy 276.299296 -37.854886) (xy 276.244453 -37.844756)
			(xy 276.191669 -37.826749) (xy 276.142069 -37.801248) (xy 276.096711 -37.768797) (xy 276.056562 -37.730088)
			(xy 276.022476 -37.685945) (xy 275.99518 -37.63731) (xy 275.975257 -37.585219) (xy 275.963131 -37.530782)
			(xy 275.95906 -37.47516) (xy 271.574867 -37.47516) (xy 271.570185 -37.477586) (xy 271.488715 -37.51079)
			(xy 271.404563 -37.536448) (xy 271.318427 -37.554348) (xy 271.23102 -37.56434) (xy 271.143066 -37.566343)
			(xy 271.055295 -37.560339) (xy 270.968433 -37.546379) (xy 270.883201 -37.524577) (xy 270.800304 -37.495116)
			(xy 270.72043 -37.458238) (xy 270.64424 -37.41425) (xy 270.572366 -37.363516) (xy 270.505404 -37.306456)
			(xy 270.443907 -37.243543) (xy 270.388386 -37.175299) (xy 270.339301 -37.102289) (xy 270.297059 -37.025117)
			(xy 270.262009 -36.944424) (xy 270.234442 -36.860879) (xy 270.214587 -36.775172) (xy 270.202607 -36.688015)
			(xy 270.198603 -36.60013) (xy 266.15009 -36.60013) (xy 268.279907 -38.729947) (xy 281.90092 -38.729947)
			(xy 281.90092 -38.675453) (xy 281.908675 -38.621512) (xy 281.924028 -38.569225) (xy 281.946665 -38.519654)
			(xy 281.976127 -38.473809) (xy 282.011813 -38.432624) (xy 282.052997 -38.396937) (xy 282.09884 -38.367473)
			(xy 282.14841 -38.344834) (xy 282.200697 -38.329479) (xy 282.254637 -38.321721) (xy 282.281884 -38.321234)
			(xy 282.310188 -38.32172) (xy 282.366178 -38.330071) (xy 282.420318 -38.346606) (xy 282.471419 -38.370961)
			(xy 282.518359 -38.402603) (xy 282.560106 -38.440835) (xy 282.595743 -38.484818) (xy 282.61056 -38.50894)
			(xy 282.618113 -38.521005) (xy 282.638741 -38.540609) (xy 282.663983 -38.553751) (xy 282.691873 -38.559407)
			(xy 282.72024 -38.557137) (xy 282.746875 -38.547117) (xy 282.769705 -38.530129) (xy 282.778708 -38.5191)
			(xy 282.796895 -38.496224) (xy 282.839058 -38.45576) (xy 282.886893 -38.422193) (xy 282.939285 -38.396306)
			(xy 282.995009 -38.378703) (xy 283.052765 -38.369797) (xy 283.081984 -38.36924) (xy 283.109241 -38.369606)
			(xy 283.163201 -38.377362) (xy 283.215507 -38.392719) (xy 283.265095 -38.415363) (xy 283.310956 -38.444834)
			(xy 283.352156 -38.480533) (xy 283.387856 -38.521731) (xy 283.417329 -38.567591) (xy 283.439976 -38.617178)
			(xy 283.455335 -38.669484) (xy 283.463093 -38.723443) (xy 283.463093 -38.777957) (xy 283.455335 -38.831916)
			(xy 283.439976 -38.884222) (xy 283.417329 -38.933809) (xy 283.387856 -38.979669) (xy 283.352156 -39.020867)
			(xy 283.310956 -39.056566) (xy 283.265095 -39.086037) (xy 283.215507 -39.108681) (xy 283.163201 -39.124038)
			(xy 283.109241 -39.131794) (xy 283.081984 -39.132256) (xy 283.053681 -39.131721) (xy 282.997694 -39.12338)
			(xy 282.943555 -39.106854) (xy 282.892453 -39.082507) (xy 282.845513 -39.050873) (xy 282.803764 -39.012647)
			(xy 282.768125 -38.968669) (xy 282.753308 -38.94455) (xy 282.745666 -38.932546) (xy 282.725056 -38.912948)
			(xy 282.699834 -38.899806) (xy 282.671962 -38.894144) (xy 282.643611 -38.896401) (xy 282.616987 -38.906403)
			(xy 282.594162 -38.923372) (xy 282.58516 -38.93439) (xy 282.566989 -38.957279) (xy 282.524823 -38.997743)
			(xy 282.476984 -39.031309) (xy 282.424589 -39.057194) (xy 282.368862 -39.074793) (xy 282.311104 -39.083695)
			(xy 282.281884 -39.08425) (xy 282.254637 -39.083679) (xy 282.200697 -39.075921) (xy 282.14841 -39.060566)
			(xy 282.09884 -39.037927) (xy 282.052997 -39.008463) (xy 282.011813 -38.972776) (xy 281.976127 -38.931591)
			(xy 281.946665 -38.885746) (xy 281.924028 -38.836175) (xy 281.908675 -38.783888) (xy 281.90092 -38.729947)
			(xy 268.279907 -38.729947) (xy 270.818715 -41.268755) (xy 274.043827 -41.268755) (xy 274.043827 -41.214245)
			(xy 274.051585 -41.16029) (xy 274.066942 -41.107988) (xy 274.089586 -41.058404) (xy 274.119057 -41.012547)
			(xy 274.154753 -40.971352) (xy 274.195949 -40.935655) (xy 274.241806 -40.906185) (xy 274.29139 -40.883541)
			(xy 274.343692 -40.868184) (xy 274.397647 -40.860427) (xy 274.424902 -40.859964) (xy 274.45364 -40.860496)
			(xy 274.510467 -40.869118) (xy 274.565357 -40.886167) (xy 274.617069 -40.911256) (xy 274.664432 -40.943819)
			(xy 274.68576 -40.963088) (xy 274.692618 -40.969692) (xy 274.710652 -40.976804) (xy 274.799552 -40.976804)
			(xy 274.817586 -40.969692) (xy 274.824444 -40.963088) (xy 274.845778 -40.943825) (xy 274.893137 -40.911255)
			(xy 274.944847 -40.886161) (xy 274.999736 -40.869108) (xy 275.056563 -40.860485) (xy 275.085302 -40.859964)
			(xy 275.112551 -40.860506) (xy 275.166495 -40.868263) (xy 275.218785 -40.883617) (xy 275.268358 -40.906256)
			(xy 275.314205 -40.93572) (xy 275.355392 -40.971409) (xy 275.391081 -41.012596) (xy 275.420545 -41.058443)
			(xy 275.443184 -41.108017) (xy 275.458538 -41.160307) (xy 275.466294 -41.214251) (xy 275.466294 -41.268749)
			(xy 275.458538 -41.322693) (xy 275.443184 -41.374983) (xy 275.420545 -41.424557) (xy 275.391081 -41.470404)
			(xy 275.355392 -41.511591) (xy 275.314205 -41.54728) (xy 275.268358 -41.576744) (xy 275.218785 -41.599383)
			(xy 275.166495 -41.614737) (xy 275.112551 -41.622494) (xy 275.085302 -41.62298) (xy 275.056564 -41.622434)
			(xy 274.999739 -41.613813) (xy 274.944849 -41.596767) (xy 274.893137 -41.571681) (xy 274.845773 -41.539123)
			(xy 274.824444 -41.519856) (xy 274.817586 -41.513252) (xy 274.799552 -41.50614) (xy 274.710652 -41.50614)
			(xy 274.692618 -41.513252) (xy 274.68576 -41.519856) (xy 274.664431 -41.539125) (xy 274.61707 -41.571692)
			(xy 274.565359 -41.596785) (xy 274.510468 -41.613836) (xy 274.453641 -41.622459) (xy 274.424902 -41.62298)
			(xy 274.397647 -41.622573) (xy 274.343692 -41.614816) (xy 274.29139 -41.599459) (xy 274.241806 -41.576815)
			(xy 274.195949 -41.547345) (xy 274.154753 -41.511648) (xy 274.119057 -41.470453) (xy 274.089586 -41.424596)
			(xy 274.066942 -41.375012) (xy 274.051585 -41.32271) (xy 274.043827 -41.268755) (xy 270.818715 -41.268755)
			(xy 270.901668 -41.351708) (xy 270.919699 -41.370479) (xy 270.950277 -41.412596) (xy 270.973901 -41.458973)
			(xy 270.98999 -41.50847) (xy 270.998152 -41.559873) (xy 270.998696 -41.585896) (xy 270.998696 -43.305222)
			(xy 276.507194 -43.305222) (xy 276.507674 -43.277852) (xy 276.515489 -43.223674) (xy 276.530975 -43.171171)
			(xy 276.553813 -43.121424) (xy 276.583534 -43.075456) (xy 276.601174 -43.054524) (xy 276.601428 -43.05427)
			(xy 276.606995 -43.04717) (xy 276.613252 -43.030263) (xy 276.61362 -43.02125) (xy 276.61362 -42.954194)
			(xy 276.613261 -42.945177) (xy 276.607014 -42.928261) (xy 276.601428 -42.921174) (xy 276.601174 -42.921174)
			(xy 276.601174 -42.92092) (xy 276.583527 -42.899995) (xy 276.553817 -42.85402) (xy 276.530983 -42.80427)
			(xy 276.515494 -42.751768) (xy 276.507667 -42.697592) (xy 276.507194 -42.670222) (xy 276.507733 -42.641484)
			(xy 276.516352 -42.584657) (xy 276.533399 -42.529767) (xy 276.558487 -42.478055) (xy 276.591049 -42.430691)
			(xy 276.610318 -42.409364) (xy 276.616922 -42.402506) (xy 276.624034 -42.384472) (xy 276.624034 -42.295572)
			(xy 276.616922 -42.277538) (xy 276.610318 -42.27068) (xy 276.591069 -42.249334) (xy 276.558504 -42.201975)
			(xy 276.533411 -42.150266) (xy 276.51636 -42.095378) (xy 276.507736 -42.038554) (xy 276.507733 -41.981078)
			(xy 276.516353 -41.924253) (xy 276.5334 -41.869364) (xy 276.558488 -41.817653) (xy 276.591049 -41.770291)
			(xy 276.610318 -41.748964) (xy 276.616922 -41.742106) (xy 276.624034 -41.724072) (xy 276.624034 -41.635172)
			(xy 276.616922 -41.617138) (xy 276.610318 -41.61028) (xy 276.591054 -41.588947) (xy 276.558488 -41.541586)
			(xy 276.533394 -41.489876) (xy 276.516342 -41.434987) (xy 276.507717 -41.378161) (xy 276.507194 -41.349422)
			(xy 276.50768 -41.322171) (xy 276.515436 -41.268223) (xy 276.530791 -41.215928) (xy 276.553433 -41.166351)
			(xy 276.582899 -41.120501) (xy 276.61859 -41.07931) (xy 276.659781 -41.043619) (xy 276.705631 -41.014153)
			(xy 276.755208 -40.991511) (xy 276.807503 -40.976156) (xy 276.861451 -40.9684) (xy 276.915953 -40.9684)
			(xy 276.939074 -40.971724) (xy 284.793942 -40.971724) (xy 284.798013 -40.916102) (xy 284.810139 -40.861665)
			(xy 284.830062 -40.809574) (xy 284.857358 -40.760939) (xy 284.891444 -40.716796) (xy 284.931593 -40.678087)
			(xy 284.976951 -40.645636) (xy 285.026551 -40.620135) (xy 285.079335 -40.602128) (xy 285.134178 -40.591998)
			(xy 285.189912 -40.589961) (xy 285.245349 -40.596061) (xy 285.299306 -40.610167) (xy 285.350635 -40.631979)
			(xy 285.398241 -40.661033) (xy 285.441109 -40.696708) (xy 285.478326 -40.738245) (xy 285.509099 -40.784758)
			(xy 285.532771 -40.835255) (xy 285.548839 -40.888662) (xy 285.556959 -40.943838) (xy 285.557468 -40.971724)
			(xy 285.556959 -40.99961) (xy 285.548839 -41.054786) (xy 285.532771 -41.108193) (xy 285.509099 -41.15869)
			(xy 285.478326 -41.205203) (xy 285.441109 -41.24674) (xy 285.398241 -41.282415) (xy 285.350635 -41.311469)
			(xy 285.299306 -41.333281) (xy 285.245349 -41.347387) (xy 285.189912 -41.353487) (xy 285.134178 -41.35145)
			(xy 285.079335 -41.34132) (xy 285.026551 -41.323313) (xy 284.976951 -41.297812) (xy 284.931593 -41.265361)
			(xy 284.891444 -41.226652) (xy 284.857358 -41.182509) (xy 284.830062 -41.133874) (xy 284.810139 -41.081783)
			(xy 284.798013 -41.027346) (xy 284.793942 -40.971724) (xy 276.939074 -40.971724) (xy 276.969901 -40.976156)
			(xy 277.022196 -40.991511) (xy 277.071773 -41.014153) (xy 277.117623 -41.043619) (xy 277.158814 -41.07931)
			(xy 277.194505 -41.120501) (xy 277.223971 -41.166351) (xy 277.246613 -41.215928) (xy 277.261968 -41.268223)
			(xy 277.269724 -41.322171) (xy 277.27021 -41.349422) (xy 277.269697 -41.378161) (xy 277.261071 -41.434989)
			(xy 277.244019 -41.48988) (xy 277.218925 -41.541591) (xy 277.186358 -41.588953) (xy 277.167086 -41.61028)
			(xy 277.160482 -41.617138) (xy 277.15337 -41.635172) (xy 277.15337 -41.724072) (xy 277.160482 -41.742106)
			(xy 277.167086 -41.748964) (xy 277.186378 -41.770272) (xy 277.218942 -41.817638) (xy 277.244032 -41.869353)
			(xy 277.261079 -41.924246) (xy 277.2697 -41.981076) (xy 277.269697 -42.038556) (xy 277.261072 -42.095385)
			(xy 277.24402 -42.150277) (xy 277.218926 -42.20199) (xy 277.186358 -42.249353) (xy 277.167086 -42.27068)
			(xy 277.160482 -42.277538) (xy 277.15337 -42.295572) (xy 277.15337 -42.384472) (xy 277.160482 -42.402506)
			(xy 277.167086 -42.409364) (xy 277.186371 -42.430679) (xy 277.218935 -42.478044) (xy 277.244024 -42.529759)
			(xy 277.261071 -42.584653) (xy 277.269691 -42.641482) (xy 277.27021 -42.670222) (xy 277.269754 -42.697593)
			(xy 277.261934 -42.751772) (xy 277.246442 -42.804275) (xy 277.225887 -42.849038) (xy 279.091896 -42.849038)
			(xy 279.095967 -42.793416) (xy 279.108093 -42.738979) (xy 279.128016 -42.686888) (xy 279.155312 -42.638253)
			(xy 279.189398 -42.59411) (xy 279.229547 -42.555401) (xy 279.274905 -42.52295) (xy 279.324505 -42.497449)
			(xy 279.377289 -42.479442) (xy 279.432132 -42.469312) (xy 279.487866 -42.467275) (xy 279.543303 -42.473375)
			(xy 279.59726 -42.487481) (xy 279.648589 -42.509293) (xy 279.696195 -42.538347) (xy 279.739063 -42.574022)
			(xy 279.77628 -42.615559) (xy 279.807053 -42.662072) (xy 279.830725 -42.712569) (xy 279.846793 -42.765976)
			(xy 279.854913 -42.821152) (xy 279.855274 -42.84091) (xy 285.133032 -42.84091) (xy 285.137103 -42.785288)
			(xy 285.149229 -42.730851) (xy 285.169152 -42.67876) (xy 285.196448 -42.630125) (xy 285.230534 -42.585982)
			(xy 285.270683 -42.547273) (xy 285.316041 -42.514822) (xy 285.365641 -42.489321) (xy 285.418425 -42.471314)
			(xy 285.473268 -42.461184) (xy 285.529002 -42.459147) (xy 285.584439 -42.465247) (xy 285.638396 -42.479353)
			(xy 285.689725 -42.501165) (xy 285.737331 -42.530219) (xy 285.780199 -42.565894) (xy 285.817416 -42.607431)
			(xy 285.848189 -42.653944) (xy 285.871861 -42.704441) (xy 285.887929 -42.757848) (xy 285.896049 -42.813024)
			(xy 285.896558 -42.84091) (xy 285.896049 -42.868796) (xy 285.887929 -42.923972) (xy 285.871861 -42.977379)
			(xy 285.848189 -43.027876) (xy 285.817416 -43.074389) (xy 285.780199 -43.115926) (xy 285.737331 -43.151601)
			(xy 285.689725 -43.180655) (xy 285.638396 -43.202467) (xy 285.584439 -43.216573) (xy 285.529002 -43.222673)
			(xy 285.473268 -43.220636) (xy 285.418425 -43.210506) (xy 285.365641 -43.192499) (xy 285.316041 -43.166998)
			(xy 285.270683 -43.134547) (xy 285.230534 -43.095838) (xy 285.196448 -43.051695) (xy 285.169152 -43.00306)
			(xy 285.149229 -42.950969) (xy 285.137103 -42.896532) (xy 285.133032 -42.84091) (xy 279.855274 -42.84091)
			(xy 279.855422 -42.849038) (xy 279.854913 -42.876924) (xy 279.846793 -42.9321) (xy 279.830725 -42.985507)
			(xy 279.807053 -43.036004) (xy 279.77628 -43.082517) (xy 279.739063 -43.124054) (xy 279.696195 -43.159729)
			(xy 279.648589 -43.188783) (xy 279.59726 -43.210595) (xy 279.543303 -43.224701) (xy 279.487866 -43.230801)
			(xy 279.432132 -43.228764) (xy 279.377289 -43.218634) (xy 279.324505 -43.200627) (xy 279.274905 -43.175126)
			(xy 279.229547 -43.142675) (xy 279.189398 -43.103966) (xy 279.155312 -43.059823) (xy 279.128016 -43.011188)
			(xy 279.108093 -42.959097) (xy 279.095967 -42.90466) (xy 279.091896 -42.849038) (xy 277.225887 -42.849038)
			(xy 277.223598 -42.854022) (xy 277.193872 -42.899988) (xy 277.17623 -42.92092) (xy 277.175976 -42.921174)
			(xy 277.170392 -42.928262) (xy 277.164144 -42.945178) (xy 277.163784 -42.954194) (xy 277.163784 -43.02125)
			(xy 277.164168 -43.030264) (xy 277.170397 -43.047181) (xy 277.175976 -43.05427) (xy 277.17623 -43.05427)
			(xy 277.17623 -43.054524) (xy 277.193852 -43.07547) (xy 277.223565 -43.121439) (xy 277.246404 -43.171184)
			(xy 277.261899 -43.223681) (xy 277.269733 -43.277854) (xy 277.27021 -43.305222) (xy 277.269724 -43.332473)
			(xy 277.261968 -43.386421) (xy 277.246613 -43.438716) (xy 277.223971 -43.488293) (xy 277.194505 -43.534143)
			(xy 277.158814 -43.575334) (xy 277.117623 -43.611025) (xy 277.071773 -43.640491) (xy 277.022196 -43.663133)
			(xy 276.969901 -43.678488) (xy 276.915953 -43.686244) (xy 276.861451 -43.686244) (xy 276.807503 -43.678488)
			(xy 276.755208 -43.663133) (xy 276.705631 -43.640491) (xy 276.659781 -43.611025) (xy 276.61859 -43.575334)
			(xy 276.582899 -43.534143) (xy 276.553433 -43.488293) (xy 276.530791 -43.438716) (xy 276.515436 -43.386421)
			(xy 276.50768 -43.332473) (xy 276.507194 -43.305222) (xy 270.998696 -43.305222) (xy 270.998696 -43.73626)
			(xy 278.412954 -43.73626) (xy 278.417025 -43.680638) (xy 278.429151 -43.626201) (xy 278.449074 -43.57411)
			(xy 278.47637 -43.525475) (xy 278.510456 -43.481332) (xy 278.550605 -43.442623) (xy 278.595963 -43.410172)
			(xy 278.645563 -43.384671) (xy 278.698347 -43.366664) (xy 278.75319 -43.356534) (xy 278.808924 -43.354497)
			(xy 278.864361 -43.360597) (xy 278.918318 -43.374703) (xy 278.969647 -43.396515) (xy 279.017253 -43.425569)
			(xy 279.060121 -43.461244) (xy 279.097338 -43.502781) (xy 279.128111 -43.549294) (xy 279.136337 -43.566842)
			(xy 281.329384 -43.566842) (xy 281.329975 -43.53143) (xy 281.338507 -43.461123) (xy 281.355451 -43.392356)
			(xy 281.380561 -43.326133) (xy 281.41347 -43.26342) (xy 281.453698 -43.205131) (xy 281.500659 -43.152115)
			(xy 281.553668 -43.105147) (xy 281.611952 -43.064911) (xy 281.67466 -43.031994) (xy 281.74088 -43.006875)
			(xy 281.809644 -42.989921) (xy 281.87995 -42.98138) (xy 281.915362 -42.980864) (xy 281.948243 -42.98131)
			(xy 282.013591 -42.988674) (xy 282.077703 -43.003313) (xy 282.139771 -43.025044) (xy 282.199014 -43.053592)
			(xy 282.254684 -43.088598) (xy 282.306082 -43.129621) (xy 282.329636 -43.152568) (xy 282.832048 -43.65498)
			(xy 282.84036 -43.662393) (xy 282.861305 -43.669896) (xy 282.872434 -43.669458) (xy 282.961588 -43.66133)
			(xy 282.981146 -43.6499) (xy 282.987496 -43.640502) (xy 283.002839 -43.619038) (xy 283.038467 -43.580124)
			(xy 283.079117 -43.546492) (xy 283.124014 -43.518781) (xy 283.172301 -43.497522) (xy 283.223058 -43.48312)
			(xy 283.275314 -43.475848) (xy 283.301694 -43.475402) (xy 283.328948 -43.475844) (xy 283.382901 -43.483601)
			(xy 283.435201 -43.498957) (xy 283.484783 -43.5216) (xy 283.530638 -43.551068) (xy 283.571833 -43.586763)
			(xy 283.607528 -43.627957) (xy 283.636997 -43.673812) (xy 283.659641 -43.723393) (xy 283.674998 -43.775693)
			(xy 283.682755 -43.829646) (xy 283.682755 -43.884154) (xy 283.674998 -43.938107) (xy 283.659641 -43.990407)
			(xy 283.636997 -44.039988) (xy 283.607528 -44.085843) (xy 283.571833 -44.127037) (xy 283.530638 -44.162732)
			(xy 283.484783 -44.1922) (xy 283.435201 -44.214843) (xy 283.382901 -44.230199) (xy 283.328948 -44.237956)
			(xy 283.301694 -44.238418) (xy 283.30144 -44.238418) (xy 283.281882 -44.23791) (xy 283.281628 -44.23791)
			(xy 283.271329 -44.237892) (xy 283.252062 -44.24512) (xy 283.24429 -44.25188) (xy 283.190696 -44.30268)
			(xy 283.183578 -44.310185) (xy 283.17544 -44.329179) (xy 283.174948 -44.33951) (xy 283.174948 -44.871132)
			(xy 283.17502 -44.87291) (xy 285.133032 -44.87291) (xy 285.137103 -44.817288) (xy 285.149229 -44.762851)
			(xy 285.169152 -44.71076) (xy 285.196448 -44.662125) (xy 285.230534 -44.617982) (xy 285.270683 -44.579273)
			(xy 285.316041 -44.546822) (xy 285.365641 -44.521321) (xy 285.418425 -44.503314) (xy 285.473268 -44.493184)
			(xy 285.529002 -44.491147) (xy 285.584439 -44.497247) (xy 285.638396 -44.511353) (xy 285.689725 -44.533165)
			(xy 285.737331 -44.562219) (xy 285.780199 -44.597894) (xy 285.817416 -44.639431) (xy 285.848189 -44.685944)
			(xy 285.871861 -44.736441) (xy 285.887929 -44.789848) (xy 285.896049 -44.845024) (xy 285.896558 -44.87291)
			(xy 285.896049 -44.900796) (xy 285.887929 -44.955972) (xy 285.871861 -45.009379) (xy 285.848189 -45.059876)
			(xy 285.817416 -45.106389) (xy 285.780199 -45.147926) (xy 285.737331 -45.183601) (xy 285.689725 -45.212655)
			(xy 285.638396 -45.234467) (xy 285.584439 -45.248573) (xy 285.529002 -45.254673) (xy 285.473268 -45.252636)
			(xy 285.418425 -45.242506) (xy 285.365641 -45.224499) (xy 285.316041 -45.198998) (xy 285.270683 -45.166547)
			(xy 285.230534 -45.127838) (xy 285.196448 -45.083695) (xy 285.169152 -45.03506) (xy 285.149229 -44.982969)
			(xy 285.137103 -44.928532) (xy 285.133032 -44.87291) (xy 283.17502 -44.87291) (xy 283.175359 -44.881294)
			(xy 283.183234 -44.90003) (xy 283.190188 -44.907454) (xy 283.24937 -44.965366) (xy 283.26842 -44.972986)
			(xy 283.27858 -44.972732) (xy 283.285692 -44.972732) (xy 283.312948 -44.973114) (xy 283.366906 -44.980871)
			(xy 283.41921 -44.996228) (xy 283.468796 -45.018873) (xy 283.514655 -45.048344) (xy 283.555853 -45.084041)
			(xy 283.591552 -45.125238) (xy 283.621023 -45.171097) (xy 283.643669 -45.220683) (xy 283.659027 -45.272987)
			(xy 283.666785 -45.326944) (xy 283.666785 -45.381456) (xy 283.659027 -45.435413) (xy 283.643669 -45.487717)
			(xy 283.621023 -45.537303) (xy 283.591552 -45.583162) (xy 283.555853 -45.624359) (xy 283.514655 -45.660056)
			(xy 283.468796 -45.689527) (xy 283.41921 -45.712172) (xy 283.366906 -45.727529) (xy 283.312948 -45.735286)
			(xy 283.285692 -45.735748) (xy 283.27858 -45.735748) (xy 283.26842 -45.735494) (xy 283.24937 -45.743114)
			(xy 283.190188 -45.801026) (xy 283.183253 -45.808459) (xy 283.175397 -45.827192) (xy 283.174948 -45.837348)
			(xy 283.174948 -46.210982) (xy 283.175354 -46.220776) (xy 283.182683 -46.238939) (xy 283.189172 -46.246288)
			(xy 283.23794 -46.297088) (xy 283.245064 -46.303827) (xy 283.262963 -46.311796) (xy 283.272738 -46.312582)
			(xy 283.299265 -46.314142) (xy 283.351555 -46.323582) (xy 283.402029 -46.340187) (xy 283.449712 -46.363634)
			(xy 283.493679 -46.393471) (xy 283.533082 -46.42912) (xy 283.567157 -46.469891) (xy 283.595245 -46.514995)
			(xy 283.616804 -46.563561) (xy 283.631415 -46.614648) (xy 283.638797 -46.667268) (xy 283.63926 -46.693836)
			(xy 283.638793 -46.720264) (xy 283.631483 -46.772612) (xy 283.617008 -46.823447) (xy 283.595646 -46.871793)
			(xy 283.58211 -46.894496) (xy 283.581856 -46.89475) (xy 283.576519 -46.904768) (xy 283.574262 -46.927318)
			(xy 283.577538 -46.938184) (xy 283.6037 -47.01286) (xy 283.608062 -47.023387) (xy 283.624166 -47.039471)
			(xy 283.634688 -47.043848) (xy 283.634942 -47.043848) (xy 283.65945 -47.05292) (xy 283.705902 -47.076862)
			(xy 283.748655 -47.106917) (xy 283.786907 -47.142524) (xy 283.819943 -47.183017) (xy 283.847147 -47.227638)
			(xy 283.868009 -47.275553) (xy 283.882139 -47.325866) (xy 283.889273 -47.377636) (xy 283.889704 -47.403766)
			(xy 283.889207 -47.431356) (xy 283.88771 -47.441612) (xy 285.161734 -47.441612) (xy 285.165805 -47.38599)
			(xy 285.177931 -47.331553) (xy 285.197854 -47.279462) (xy 285.22515 -47.230827) (xy 285.259236 -47.186684)
			(xy 285.299385 -47.147975) (xy 285.344743 -47.115524) (xy 285.394343 -47.090023) (xy 285.447127 -47.072016)
			(xy 285.50197 -47.061886) (xy 285.557704 -47.059849) (xy 285.613141 -47.065949) (xy 285.667098 -47.080055)
			(xy 285.718427 -47.101867) (xy 285.766033 -47.130921) (xy 285.808901 -47.166596) (xy 285.846118 -47.208133)
			(xy 285.876891 -47.254646) (xy 285.900563 -47.305143) (xy 285.916631 -47.35855) (xy 285.924751 -47.413726)
			(xy 285.92526 -47.441612) (xy 285.924751 -47.469498) (xy 285.916631 -47.524674) (xy 285.900563 -47.578081)
			(xy 285.876891 -47.628578) (xy 285.846118 -47.675091) (xy 285.808901 -47.716628) (xy 285.766033 -47.752303)
			(xy 285.718427 -47.781357) (xy 285.667098 -47.803169) (xy 285.613141 -47.817275) (xy 285.557704 -47.823375)
			(xy 285.50197 -47.821338) (xy 285.447127 -47.811208) (xy 285.394343 -47.793201) (xy 285.344743 -47.7677)
			(xy 285.299385 -47.735249) (xy 285.259236 -47.69654) (xy 285.22515 -47.652397) (xy 285.197854 -47.603762)
			(xy 285.177931 -47.551671) (xy 285.165805 -47.497234) (xy 285.161734 -47.441612) (xy 283.88771 -47.441612)
			(xy 283.881235 -47.485957) (xy 283.865483 -47.53884) (xy 283.842279 -47.588904) (xy 283.812105 -47.635103)
			(xy 283.775592 -47.676475) (xy 283.733501 -47.712156) (xy 283.68671 -47.741403) (xy 283.636195 -47.763606)
			(xy 283.583008 -47.778302) (xy 283.555694 -47.782226) (xy 283.55544 -47.782226) (xy 283.547224 -47.783608)
			(xy 283.532302 -47.790999) (xy 283.52623 -47.796704) (xy 283.525976 -47.796958) (xy 283.519315 -47.80439)
			(xy 283.511707 -47.822814) (xy 283.511699 -47.842747) (xy 283.519293 -47.861177) (xy 283.525976 -47.868586)
			(xy 283.550106 -47.892716) (xy 283.573014 -47.916271) (xy 283.613977 -47.96765) (xy 283.648929 -48.023292)
			(xy 283.677433 -48.082497) (xy 283.699129 -48.144521) (xy 283.713746 -48.208585) (xy 283.721098 -48.273881)
			(xy 283.721556 -48.306736) (xy 283.721556 -48.30699) (xy 283.721035 -48.342394) (xy 283.712503 -48.412685)
			(xy 283.695563 -48.481436) (xy 283.670461 -48.547645) (xy 283.637564 -48.610346) (xy 283.59735 -48.668626)
			(xy 283.550406 -48.721635) (xy 283.497417 -48.768601) (xy 283.439153 -48.808838) (xy 283.376466 -48.841762)
			(xy 283.310267 -48.866891) (xy 283.241523 -48.883859) (xy 283.171235 -48.89242) (xy 283.135832 -48.892968)
			(xy 283.102951 -48.892517) (xy 283.037603 -48.885152) (xy 282.973492 -48.870513) (xy 282.911424 -48.848783)
			(xy 282.852182 -48.820236) (xy 282.796511 -48.785232) (xy 282.745112 -48.744211) (xy 282.721558 -48.721264)
			(xy 282.17495 -48.174656) (xy 282.152038 -48.151104) (xy 282.111075 -48.099725) (xy 282.076121 -48.044083)
			(xy 282.047617 -47.984877) (xy 282.025921 -47.922853) (xy 282.011307 -47.858789) (xy 282.003957 -47.793491)
			(xy 282.0035 -47.760636) (xy 282.0035 -44.504356) (xy 282.003124 -44.494281) (xy 281.995372 -44.475682)
			(xy 281.988514 -44.468288) (xy 281.501088 -43.981116) (xy 281.478173 -43.957535) (xy 281.437177 -43.906126)
			(xy 281.402189 -43.850453) (xy 281.373648 -43.791215) (xy 281.351913 -43.729157) (xy 281.337257 -43.665056)
			(xy 281.329863 -43.599719) (xy 281.329384 -43.566842) (xy 279.136337 -43.566842) (xy 279.151783 -43.599791)
			(xy 279.167851 -43.653198) (xy 279.175971 -43.708374) (xy 279.17648 -43.73626) (xy 279.175971 -43.764146)
			(xy 279.167851 -43.819322) (xy 279.151783 -43.872729) (xy 279.128111 -43.923226) (xy 279.097338 -43.969739)
			(xy 279.060121 -44.011276) (xy 279.017253 -44.046951) (xy 278.969647 -44.076005) (xy 278.918318 -44.097817)
			(xy 278.864361 -44.111923) (xy 278.808924 -44.118023) (xy 278.75319 -44.115986) (xy 278.698347 -44.105856)
			(xy 278.645563 -44.087849) (xy 278.595963 -44.062348) (xy 278.550605 -44.029897) (xy 278.510456 -43.991188)
			(xy 278.47637 -43.947045) (xy 278.449074 -43.89841) (xy 278.429151 -43.846319) (xy 278.417025 -43.791882)
			(xy 278.412954 -43.73626) (xy 270.998696 -43.73626) (xy 270.998696 -45.114464) (xy 278.26538 -45.114464)
			(xy 278.269451 -45.058842) (xy 278.281577 -45.004405) (xy 278.3015 -44.952314) (xy 278.328796 -44.903679)
			(xy 278.362882 -44.859536) (xy 278.403031 -44.820827) (xy 278.448389 -44.788376) (xy 278.497989 -44.762875)
			(xy 278.550773 -44.744868) (xy 278.605616 -44.734738) (xy 278.66135 -44.732701) (xy 278.716787 -44.738801)
			(xy 278.770744 -44.752907) (xy 278.822073 -44.774719) (xy 278.869679 -44.803773) (xy 278.912547 -44.839448)
			(xy 278.949764 -44.880985) (xy 278.980537 -44.927498) (xy 279.004209 -44.977995) (xy 279.020277 -45.031402)
			(xy 279.028397 -45.086578) (xy 279.028906 -45.114464) (xy 279.028397 -45.14235) (xy 279.020277 -45.197526)
			(xy 279.004209 -45.250933) (xy 278.980537 -45.30143) (xy 278.949764 -45.347943) (xy 278.912547 -45.38948)
			(xy 278.869679 -45.425155) (xy 278.822073 -45.454209) (xy 278.770744 -45.476021) (xy 278.716787 -45.490127)
			(xy 278.66135 -45.496227) (xy 278.605616 -45.49419) (xy 278.550773 -45.48406) (xy 278.497989 -45.466053)
			(xy 278.448389 -45.440552) (xy 278.403031 -45.408101) (xy 278.362882 -45.369392) (xy 278.328796 -45.325249)
			(xy 278.3015 -45.276614) (xy 278.281577 -45.224523) (xy 278.269451 -45.170086) (xy 278.26538 -45.114464)
			(xy 270.998696 -45.114464) (xy 270.998696 -46.082204) (xy 276.252432 -46.082204) (xy 276.252859 -46.054949)
			(xy 276.260617 -46.000995) (xy 276.275974 -45.948694) (xy 276.298619 -45.899111) (xy 276.32809 -45.853256)
			(xy 276.363788 -45.812063) (xy 276.404985 -45.776369) (xy 276.450843 -45.746902) (xy 276.500428 -45.724262)
			(xy 276.55273 -45.708909) (xy 276.606685 -45.701157) (xy 276.63394 -45.700696) (xy 276.660844 -45.701128)
			(xy 276.714115 -45.708705) (xy 276.765794 -45.72369) (xy 276.814856 -45.745785) (xy 276.860328 -45.774552)
			(xy 276.901308 -45.809421) (xy 276.936985 -45.8497) (xy 276.952202 -45.871892) (xy 276.959314 -45.882814)
			(xy 276.982174 -45.894752) (xy 277.094442 -45.89272) (xy 277.116794 -45.879766) (xy 277.123652 -45.86859)
			(xy 277.138552 -45.844974) (xy 277.174234 -45.802022) (xy 277.215796 -45.76473) (xy 277.26235 -45.733895)
			(xy 277.312901 -45.710174) (xy 277.36637 -45.694074) (xy 277.421614 -45.68594) (xy 277.449534 -45.685456)
			(xy 277.476528 -45.685897) (xy 277.529977 -45.693508) (xy 277.581821 -45.708573) (xy 277.631025 -45.730791)
			(xy 277.676608 -45.75972) (xy 277.697438 -45.776896) (xy 277.705566 -45.784008) (xy 277.72614 -45.790104)
			(xy 277.811484 -45.779182) (xy 277.822029 -45.77741) (xy 277.840312 -45.766354) (xy 277.84679 -45.757846)
			(xy 277.862156 -45.736625) (xy 277.897741 -45.698172) (xy 277.938256 -45.664953) (xy 277.982937 -45.637593)
			(xy 278.030943 -45.616608) (xy 278.08137 -45.602392) (xy 278.133268 -45.595215) (xy 278.159464 -45.594778)
			(xy 278.186718 -45.595267) (xy 278.24067 -45.603019) (xy 278.292971 -45.618372) (xy 278.342553 -45.641011)
			(xy 278.388409 -45.670477) (xy 278.429605 -45.70617) (xy 278.465301 -45.747362) (xy 278.494771 -45.793215)
			(xy 278.517416 -45.842796) (xy 278.532773 -45.895094) (xy 278.540531 -45.949047) (xy 278.540531 -46.003553)
			(xy 278.532773 -46.057506) (xy 278.517416 -46.109804) (xy 278.494771 -46.159385) (xy 278.465301 -46.205238)
			(xy 278.429605 -46.24643) (xy 278.388409 -46.282123) (xy 278.342553 -46.311589) (xy 278.292971 -46.334228)
			(xy 278.24067 -46.349581) (xy 278.186718 -46.357333) (xy 278.159464 -46.357794) (xy 278.132471 -46.357342)
			(xy 278.079022 -46.349732) (xy 278.027179 -46.334669) (xy 277.977975 -46.312453) (xy 277.932391 -46.283528)
			(xy 277.91156 -46.266354) (xy 277.903432 -46.259242) (xy 277.882858 -46.253146) (xy 277.797514 -46.264068)
			(xy 277.786973 -46.265857) (xy 277.76869 -46.276902) (xy 277.762208 -46.285404) (xy 277.744591 -46.309701)
			(xy 277.702998 -46.352963) (xy 277.679404 -46.37151) (xy 277.67153 -46.377352) (xy 277.661116 -46.394878)
			(xy 277.647908 -46.485302) (xy 277.652734 -46.504606) (xy 277.658576 -46.51248) (xy 277.658576 -46.512734)
			(xy 277.676079 -46.537478) (xy 277.703882 -46.591331) (xy 277.722818 -46.648903) (xy 277.732411 -46.708745)
			(xy 277.732998 -46.739048) (xy 277.732567 -46.766301) (xy 277.724803 -46.820251) (xy 277.709442 -46.872547)
			(xy 277.686794 -46.922126) (xy 277.657322 -46.967976) (xy 277.621625 -47.009166) (xy 277.58043 -47.044857)
			(xy 277.534575 -47.074322) (xy 277.484993 -47.096962) (xy 277.432694 -47.112316) (xy 277.378743 -47.120071)
			(xy 277.35149 -47.120556) (xy 277.325456 -47.120107) (xy 277.273874 -47.11302) (xy 277.223732 -47.09899)
			(xy 277.175961 -47.07828) (xy 277.131446 -47.051272) (xy 277.110952 -47.035212) (xy 277.103187 -47.029483)
			(xy 277.084783 -47.023735) (xy 277.075138 -47.024036) (xy 276.995382 -47.030386) (xy 276.977602 -47.039022)
			(xy 276.971252 -47.046388) (xy 276.953068 -47.066031) (xy 276.912161 -47.100553) (xy 276.866833 -47.129023)
			(xy 276.817972 -47.150881) (xy 276.766536 -47.165699) (xy 276.713536 -47.173186) (xy 276.686772 -47.173642)
			(xy 276.659522 -47.173148) (xy 276.605576 -47.165389) (xy 276.553283 -47.150032) (xy 276.503708 -47.12739)
			(xy 276.45786 -47.097924) (xy 276.416671 -47.062234) (xy 276.38098 -47.021045) (xy 276.351513 -46.975197)
			(xy 276.32887 -46.925622) (xy 276.313512 -46.87333) (xy 276.305752 -46.819384) (xy 276.305264 -46.792134)
			(xy 276.305798 -46.76336) (xy 276.314448 -46.706467) (xy 276.331543 -46.651517) (xy 276.356694 -46.599757)
			(xy 276.389331 -46.55236) (xy 276.408642 -46.531022) (xy 276.416008 -46.523148) (xy 276.42312 -46.503336)
			(xy 276.415754 -46.40707) (xy 276.405848 -46.388274) (xy 276.397466 -46.38167) (xy 276.375291 -46.363434)
			(xy 276.336078 -46.321502) (xy 276.30359 -46.274169) (xy 276.27856 -46.222503) (xy 276.261552 -46.167671)
			(xy 276.25295 -46.110909) (xy 276.252432 -46.082204) (xy 270.998696 -46.082204) (xy 270.998696 -48.753014)
			(xy 279.368248 -48.753014) (xy 279.372319 -48.697392) (xy 279.384445 -48.642955) (xy 279.404368 -48.590864)
			(xy 279.431664 -48.542229) (xy 279.46575 -48.498086) (xy 279.505899 -48.459377) (xy 279.551257 -48.426926)
			(xy 279.600857 -48.401425) (xy 279.653641 -48.383418) (xy 279.708484 -48.373288) (xy 279.764218 -48.371251)
			(xy 279.819655 -48.377351) (xy 279.873612 -48.391457) (xy 279.924941 -48.413269) (xy 279.972547 -48.442323)
			(xy 280.015415 -48.477998) (xy 280.052632 -48.519535) (xy 280.083405 -48.566048) (xy 280.107077 -48.616545)
			(xy 280.123145 -48.669952) (xy 280.131265 -48.725128) (xy 280.131774 -48.753014) (xy 280.131265 -48.7809)
			(xy 280.123145 -48.836076) (xy 280.107077 -48.889483) (xy 280.105681 -48.89246) (xy 281.413964 -48.89246)
			(xy 281.418035 -48.836838) (xy 281.430161 -48.782401) (xy 281.450084 -48.73031) (xy 281.47738 -48.681675)
			(xy 281.511466 -48.637532) (xy 281.551615 -48.598823) (xy 281.596973 -48.566372) (xy 281.646573 -48.540871)
			(xy 281.699357 -48.522864) (xy 281.7542 -48.512734) (xy 281.809934 -48.510697) (xy 281.865371 -48.516797)
			(xy 281.919328 -48.530903) (xy 281.970657 -48.552715) (xy 282.018263 -48.581769) (xy 282.061131 -48.617444)
			(xy 282.098348 -48.658981) (xy 282.129121 -48.705494) (xy 282.152793 -48.755991) (xy 282.168861 -48.809398)
			(xy 282.176981 -48.864574) (xy 282.17749 -48.89246) (xy 282.176981 -48.920346) (xy 282.174543 -48.93691)
			(xy 285.133032 -48.93691) (xy 285.137103 -48.881288) (xy 285.149229 -48.826851) (xy 285.169152 -48.77476)
			(xy 285.196448 -48.726125) (xy 285.230534 -48.681982) (xy 285.270683 -48.643273) (xy 285.316041 -48.610822)
			(xy 285.365641 -48.585321) (xy 285.418425 -48.567314) (xy 285.473268 -48.557184) (xy 285.529002 -48.555147)
			(xy 285.584439 -48.561247) (xy 285.638396 -48.575353) (xy 285.689725 -48.597165) (xy 285.737331 -48.626219)
			(xy 285.780199 -48.661894) (xy 285.817416 -48.703431) (xy 285.848189 -48.749944) (xy 285.871861 -48.800441)
			(xy 285.887929 -48.853848) (xy 285.896049 -48.909024) (xy 285.896558 -48.93691) (xy 285.896049 -48.964796)
			(xy 285.887929 -49.019972) (xy 285.871861 -49.073379) (xy 285.848189 -49.123876) (xy 285.817416 -49.170389)
			(xy 285.780199 -49.211926) (xy 285.737331 -49.247601) (xy 285.689725 -49.276655) (xy 285.638396 -49.298467)
			(xy 285.584439 -49.312573) (xy 285.529002 -49.318673) (xy 285.473268 -49.316636) (xy 285.418425 -49.306506)
			(xy 285.365641 -49.288499) (xy 285.316041 -49.262998) (xy 285.270683 -49.230547) (xy 285.230534 -49.191838)
			(xy 285.196448 -49.147695) (xy 285.169152 -49.09906) (xy 285.149229 -49.046969) (xy 285.137103 -48.992532)
			(xy 285.133032 -48.93691) (xy 282.174543 -48.93691) (xy 282.168861 -48.975522) (xy 282.152793 -49.028929)
			(xy 282.129121 -49.079426) (xy 282.098348 -49.125939) (xy 282.061131 -49.167476) (xy 282.018263 -49.203151)
			(xy 281.970657 -49.232205) (xy 281.919328 -49.254017) (xy 281.865371 -49.268123) (xy 281.809934 -49.274223)
			(xy 281.7542 -49.272186) (xy 281.699357 -49.262056) (xy 281.646573 -49.244049) (xy 281.596973 -49.218548)
			(xy 281.551615 -49.186097) (xy 281.511466 -49.147388) (xy 281.47738 -49.103245) (xy 281.450084 -49.05461)
			(xy 281.430161 -49.002519) (xy 281.418035 -48.948082) (xy 281.413964 -48.89246) (xy 280.105681 -48.89246)
			(xy 280.083405 -48.93998) (xy 280.052632 -48.986493) (xy 280.015415 -49.02803) (xy 279.972547 -49.063705)
			(xy 279.924941 -49.092759) (xy 279.873612 -49.114571) (xy 279.819655 -49.128677) (xy 279.764218 -49.134777)
			(xy 279.708484 -49.13274) (xy 279.653641 -49.12261) (xy 279.600857 -49.104603) (xy 279.551257 -49.079102)
			(xy 279.505899 -49.046651) (xy 279.46575 -49.007942) (xy 279.431664 -48.963799) (xy 279.404368 -48.915164)
			(xy 279.384445 -48.863073) (xy 279.372319 -48.808636) (xy 279.368248 -48.753014) (xy 270.998696 -48.753014)
			(xy 270.998696 -49.95291) (xy 285.133032 -49.95291) (xy 285.137103 -49.897288) (xy 285.149229 -49.842851)
			(xy 285.169152 -49.79076) (xy 285.196448 -49.742125) (xy 285.230534 -49.697982) (xy 285.270683 -49.659273)
			(xy 285.316041 -49.626822) (xy 285.365641 -49.601321) (xy 285.418425 -49.583314) (xy 285.473268 -49.573184)
			(xy 285.529002 -49.571147) (xy 285.584439 -49.577247) (xy 285.638396 -49.591353) (xy 285.663331 -49.601949)
			(xy 290.312882 -49.601949) (xy 290.312882 -49.547451) (xy 290.320637 -49.493508) (xy 290.33599 -49.441217)
			(xy 290.358627 -49.391643) (xy 290.388089 -49.345795) (xy 290.423776 -49.304607) (xy 290.46496 -49.268916)
			(xy 290.510805 -49.239448) (xy 290.560376 -49.216805) (xy 290.612665 -49.201446) (xy 290.666607 -49.193685)
			(xy 290.693856 -49.193196) (xy 290.721225 -49.193689) (xy 290.775403 -49.2015) (xy 290.827906 -49.216983)
			(xy 290.877653 -49.239819) (xy 290.923621 -49.269538) (xy 290.944554 -49.287176) (xy 290.944808 -49.28743)
			(xy 290.951886 -49.293029) (xy 290.968809 -49.299267) (xy 290.977828 -49.299622) (xy 291.044884 -49.299622)
			(xy 291.053899 -49.299253) (xy 291.070816 -49.293013) (xy 291.077904 -49.28743) (xy 291.077904 -49.287176)
			(xy 291.078158 -49.287176) (xy 291.099091 -49.269535) (xy 291.145059 -49.239811) (xy 291.194805 -49.216965)
			(xy 291.247307 -49.201469) (xy 291.301485 -49.19364) (xy 291.356227 -49.19364) (xy 291.410405 -49.201469)
			(xy 291.462907 -49.216965) (xy 291.512653 -49.239811) (xy 291.558621 -49.269535) (xy 291.579554 -49.287176)
			(xy 291.579808 -49.28743) (xy 291.586886 -49.293029) (xy 291.603809 -49.299267) (xy 291.612828 -49.299622)
			(xy 291.679884 -49.299622) (xy 291.688899 -49.299253) (xy 291.705816 -49.293013) (xy 291.712904 -49.28743)
			(xy 291.712904 -49.287176) (xy 291.713158 -49.287176) (xy 291.734091 -49.269535) (xy 291.780059 -49.239811)
			(xy 291.829805 -49.216965) (xy 291.882307 -49.201469) (xy 291.936485 -49.19364) (xy 291.991227 -49.19364)
			(xy 292.045405 -49.201469) (xy 292.097907 -49.216965) (xy 292.147653 -49.239811) (xy 292.193621 -49.269535)
			(xy 292.214554 -49.287176) (xy 292.214808 -49.28743) (xy 292.221886 -49.293029) (xy 292.238809 -49.299267)
			(xy 292.247828 -49.299622) (xy 292.314884 -49.299622) (xy 292.323899 -49.299253) (xy 292.340816 -49.293013)
			(xy 292.347904 -49.28743) (xy 292.347904 -49.287176) (xy 292.348158 -49.287176) (xy 292.369092 -49.269539)
			(xy 292.415065 -49.239828) (xy 292.464812 -49.216992) (xy 292.517312 -49.2015) (xy 292.571487 -49.193671)
			(xy 292.598856 -49.193196) (xy 292.626111 -49.193648) (xy 292.680067 -49.2014) (xy 292.732371 -49.216753)
			(xy 292.781957 -49.239393) (xy 292.827816 -49.26886) (xy 292.869015 -49.304554) (xy 292.904714 -49.345748)
			(xy 292.934186 -49.391604) (xy 292.956832 -49.441188) (xy 292.97219 -49.49349) (xy 292.979949 -49.547445)
			(xy 292.979949 -49.601955) (xy 292.97219 -49.65591) (xy 292.956832 -49.708212) (xy 292.934186 -49.757796)
			(xy 292.904714 -49.803652) (xy 292.869015 -49.844846) (xy 292.827816 -49.88054) (xy 292.781957 -49.910007)
			(xy 292.732371 -49.932647) (xy 292.680067 -49.948) (xy 292.626111 -49.955752) (xy 292.598856 -49.956212)
			(xy 292.571487 -49.95571) (xy 292.51731 -49.947901) (xy 292.464807 -49.93242) (xy 292.41506 -49.909586)
			(xy 292.369091 -49.879869) (xy 292.348158 -49.862232) (xy 292.347904 -49.861978) (xy 292.340822 -49.856385)
			(xy 292.323902 -49.850143) (xy 292.314884 -49.849786) (xy 292.247828 -49.849786) (xy 292.238813 -49.850159)
			(xy 292.221896 -49.856396) (xy 292.214808 -49.861978) (xy 292.214554 -49.862232) (xy 292.193621 -49.879873)
			(xy 292.147653 -49.909597) (xy 292.097907 -49.932443) (xy 292.045405 -49.947939) (xy 291.991227 -49.955768)
			(xy 291.936485 -49.955768) (xy 291.882307 -49.947939) (xy 291.829805 -49.932443) (xy 291.780059 -49.909597)
			(xy 291.734091 -49.879873) (xy 291.713158 -49.862232) (xy 291.712904 -49.861978) (xy 291.705822 -49.856385)
			(xy 291.688902 -49.850143) (xy 291.679884 -49.849786) (xy 291.612828 -49.849786) (xy 291.603813 -49.850159)
			(xy 291.586896 -49.856396) (xy 291.579808 -49.861978) (xy 291.579808 -49.862232) (xy 291.579554 -49.862232)
			(xy 291.558621 -49.879873) (xy 291.512653 -49.909597) (xy 291.462907 -49.932443) (xy 291.410405 -49.947939)
			(xy 291.356227 -49.955768) (xy 291.301485 -49.955768) (xy 291.247307 -49.947939) (xy 291.194805 -49.932443)
			(xy 291.145059 -49.909597) (xy 291.099091 -49.879873) (xy 291.078158 -49.862232) (xy 291.077904 -49.861978)
			(xy 291.070822 -49.856385) (xy 291.053902 -49.850143) (xy 291.044884 -49.849786) (xy 290.977828 -49.849786)
			(xy 290.968813 -49.850159) (xy 290.951896 -49.856396) (xy 290.944808 -49.861978) (xy 290.944808 -49.862232)
			(xy 290.944554 -49.862232) (xy 290.923616 -49.879864) (xy 290.877645 -49.909576) (xy 290.827898 -49.932413)
			(xy 290.775399 -49.947906) (xy 290.721225 -49.955736) (xy 290.693856 -49.956212) (xy 290.666607 -49.955715)
			(xy 290.612665 -49.947954) (xy 290.560376 -49.932595) (xy 290.510805 -49.909952) (xy 290.46496 -49.880484)
			(xy 290.423776 -49.844793) (xy 290.388089 -49.803605) (xy 290.358627 -49.757757) (xy 290.33599 -49.708183)
			(xy 290.320637 -49.655892) (xy 290.312882 -49.601949) (xy 285.663331 -49.601949) (xy 285.689725 -49.613165)
			(xy 285.737331 -49.642219) (xy 285.780199 -49.677894) (xy 285.817416 -49.719431) (xy 285.848189 -49.765944)
			(xy 285.871861 -49.816441) (xy 285.887929 -49.869848) (xy 285.896049 -49.925024) (xy 285.896558 -49.95291)
			(xy 285.896049 -49.980796) (xy 285.887929 -50.035972) (xy 285.871861 -50.089379) (xy 285.848189 -50.139876)
			(xy 285.817416 -50.186389) (xy 285.780199 -50.227926) (xy 285.737331 -50.263601) (xy 285.689725 -50.292655)
			(xy 285.638396 -50.314467) (xy 285.584439 -50.328573) (xy 285.529002 -50.334673) (xy 285.473268 -50.332636)
			(xy 285.418425 -50.322506) (xy 285.365641 -50.304499) (xy 285.316041 -50.278998) (xy 285.270683 -50.246547)
			(xy 285.230534 -50.207838) (xy 285.196448 -50.163695) (xy 285.169152 -50.11506) (xy 285.149229 -50.062969)
			(xy 285.137103 -50.008532) (xy 285.133032 -49.95291) (xy 270.998696 -49.95291) (xy 270.998696 -51.019456)
			(xy 282.949394 -51.019456) (xy 282.953465 -50.963834) (xy 282.965591 -50.909397) (xy 282.985514 -50.857306)
			(xy 283.01281 -50.808671) (xy 283.046896 -50.764528) (xy 283.087045 -50.725819) (xy 283.132403 -50.693368)
			(xy 283.182003 -50.667867) (xy 283.234787 -50.64986) (xy 283.28963 -50.63973) (xy 283.345364 -50.637693)
			(xy 283.400801 -50.643793) (xy 283.454758 -50.657899) (xy 283.506087 -50.679711) (xy 283.553693 -50.708765)
			(xy 283.596561 -50.74444) (xy 283.633778 -50.785977) (xy 283.664551 -50.83249) (xy 283.688223 -50.882987)
			(xy 283.704291 -50.936394) (xy 283.712411 -50.99157) (xy 283.71292 -51.019456) (xy 283.712411 -51.047342)
			(xy 283.704291 -51.102518) (xy 283.688223 -51.155925) (xy 283.664551 -51.206422) (xy 283.639695 -51.243992)
			(xy 291.33292 -51.243992) (xy 291.333377 -51.216621) (xy 291.341196 -51.162442) (xy 291.356687 -51.109938)
			(xy 291.379531 -51.060192) (xy 291.409258 -51.014225) (xy 291.4269 -50.993294) (xy 291.427154 -50.99304)
			(xy 291.432736 -50.985951) (xy 291.438984 -50.969036) (xy 291.439346 -50.96002) (xy 291.439346 -50.892964)
			(xy 291.439018 -50.883944) (xy 291.432752 -50.867027) (xy 291.427154 -50.859944) (xy 291.4269 -50.859944)
			(xy 291.4269 -50.85969) (xy 291.409243 -50.838773) (xy 291.379534 -50.792796) (xy 291.356701 -50.743045)
			(xy 291.341214 -50.690541) (xy 291.333391 -50.636362) (xy 291.33292 -50.608992) (xy 291.333348 -50.581738)
			(xy 291.341107 -50.527784) (xy 291.356465 -50.475484) (xy 291.379111 -50.425902) (xy 291.408582 -50.380047)
			(xy 291.44428 -50.338854) (xy 291.485476 -50.303161) (xy 291.531333 -50.273693) (xy 291.580918 -50.251053)
			(xy 291.633219 -50.235699) (xy 291.687174 -50.227945) (xy 291.714428 -50.227484) (xy 291.743345 -50.228022)
			(xy 291.800516 -50.236743) (xy 291.855716 -50.253995) (xy 291.907679 -50.279382) (xy 291.955213 -50.312324)
			(xy 291.997229 -50.352065) (xy 292.015418 -50.37455) (xy 292.023018 -50.383364) (xy 292.043925 -50.393542)
			(xy 292.05555 -50.394108) (xy 292.135306 -50.394108) (xy 292.146936 -50.393555) (xy 292.167846 -50.383376)
			(xy 292.175438 -50.37455) (xy 292.193595 -50.352038) (xy 292.235623 -50.312307) (xy 292.283166 -50.279373)
			(xy 292.335133 -50.25399) (xy 292.390336 -50.236739) (xy 292.44751 -50.228016) (xy 292.476428 -50.227484)
			(xy 292.50368 -50.227952) (xy 292.557628 -50.235712) (xy 292.609922 -50.25107) (xy 292.659499 -50.273714)
			(xy 292.705349 -50.303182) (xy 292.746538 -50.338876) (xy 292.78223 -50.380067) (xy 292.811696 -50.425919)
			(xy 292.834337 -50.475497) (xy 292.849692 -50.527792) (xy 292.85745 -50.58174) (xy 292.857936 -50.608992)
			(xy 292.857452 -50.635305) (xy 292.850219 -50.687433) (xy 292.835902 -50.738075) (xy 292.814773 -50.786273)
			(xy 292.78723 -50.831117) (xy 292.753796 -50.871758) (xy 292.734746 -50.889916) (xy 292.727342 -50.897436)
			(xy 292.718818 -50.916717) (xy 292.718236 -50.927254) (xy 292.718236 -51.00193) (xy 292.718779 -51.012478)
			(xy 292.727303 -51.031775) (xy 292.734746 -51.039268) (xy 292.753836 -51.057388) (xy 292.787289 -51.098027)
			(xy 292.814842 -51.142875) (xy 292.835974 -51.191082) (xy 292.850284 -51.241735) (xy 292.857501 -51.293874)
			(xy 292.857936 -51.320192) (xy 292.857415 -51.347442) (xy 292.84966 -51.401387) (xy 292.834307 -51.453679)
			(xy 292.811669 -51.503255) (xy 292.782206 -51.549104) (xy 292.746519 -51.590293) (xy 292.705332 -51.625985)
			(xy 292.659486 -51.655452) (xy 292.609913 -51.678095) (xy 292.557622 -51.693453) (xy 292.503678 -51.701212)
			(xy 292.476428 -51.7017) (xy 292.448764 -51.701166) (xy 292.394016 -51.69317) (xy 292.340994 -51.677358)
			(xy 292.290811 -51.654058) (xy 292.244515 -51.62376) (xy 292.203076 -51.587098) (xy 292.167362 -51.544839)
			(xy 292.152324 -51.521614) (xy 292.145686 -51.511939) (xy 292.125825 -51.499495) (xy 292.114224 -51.497738)
			(xy 292.034214 -51.489864) (xy 292.022576 -51.489244) (xy 292.000739 -51.497316) (xy 291.992304 -51.505358)
			(xy 291.99205 -51.505612) (xy 291.973978 -51.524202) (xy 291.933644 -51.556779) (xy 291.889267 -51.583591)
			(xy 291.841667 -51.604142) (xy 291.791722 -51.618054) (xy 291.740352 -51.625069) (xy 291.714428 -51.6255)
			(xy 291.687175 -51.625019) (xy 291.633225 -51.617265) (xy 291.580927 -51.601912) (xy 291.531346 -51.579273)
			(xy 291.485493 -51.549807) (xy 291.444299 -51.514115) (xy 291.408605 -51.472923) (xy 291.379137 -51.427071)
			(xy 291.356495 -51.377492) (xy 291.341139 -51.325195) (xy 291.333383 -51.271244) (xy 291.33292 -51.243992)
			(xy 283.639695 -51.243992) (xy 283.633778 -51.252935) (xy 283.596561 -51.294472) (xy 283.553693 -51.330147)
			(xy 283.506087 -51.359201) (xy 283.454758 -51.381013) (xy 283.400801 -51.395119) (xy 283.345364 -51.401219)
			(xy 283.28963 -51.399182) (xy 283.234787 -51.389052) (xy 283.182003 -51.371045) (xy 283.132403 -51.345544)
			(xy 283.087045 -51.313093) (xy 283.046896 -51.274384) (xy 283.01281 -51.230241) (xy 282.985514 -51.181606)
			(xy 282.965591 -51.129515) (xy 282.953465 -51.075078) (xy 282.949394 -51.019456) (xy 270.998696 -51.019456)
			(xy 270.998696 -52.035456) (xy 285.14116 -52.035456) (xy 285.145231 -51.979834) (xy 285.157357 -51.925397)
			(xy 285.17728 -51.873306) (xy 285.204576 -51.824671) (xy 285.238662 -51.780528) (xy 285.278811 -51.741819)
			(xy 285.324169 -51.709368) (xy 285.373769 -51.683867) (xy 285.426553 -51.66586) (xy 285.481396 -51.65573)
			(xy 285.53713 -51.653693) (xy 285.592567 -51.659793) (xy 285.646524 -51.673899) (xy 285.697853 -51.695711)
			(xy 285.745459 -51.724765) (xy 285.788327 -51.76044) (xy 285.825544 -51.801977) (xy 285.856317 -51.84849)
			(xy 285.879989 -51.898987) (xy 285.896057 -51.952394) (xy 285.904177 -52.00757) (xy 285.904686 -52.035456)
			(xy 285.904177 -52.063342) (xy 285.896057 -52.118518) (xy 285.879989 -52.171925) (xy 285.856317 -52.222422)
			(xy 285.825544 -52.268935) (xy 285.788327 -52.310472) (xy 285.745459 -52.346147) (xy 285.697853 -52.375201)
			(xy 285.646524 -52.397013) (xy 285.592567 -52.411119) (xy 285.53713 -52.417219) (xy 285.481396 -52.415182)
			(xy 285.426553 -52.405052) (xy 285.373769 -52.387045) (xy 285.324169 -52.361544) (xy 285.278811 -52.329093)
			(xy 285.238662 -52.290384) (xy 285.204576 -52.246241) (xy 285.17728 -52.197606) (xy 285.157357 -52.145515)
			(xy 285.145231 -52.091078) (xy 285.14116 -52.035456) (xy 270.998696 -52.035456) (xy 270.998696 -54.731412)
			(xy 271.720564 -54.731412) (xy 271.721021 -54.704041) (xy 271.728839 -54.649861) (xy 271.744329 -54.597357)
			(xy 271.767173 -54.547611) (xy 271.796901 -54.501645) (xy 271.814544 -54.480714) (xy 271.814798 -54.48046)
			(xy 271.820365 -54.47336) (xy 271.826624 -54.456454) (xy 271.82699 -54.44744) (xy 271.82699 -54.380384)
			(xy 271.826643 -54.371366) (xy 271.820389 -54.354449) (xy 271.814798 -54.347364) (xy 271.814544 -54.347364)
			(xy 271.814544 -54.34711) (xy 271.796914 -54.326168) (xy 271.767188 -54.280202) (xy 271.744341 -54.230458)
			(xy 271.728843 -54.177957) (xy 271.721013 -54.123779) (xy 271.721011 -54.069039) (xy 271.728839 -54.014861)
			(xy 271.744334 -53.962359) (xy 271.767179 -53.912614) (xy 271.796903 -53.866646) (xy 271.814544 -53.845714)
			(xy 271.814798 -53.84546) (xy 271.820365 -53.83836) (xy 271.826624 -53.821454) (xy 271.82699 -53.81244)
			(xy 271.82699 -53.745384) (xy 271.826643 -53.736366) (xy 271.820389 -53.719449) (xy 271.814798 -53.712364)
			(xy 271.814544 -53.712364) (xy 271.814544 -53.71211) (xy 271.796914 -53.691168) (xy 271.767188 -53.645202)
			(xy 271.744341 -53.595458) (xy 271.728843 -53.542957) (xy 271.721013 -53.488779) (xy 271.721011 -53.434039)
			(xy 271.728839 -53.379861) (xy 271.744334 -53.327359) (xy 271.767179 -53.277614) (xy 271.796903 -53.231646)
			(xy 271.814544 -53.210714) (xy 271.814798 -53.21046) (xy 271.820365 -53.20336) (xy 271.826624 -53.186454)
			(xy 271.82699 -53.17744) (xy 271.82699 -53.110384) (xy 271.826643 -53.101366) (xy 271.820389 -53.084449)
			(xy 271.814798 -53.077364) (xy 271.814544 -53.077364) (xy 271.814544 -53.07711) (xy 271.796903 -53.056179)
			(xy 271.76719 -53.010207) (xy 271.744354 -52.960459) (xy 271.728863 -52.907958) (xy 271.721037 -52.853781)
			(xy 271.720564 -52.826412) (xy 271.72105 -52.799161) (xy 271.728806 -52.745213) (xy 271.744161 -52.692918)
			(xy 271.766803 -52.643341) (xy 271.796269 -52.597491) (xy 271.83196 -52.5563) (xy 271.873151 -52.520609)
			(xy 271.919001 -52.491143) (xy 271.968578 -52.468501) (xy 272.020873 -52.453146) (xy 272.074821 -52.44539)
			(xy 272.129323 -52.44539) (xy 272.183271 -52.453146) (xy 272.235566 -52.468501) (xy 272.285143 -52.491143)
			(xy 272.330993 -52.520609) (xy 272.372184 -52.5563) (xy 272.407875 -52.597491) (xy 272.437341 -52.643341)
			(xy 272.459983 -52.692918) (xy 272.475338 -52.745213) (xy 272.483094 -52.799161) (xy 272.48358 -52.826412)
			(xy 272.483126 -52.853783) (xy 272.475306 -52.907963) (xy 272.459814 -52.960466) (xy 272.43697 -53.010213)
			(xy 272.407243 -53.056179) (xy 272.3896 -53.07711) (xy 272.389346 -53.077364) (xy 272.383762 -53.084452)
			(xy 272.377515 -53.101368) (xy 272.377154 -53.110384) (xy 272.377154 -53.17744) (xy 272.37748 -53.18646)
			(xy 272.383748 -53.203378) (xy 272.389346 -53.21046) (xy 272.3896 -53.21046) (xy 272.3896 -53.210714)
			(xy 272.407251 -53.231638) (xy 272.436974 -53.277608) (xy 272.459817 -53.327356) (xy 272.475311 -53.379859)
			(xy 272.483138 -53.434038) (xy 272.483136 -53.48878) (xy 272.475307 -53.542959) (xy 272.45981 -53.595461)
			(xy 272.436965 -53.645208) (xy 272.40724 -53.691177) (xy 272.3896 -53.71211) (xy 272.389346 -53.712364)
			(xy 272.383762 -53.719452) (xy 272.377515 -53.736368) (xy 272.377154 -53.745384) (xy 272.377154 -53.81244)
			(xy 272.37748 -53.82146) (xy 272.383748 -53.838378) (xy 272.389346 -53.84546) (xy 272.3896 -53.84546)
			(xy 272.3896 -53.845714) (xy 272.407251 -53.866638) (xy 272.436974 -53.912608) (xy 272.459817 -53.962356)
			(xy 272.475311 -54.014859) (xy 272.483138 -54.069038) (xy 272.483136 -54.12378) (xy 272.475307 -54.177959)
			(xy 272.45981 -54.230461) (xy 272.436965 -54.280208) (xy 272.40724 -54.326177) (xy 272.3896 -54.34711)
			(xy 272.389346 -54.347364) (xy 272.383762 -54.354452) (xy 272.377515 -54.371368) (xy 272.377154 -54.380384)
			(xy 272.377154 -54.44744) (xy 272.37748 -54.45646) (xy 272.383748 -54.473378) (xy 272.389346 -54.48046)
			(xy 272.3896 -54.48046) (xy 272.3896 -54.480714) (xy 272.407212 -54.501668) (xy 272.436928 -54.547635)
			(xy 272.459769 -54.597377) (xy 272.475267 -54.649872) (xy 272.483102 -54.704044) (xy 272.48358 -54.731412)
			(xy 272.483094 -54.758663) (xy 272.47843 -54.791102) (xy 274.376388 -54.791102) (xy 274.376858 -54.763732)
			(xy 274.384675 -54.709553) (xy 274.400164 -54.65705) (xy 274.423004 -54.607303) (xy 274.452728 -54.561336)
			(xy 274.470368 -54.540404) (xy 274.470622 -54.54015) (xy 274.476196 -54.533055) (xy 274.48245 -54.516145)
			(xy 274.482814 -54.50713) (xy 274.482814 -54.440074) (xy 274.482466 -54.431056) (xy 274.476212 -54.41414)
			(xy 274.470622 -54.407054) (xy 274.470368 -54.407054) (xy 274.470368 -54.4068) (xy 274.452728 -54.385866)
			(xy 274.423 -54.3399) (xy 274.400152 -54.290154) (xy 274.384653 -54.237652) (xy 274.376824 -54.183472)
			(xy 274.376823 -54.128731) (xy 274.384653 -54.074551) (xy 274.400151 -54.022049) (xy 274.422998 -53.972303)
			(xy 274.452726 -53.926336) (xy 274.470368 -53.905404) (xy 274.470622 -53.90515) (xy 274.476196 -53.898055)
			(xy 274.48245 -53.881145) (xy 274.482814 -53.87213) (xy 274.482814 -53.805074) (xy 274.482466 -53.796056)
			(xy 274.476212 -53.77914) (xy 274.470622 -53.772054) (xy 274.470368 -53.772054) (xy 274.470368 -53.7718)
			(xy 274.452728 -53.750866) (xy 274.423 -53.7049) (xy 274.400152 -53.655154) (xy 274.384653 -53.602652)
			(xy 274.376824 -53.548472) (xy 274.376823 -53.493731) (xy 274.384653 -53.439551) (xy 274.400151 -53.387049)
			(xy 274.422998 -53.337303) (xy 274.452726 -53.291336) (xy 274.470368 -53.270404) (xy 274.470622 -53.27015)
			(xy 274.476196 -53.263055) (xy 274.48245 -53.246145) (xy 274.482814 -53.23713) (xy 274.482814 -53.170074)
			(xy 274.482466 -53.161056) (xy 274.476212 -53.14414) (xy 274.470622 -53.137054) (xy 274.470368 -53.137054)
			(xy 274.470368 -53.1368) (xy 274.45271 -53.115883) (xy 274.423002 -53.069905) (xy 274.400171 -53.020154)
			(xy 274.384684 -52.96765) (xy 274.37686 -52.913472) (xy 274.376388 -52.886102) (xy 274.376874 -52.858851)
			(xy 274.38463 -52.804903) (xy 274.399985 -52.752608) (xy 274.422627 -52.703031) (xy 274.452093 -52.657181)
			(xy 274.487784 -52.61599) (xy 274.528975 -52.580299) (xy 274.574825 -52.550833) (xy 274.624402 -52.528191)
			(xy 274.676697 -52.512836) (xy 274.730645 -52.50508) (xy 274.785147 -52.50508) (xy 274.839095 -52.512836)
			(xy 274.89139 -52.528191) (xy 274.93049 -52.546048) (xy 279.879596 -52.546048) (xy 279.879596 -52.491552)
			(xy 279.887351 -52.437611) (xy 279.902703 -52.385323) (xy 279.925339 -52.335751) (xy 279.9548 -52.289905)
			(xy 279.990484 -52.248718) (xy 280.031667 -52.213029) (xy 280.077509 -52.183563) (xy 280.127078 -52.16092)
			(xy 280.179364 -52.145561) (xy 280.233304 -52.1378) (xy 280.260552 -52.13731) (xy 280.287921 -52.137802)
			(xy 280.342099 -52.145613) (xy 280.394602 -52.161096) (xy 280.44435 -52.183932) (xy 280.490318 -52.213651)
			(xy 280.51125 -52.23129) (xy 280.511504 -52.231544) (xy 280.518581 -52.237144) (xy 280.535505 -52.243381)
			(xy 280.544524 -52.243736) (xy 280.61158 -52.243736) (xy 280.620595 -52.243361) (xy 280.637512 -52.237125)
			(xy 280.6446 -52.231544) (xy 280.6446 -52.23129) (xy 280.644854 -52.23129) (xy 280.665787 -52.213649)
			(xy 280.711755 -52.183925) (xy 280.761501 -52.161079) (xy 280.814003 -52.145583) (xy 280.868181 -52.137754)
			(xy 280.922923 -52.137754) (xy 280.977101 -52.145583) (xy 281.029603 -52.161079) (xy 281.079349 -52.183925)
			(xy 281.125317 -52.213649) (xy 281.14625 -52.23129) (xy 281.146504 -52.231544) (xy 281.153581 -52.237144)
			(xy 281.170505 -52.243381) (xy 281.179524 -52.243736) (xy 281.24658 -52.243736) (xy 281.255595 -52.243361)
			(xy 281.272512 -52.237125) (xy 281.2796 -52.231544) (xy 281.2796 -52.23129) (xy 281.279854 -52.23129)
			(xy 281.300791 -52.213657) (xy 281.346763 -52.183945) (xy 281.396509 -52.161108) (xy 281.449008 -52.145615)
			(xy 281.503183 -52.137785) (xy 281.530552 -52.13731) (xy 281.557808 -52.137734) (xy 281.611767 -52.145485)
			(xy 281.664073 -52.160838) (xy 281.713662 -52.183479) (xy 281.759523 -52.212947) (xy 281.800724 -52.248642)
			(xy 281.836424 -52.289838) (xy 281.865898 -52.335696) (xy 281.888545 -52.385282) (xy 281.903904 -52.437586)
			(xy 281.911663 -52.491544) (xy 281.911663 -52.546056) (xy 281.905718 -52.587398) (xy 282.955236 -52.587398)
			(xy 282.959307 -52.531776) (xy 282.971433 -52.477339) (xy 282.991356 -52.425248) (xy 283.018652 -52.376613)
			(xy 283.052738 -52.33247) (xy 283.092887 -52.293761) (xy 283.138245 -52.26131) (xy 283.187845 -52.235809)
			(xy 283.240629 -52.217802) (xy 283.295472 -52.207672) (xy 283.351206 -52.205635) (xy 283.406643 -52.211735)
			(xy 283.4606 -52.225841) (xy 283.511929 -52.247653) (xy 283.559535 -52.276707) (xy 283.602403 -52.312382)
			(xy 283.63962 -52.353919) (xy 283.670393 -52.400432) (xy 283.694065 -52.450929) (xy 283.710133 -52.504336)
			(xy 283.717729 -52.555948) (xy 290.783802 -52.555948) (xy 290.783802 -52.501452) (xy 290.791557 -52.44751)
			(xy 290.80691 -52.395221) (xy 290.829548 -52.345649) (xy 290.85901 -52.299802) (xy 290.894696 -52.258616)
			(xy 290.93588 -52.222926) (xy 290.981724 -52.193461) (xy 291.031295 -52.17082) (xy 291.083583 -52.155463)
			(xy 291.137524 -52.147704) (xy 291.164772 -52.147216) (xy 291.192142 -52.147695) (xy 291.246321 -52.155509)
			(xy 291.298824 -52.170995) (xy 291.348571 -52.193834) (xy 291.394538 -52.223556) (xy 291.41547 -52.241196)
			(xy 291.415724 -52.24145) (xy 291.422795 -52.247059) (xy 291.439724 -52.253291) (xy 291.448744 -52.253642)
			(xy 291.5158 -52.253642) (xy 291.524818 -52.253297) (xy 291.541736 -52.247043) (xy 291.54882 -52.24145)
			(xy 291.54882 -52.241196) (xy 291.549074 -52.241196) (xy 291.570005 -52.223555) (xy 291.615978 -52.193844)
			(xy 291.665726 -52.171008) (xy 291.718227 -52.155517) (xy 291.772403 -52.14769) (xy 291.799772 -52.147216)
			(xy 291.827028 -52.147629) (xy 291.880985 -52.155383) (xy 291.93329 -52.170738) (xy 291.982877 -52.19338)
			(xy 292.028736 -52.222849) (xy 292.069935 -52.258545) (xy 292.105634 -52.299741) (xy 292.135106 -52.345599)
			(xy 292.157752 -52.395184) (xy 292.173111 -52.447487) (xy 292.180869 -52.501444) (xy 292.180869 -52.555956)
			(xy 292.173111 -52.609913) (xy 292.157752 -52.662216) (xy 292.135106 -52.711801) (xy 292.105634 -52.757659)
			(xy 292.069935 -52.798855) (xy 292.028736 -52.834551) (xy 291.982877 -52.86402) (xy 291.93329 -52.886662)
			(xy 291.880985 -52.902017) (xy 291.827028 -52.909771) (xy 291.799772 -52.910232) (xy 291.7724 -52.909799)
			(xy 291.718219 -52.901976) (xy 291.665715 -52.88648) (xy 291.615969 -52.86363) (xy 291.570004 -52.833897)
			(xy 291.549074 -52.816252) (xy 291.54882 -52.815998) (xy 291.541732 -52.810413) (xy 291.524816 -52.804166)
			(xy 291.5158 -52.803806) (xy 291.448744 -52.803806) (xy 291.439729 -52.804183) (xy 291.422812 -52.810417)
			(xy 291.415724 -52.815998) (xy 291.415724 -52.816252) (xy 291.41547 -52.816252) (xy 291.394516 -52.833864)
			(xy 291.34855 -52.863582) (xy 291.298808 -52.886424) (xy 291.246312 -52.901921) (xy 291.19214 -52.909755)
			(xy 291.164772 -52.910232) (xy 291.137524 -52.909696) (xy 291.083583 -52.901937) (xy 291.031295 -52.88658)
			(xy 290.981724 -52.863939) (xy 290.93588 -52.834474) (xy 290.894696 -52.798784) (xy 290.85901 -52.757598)
			(xy 290.829548 -52.711751) (xy 290.80691 -52.662179) (xy 290.791557 -52.60989) (xy 290.783802 -52.555948)
			(xy 283.717729 -52.555948) (xy 283.718253 -52.559512) (xy 283.718762 -52.587398) (xy 283.718253 -52.615284)
			(xy 283.710133 -52.67046) (xy 283.694065 -52.723867) (xy 283.670393 -52.774364) (xy 283.63962 -52.820877)
			(xy 283.602403 -52.862414) (xy 283.559535 -52.898089) (xy 283.511929 -52.927143) (xy 283.4606 -52.948955)
			(xy 283.406643 -52.963061) (xy 283.351206 -52.969161) (xy 283.295472 -52.967124) (xy 283.240629 -52.956994)
			(xy 283.187845 -52.938987) (xy 283.138245 -52.913486) (xy 283.092887 -52.881035) (xy 283.052738 -52.842326)
			(xy 283.018652 -52.798183) (xy 282.991356 -52.749548) (xy 282.971433 -52.697457) (xy 282.959307 -52.64302)
			(xy 282.955236 -52.587398) (xy 281.905718 -52.587398) (xy 281.903904 -52.600014) (xy 281.888545 -52.652318)
			(xy 281.865898 -52.701904) (xy 281.836424 -52.747762) (xy 281.800724 -52.788958) (xy 281.759523 -52.824653)
			(xy 281.713662 -52.854121) (xy 281.664073 -52.876762) (xy 281.611767 -52.892115) (xy 281.557808 -52.899866)
			(xy 281.530552 -52.900326) (xy 281.503182 -52.899847) (xy 281.449003 -52.892035) (xy 281.396499 -52.87655)
			(xy 281.346752 -52.853711) (xy 281.300785 -52.823987) (xy 281.279854 -52.806346) (xy 281.2796 -52.806092)
			(xy 281.272518 -52.800498) (xy 281.255598 -52.794256) (xy 281.24658 -52.7939) (xy 281.179524 -52.7939)
			(xy 281.170508 -52.794268) (xy 281.153591 -52.800508) (xy 281.146504 -52.806092) (xy 281.14625 -52.806346)
			(xy 281.125317 -52.823987) (xy 281.079349 -52.853711) (xy 281.029603 -52.876557) (xy 280.977101 -52.892053)
			(xy 280.922923 -52.899882) (xy 280.868181 -52.899882) (xy 280.814003 -52.892053) (xy 280.761501 -52.876557)
			(xy 280.711755 -52.853711) (xy 280.665787 -52.823987) (xy 280.644854 -52.806346) (xy 280.6446 -52.806092)
			(xy 280.637518 -52.800498) (xy 280.620598 -52.794256) (xy 280.61158 -52.7939) (xy 280.544524 -52.7939)
			(xy 280.535508 -52.794268) (xy 280.518591 -52.800508) (xy 280.511504 -52.806092) (xy 280.511504 -52.806346)
			(xy 280.51125 -52.806346) (xy 280.490303 -52.823967) (xy 280.444335 -52.853683) (xy 280.394592 -52.876524)
			(xy 280.342094 -52.892019) (xy 280.28792 -52.89985) (xy 280.260552 -52.900326) (xy 280.233304 -52.8998)
			(xy 280.179364 -52.892039) (xy 280.127078 -52.87668) (xy 280.077509 -52.854037) (xy 280.031667 -52.824571)
			(xy 279.990484 -52.788882) (xy 279.9548 -52.747695) (xy 279.925339 -52.701849) (xy 279.902703 -52.652277)
			(xy 279.887351 -52.599989) (xy 279.879596 -52.546048) (xy 274.93049 -52.546048) (xy 274.940967 -52.550833)
			(xy 274.986817 -52.580299) (xy 275.028008 -52.61599) (xy 275.063699 -52.657181) (xy 275.093165 -52.703031)
			(xy 275.115807 -52.752608) (xy 275.131162 -52.804903) (xy 275.138918 -52.858851) (xy 275.139404 -52.886102)
			(xy 275.138938 -52.913472) (xy 275.13112 -52.967651) (xy 275.115631 -53.020154) (xy 275.092789 -53.069901)
			(xy 275.063065 -53.115868) (xy 275.045424 -53.1368) (xy 275.04517 -53.137054) (xy 275.039593 -53.144147)
			(xy 275.033342 -53.161059) (xy 275.032978 -53.170074) (xy 275.032978 -53.23713) (xy 275.033325 -53.246148)
			(xy 275.03958 -53.263064) (xy 275.04517 -53.27015) (xy 275.045424 -53.27015) (xy 275.045424 -53.270404)
			(xy 275.063069 -53.291334) (xy 275.092797 -53.337301) (xy 275.115645 -53.387048) (xy 275.131144 -53.43955)
			(xy 275.138973 -53.49373) (xy 275.138973 -53.548473) (xy 275.131143 -53.602652) (xy 275.115644 -53.655155)
			(xy 275.092796 -53.704901) (xy 275.063067 -53.750868) (xy 275.046494 -53.77053) (xy 275.410676 -53.77053)
			(xy 275.411187 -53.741612) (xy 275.419913 -53.68444) (xy 275.437171 -53.629239) (xy 275.462564 -53.577277)
			(xy 275.49551 -53.529744) (xy 275.535255 -53.487729) (xy 275.557742 -53.46954) (xy 275.566528 -53.461913)
			(xy 275.576721 -53.441027) (xy 275.5773 -53.429408) (xy 275.5773 -53.349652) (xy 275.576774 -53.338018)
			(xy 275.566576 -53.317109) (xy 275.557742 -53.30952) (xy 275.535277 -53.291307) (xy 275.495539 -53.249293)
			(xy 275.462596 -53.201763) (xy 275.437204 -53.149806) (xy 275.419945 -53.094612) (xy 275.411212 -53.037445)
			(xy 275.410676 -53.00853) (xy 275.411183 -52.981279) (xy 275.418936 -52.92733) (xy 275.434287 -52.875034)
			(xy 275.456925 -52.825455) (xy 275.486388 -52.779603) (xy 275.522077 -52.73841) (xy 275.563266 -52.702716)
			(xy 275.609115 -52.673247) (xy 275.658691 -52.650603) (xy 275.710985 -52.635245) (xy 275.764933 -52.627486)
			(xy 275.792184 -52.627022) (xy 275.818498 -52.627493) (xy 275.870627 -52.634726) (xy 275.921269 -52.649044)
			(xy 275.969469 -52.670176) (xy 276.014312 -52.697722) (xy 276.054952 -52.73116) (xy 276.073108 -52.750212)
			(xy 276.080623 -52.757621) (xy 276.099908 -52.766141) (xy 276.110446 -52.766722) (xy 276.185122 -52.766722)
			(xy 276.195667 -52.766158) (xy 276.214963 -52.757647) (xy 276.22246 -52.750212) (xy 276.240596 -52.731137)
			(xy 276.281229 -52.697681) (xy 276.326074 -52.670124) (xy 276.374279 -52.648989) (xy 276.42493 -52.634676)
			(xy 276.477067 -52.627457) (xy 276.503384 -52.627022) (xy 276.530638 -52.62747) (xy 276.584591 -52.635226)
			(xy 276.636891 -52.650581) (xy 276.686473 -52.673224) (xy 276.732328 -52.702693) (xy 276.773521 -52.738389)
			(xy 276.809215 -52.779584) (xy 276.838683 -52.825439) (xy 276.861324 -52.875022) (xy 276.876677 -52.927323)
			(xy 276.884431 -52.981276) (xy 276.884892 -53.00853) (xy 276.884407 -53.036196) (xy 276.876403 -53.090947)
			(xy 276.860582 -53.143969) (xy 276.837275 -53.194153) (xy 276.806969 -53.240449) (xy 276.7703 -53.281886)
			(xy 276.728035 -53.317598) (xy 276.704806 -53.332634) (xy 276.695126 -53.339267) (xy 276.682681 -53.35913)
			(xy 276.68093 -53.370734) (xy 276.673056 -53.450744) (xy 276.672403 -53.462383) (xy 276.680498 -53.484222)
			(xy 276.68855 -53.492654) (xy 276.688804 -53.492908) (xy 276.707372 -53.511002) (xy 276.739952 -53.551331)
			(xy 276.766766 -53.595703) (xy 276.787321 -53.643299) (xy 276.801238 -53.693241) (xy 276.808258 -53.744608)
			(xy 276.808692 -53.77053) (xy 276.80825 -53.797783) (xy 276.800489 -53.851733) (xy 276.785129 -53.904029)
			(xy 276.762483 -53.953608) (xy 276.733013 -53.999459) (xy 276.697317 -54.040649) (xy 276.656122 -54.07634)
			(xy 276.610267 -54.105806) (xy 276.560686 -54.128445) (xy 276.508388 -54.143799) (xy 276.454437 -54.151553)
			(xy 276.427184 -54.152038) (xy 276.399813 -54.151596) (xy 276.345632 -54.143775) (xy 276.293128 -54.128281)
			(xy 276.243381 -54.105433) (xy 276.197416 -54.075703) (xy 276.176486 -54.058058) (xy 276.176232 -54.057804)
			(xy 276.16914 -54.052225) (xy 276.152227 -54.045974) (xy 276.143212 -54.045612) (xy 276.076156 -54.045612)
			(xy 276.067142 -54.045993) (xy 276.050224 -54.052224) (xy 276.043136 -54.057804) (xy 276.043136 -54.058058)
			(xy 276.042882 -54.058058) (xy 276.021924 -54.075666) (xy 275.975959 -54.105384) (xy 275.926218 -54.128226)
			(xy 275.873723 -54.143725) (xy 275.819552 -54.15156) (xy 275.792184 -54.152038) (xy 275.764934 -54.151537)
			(xy 275.710988 -54.143779) (xy 275.658695 -54.128424) (xy 275.60912 -54.105783) (xy 275.563271 -54.076318)
			(xy 275.522082 -54.040628) (xy 275.486391 -53.99944) (xy 275.456924 -53.953592) (xy 275.434281 -53.904018)
			(xy 275.418924 -53.851726) (xy 275.411164 -53.79778) (xy 275.410676 -53.77053) (xy 275.046494 -53.77053)
			(xy 275.045424 -53.7718) (xy 275.04517 -53.772054) (xy 275.039593 -53.779147) (xy 275.033342 -53.796059)
			(xy 275.032978 -53.805074) (xy 275.032978 -53.87213) (xy 275.033325 -53.881148) (xy 275.03958 -53.898064)
			(xy 275.04517 -53.90515) (xy 275.045424 -53.90515) (xy 275.045424 -53.905404) (xy 275.063069 -53.926334)
			(xy 275.092797 -53.972301) (xy 275.115645 -54.022048) (xy 275.131144 -54.07455) (xy 275.138973 -54.12873)
			(xy 275.138973 -54.183473) (xy 275.131143 -54.237652) (xy 275.115644 -54.290155) (xy 275.101851 -54.320186)
			(xy 277.330408 -54.320186) (xy 277.330864 -54.292815) (xy 277.338684 -54.238636) (xy 277.354175 -54.186132)
			(xy 277.377019 -54.136386) (xy 277.406746 -54.090419) (xy 277.424388 -54.069488) (xy 277.424642 -54.069234)
			(xy 277.430226 -54.062146) (xy 277.436473 -54.04523) (xy 277.436834 -54.036214) (xy 277.436834 -53.969158)
			(xy 277.436442 -53.960145) (xy 277.430218 -53.943228) (xy 277.424642 -53.936138) (xy 277.424388 -53.936138)
			(xy 277.424388 -53.935884) (xy 277.406773 -53.914933) (xy 277.377058 -53.868965) (xy 277.354218 -53.819222)
			(xy 277.338721 -53.766726) (xy 277.330886 -53.712554) (xy 277.330408 -53.685186) (xy 277.330894 -53.657935)
			(xy 277.33865 -53.603987) (xy 277.354005 -53.551692) (xy 277.376647 -53.502115) (xy 277.406113 -53.456265)
			(xy 277.441804 -53.415074) (xy 277.482995 -53.379383) (xy 277.528845 -53.349917) (xy 277.578422 -53.327275)
			(xy 277.630717 -53.31192) (xy 277.684665 -53.304164) (xy 277.739167 -53.304164) (xy 277.793115 -53.31192)
			(xy 277.84541 -53.327275) (xy 277.894987 -53.349917) (xy 277.940837 -53.379383) (xy 277.982028 -53.415074)
			(xy 278.017719 -53.456265) (xy 278.047185 -53.502115) (xy 278.069827 -53.551692) (xy 278.085182 -53.603987)
			(xy 278.092938 -53.657935) (xy 278.093424 -53.685186) (xy 278.092968 -53.712557) (xy 278.085151 -53.766737)
			(xy 278.06966 -53.819241) (xy 278.046816 -53.868988) (xy 278.017087 -53.914953) (xy 277.999444 -53.935884)
			(xy 277.99919 -53.936138) (xy 277.993622 -53.943237) (xy 277.987365 -53.960144) (xy 277.986998 -53.969158)
			(xy 277.986998 -54.036214) (xy 277.987349 -54.045231) (xy 277.993601 -54.062148) (xy 277.99919 -54.069234)
			(xy 277.999444 -54.069234) (xy 277.999444 -54.069488) (xy 278.017098 -54.090408) (xy 278.046806 -54.136385)
			(xy 278.069639 -54.186135) (xy 278.085127 -54.238638) (xy 278.092952 -54.292816) (xy 278.093424 -54.320186)
			(xy 278.092938 -54.347437) (xy 278.085182 -54.401385) (xy 278.069827 -54.45368) (xy 278.047185 -54.503257)
			(xy 278.017719 -54.549107) (xy 277.982028 -54.590298) (xy 277.940837 -54.625989) (xy 277.894987 -54.655455)
			(xy 277.84541 -54.678097) (xy 277.793115 -54.693452) (xy 277.739167 -54.701208) (xy 277.684665 -54.701208)
			(xy 277.630717 -54.693452) (xy 277.578422 -54.678097) (xy 277.528845 -54.655455) (xy 277.482995 -54.625989)
			(xy 277.441804 -54.590298) (xy 277.406113 -54.549107) (xy 277.376647 -54.503257) (xy 277.354005 -54.45368)
			(xy 277.33865 -54.401385) (xy 277.330894 -54.347437) (xy 277.330408 -54.320186) (xy 275.101851 -54.320186)
			(xy 275.092796 -54.339901) (xy 275.063067 -54.385868) (xy 275.045424 -54.4068) (xy 275.04517 -54.407054)
			(xy 275.039593 -54.414147) (xy 275.033342 -54.431059) (xy 275.032978 -54.440074) (xy 275.032978 -54.50713)
			(xy 275.033325 -54.516148) (xy 275.03958 -54.533064) (xy 275.04517 -54.54015) (xy 275.045424 -54.54015)
			(xy 275.045424 -54.540404) (xy 275.063082 -54.561321) (xy 275.09279 -54.607298) (xy 275.115622 -54.65705)
			(xy 275.131109 -54.709553) (xy 275.138932 -54.763732) (xy 275.139049 -54.770528) (xy 278.27097 -54.770528)
			(xy 278.271435 -54.743158) (xy 278.279251 -54.688978) (xy 278.294739 -54.636474) (xy 278.317581 -54.586727)
			(xy 278.347308 -54.540761) (xy 278.36495 -54.51983) (xy 278.365204 -54.519576) (xy 278.370807 -54.512501)
			(xy 278.377044 -54.495575) (xy 278.377396 -54.486556) (xy 278.377396 -54.4195) (xy 278.37704 -54.410483)
			(xy 278.370792 -54.393566) (xy 278.365204 -54.38648) (xy 278.36495 -54.38648) (xy 278.36495 -54.386226)
			(xy 278.347317 -54.365289) (xy 278.317603 -54.319318) (xy 278.294765 -54.269572) (xy 278.279272 -54.217072)
			(xy 278.271444 -54.162897) (xy 278.27097 -54.135528) (xy 278.271456 -54.108277) (xy 278.279212 -54.054329)
			(xy 278.294567 -54.002034) (xy 278.317209 -53.952457) (xy 278.346675 -53.906607) (xy 278.382366 -53.865416)
			(xy 278.423557 -53.829725) (xy 278.469407 -53.800259) (xy 278.518984 -53.777617) (xy 278.571279 -53.762262)
			(xy 278.625227 -53.754506) (xy 278.679729 -53.754506) (xy 278.733677 -53.762262) (xy 278.785972 -53.777617)
			(xy 278.835549 -53.800259) (xy 278.881399 -53.829725) (xy 278.92259 -53.865416) (xy 278.958281 -53.906607)
			(xy 278.987747 -53.952457) (xy 278.992822 -53.96357) (xy 282.972 -53.96357) (xy 282.976071 -53.907948)
			(xy 282.988197 -53.853511) (xy 283.00812 -53.80142) (xy 283.035416 -53.752785) (xy 283.069502 -53.708642)
			(xy 283.109651 -53.669933) (xy 283.155009 -53.637482) (xy 283.204609 -53.611981) (xy 283.257393 -53.593974)
			(xy 283.312236 -53.583844) (xy 283.36797 -53.581807) (xy 283.423407 -53.587907) (xy 283.477364 -53.602013)
			(xy 283.528693 -53.623825) (xy 283.576299 -53.652879) (xy 283.619167 -53.688554) (xy 283.656384 -53.730091)
			(xy 283.687157 -53.776604) (xy 283.710829 -53.827101) (xy 283.726897 -53.880508) (xy 283.735017 -53.935684)
			(xy 283.735526 -53.96357) (xy 283.735017 -53.991456) (xy 283.726897 -54.046632) (xy 283.710829 -54.100039)
			(xy 283.687157 -54.150536) (xy 283.656384 -54.197049) (xy 283.619167 -54.238586) (xy 283.576299 -54.274261)
			(xy 283.528693 -54.303315) (xy 283.477364 -54.325127) (xy 283.423407 -54.339233) (xy 283.36797 -54.345333)
			(xy 283.312236 -54.343296) (xy 283.257393 -54.333166) (xy 283.204609 -54.315159) (xy 283.155009 -54.289658)
			(xy 283.109651 -54.257207) (xy 283.069502 -54.218498) (xy 283.035416 -54.174355) (xy 283.00812 -54.12572)
			(xy 282.988197 -54.073629) (xy 282.976071 -54.019192) (xy 282.972 -53.96357) (xy 278.992822 -53.96357)
			(xy 279.010389 -54.002034) (xy 279.025744 -54.054329) (xy 279.0335 -54.108277) (xy 279.033986 -54.135528)
			(xy 279.03354 -54.162899) (xy 279.025718 -54.217079) (xy 279.010224 -54.269583) (xy 278.987378 -54.319329)
			(xy 278.957649 -54.365295) (xy 278.940006 -54.386226) (xy 278.939752 -54.38648) (xy 278.934162 -54.393564)
			(xy 278.927919 -54.410483) (xy 278.92756 -54.4195) (xy 278.92756 -54.486556) (xy 278.927925 -54.495572)
			(xy 278.934166 -54.51249) (xy 278.939752 -54.519576) (xy 278.940006 -54.519576) (xy 278.940006 -54.51983)
			(xy 278.957627 -54.540777) (xy 278.987341 -54.586746) (xy 279.01018 -54.636489) (xy 279.025676 -54.688987)
			(xy 279.033509 -54.74316) (xy 279.033986 -54.770528) (xy 279.0335 -54.797779) (xy 279.025744 -54.851727)
			(xy 279.010389 -54.904022) (xy 278.987747 -54.953599) (xy 278.958281 -54.999449) (xy 278.92259 -55.04064)
			(xy 278.881399 -55.076331) (xy 278.835549 -55.105797) (xy 278.785972 -55.128439) (xy 278.733677 -55.143794)
			(xy 278.679729 -55.15155) (xy 278.625227 -55.15155) (xy 278.571279 -55.143794) (xy 278.518984 -55.128439)
			(xy 278.469407 -55.105797) (xy 278.423557 -55.076331) (xy 278.382366 -55.04064) (xy 278.346675 -54.999449)
			(xy 278.317209 -54.953599) (xy 278.294567 -54.904022) (xy 278.279212 -54.851727) (xy 278.271456 -54.797779)
			(xy 278.27097 -54.770528) (xy 275.139049 -54.770528) (xy 275.139404 -54.791102) (xy 275.138918 -54.818353)
			(xy 275.131162 -54.872301) (xy 275.115807 -54.924596) (xy 275.093165 -54.974173) (xy 275.063699 -55.020023)
			(xy 275.028008 -55.061214) (xy 274.986817 -55.096905) (xy 274.940967 -55.126371) (xy 274.89139 -55.149013)
			(xy 274.839095 -55.164368) (xy 274.785147 -55.172124) (xy 274.730645 -55.172124) (xy 274.676697 -55.164368)
			(xy 274.624402 -55.149013) (xy 274.574825 -55.126371) (xy 274.528975 -55.096905) (xy 274.487784 -55.061214)
			(xy 274.452093 -55.020023) (xy 274.422627 -54.974173) (xy 274.399985 -54.924596) (xy 274.38463 -54.872301)
			(xy 274.376874 -54.818353) (xy 274.376388 -54.791102) (xy 272.47843 -54.791102) (xy 272.475338 -54.812611)
			(xy 272.459983 -54.864906) (xy 272.437341 -54.914483) (xy 272.407875 -54.960333) (xy 272.372184 -55.001524)
			(xy 272.330993 -55.037215) (xy 272.285143 -55.066681) (xy 272.235566 -55.089323) (xy 272.183271 -55.104678)
			(xy 272.129323 -55.112434) (xy 272.074821 -55.112434) (xy 272.020873 -55.104678) (xy 271.968578 -55.089323)
			(xy 271.919001 -55.066681) (xy 271.873151 -55.037215) (xy 271.83196 -55.001524) (xy 271.796269 -54.960333)
			(xy 271.766803 -54.914483) (xy 271.744161 -54.864906) (xy 271.728806 -54.812611) (xy 271.72105 -54.758663)
			(xy 271.720564 -54.731412) (xy 270.998696 -54.731412) (xy 270.998696 -57.002934) (xy 279.763474 -57.002934)
			(xy 279.764 -56.974844) (xy 279.772222 -56.919268) (xy 279.788508 -56.8655) (xy 279.812505 -56.814703)
			(xy 279.843695 -56.767976) (xy 279.881403 -56.726329) (xy 279.924812 -56.690666) (xy 279.94864 -56.675782)
			(xy 279.95753 -56.670448) (xy 279.969722 -56.65343) (xy 279.990042 -56.560212) (xy 279.985724 -56.539638)
			(xy 279.979882 -56.531002) (xy 279.963879 -56.50694) (xy 279.938537 -56.455008) (xy 279.921313 -56.399849)
			(xy 279.912598 -56.342725) (xy 279.912064 -56.313832) (xy 279.912585 -56.286581) (xy 279.920337 -56.232634)
			(xy 279.935687 -56.180339) (xy 279.958324 -56.130761) (xy 279.987786 -56.084909) (xy 280.023474 -56.043716)
			(xy 280.064661 -56.008022) (xy 280.110508 -55.978553) (xy 280.160082 -55.955908) (xy 280.212375 -55.94055)
			(xy 280.266321 -55.932789) (xy 280.293572 -55.932324) (xy 280.320942 -55.932801) (xy 280.375121 -55.940615)
			(xy 280.427624 -55.956101) (xy 280.477371 -55.978941) (xy 280.523338 -56.008664) (xy 280.54427 -56.026304)
			(xy 280.544524 -56.026558) (xy 280.551595 -56.032168) (xy 280.568524 -56.038399) (xy 280.577544 -56.03875)
			(xy 280.6446 -56.03875) (xy 280.653618 -56.038404) (xy 280.670536 -56.03215) (xy 280.67762 -56.026558)
			(xy 280.67762 -56.026304) (xy 280.677874 -56.026304) (xy 280.698807 -56.008663) (xy 280.744775 -55.978939)
			(xy 280.794521 -55.956093) (xy 280.847023 -55.940597) (xy 280.901201 -55.932768) (xy 280.955943 -55.932768)
			(xy 281.010121 -55.940597) (xy 281.062623 -55.956093) (xy 281.112369 -55.978939) (xy 281.158337 -56.008663)
			(xy 281.17927 -56.026304) (xy 281.179524 -56.026558) (xy 281.186595 -56.032168) (xy 281.203524 -56.038399)
			(xy 281.212544 -56.03875) (xy 281.2796 -56.03875) (xy 281.288618 -56.038404) (xy 281.305536 -56.03215)
			(xy 281.31262 -56.026558) (xy 281.31262 -56.026304) (xy 281.312874 -56.026304) (xy 281.333806 -56.008664)
			(xy 281.379778 -55.978952) (xy 281.429526 -55.956116) (xy 281.482027 -55.940626) (xy 281.536203 -55.932798)
			(xy 281.563572 -55.932324) (xy 281.590828 -55.932721) (xy 281.644787 -55.940475) (xy 281.697093 -55.95583)
			(xy 281.746681 -55.978473) (xy 281.792541 -56.007943) (xy 281.833741 -56.04364) (xy 281.86944 -56.084836)
			(xy 281.898913 -56.130695) (xy 281.92156 -56.180281) (xy 281.936919 -56.232586) (xy 281.944677 -56.286544)
			(xy 281.944677 -56.341056) (xy 281.936919 -56.395014) (xy 281.92156 -56.447319) (xy 281.898913 -56.496905)
			(xy 281.86944 -56.542764) (xy 281.833741 -56.58396) (xy 281.792541 -56.619657) (xy 281.746681 -56.649127)
			(xy 281.697093 -56.67177) (xy 281.644787 -56.687125) (xy 281.590828 -56.694879) (xy 281.563572 -56.69534)
			(xy 281.5362 -56.694905) (xy 281.482019 -56.687082) (xy 281.429515 -56.671586) (xy 281.379769 -56.648737)
			(xy 281.333804 -56.619005) (xy 281.312874 -56.60136) (xy 281.31262 -56.601106) (xy 281.305531 -56.595522)
			(xy 281.288616 -56.589274) (xy 281.2796 -56.588914) (xy 281.212544 -56.588914) (xy 281.203529 -56.589289)
			(xy 281.186612 -56.595524) (xy 281.179524 -56.601106) (xy 281.179524 -56.60136) (xy 281.17927 -56.60136)
			(xy 281.158337 -56.619001) (xy 281.112369 -56.648725) (xy 281.062623 -56.671571) (xy 281.010121 -56.687067)
			(xy 280.955943 -56.694896) (xy 280.901201 -56.694896) (xy 280.847023 -56.687067) (xy 280.794521 -56.671571)
			(xy 280.744775 -56.648725) (xy 280.698807 -56.619001) (xy 280.677874 -56.60136) (xy 280.67762 -56.601106)
			(xy 280.670531 -56.595522) (xy 280.653616 -56.589274) (xy 280.6446 -56.588914) (xy 280.577544 -56.588914)
			(xy 280.568529 -56.589289) (xy 280.551612 -56.595524) (xy 280.544524 -56.601106) (xy 280.544016 -56.60136)
			(xy 280.531285 -56.612308) (xy 280.504191 -56.632147) (xy 280.489914 -56.640984) (xy 280.481024 -56.646318)
			(xy 280.468832 -56.663336) (xy 280.448512 -56.756554) (xy 280.45283 -56.777128) (xy 280.458672 -56.785764)
			(xy 280.474656 -56.809838) (xy 280.500003 -56.861766) (xy 280.517233 -56.91692) (xy 280.525953 -56.974042)
			(xy 280.52649 -57.002934) (xy 280.526004 -57.030185) (xy 280.518248 -57.084133) (xy 280.502893 -57.136428)
			(xy 280.480251 -57.186005) (xy 280.450785 -57.231855) (xy 280.415094 -57.273046) (xy 280.373903 -57.308737)
			(xy 280.328053 -57.338203) (xy 280.278476 -57.360845) (xy 280.226181 -57.3762) (xy 280.172233 -57.383956)
			(xy 280.117731 -57.383956) (xy 280.063783 -57.3762) (xy 280.011488 -57.360845) (xy 279.961911 -57.338203)
			(xy 279.916061 -57.308737) (xy 279.87487 -57.273046) (xy 279.839179 -57.231855) (xy 279.809713 -57.186005)
			(xy 279.787071 -57.136428) (xy 279.771716 -57.084133) (xy 279.76396 -57.030185) (xy 279.763474 -57.002934)
			(xy 270.998696 -57.002934) (xy 270.998696 -58.679334) (xy 280.195274 -58.679334) (xy 280.195706 -58.653019)
			(xy 280.202949 -58.600889) (xy 280.217276 -58.550246) (xy 280.238415 -58.502047) (xy 280.265967 -58.457205)
			(xy 280.29941 -58.416566) (xy 280.318464 -58.39841) (xy 280.325858 -58.390882) (xy 280.334388 -58.371607)
			(xy 280.334974 -58.361072) (xy 280.334974 -58.286396) (xy 280.334468 -58.275843) (xy 280.325917 -58.256548)
			(xy 280.318464 -58.249058) (xy 280.299388 -58.230923) (xy 280.265934 -58.190288) (xy 280.238379 -58.145443)
			(xy 280.217244 -58.097239) (xy 280.202931 -58.046588) (xy 280.19571 -57.994451) (xy 280.195274 -57.968134)
			(xy 280.19576 -57.940883) (xy 280.203516 -57.886935) (xy 280.218871 -57.83464) (xy 280.241513 -57.785063)
			(xy 280.270979 -57.739213) (xy 280.30667 -57.698022) (xy 280.347861 -57.662331) (xy 280.393711 -57.632865)
			(xy 280.443288 -57.610223) (xy 280.495583 -57.594868) (xy 280.549531 -57.587112) (xy 280.604033 -57.587112)
			(xy 280.657981 -57.594868) (xy 280.710276 -57.610223) (xy 280.759853 -57.632865) (xy 280.805703 -57.662331)
			(xy 280.846894 -57.698022) (xy 280.882585 -57.739213) (xy 280.912051 -57.785063) (xy 280.934693 -57.83464)
			(xy 280.950048 -57.886935) (xy 280.957804 -57.940883) (xy 280.95829 -57.968134) (xy 280.957848 -57.994449)
			(xy 280.950609 -58.046579) (xy 280.936285 -58.097222) (xy 280.915148 -58.145421) (xy 280.887597 -58.190264)
			(xy 280.854154 -58.230902) (xy 280.8351 -58.249058) (xy 280.827715 -58.256593) (xy 280.819181 -58.275863)
			(xy 280.81859 -58.286396) (xy 280.81859 -58.361072) (xy 280.819124 -58.371621) (xy 280.827656 -58.390916)
			(xy 280.8351 -58.39841) (xy 280.854153 -58.416568) (xy 280.887611 -58.457197) (xy 280.91517 -58.502037)
			(xy 280.936309 -58.550237) (xy 280.950626 -58.600884) (xy 280.957851 -58.653018) (xy 280.95829 -58.679334)
			(xy 280.957804 -58.706585) (xy 280.950048 -58.760533) (xy 280.934693 -58.812828) (xy 280.912051 -58.862405)
			(xy 280.882585 -58.908255) (xy 280.846894 -58.949446) (xy 280.805703 -58.985137) (xy 280.759853 -59.014603)
			(xy 280.710276 -59.037245) (xy 280.657981 -59.0526) (xy 280.604033 -59.060356) (xy 280.549531 -59.060356)
			(xy 280.495583 -59.0526) (xy 280.443288 -59.037245) (xy 280.393711 -59.014603) (xy 280.347861 -58.985137)
			(xy 280.30667 -58.949446) (xy 280.270979 -58.908255) (xy 280.241513 -58.862405) (xy 280.218871 -58.812828)
			(xy 280.203516 -58.760533) (xy 280.19576 -58.706585) (xy 280.195274 -58.679334) (xy 270.998696 -58.679334)
			(xy 270.998696 -60.019254) (xy 280.335661 -60.019254) (xy 280.335661 -59.964746) (xy 280.343419 -59.910793)
			(xy 280.358777 -59.858493) (xy 280.381422 -59.808911) (xy 280.410892 -59.763057) (xy 280.446589 -59.721864)
			(xy 280.487786 -59.686171) (xy 280.533643 -59.656704) (xy 280.583227 -59.634064) (xy 280.635528 -59.618712)
			(xy 280.689482 -59.610959) (xy 280.716736 -59.610498) (xy 280.744107 -59.610943) (xy 280.798287 -59.618766)
			(xy 280.85079 -59.63426) (xy 280.900537 -59.657107) (xy 280.946503 -59.686835) (xy 280.967434 -59.704478)
			(xy 280.967688 -59.704732) (xy 280.974771 -59.710323) (xy 280.991691 -59.716566) (xy 281.000708 -59.716924)
			(xy 281.067764 -59.716924) (xy 281.076778 -59.716545) (xy 281.093695 -59.710312) (xy 281.100784 -59.704732)
			(xy 281.100784 -59.704478) (xy 281.101038 -59.704478) (xy 281.121971 -59.686837) (xy 281.167939 -59.657113)
			(xy 281.217685 -59.634267) (xy 281.270187 -59.618771) (xy 281.324365 -59.610942) (xy 281.379107 -59.610942)
			(xy 281.433285 -59.618771) (xy 281.485787 -59.634267) (xy 281.535533 -59.657113) (xy 281.581501 -59.686837)
			(xy 281.602434 -59.704478) (xy 281.602688 -59.704732) (xy 281.609771 -59.710323) (xy 281.626691 -59.716566)
			(xy 281.635708 -59.716924) (xy 281.702764 -59.716924) (xy 281.711778 -59.716545) (xy 281.728695 -59.710312)
			(xy 281.735784 -59.704732) (xy 281.735784 -59.704478) (xy 281.736038 -59.704478) (xy 281.75698 -59.686851)
			(xy 281.80295 -59.657138) (xy 281.852695 -59.6343) (xy 281.905194 -59.618806) (xy 281.959368 -59.610974)
			(xy 281.986736 -59.610498) (xy 282.013986 -59.610974) (xy 282.067931 -59.618735) (xy 282.120222 -59.634094)
			(xy 282.169795 -59.656737) (xy 282.215642 -59.686205) (xy 282.256829 -59.721897) (xy 282.292517 -59.763087)
			(xy 282.32198 -59.808936) (xy 282.344619 -59.858512) (xy 282.359973 -59.910805) (xy 282.367728 -59.96475)
			(xy 282.367728 -60.01925) (xy 282.359973 -60.073195) (xy 282.344619 -60.125488) (xy 282.32198 -60.175064)
			(xy 282.292517 -60.220913) (xy 282.256829 -60.262103) (xy 282.215642 -60.297795) (xy 282.169795 -60.327263)
			(xy 282.120222 -60.349906) (xy 282.067931 -60.365265) (xy 282.013986 -60.373026) (xy 281.986736 -60.373514)
			(xy 281.959367 -60.373023) (xy 281.905189 -60.365211) (xy 281.852686 -60.349727) (xy 281.802939 -60.326891)
			(xy 281.756971 -60.297172) (xy 281.736038 -60.279534) (xy 281.735784 -60.27928) (xy 281.728708 -60.273678)
			(xy 281.711783 -60.267441) (xy 281.702764 -60.267088) (xy 281.635708 -60.267088) (xy 281.626692 -60.267451)
			(xy 281.609775 -60.273695) (xy 281.602688 -60.27928) (xy 281.602434 -60.279534) (xy 281.581501 -60.297175)
			(xy 281.535533 -60.326899) (xy 281.485787 -60.349745) (xy 281.433285 -60.365241) (xy 281.379107 -60.37307)
			(xy 281.324365 -60.37307) (xy 281.270187 -60.365241) (xy 281.217685 -60.349745) (xy 281.167939 -60.326899)
			(xy 281.121971 -60.297175) (xy 281.101038 -60.279534) (xy 281.100784 -60.27928) (xy 281.093708 -60.273678)
			(xy 281.076783 -60.267441) (xy 281.067764 -60.267088) (xy 281.000708 -60.267088) (xy 280.991692 -60.267451)
			(xy 280.974775 -60.273695) (xy 280.967688 -60.27928) (xy 280.967688 -60.279534) (xy 280.967434 -60.279534)
			(xy 280.946504 -60.297176) (xy 280.90053 -60.326886) (xy 280.850782 -60.349721) (xy 280.798281 -60.365212)
			(xy 280.744105 -60.37304) (xy 280.716736 -60.373514) (xy 280.689482 -60.373041) (xy 280.635528 -60.365288)
			(xy 280.583227 -60.349936) (xy 280.533643 -60.327296) (xy 280.487786 -60.297829) (xy 280.446589 -60.262136)
			(xy 280.410892 -60.220943) (xy 280.381422 -60.175089) (xy 280.358777 -60.125507) (xy 280.343419 -60.073207)
			(xy 280.335661 -60.019254) (xy 270.998696 -60.019254) (xy 270.998696 -67.128953) (xy 272.566575 -67.128953)
			(xy 272.566575 -67.074447) (xy 272.574333 -67.020495) (xy 272.58969 -66.968197) (xy 272.612334 -66.918617)
			(xy 272.641804 -66.872765) (xy 272.6775 -66.831573) (xy 272.718695 -66.795881) (xy 272.764551 -66.766416)
			(xy 272.814133 -66.743777) (xy 272.866433 -66.728425) (xy 272.920385 -66.720673) (xy 272.947638 -66.720212)
			(xy 272.975007 -66.720711) (xy 273.029185 -66.728521) (xy 273.081688 -66.744002) (xy 273.131435 -66.766836)
			(xy 273.177403 -66.796554) (xy 273.198336 -66.814192) (xy 273.19859 -66.814446) (xy 273.205671 -66.82004)
			(xy 273.222592 -66.826281) (xy 273.23161 -66.826638) (xy 273.298666 -66.826638) (xy 273.30768 -66.826256)
			(xy 273.324597 -66.820025) (xy 273.331686 -66.814446) (xy 273.331686 -66.814192) (xy 273.33194 -66.814192)
			(xy 273.352883 -66.796566) (xy 273.398853 -66.766853) (xy 273.448598 -66.744014) (xy 273.501096 -66.72852)
			(xy 273.55527 -66.720688) (xy 273.582638 -66.720212) (xy 273.609889 -66.72066) (xy 273.663835 -66.728422)
			(xy 273.716128 -66.743781) (xy 273.765703 -66.766425) (xy 273.811551 -66.795894) (xy 273.852739 -66.831588)
			(xy 273.888428 -66.872779) (xy 273.917893 -66.91863) (xy 273.940532 -66.968207) (xy 273.955886 -67.020502)
			(xy 273.963642 -67.074449) (xy 273.963642 -67.128951) (xy 273.955886 -67.182898) (xy 273.940532 -67.235193)
			(xy 273.917893 -67.28477) (xy 273.888428 -67.330621) (xy 273.852739 -67.371812) (xy 273.811551 -67.407506)
			(xy 273.765703 -67.436975) (xy 273.716128 -67.459619) (xy 273.663835 -67.474978) (xy 273.609889 -67.48274)
			(xy 273.582638 -67.483228) (xy 273.555268 -67.482757) (xy 273.501088 -67.474943) (xy 273.448584 -67.459456)
			(xy 273.398837 -67.436615) (xy 273.352871 -67.40689) (xy 273.33194 -67.389248) (xy 273.331686 -67.388994)
			(xy 273.324608 -67.383395) (xy 273.307685 -67.377156) (xy 273.298666 -67.376802) (xy 273.23161 -67.376802)
			(xy 273.222594 -67.377163) (xy 273.205677 -67.383408) (xy 273.19859 -67.388994) (xy 273.19859 -67.389248)
			(xy 273.198336 -67.389248) (xy 273.177395 -67.406876) (xy 273.131425 -67.436591) (xy 273.08168 -67.45943)
			(xy 273.029181 -67.474924) (xy 272.975007 -67.482753) (xy 272.947638 -67.483228) (xy 272.920385 -67.482727)
			(xy 272.866433 -67.474975) (xy 272.814133 -67.459623) (xy 272.764551 -67.436984) (xy 272.718695 -67.407519)
			(xy 272.6775 -67.371827) (xy 272.641804 -67.330635) (xy 272.612334 -67.284783) (xy 272.58969 -67.235203)
			(xy 272.574333 -67.182905) (xy 272.566575 -67.128953) (xy 270.998696 -67.128953) (xy 270.998696 -67.488054)
			(xy 276.979124 -67.488054) (xy 276.983195 -67.432432) (xy 276.995321 -67.377995) (xy 277.015244 -67.325904)
			(xy 277.04254 -67.277269) (xy 277.076626 -67.233126) (xy 277.116775 -67.194417) (xy 277.162133 -67.161966)
			(xy 277.211733 -67.136465) (xy 277.264517 -67.118458) (xy 277.31936 -67.108328) (xy 277.375094 -67.106291)
			(xy 277.430531 -67.112391) (xy 277.484488 -67.126497) (xy 277.535817 -67.148309) (xy 277.583423 -67.177363)
			(xy 277.626291 -67.213038) (xy 277.663508 -67.254575) (xy 277.694281 -67.301088) (xy 277.717953 -67.351585)
			(xy 277.734021 -67.404992) (xy 277.742141 -67.460168) (xy 277.74265 -67.488054) (xy 277.742141 -67.51594)
			(xy 277.738956 -67.537584) (xy 278.271222 -67.537584) (xy 278.275293 -67.481962) (xy 278.287419 -67.427525)
			(xy 278.307342 -67.375434) (xy 278.334638 -67.326799) (xy 278.368724 -67.282656) (xy 278.408873 -67.243947)
			(xy 278.454231 -67.211496) (xy 278.503831 -67.185995) (xy 278.556615 -67.167988) (xy 278.611458 -67.157858)
			(xy 278.667192 -67.155821) (xy 278.722629 -67.161921) (xy 278.776586 -67.176027) (xy 278.827915 -67.197839)
			(xy 278.875521 -67.226893) (xy 278.918389 -67.262568) (xy 278.955606 -67.304105) (xy 278.986379 -67.350618)
			(xy 279.010051 -67.401115) (xy 279.026119 -67.454522) (xy 279.034239 -67.509698) (xy 279.034748 -67.537584)
			(xy 279.034239 -67.56547) (xy 279.030194 -67.592956) (xy 279.545286 -67.592956) (xy 279.549357 -67.537334)
			(xy 279.561483 -67.482897) (xy 279.581406 -67.430806) (xy 279.608702 -67.382171) (xy 279.642788 -67.338028)
			(xy 279.682937 -67.299319) (xy 279.728295 -67.266868) (xy 279.777895 -67.241367) (xy 279.830679 -67.22336)
			(xy 279.885522 -67.21323) (xy 279.941256 -67.211193) (xy 279.996693 -67.217293) (xy 280.05065 -67.231399)
			(xy 280.101979 -67.253211) (xy 280.149585 -67.282265) (xy 280.192453 -67.31794) (xy 280.22967 -67.359477)
			(xy 280.260443 -67.40599) (xy 280.284115 -67.456487) (xy 280.300183 -67.509894) (xy 280.3083 -67.565051)
			(xy 282.646593 -67.565051) (xy 282.646593 -67.510549) (xy 282.65435 -67.456601) (xy 282.669706 -67.404306)
			(xy 282.692348 -67.354729) (xy 282.721816 -67.308879) (xy 282.757509 -67.267689) (xy 282.798701 -67.231999)
			(xy 282.844553 -67.202535) (xy 282.894132 -67.179896) (xy 282.946428 -67.164544) (xy 283.000377 -67.156791)
			(xy 283.027628 -67.15633) (xy 283.054999 -67.156772) (xy 283.10918 -67.164595) (xy 283.161683 -67.180089)
			(xy 283.21143 -67.202936) (xy 283.257395 -67.232666) (xy 283.278326 -67.25031) (xy 283.27858 -67.250564)
			(xy 283.285663 -67.256156) (xy 283.302583 -67.262398) (xy 283.3116 -67.262756) (xy 283.378656 -67.262756)
			(xy 283.387672 -67.262387) (xy 283.404589 -67.256149) (xy 283.411676 -67.250564) (xy 283.411676 -67.25031)
			(xy 283.41193 -67.25031) (xy 283.432879 -67.232692) (xy 283.478847 -67.202976) (xy 283.52859 -67.180136)
			(xy 283.581087 -67.16464) (xy 283.63526 -67.156807) (xy 283.662628 -67.15633) (xy 283.689881 -67.156742)
			(xy 283.743831 -67.164502) (xy 283.796127 -67.179861) (xy 283.845706 -67.202506) (xy 283.891557 -67.231976)
			(xy 283.932748 -67.267671) (xy 283.96844 -67.308865) (xy 283.997907 -67.354719) (xy 284.020548 -67.404299)
			(xy 284.035904 -67.456597) (xy 284.04366 -67.510547) (xy 284.04366 -67.565053) (xy 284.035904 -67.619003)
			(xy 284.020548 -67.671301) (xy 283.997907 -67.720881) (xy 283.96844 -67.766735) (xy 283.932748 -67.807929)
			(xy 283.891557 -67.843624) (xy 283.845706 -67.873094) (xy 283.796127 -67.895739) (xy 283.743831 -67.911098)
			(xy 283.689881 -67.918858) (xy 283.662628 -67.919346) (xy 283.635258 -67.918877) (xy 283.581078 -67.911062)
			(xy 283.528575 -67.895574) (xy 283.478828 -67.872733) (xy 283.432861 -67.843008) (xy 283.41193 -67.825366)
			(xy 283.411676 -67.825112) (xy 283.4046 -67.819511) (xy 283.387675 -67.813272) (xy 283.378656 -67.81292)
			(xy 283.3116 -67.81292) (xy 283.302583 -67.813273) (xy 283.285665 -67.819523) (xy 283.27858 -67.825112)
			(xy 283.27858 -67.825366) (xy 283.278326 -67.825366) (xy 283.257391 -67.843001) (xy 283.211419 -67.872715)
			(xy 283.161673 -67.895552) (xy 283.109172 -67.911044) (xy 283.054997 -67.918872) (xy 283.027628 -67.919346)
			(xy 283.000377 -67.918809) (xy 282.946428 -67.911056) (xy 282.894132 -67.895704) (xy 282.844553 -67.873065)
			(xy 282.798701 -67.843601) (xy 282.757509 -67.807911) (xy 282.721816 -67.766721) (xy 282.692348 -67.720871)
			(xy 282.669706 -67.671294) (xy 282.65435 -67.618999) (xy 282.646593 -67.565051) (xy 280.3083 -67.565051)
			(xy 280.308303 -67.56507) (xy 280.308812 -67.592956) (xy 280.308303 -67.620842) (xy 280.300183 -67.676018)
			(xy 280.284115 -67.729425) (xy 280.260443 -67.779922) (xy 280.22967 -67.826435) (xy 280.192453 -67.867972)
			(xy 280.149585 -67.903647) (xy 280.101979 -67.932701) (xy 280.05065 -67.954513) (xy 279.996693 -67.968619)
			(xy 279.941256 -67.974719) (xy 279.885522 -67.972682) (xy 279.830679 -67.962552) (xy 279.777895 -67.944545)
			(xy 279.728295 -67.919044) (xy 279.682937 -67.886593) (xy 279.642788 -67.847884) (xy 279.608702 -67.803741)
			(xy 279.581406 -67.755106) (xy 279.561483 -67.703015) (xy 279.549357 -67.648578) (xy 279.545286 -67.592956)
			(xy 279.030194 -67.592956) (xy 279.026119 -67.620646) (xy 279.010051 -67.674053) (xy 278.986379 -67.72455)
			(xy 278.955606 -67.771063) (xy 278.918389 -67.8126) (xy 278.875521 -67.848275) (xy 278.827915 -67.877329)
			(xy 278.776586 -67.899141) (xy 278.722629 -67.913247) (xy 278.667192 -67.919347) (xy 278.611458 -67.91731)
			(xy 278.556615 -67.90718) (xy 278.503831 -67.889173) (xy 278.454231 -67.863672) (xy 278.408873 -67.831221)
			(xy 278.368724 -67.792512) (xy 278.334638 -67.748369) (xy 278.307342 -67.699734) (xy 278.287419 -67.647643)
			(xy 278.275293 -67.593206) (xy 278.271222 -67.537584) (xy 277.738956 -67.537584) (xy 277.734021 -67.571116)
			(xy 277.717953 -67.624523) (xy 277.694281 -67.67502) (xy 277.663508 -67.721533) (xy 277.626291 -67.76307)
			(xy 277.583423 -67.798745) (xy 277.535817 -67.827799) (xy 277.484488 -67.849611) (xy 277.430531 -67.863717)
			(xy 277.375094 -67.869817) (xy 277.31936 -67.86778) (xy 277.264517 -67.85765) (xy 277.211733 -67.839643)
			(xy 277.162133 -67.814142) (xy 277.116775 -67.781691) (xy 277.076626 -67.742982) (xy 277.04254 -67.698839)
			(xy 277.015244 -67.650204) (xy 276.995321 -67.598113) (xy 276.983195 -67.543676) (xy 276.979124 -67.488054)
			(xy 270.998696 -67.488054) (xy 270.998696 -68.586604) (xy 274.825206 -68.586604) (xy 274.825673 -68.559234)
			(xy 274.83349 -68.505055) (xy 274.848979 -68.452552) (xy 274.871821 -68.402805) (xy 274.901545 -68.356838)
			(xy 274.919186 -68.335906) (xy 274.91944 -68.335652) (xy 274.925016 -68.328558) (xy 274.931268 -68.311647)
			(xy 274.931632 -68.302632) (xy 274.931632 -68.235576) (xy 274.93128 -68.226559) (xy 274.925028 -68.209642)
			(xy 274.91944 -68.202556) (xy 274.919186 -68.202556) (xy 274.919186 -68.202302) (xy 274.901532 -68.181382)
			(xy 274.871823 -68.135406) (xy 274.84899 -68.085655) (xy 274.833503 -68.033152) (xy 274.825678 -67.978974)
			(xy 274.825206 -67.951604) (xy 274.825659 -67.924351) (xy 274.833416 -67.870399) (xy 274.848772 -67.8181)
			(xy 274.871415 -67.768519) (xy 274.900884 -67.722665) (xy 274.936579 -67.681472) (xy 274.977773 -67.645778)
			(xy 275.023627 -67.61631) (xy 275.073209 -67.593669) (xy 275.125508 -67.578314) (xy 275.179461 -67.570558)
			(xy 275.206714 -67.570096) (xy 275.233028 -67.570555) (xy 275.285157 -67.577792) (xy 275.3358 -67.592113)
			(xy 275.383999 -67.613247) (xy 275.428842 -67.640794) (xy 275.469482 -67.674234) (xy 275.487638 -67.693286)
			(xy 275.495145 -67.700704) (xy 275.514436 -67.70922) (xy 275.524976 -67.709796) (xy 275.599652 -67.709796)
			(xy 275.6102 -67.709256) (xy 275.629496 -67.700729) (xy 275.63699 -67.693286) (xy 275.655155 -67.67424)
			(xy 275.695783 -67.640782) (xy 275.740621 -67.613222) (xy 275.78882 -67.592082) (xy 275.839466 -67.577763)
			(xy 275.891598 -67.570536) (xy 275.917914 -67.570096) (xy 275.945284 -67.570555) (xy 275.999464 -67.578375)
			(xy 276.051967 -67.593865) (xy 276.101714 -67.616709) (xy 276.14768 -67.646434) (xy 276.168612 -67.664076)
			(xy 276.168866 -67.66433) (xy 276.175956 -67.669912) (xy 276.19287 -67.67616) (xy 276.201886 -67.676522)
			(xy 276.268942 -67.676522) (xy 276.277956 -67.676133) (xy 276.294873 -67.669907) (xy 276.301962 -67.66433)
			(xy 276.301962 -67.664076) (xy 276.302216 -67.664076) (xy 276.323166 -67.646459) (xy 276.369134 -67.616745)
			(xy 276.418877 -67.593905) (xy 276.471374 -67.578409) (xy 276.525546 -67.570574) (xy 276.552914 -67.570096)
			(xy 276.580166 -67.570565) (xy 276.634114 -67.578323) (xy 276.68641 -67.59368) (xy 276.735987 -67.616323)
			(xy 276.781838 -67.645792) (xy 276.823028 -67.681485) (xy 276.858719 -67.722677) (xy 276.888185 -67.768529)
			(xy 276.910826 -67.818107) (xy 276.926181 -67.870403) (xy 276.933937 -67.924352) (xy 276.934422 -67.951604)
			(xy 276.933977 -67.978975) (xy 276.926157 -68.033156) (xy 276.910664 -68.08566) (xy 276.887817 -68.135407)
			(xy 276.858087 -68.181372) (xy 276.840442 -68.202302) (xy 276.840188 -68.202556) (xy 276.834612 -68.20965)
			(xy 276.828359 -68.226561) (xy 276.827996 -68.235576) (xy 276.827996 -68.302632) (xy 276.828339 -68.31165)
			(xy 276.834596 -68.328567) (xy 276.840188 -68.335652) (xy 276.840442 -68.335652) (xy 276.840442 -68.335906)
			(xy 276.858104 -68.356819) (xy 276.887811 -68.402798) (xy 276.910642 -68.45255) (xy 276.926128 -68.505055)
			(xy 276.933951 -68.559234) (xy 276.934422 -68.586604) (xy 276.933926 -68.613855) (xy 276.926169 -68.667801)
			(xy 276.910814 -68.720095) (xy 276.894175 -68.75653) (xy 280.37028 -68.75653) (xy 280.370744 -68.729159)
			(xy 280.378559 -68.67498) (xy 280.394048 -68.622476) (xy 280.416891 -68.572729) (xy 280.446617 -68.526763)
			(xy 280.46426 -68.505832) (xy 280.464514 -68.505578) (xy 280.470117 -68.498503) (xy 280.476354 -68.481577)
			(xy 280.476706 -68.472558) (xy 280.476706 -68.405502) (xy 280.476347 -68.396485) (xy 280.470101 -68.379568)
			(xy 280.464514 -68.372482) (xy 280.46426 -68.372482) (xy 280.46426 -68.372228) (xy 280.446614 -68.351302)
			(xy 280.416904 -68.305327) (xy 280.39407 -68.255578) (xy 280.378581 -68.203076) (xy 280.370753 -68.148899)
			(xy 280.37028 -68.12153) (xy 280.370783 -68.094278) (xy 280.378536 -68.04033) (xy 280.393887 -67.988033)
			(xy 280.416526 -67.938454) (xy 280.445989 -67.892601) (xy 280.481679 -67.851409) (xy 280.522868 -67.815714)
			(xy 280.568717 -67.786246) (xy 280.618294 -67.763602) (xy 280.670588 -67.748245) (xy 280.724536 -67.740486)
			(xy 280.751788 -67.740022) (xy 280.779158 -67.74049) (xy 280.833337 -67.748306) (xy 280.885841 -67.763795)
			(xy 280.935588 -67.786636) (xy 280.981554 -67.816361) (xy 281.002486 -67.834002) (xy 281.00274 -67.834256)
			(xy 281.009835 -67.83983) (xy 281.026745 -67.846083) (xy 281.03576 -67.846448) (xy 281.102816 -67.846448)
			(xy 281.111835 -67.84611) (xy 281.128752 -67.83985) (xy 281.135836 -67.834256) (xy 281.135836 -67.834002)
			(xy 281.13609 -67.834002) (xy 281.157015 -67.816354) (xy 281.20299 -67.786644) (xy 281.252739 -67.763809)
			(xy 281.305241 -67.74832) (xy 281.359418 -67.740495) (xy 281.386788 -67.740022) (xy 281.413102 -67.74049)
			(xy 281.465231 -67.747724) (xy 281.515874 -67.762042) (xy 281.564073 -67.783175) (xy 281.608916 -67.810721)
			(xy 281.649556 -67.84416) (xy 281.667712 -67.863212) (xy 281.675226 -67.870623) (xy 281.694512 -67.879142)
			(xy 281.70505 -67.879722) (xy 281.779726 -67.879722) (xy 281.790272 -67.87916) (xy 281.809567 -67.870647)
			(xy 281.817064 -67.863212) (xy 281.835198 -67.844135) (xy 281.875832 -67.810679) (xy 281.920677 -67.783123)
			(xy 281.968882 -67.761988) (xy 282.019533 -67.747676) (xy 282.071671 -67.740457) (xy 282.097988 -67.740022)
			(xy 282.125242 -67.740467) (xy 282.179195 -67.748223) (xy 282.231495 -67.763579) (xy 282.281077 -67.786222)
			(xy 282.326932 -67.815692) (xy 282.368125 -67.851387) (xy 282.403819 -67.892583) (xy 282.433287 -67.938439)
			(xy 282.455928 -67.988022) (xy 282.471281 -68.040323) (xy 282.479035 -68.094276) (xy 282.479496 -68.12153)
			(xy 282.479048 -68.148901) (xy 282.471226 -68.203081) (xy 282.455733 -68.255584) (xy 282.432887 -68.305331)
			(xy 282.403159 -68.351297) (xy 282.385516 -68.372228) (xy 282.385262 -68.372482) (xy 282.379673 -68.379566)
			(xy 282.373429 -68.396485) (xy 282.37307 -68.405502) (xy 282.37307 -68.472558) (xy 282.373454 -68.481572)
			(xy 282.379683 -68.498489) (xy 282.385262 -68.505578) (xy 282.385516 -68.505578) (xy 282.385516 -68.505832)
			(xy 282.403139 -68.526777) (xy 282.432853 -68.572746) (xy 282.455692 -68.622491) (xy 282.471186 -68.674988)
			(xy 282.479019 -68.729162) (xy 282.479496 -68.75653) (xy 282.47905 -68.783783) (xy 282.471289 -68.837732)
			(xy 282.45593 -68.890029) (xy 282.433284 -68.939607) (xy 282.403814 -68.985457) (xy 282.368118 -69.026648)
			(xy 282.326924 -69.062339) (xy 282.28107 -69.091804) (xy 282.231489 -69.114444) (xy 282.179191 -69.129798)
			(xy 282.125241 -69.137553) (xy 282.097988 -69.138038) (xy 282.071673 -69.137598) (xy 282.019542 -69.130361)
			(xy 281.968898 -69.116037) (xy 281.920699 -69.0949) (xy 281.875856 -69.067348) (xy 281.835219 -69.033903)
			(xy 281.817064 -69.014848) (xy 281.809551 -69.007436) (xy 281.790265 -68.998916) (xy 281.779726 -68.998338)
			(xy 281.70505 -68.998338) (xy 281.6945 -68.998869) (xy 281.675204 -69.007402) (xy 281.667712 -69.014848)
			(xy 281.649553 -69.0339) (xy 281.608923 -69.067356) (xy 281.564083 -69.094914) (xy 281.515883 -69.116053)
			(xy 281.465237 -69.130371) (xy 281.413104 -69.137598) (xy 281.386788 -69.138038) (xy 281.359417 -69.137594)
			(xy 281.305236 -69.129773) (xy 281.252732 -69.11428) (xy 281.202986 -69.091433) (xy 281.15702 -69.061702)
			(xy 281.13609 -69.044058) (xy 281.135836 -69.043804) (xy 281.128743 -69.038227) (xy 281.111831 -69.031974)
			(xy 281.102816 -69.031612) (xy 281.03576 -69.031612) (xy 281.026741 -69.031947) (xy 281.009824 -69.03821)
			(xy 281.00274 -69.043804) (xy 281.00274 -69.044058) (xy 281.002486 -69.044058) (xy 280.981527 -69.061664)
			(xy 280.935562 -69.091382) (xy 280.885822 -69.114225) (xy 280.833327 -69.129724) (xy 280.779155 -69.13756)
			(xy 280.751788 -69.138038) (xy 280.724538 -69.137533) (xy 280.670592 -69.129776) (xy 280.6183 -69.114421)
			(xy 280.568724 -69.091781) (xy 280.522876 -69.062316) (xy 280.481686 -69.026626) (xy 280.445995 -68.985439)
			(xy 280.416528 -68.939591) (xy 280.393885 -68.890017) (xy 280.378528 -68.837725) (xy 280.370768 -68.78378)
			(xy 280.37028 -68.75653) (xy 276.894175 -68.75653) (xy 276.888174 -68.769671) (xy 276.858708 -68.815521)
			(xy 276.823018 -68.856711) (xy 276.781829 -68.892402) (xy 276.73598 -68.921869) (xy 276.686404 -68.944511)
			(xy 276.634111 -68.959867) (xy 276.580165 -68.967625) (xy 276.552914 -68.968112) (xy 276.525544 -68.967635)
			(xy 276.471366 -68.959819) (xy 276.418863 -68.944333) (xy 276.369116 -68.921493) (xy 276.323148 -68.891772)
			(xy 276.302216 -68.874132) (xy 276.301962 -68.873878) (xy 276.294864 -68.868309) (xy 276.277956 -68.862052)
			(xy 276.268942 -68.861686) (xy 276.201886 -68.861686) (xy 276.192869 -68.86204) (xy 276.175952 -68.86829)
			(xy 276.168866 -68.873878) (xy 276.168866 -68.874132) (xy 276.168612 -68.874132) (xy 276.14769 -68.891784)
			(xy 276.101714 -68.921493) (xy 276.051964 -68.944326) (xy 275.999461 -68.959814) (xy 275.945284 -68.967639)
			(xy 275.917914 -68.968112) (xy 275.891601 -68.967631) (xy 275.839473 -68.960399) (xy 275.78883 -68.946082)
			(xy 275.740631 -68.924952) (xy 275.695788 -68.897408) (xy 275.655147 -68.863972) (xy 275.63699 -68.844922)
			(xy 275.629471 -68.837517) (xy 275.610189 -68.828994) (xy 275.599652 -68.828412) (xy 275.524976 -68.828412)
			(xy 275.514429 -68.828965) (xy 275.495133 -68.837483) (xy 275.487638 -68.844922) (xy 275.46951 -68.864005)
			(xy 275.428874 -68.897459) (xy 275.384028 -68.925014) (xy 275.335822 -68.946147) (xy 275.285169 -68.960459)
			(xy 275.233032 -68.967677) (xy 275.206714 -68.968112) (xy 275.179462 -68.967632) (xy 275.125512 -68.959877)
			(xy 275.073214 -68.944523) (xy 275.023634 -68.921882) (xy 274.977781 -68.892416) (xy 274.936589 -68.856724)
			(xy 274.900895 -68.815533) (xy 274.871427 -68.769681) (xy 274.848784 -68.720103) (xy 274.833427 -68.667806)
			(xy 274.82567 -68.613856) (xy 274.825206 -68.586604) (xy 270.998696 -68.586604) (xy 270.998696 -71.555864)
			(xy 277.394414 -71.555864) (xy 277.398485 -71.500242) (xy 277.410611 -71.445805) (xy 277.430534 -71.393714)
			(xy 277.45783 -71.345079) (xy 277.491916 -71.300936) (xy 277.532065 -71.262227) (xy 277.577423 -71.229776)
			(xy 277.627023 -71.204275) (xy 277.679807 -71.186268) (xy 277.73465 -71.176138) (xy 277.790384 -71.174101)
			(xy 277.845821 -71.180201) (xy 277.899778 -71.194307) (xy 277.951107 -71.216119) (xy 277.998713 -71.245173)
			(xy 278.041581 -71.280848) (xy 278.078798 -71.322385) (xy 278.109571 -71.368898) (xy 278.133243 -71.419395)
			(xy 278.149311 -71.472802) (xy 278.157431 -71.527978) (xy 278.15794 -71.555864) (xy 278.157431 -71.58375)
			(xy 278.151592 -71.623428) (xy 278.903428 -71.623428) (xy 278.907499 -71.567806) (xy 278.919625 -71.513369)
			(xy 278.939548 -71.461278) (xy 278.966844 -71.412643) (xy 279.00093 -71.3685) (xy 279.041079 -71.329791)
			(xy 279.086437 -71.29734) (xy 279.136037 -71.271839) (xy 279.188821 -71.253832) (xy 279.243664 -71.243702)
			(xy 279.299398 -71.241665) (xy 279.354835 -71.247765) (xy 279.408792 -71.261871) (xy 279.460121 -71.283683)
			(xy 279.507727 -71.312737) (xy 279.550595 -71.348412) (xy 279.587812 -71.389949) (xy 279.618585 -71.436462)
			(xy 279.642257 -71.486959) (xy 279.658325 -71.540366) (xy 279.666445 -71.595542) (xy 279.666954 -71.623428)
			(xy 279.666445 -71.651314) (xy 279.658325 -71.70649) (xy 279.642257 -71.759897) (xy 279.618585 -71.810394)
			(xy 279.587812 -71.856907) (xy 279.550595 -71.898444) (xy 279.507727 -71.934119) (xy 279.460121 -71.963173)
			(xy 279.408792 -71.984985) (xy 279.354835 -71.999091) (xy 279.299398 -72.005191) (xy 279.243664 -72.003154)
			(xy 279.188821 -71.993024) (xy 279.136037 -71.975017) (xy 279.086437 -71.949516) (xy 279.041079 -71.917065)
			(xy 279.00093 -71.878356) (xy 278.966844 -71.834213) (xy 278.939548 -71.785578) (xy 278.919625 -71.733487)
			(xy 278.907499 -71.67905) (xy 278.903428 -71.623428) (xy 278.151592 -71.623428) (xy 278.149311 -71.638926)
			(xy 278.133243 -71.692333) (xy 278.109571 -71.74283) (xy 278.078798 -71.789343) (xy 278.041581 -71.83088)
			(xy 277.998713 -71.866555) (xy 277.951107 -71.895609) (xy 277.899778 -71.917421) (xy 277.845821 -71.931527)
			(xy 277.790384 -71.937627) (xy 277.73465 -71.93559) (xy 277.679807 -71.92546) (xy 277.627023 -71.907453)
			(xy 277.577423 -71.881952) (xy 277.532065 -71.849501) (xy 277.491916 -71.810792) (xy 277.45783 -71.766649)
			(xy 277.430534 -71.718014) (xy 277.410611 -71.665923) (xy 277.398485 -71.611486) (xy 277.394414 -71.555864)
			(xy 270.998696 -71.555864) (xy 270.998696 -73.938384) (xy 270.998867 -73.944393) (xy 271.001698 -73.956071)
			(xy 271.004284 -73.961498) (xy 271.006122 -73.964973) (xy 271.010713 -73.971355) (xy 271.013428 -73.974198)
			(xy 274.213066 -77.173836) (xy 274.215915 -77.176545) (xy 274.22229 -77.181144) (xy 274.225766 -77.18298)
			(xy 274.231193 -77.185562) (xy 274.242873 -77.188381) (xy 274.24888 -77.188568) (xy 277.142194 -77.188568)
			(xy 277.168216 -77.189099) (xy 277.219616 -77.197272) (xy 277.269108 -77.213372) (xy 277.315479 -77.237003)
			(xy 277.357591 -77.267586) (xy 277.376382 -77.285596) (xy 278.473154 -78.382368) (xy 278.491268 -78.401148)
			(xy 278.521953 -78.443344) (xy 278.545653 -78.489825) (xy 278.561782 -78.539444) (xy 278.569942 -78.590977)
			(xy 278.570436 -78.617064) (xy 278.570436 -83.23707) (xy 281.247848 -83.23707) (xy 281.251919 -83.181448)
			(xy 281.264045 -83.127011) (xy 281.283968 -83.07492) (xy 281.311264 -83.026285) (xy 281.34535 -82.982142)
			(xy 281.385499 -82.943433) (xy 281.430857 -82.910982) (xy 281.480457 -82.885481) (xy 281.533241 -82.867474)
			(xy 281.588084 -82.857344) (xy 281.643818 -82.855307) (xy 281.699255 -82.861407) (xy 281.753212 -82.875513)
			(xy 281.804541 -82.897325) (xy 281.852147 -82.926379) (xy 281.895015 -82.962054) (xy 281.932232 -83.003591)
			(xy 281.963005 -83.050104) (xy 281.986677 -83.100601) (xy 282.002745 -83.154008) (xy 282.010865 -83.209184)
			(xy 282.011374 -83.23707) (xy 282.010865 -83.264956) (xy 282.002745 -83.320132) (xy 281.986677 -83.373539)
			(xy 281.963005 -83.424036) (xy 281.932232 -83.470549) (xy 281.895015 -83.512086) (xy 281.852147 -83.547761)
			(xy 281.822262 -83.566) (xy 282.827982 -83.566) (xy 282.832053 -83.510378) (xy 282.844179 -83.455941)
			(xy 282.864102 -83.40385) (xy 282.891398 -83.355215) (xy 282.925484 -83.311072) (xy 282.965633 -83.272363)
			(xy 283.010991 -83.239912) (xy 283.060591 -83.214411) (xy 283.113375 -83.196404) (xy 283.168218 -83.186274)
			(xy 283.223952 -83.184237) (xy 283.279389 -83.190337) (xy 283.333346 -83.204443) (xy 283.384675 -83.226255)
			(xy 283.432281 -83.255309) (xy 283.475149 -83.290984) (xy 283.512366 -83.332521) (xy 283.543139 -83.379034)
			(xy 283.566811 -83.429531) (xy 283.582879 -83.482938) (xy 283.590999 -83.538114) (xy 283.591508 -83.566)
			(xy 283.590999 -83.593886) (xy 283.582879 -83.649062) (xy 283.566811 -83.702469) (xy 283.543139 -83.752966)
			(xy 283.512366 -83.799479) (xy 283.475149 -83.841016) (xy 283.432281 -83.876691) (xy 283.384675 -83.905745)
			(xy 283.333346 -83.927557) (xy 283.279389 -83.941663) (xy 283.223952 -83.947763) (xy 283.168218 -83.945726)
			(xy 283.113375 -83.935596) (xy 283.060591 -83.917589) (xy 283.010991 -83.892088) (xy 282.965633 -83.859637)
			(xy 282.925484 -83.820928) (xy 282.891398 -83.776785) (xy 282.864102 -83.72815) (xy 282.844179 -83.676059)
			(xy 282.832053 -83.621622) (xy 282.827982 -83.566) (xy 281.822262 -83.566) (xy 281.804541 -83.576815)
			(xy 281.753212 -83.598627) (xy 281.699255 -83.612733) (xy 281.643818 -83.618833) (xy 281.588084 -83.616796)
			(xy 281.533241 -83.606666) (xy 281.480457 -83.588659) (xy 281.430857 -83.563158) (xy 281.385499 -83.530707)
			(xy 281.34535 -83.491998) (xy 281.311264 -83.447855) (xy 281.283968 -83.39922) (xy 281.264045 -83.347129)
			(xy 281.251919 -83.292692) (xy 281.247848 -83.23707) (xy 278.570436 -83.23707) (xy 278.570436 -84.836)
			(xy 282.827982 -84.836) (xy 282.832053 -84.780378) (xy 282.844179 -84.725941) (xy 282.864102 -84.67385)
			(xy 282.891398 -84.625215) (xy 282.925484 -84.581072) (xy 282.965633 -84.542363) (xy 283.010991 -84.509912)
			(xy 283.060591 -84.484411) (xy 283.113375 -84.466404) (xy 283.168218 -84.456274) (xy 283.223952 -84.454237)
			(xy 283.279389 -84.460337) (xy 283.333346 -84.474443) (xy 283.384675 -84.496255) (xy 283.432281 -84.525309)
			(xy 283.475149 -84.560984) (xy 283.512366 -84.602521) (xy 283.543139 -84.649034) (xy 283.566811 -84.699531)
			(xy 283.582879 -84.752938) (xy 283.590999 -84.808114) (xy 283.591508 -84.836) (xy 283.590999 -84.863886)
			(xy 283.582879 -84.919062) (xy 283.566811 -84.972469) (xy 283.543139 -85.022966) (xy 283.512366 -85.069479)
			(xy 283.475149 -85.111016) (xy 283.432281 -85.146691) (xy 283.384675 -85.175745) (xy 283.333346 -85.197557)
			(xy 283.279389 -85.211663) (xy 283.223952 -85.217763) (xy 283.168218 -85.215726) (xy 283.113375 -85.205596)
			(xy 283.060591 -85.187589) (xy 283.010991 -85.162088) (xy 282.965633 -85.129637) (xy 282.925484 -85.090928)
			(xy 282.891398 -85.046785) (xy 282.864102 -84.99815) (xy 282.844179 -84.946059) (xy 282.832053 -84.891622)
			(xy 282.827982 -84.836) (xy 278.570436 -84.836) (xy 278.570436 -85.40242) (xy 288.626802 -85.40242)
			(xy 288.630873 -85.346798) (xy 288.642999 -85.292361) (xy 288.662922 -85.24027) (xy 288.690218 -85.191635)
			(xy 288.724304 -85.147492) (xy 288.764453 -85.108783) (xy 288.809811 -85.076332) (xy 288.859411 -85.050831)
			(xy 288.912195 -85.032824) (xy 288.967038 -85.022694) (xy 289.022772 -85.020657) (xy 289.078209 -85.026757)
			(xy 289.132166 -85.040863) (xy 289.183495 -85.062675) (xy 289.231101 -85.091729) (xy 289.273969 -85.127404)
			(xy 289.311186 -85.168941) (xy 289.341959 -85.215454) (xy 289.365631 -85.265951) (xy 289.381699 -85.319358)
			(xy 289.389819 -85.374534) (xy 289.390328 -85.40242) (xy 289.389819 -85.430306) (xy 289.388316 -85.44052)
			(xy 299.277276 -85.44052) (xy 299.281347 -85.384898) (xy 299.293473 -85.330461) (xy 299.313396 -85.27837)
			(xy 299.340692 -85.229735) (xy 299.374778 -85.185592) (xy 299.414927 -85.146883) (xy 299.460285 -85.114432)
			(xy 299.509885 -85.088931) (xy 299.562669 -85.070924) (xy 299.617512 -85.060794) (xy 299.673246 -85.058757)
			(xy 299.728683 -85.064857) (xy 299.78264 -85.078963) (xy 299.833969 -85.100775) (xy 299.881575 -85.129829)
			(xy 299.924443 -85.165504) (xy 299.96166 -85.207041) (xy 299.992433 -85.253554) (xy 300.016105 -85.304051)
			(xy 300.032173 -85.357458) (xy 300.040293 -85.412634) (xy 300.040802 -85.44052) (xy 300.040293 -85.468406)
			(xy 300.032173 -85.523582) (xy 300.016105 -85.576989) (xy 299.992433 -85.627486) (xy 299.96166 -85.673999)
			(xy 299.924443 -85.715536) (xy 299.881575 -85.751211) (xy 299.833969 -85.780265) (xy 299.78264 -85.802077)
			(xy 299.728683 -85.816183) (xy 299.673246 -85.822283) (xy 299.617512 -85.820246) (xy 299.562669 -85.810116)
			(xy 299.509885 -85.792109) (xy 299.460285 -85.766608) (xy 299.414927 -85.734157) (xy 299.374778 -85.695448)
			(xy 299.340692 -85.651305) (xy 299.313396 -85.60267) (xy 299.293473 -85.550579) (xy 299.281347 -85.496142)
			(xy 299.277276 -85.44052) (xy 289.388316 -85.44052) (xy 289.381699 -85.485482) (xy 289.365631 -85.538889)
			(xy 289.341959 -85.589386) (xy 289.311186 -85.635899) (xy 289.273969 -85.677436) (xy 289.231101 -85.713111)
			(xy 289.183495 -85.742165) (xy 289.132166 -85.763977) (xy 289.078209 -85.778083) (xy 289.022772 -85.784183)
			(xy 288.967038 -85.782146) (xy 288.912195 -85.772016) (xy 288.859411 -85.754009) (xy 288.809811 -85.728508)
			(xy 288.764453 -85.696057) (xy 288.724304 -85.657348) (xy 288.690218 -85.613205) (xy 288.662922 -85.56457)
			(xy 288.642999 -85.512479) (xy 288.630873 -85.458042) (xy 288.626802 -85.40242) (xy 278.570436 -85.40242)
			(xy 278.570436 -86.08314) (xy 278.570436 -86.084156) (xy 278.570935 -86.092677) (xy 278.576866 -86.108673)
			(xy 278.587717 -86.121837) (xy 278.59482 -86.126574) (xy 278.603456 -86.1314) (xy 278.607266 -86.133686)
			(xy 278.60752 -86.133686) (xy 278.62022 -86.141052) (xy 278.620728 -86.141052) (xy 278.62403 -86.143338)
			(xy 278.624792 -86.143846) (xy 278.628602 -86.146894) (xy 278.635968 -86.153244) (xy 278.638254 -86.155276)
			(xy 278.662892 -86.16061) (xy 278.6634 -86.160356) (xy 278.66467 -86.160102) (xy 278.691848 -86.152482)
			(xy 278.697182 -86.149434) (xy 278.722324 -86.135715) (xy 278.775779 -86.115152) (xy 278.83171 -86.102825)
			(xy 278.86025 -86.100412) (xy 278.863298 -86.100412) (xy 278.864314 -86.100158) (xy 278.866346 -86.100158)
			(xy 278.868124 -86.099904) (xy 278.87422 -86.099904) (xy 278.876506 -86.09965) (xy 278.887428 -86.09965)
			(xy 278.914611 -86.10024) (xy 278.953665 -86.106) (xy 282.827982 -86.106) (xy 282.832053 -86.050378)
			(xy 282.844179 -85.995941) (xy 282.864102 -85.94385) (xy 282.891398 -85.895215) (xy 282.925484 -85.851072)
			(xy 282.965633 -85.812363) (xy 283.010991 -85.779912) (xy 283.060591 -85.754411) (xy 283.113375 -85.736404)
			(xy 283.168218 -85.726274) (xy 283.223952 -85.724237) (xy 283.279389 -85.730337) (xy 283.333346 -85.744443)
			(xy 283.384675 -85.766255) (xy 283.432281 -85.795309) (xy 283.475149 -85.830984) (xy 283.512366 -85.872521)
			(xy 283.543139 -85.919034) (xy 283.566811 -85.969531) (xy 283.582879 -86.022938) (xy 283.590999 -86.078114)
			(xy 283.591508 -86.106) (xy 283.590999 -86.133886) (xy 283.589571 -86.143592) (xy 290.59708 -86.143592)
			(xy 290.601151 -86.08797) (xy 290.613277 -86.033533) (xy 290.6332 -85.981442) (xy 290.660496 -85.932807)
			(xy 290.694582 -85.888664) (xy 290.734731 -85.849955) (xy 290.780089 -85.817504) (xy 290.829689 -85.792003)
			(xy 290.882473 -85.773996) (xy 290.937316 -85.763866) (xy 290.99305 -85.761829) (xy 291.048487 -85.767929)
			(xy 291.102444 -85.782035) (xy 291.153773 -85.803847) (xy 291.201379 -85.832901) (xy 291.244247 -85.868576)
			(xy 291.281464 -85.910113) (xy 291.312237 -85.956626) (xy 291.335909 -86.007123) (xy 291.351977 -86.06053)
			(xy 291.360097 -86.115706) (xy 291.360606 -86.143592) (xy 291.360097 -86.171478) (xy 291.351977 -86.226654)
			(xy 291.335909 -86.280061) (xy 291.312237 -86.330558) (xy 291.281464 -86.377071) (xy 291.244247 -86.418608)
			(xy 291.201379 -86.454283) (xy 291.153773 -86.483337) (xy 291.102444 -86.505149) (xy 291.048487 -86.519255)
			(xy 290.99305 -86.525355) (xy 290.937316 -86.523318) (xy 290.882473 -86.513188) (xy 290.829689 -86.495181)
			(xy 290.780089 -86.46968) (xy 290.734731 -86.437229) (xy 290.694582 -86.39852) (xy 290.660496 -86.354377)
			(xy 290.6332 -86.305742) (xy 290.613277 -86.253651) (xy 290.601151 -86.199214) (xy 290.59708 -86.143592)
			(xy 283.589571 -86.143592) (xy 283.582879 -86.189062) (xy 283.566811 -86.242469) (xy 283.543139 -86.292966)
			(xy 283.512366 -86.339479) (xy 283.475149 -86.381016) (xy 283.432281 -86.416691) (xy 283.384675 -86.445745)
			(xy 283.333346 -86.467557) (xy 283.279389 -86.481663) (xy 283.223952 -86.487763) (xy 283.168218 -86.485726)
			(xy 283.113375 -86.475596) (xy 283.060591 -86.457589) (xy 283.010991 -86.432088) (xy 282.965633 -86.399637)
			(xy 282.925484 -86.360928) (xy 282.891398 -86.316785) (xy 282.864102 -86.26815) (xy 282.844179 -86.216059)
			(xy 282.832053 -86.161622) (xy 282.827982 -86.106) (xy 278.953665 -86.106) (xy 278.968399 -86.108173)
			(xy 279.020517 -86.123662) (xy 279.069907 -86.146392) (xy 279.115571 -86.175903) (xy 279.156584 -86.211598)
			(xy 279.192114 -86.252753) (xy 279.221442 -86.298535) (xy 279.243974 -86.348016) (xy 279.259254 -86.400195)
			(xy 279.266972 -86.454015) (xy 279.266972 -86.498176) (xy 279.88971 -86.498176) (xy 279.893781 -86.442554)
			(xy 279.905907 -86.388117) (xy 279.92583 -86.336026) (xy 279.953126 -86.287391) (xy 279.987212 -86.243248)
			(xy 280.027361 -86.204539) (xy 280.072719 -86.172088) (xy 280.122319 -86.146587) (xy 280.175103 -86.12858)
			(xy 280.229946 -86.11845) (xy 280.28568 -86.116413) (xy 280.341117 -86.122513) (xy 280.395074 -86.136619)
			(xy 280.446403 -86.158431) (xy 280.494009 -86.187485) (xy 280.536877 -86.22316) (xy 280.574094 -86.264697)
			(xy 280.604867 -86.31121) (xy 280.628539 -86.361707) (xy 280.644607 -86.415114) (xy 280.652727 -86.47029)
			(xy 280.653236 -86.498176) (xy 280.652727 -86.526062) (xy 280.644607 -86.581238) (xy 280.628539 -86.634645)
			(xy 280.604867 -86.685142) (xy 280.574094 -86.731655) (xy 280.536877 -86.773192) (xy 280.494009 -86.808867)
			(xy 280.446403 -86.837921) (xy 280.395074 -86.859733) (xy 280.341117 -86.873839) (xy 280.28568 -86.879939)
			(xy 280.229946 -86.877902) (xy 280.175103 -86.867772) (xy 280.122319 -86.849765) (xy 280.072719 -86.824264)
			(xy 280.027361 -86.791813) (xy 279.987212 -86.753104) (xy 279.953126 -86.708961) (xy 279.92583 -86.660326)
			(xy 279.905907 -86.608235) (xy 279.893781 -86.553798) (xy 279.88971 -86.498176) (xy 279.266972 -86.498176)
			(xy 279.266972 -86.508385) (xy 279.259254 -86.562205) (xy 279.243974 -86.614383) (xy 279.221442 -86.663865)
			(xy 279.192114 -86.709647) (xy 279.156584 -86.750802) (xy 279.115572 -86.786496) (xy 279.069908 -86.816008)
			(xy 279.020517 -86.838738) (xy 278.9684 -86.854227) (xy 278.914611 -86.86216) (xy 278.887428 -86.862666)
			(xy 278.885396 -86.862666) (xy 278.861068 -86.862251) (xy 278.812813 -86.856003) (xy 278.765744 -86.843673)
			(xy 278.720623 -86.82546) (xy 278.699214 -86.813898) (xy 278.693626 -86.81085) (xy 278.673814 -86.805516)
			(xy 278.6696 -86.804777) (xy 278.661048 -86.804526) (xy 278.656796 -86.805008) (xy 278.644858 -86.807294)
			(xy 278.635714 -86.812628) (xy 278.634952 -86.813136) (xy 278.59609 -86.835234) (xy 278.588506 -86.839935)
			(xy 278.576966 -86.853529) (xy 278.570798 -86.870261) (xy 278.570436 -86.879176) (xy 278.570436 -89.764616)
			(xy 278.724612 -89.764616) (xy 278.728683 -89.708994) (xy 278.740809 -89.654557) (xy 278.760732 -89.602466)
			(xy 278.788028 -89.553831) (xy 278.822114 -89.509688) (xy 278.862263 -89.470979) (xy 278.907621 -89.438528)
			(xy 278.957221 -89.413027) (xy 279.010005 -89.39502) (xy 279.064848 -89.38489) (xy 279.120582 -89.382853)
			(xy 279.176019 -89.388953) (xy 279.229976 -89.403059) (xy 279.281305 -89.424871) (xy 279.328911 -89.453925)
			(xy 279.371779 -89.4896) (xy 279.408996 -89.531137) (xy 279.439769 -89.57765) (xy 279.463441 -89.628147)
			(xy 279.479509 -89.681554) (xy 279.487629 -89.73673) (xy 279.488138 -89.764616) (xy 279.487674 -89.790016)
			(xy 280.29103 -89.790016) (xy 280.295101 -89.734394) (xy 280.307227 -89.679957) (xy 280.32715 -89.627866)
			(xy 280.354446 -89.579231) (xy 280.388532 -89.535088) (xy 280.428681 -89.496379) (xy 280.474039 -89.463928)
			(xy 280.523639 -89.438427) (xy 280.576423 -89.42042) (xy 280.631266 -89.41029) (xy 280.687 -89.408253)
			(xy 280.742437 -89.414353) (xy 280.796394 -89.428459) (xy 280.847723 -89.450271) (xy 280.895329 -89.479325)
			(xy 280.938197 -89.515) (xy 280.975414 -89.556537) (xy 281.006187 -89.60305) (xy 281.029859 -89.653547)
			(xy 281.045927 -89.706954) (xy 281.054047 -89.76213) (xy 281.054556 -89.790016) (xy 281.054047 -89.817902)
			(xy 281.045927 -89.873078) (xy 281.029859 -89.926485) (xy 281.006187 -89.976982) (xy 280.975414 -90.023495)
			(xy 280.938197 -90.065032) (xy 280.895329 -90.100707) (xy 280.847723 -90.129761) (xy 280.796394 -90.151573)
			(xy 280.742437 -90.165679) (xy 280.687 -90.171779) (xy 280.631266 -90.169742) (xy 280.576423 -90.159612)
			(xy 280.523639 -90.141605) (xy 280.474039 -90.116104) (xy 280.428681 -90.083653) (xy 280.388532 -90.044944)
			(xy 280.354446 -90.000801) (xy 280.32715 -89.952166) (xy 280.307227 -89.900075) (xy 280.295101 -89.845638)
			(xy 280.29103 -89.790016) (xy 279.487674 -89.790016) (xy 279.487629 -89.792502) (xy 279.479509 -89.847678)
			(xy 279.463441 -89.901085) (xy 279.439769 -89.951582) (xy 279.408996 -89.998095) (xy 279.371779 -90.039632)
			(xy 279.328911 -90.075307) (xy 279.281305 -90.104361) (xy 279.229976 -90.126173) (xy 279.176019 -90.140279)
			(xy 279.120582 -90.146379) (xy 279.064848 -90.144342) (xy 279.010005 -90.134212) (xy 278.957221 -90.116205)
			(xy 278.907621 -90.090704) (xy 278.862263 -90.058253) (xy 278.822114 -90.019544) (xy 278.788028 -89.975401)
			(xy 278.760732 -89.926766) (xy 278.740809 -89.874675) (xy 278.728683 -89.820238) (xy 278.724612 -89.764616)
			(xy 278.570436 -89.764616) (xy 278.570436 -89.969086) (xy 278.569951 -89.995174) (xy 278.561786 -90.046706)
			(xy 278.545654 -90.096324) (xy 278.521955 -90.142806) (xy 278.491271 -90.185005) (xy 278.473154 -90.203782)
			(xy 274.357846 -94.31909) (xy 277.453596 -94.31909) (xy 277.457667 -94.263468) (xy 277.469793 -94.209031)
			(xy 277.489716 -94.15694) (xy 277.517012 -94.108305) (xy 277.551098 -94.064162) (xy 277.591247 -94.025453)
			(xy 277.636605 -93.993002) (xy 277.686205 -93.967501) (xy 277.738989 -93.949494) (xy 277.793832 -93.939364)
			(xy 277.849566 -93.937327) (xy 277.905003 -93.943427) (xy 277.95896 -93.957533) (xy 278.010289 -93.979345)
			(xy 278.057895 -94.008399) (xy 278.100763 -94.044074) (xy 278.13798 -94.085611) (xy 278.168753 -94.132124)
			(xy 278.192425 -94.182621) (xy 278.208493 -94.236028) (xy 278.216613 -94.291204) (xy 278.217122 -94.31909)
			(xy 278.216613 -94.346976) (xy 278.208493 -94.402152) (xy 278.192425 -94.455559) (xy 278.168753 -94.506056)
			(xy 278.13798 -94.552569) (xy 278.100763 -94.594106) (xy 278.057895 -94.629781) (xy 278.010289 -94.658835)
			(xy 277.95896 -94.680647) (xy 277.905003 -94.694753) (xy 277.849566 -94.700853) (xy 277.793832 -94.698816)
			(xy 277.738989 -94.688686) (xy 277.686205 -94.670679) (xy 277.636605 -94.645178) (xy 277.591247 -94.612727)
			(xy 277.551098 -94.574018) (xy 277.517012 -94.529875) (xy 277.489716 -94.48124) (xy 277.469793 -94.429149)
			(xy 277.457667 -94.374712) (xy 277.453596 -94.31909) (xy 274.357846 -94.31909) (xy 273.475196 -95.20174)
			(xy 276.739856 -95.20174) (xy 276.743927 -95.146118) (xy 276.756053 -95.091681) (xy 276.775976 -95.03959)
			(xy 276.803272 -94.990955) (xy 276.837358 -94.946812) (xy 276.877507 -94.908103) (xy 276.922865 -94.875652)
			(xy 276.972465 -94.850151) (xy 277.025249 -94.832144) (xy 277.080092 -94.822014) (xy 277.135826 -94.819977)
			(xy 277.191263 -94.826077) (xy 277.24522 -94.840183) (xy 277.296549 -94.861995) (xy 277.344155 -94.891049)
			(xy 277.387023 -94.926724) (xy 277.42424 -94.968261) (xy 277.455013 -95.014774) (xy 277.478685 -95.065271)
			(xy 277.494753 -95.118678) (xy 277.502873 -95.173854) (xy 277.503382 -95.20174) (xy 277.503141 -95.214948)
			(xy 279.474181 -95.214948) (xy 279.478136 -95.123111) (xy 279.489971 -95.031954) (xy 279.509598 -94.942151)
			(xy 279.536872 -94.854369) (xy 279.571592 -94.769255) (xy 279.6135 -94.687442) (xy 279.662286 -94.609534)
			(xy 279.717589 -94.536109) (xy 279.778999 -94.467709) (xy 279.846061 -94.404842) (xy 279.91828 -94.347972)
			(xy 279.99512 -94.297521) (xy 280.076013 -94.253862) (xy 280.160359 -94.217319) (xy 280.247535 -94.188162)
			(xy 280.336894 -94.166608) (xy 280.427775 -94.152814) (xy 280.519506 -94.146884) (xy 280.611407 -94.148862)
			(xy 280.702798 -94.158733) (xy 280.793002 -94.176423) (xy 280.881351 -94.201803) (xy 280.967191 -94.234683)
			(xy 281.049887 -94.274821) (xy 281.128827 -94.32192) (xy 281.203425 -94.37563) (xy 281.273131 -94.435554)
			(xy 281.337426 -94.501248) (xy 281.395837 -94.572226) (xy 281.447929 -94.647963) (xy 281.493318 -94.727898)
			(xy 281.531668 -94.811438) (xy 281.562693 -94.897966) (xy 281.586166 -94.986841) (xy 281.601912 -95.077405)
			(xy 281.609814 -95.168987) (xy 281.610308 -95.214948) (xy 303.839131 -95.214948) (xy 303.843086 -95.123111)
			(xy 303.854921 -95.031954) (xy 303.874548 -94.942151) (xy 303.901822 -94.854369) (xy 303.936542 -94.769255)
			(xy 303.97845 -94.687442) (xy 304.027236 -94.609534) (xy 304.082539 -94.536109) (xy 304.143949 -94.467709)
			(xy 304.211011 -94.404842) (xy 304.28323 -94.347972) (xy 304.36007 -94.297521) (xy 304.440963 -94.253862)
			(xy 304.525309 -94.217319) (xy 304.612485 -94.188162) (xy 304.701844 -94.166608) (xy 304.792725 -94.152814)
			(xy 304.884456 -94.146884) (xy 304.976357 -94.148862) (xy 305.067748 -94.158733) (xy 305.157952 -94.176423)
			(xy 305.246301 -94.201803) (xy 305.332141 -94.234683) (xy 305.414837 -94.274821) (xy 305.493777 -94.32192)
			(xy 305.568375 -94.37563) (xy 305.638081 -94.435554) (xy 305.702376 -94.501248) (xy 305.760787 -94.572226)
			(xy 305.812879 -94.647963) (xy 305.858268 -94.727898) (xy 305.896618 -94.811438) (xy 305.927643 -94.897966)
			(xy 305.951116 -94.986841) (xy 305.966862 -95.077405) (xy 305.974764 -95.168987) (xy 305.975258 -95.214948)
			(xy 305.974764 -95.260909) (xy 305.966862 -95.352491) (xy 305.951116 -95.443055) (xy 305.927643 -95.53193)
			(xy 305.896618 -95.618458) (xy 305.858268 -95.701998) (xy 305.812879 -95.781933) (xy 305.760787 -95.85767)
			(xy 305.702376 -95.928648) (xy 305.642675 -95.989648) (xy 307.763924 -95.989648) (xy 307.767995 -95.934026)
			(xy 307.780121 -95.879589) (xy 307.800044 -95.827498) (xy 307.82734 -95.778863) (xy 307.861426 -95.73472)
			(xy 307.901575 -95.696011) (xy 307.946933 -95.66356) (xy 307.996533 -95.638059) (xy 308.049317 -95.620052)
			(xy 308.10416 -95.609922) (xy 308.159894 -95.607885) (xy 308.215331 -95.613985) (xy 308.269288 -95.628091)
			(xy 308.320617 -95.649903) (xy 308.368223 -95.678957) (xy 308.411091 -95.714632) (xy 308.448308 -95.756169)
			(xy 308.479081 -95.802682) (xy 308.502753 -95.853179) (xy 308.518821 -95.906586) (xy 308.526941 -95.961762)
			(xy 308.52745 -95.989648) (xy 308.526941 -96.017534) (xy 308.518821 -96.07271) (xy 308.502753 -96.126117)
			(xy 308.479081 -96.176614) (xy 308.448308 -96.223127) (xy 308.411091 -96.264664) (xy 308.368223 -96.300339)
			(xy 308.320617 -96.329393) (xy 308.269288 -96.351205) (xy 308.215331 -96.365311) (xy 308.159894 -96.371411)
			(xy 308.10416 -96.369374) (xy 308.049317 -96.359244) (xy 307.996533 -96.341237) (xy 307.946933 -96.315736)
			(xy 307.901575 -96.283285) (xy 307.861426 -96.244576) (xy 307.82734 -96.200433) (xy 307.800044 -96.151798)
			(xy 307.780121 -96.099707) (xy 307.767995 -96.04527) (xy 307.763924 -95.989648) (xy 305.642675 -95.989648)
			(xy 305.638081 -95.994342) (xy 305.568375 -96.054266) (xy 305.493777 -96.107976) (xy 305.414837 -96.155075)
			(xy 305.332141 -96.195213) (xy 305.246301 -96.228093) (xy 305.157952 -96.253473) (xy 305.067748 -96.271163)
			(xy 304.976357 -96.281034) (xy 304.884456 -96.283012) (xy 304.792725 -96.277082) (xy 304.701844 -96.263288)
			(xy 304.612485 -96.241734) (xy 304.525309 -96.212577) (xy 304.440963 -96.176034) (xy 304.36007 -96.132375)
			(xy 304.28323 -96.081924) (xy 304.211011 -96.025054) (xy 304.143949 -95.962187) (xy 304.082539 -95.893787)
			(xy 304.027236 -95.820362) (xy 303.97845 -95.742454) (xy 303.936542 -95.660641) (xy 303.901822 -95.575527)
			(xy 303.874548 -95.487745) (xy 303.854921 -95.397942) (xy 303.843086 -95.306785) (xy 303.839131 -95.214948)
			(xy 281.610308 -95.214948) (xy 281.609814 -95.260909) (xy 281.601912 -95.352491) (xy 281.586166 -95.443055)
			(xy 281.562693 -95.53193) (xy 281.531668 -95.618458) (xy 281.493318 -95.701998) (xy 281.447929 -95.781933)
			(xy 281.395837 -95.85767) (xy 281.337426 -95.928648) (xy 281.273131 -95.994342) (xy 281.203425 -96.054266)
			(xy 281.128827 -96.107976) (xy 281.049887 -96.155075) (xy 280.967191 -96.195213) (xy 280.881351 -96.228093)
			(xy 280.793002 -96.253473) (xy 280.702798 -96.271163) (xy 280.611407 -96.281034) (xy 280.519506 -96.283012)
			(xy 280.427775 -96.277082) (xy 280.336894 -96.263288) (xy 280.247535 -96.241734) (xy 280.160359 -96.212577)
			(xy 280.076013 -96.176034) (xy 279.99512 -96.132375) (xy 279.91828 -96.081924) (xy 279.846061 -96.025054)
			(xy 279.778999 -95.962187) (xy 279.717589 -95.893787) (xy 279.662286 -95.820362) (xy 279.6135 -95.742454)
			(xy 279.571592 -95.660641) (xy 279.536872 -95.575527) (xy 279.509598 -95.487745) (xy 279.489971 -95.397942)
			(xy 279.478136 -95.306785) (xy 279.474181 -95.214948) (xy 277.503141 -95.214948) (xy 277.502873 -95.229626)
			(xy 277.494753 -95.284802) (xy 277.478685 -95.338209) (xy 277.455013 -95.388706) (xy 277.42424 -95.435219)
			(xy 277.387023 -95.476756) (xy 277.344155 -95.512431) (xy 277.296549 -95.541485) (xy 277.24522 -95.563297)
			(xy 277.191263 -95.577403) (xy 277.135826 -95.583503) (xy 277.080092 -95.581466) (xy 277.025249 -95.571336)
			(xy 276.972465 -95.553329) (xy 276.922865 -95.527828) (xy 276.877507 -95.495377) (xy 276.837358 -95.456668)
			(xy 276.803272 -95.412525) (xy 276.775976 -95.36389) (xy 276.756053 -95.311799) (xy 276.743927 -95.257362)
			(xy 276.739856 -95.20174) (xy 273.475196 -95.20174) (xy 271.62125 -97.055686) (xy 283.805374 -97.055686)
			(xy 283.809445 -97.000064) (xy 283.821571 -96.945627) (xy 283.841494 -96.893536) (xy 283.86879 -96.844901)
			(xy 283.902876 -96.800758) (xy 283.943025 -96.762049) (xy 283.988383 -96.729598) (xy 284.037983 -96.704097)
			(xy 284.090767 -96.68609) (xy 284.14561 -96.67596) (xy 284.201344 -96.673923) (xy 284.256781 -96.680023)
			(xy 284.310738 -96.694129) (xy 284.362067 -96.715941) (xy 284.409673 -96.744995) (xy 284.452541 -96.78067)
			(xy 284.489758 -96.822207) (xy 284.520531 -96.86872) (xy 284.535663 -96.901) (xy 301.521874 -96.901)
			(xy 301.525945 -96.845378) (xy 301.538071 -96.790941) (xy 301.557994 -96.73885) (xy 301.58529 -96.690215)
			(xy 301.619376 -96.646072) (xy 301.659525 -96.607363) (xy 301.704883 -96.574912) (xy 301.754483 -96.549411)
			(xy 301.807267 -96.531404) (xy 301.86211 -96.521274) (xy 301.917844 -96.519237) (xy 301.973281 -96.525337)
			(xy 302.027238 -96.539443) (xy 302.078567 -96.561255) (xy 302.126173 -96.590309) (xy 302.169041 -96.625984)
			(xy 302.206258 -96.667521) (xy 302.237031 -96.714034) (xy 302.260703 -96.764531) (xy 302.276771 -96.817938)
			(xy 302.284891 -96.873114) (xy 302.2854 -96.901) (xy 302.284891 -96.928886) (xy 302.276771 -96.984062)
			(xy 302.260703 -97.037469) (xy 302.259546 -97.039938) (xy 306.92547 -97.039938) (xy 306.929541 -96.984316)
			(xy 306.941667 -96.929879) (xy 306.96159 -96.877788) (xy 306.988886 -96.829153) (xy 307.022972 -96.78501)
			(xy 307.063121 -96.746301) (xy 307.108479 -96.71385) (xy 307.158079 -96.688349) (xy 307.210863 -96.670342)
			(xy 307.265706 -96.660212) (xy 307.32144 -96.658175) (xy 307.376877 -96.664275) (xy 307.430834 -96.678381)
			(xy 307.482163 -96.700193) (xy 307.529769 -96.729247) (xy 307.572637 -96.764922) (xy 307.609854 -96.806459)
			(xy 307.640627 -96.852972) (xy 307.664299 -96.903469) (xy 307.680367 -96.956876) (xy 307.688487 -97.012052)
			(xy 307.688996 -97.039938) (xy 307.688487 -97.067824) (xy 307.680367 -97.123) (xy 307.664299 -97.176407)
			(xy 307.640627 -97.226904) (xy 307.609854 -97.273417) (xy 307.572637 -97.314954) (xy 307.529769 -97.350629)
			(xy 307.482163 -97.379683) (xy 307.430834 -97.401495) (xy 307.376877 -97.415601) (xy 307.32144 -97.421701)
			(xy 307.265706 -97.419664) (xy 307.210863 -97.409534) (xy 307.158079 -97.391527) (xy 307.108479 -97.366026)
			(xy 307.063121 -97.333575) (xy 307.022972 -97.294866) (xy 306.988886 -97.250723) (xy 306.96159 -97.202088)
			(xy 306.941667 -97.149997) (xy 306.929541 -97.09556) (xy 306.92547 -97.039938) (xy 302.259546 -97.039938)
			(xy 302.237031 -97.087966) (xy 302.206258 -97.134479) (xy 302.169041 -97.176016) (xy 302.126173 -97.211691)
			(xy 302.078567 -97.240745) (xy 302.027238 -97.262557) (xy 301.973281 -97.276663) (xy 301.917844 -97.282763)
			(xy 301.86211 -97.280726) (xy 301.807267 -97.270596) (xy 301.754483 -97.252589) (xy 301.704883 -97.227088)
			(xy 301.659525 -97.194637) (xy 301.619376 -97.155928) (xy 301.58529 -97.111785) (xy 301.557994 -97.06315)
			(xy 301.538071 -97.011059) (xy 301.525945 -96.956622) (xy 301.521874 -96.901) (xy 284.535663 -96.901)
			(xy 284.544203 -96.919217) (xy 284.560271 -96.972624) (xy 284.568391 -97.0278) (xy 284.5689 -97.055686)
			(xy 284.568391 -97.083572) (xy 284.560271 -97.138748) (xy 284.544203 -97.192155) (xy 284.520531 -97.242652)
			(xy 284.489758 -97.289165) (xy 284.452541 -97.330702) (xy 284.409673 -97.366377) (xy 284.362067 -97.395431)
			(xy 284.310738 -97.417243) (xy 284.256781 -97.431349) (xy 284.201344 -97.437449) (xy 284.14561 -97.435412)
			(xy 284.090767 -97.425282) (xy 284.037983 -97.407275) (xy 283.988383 -97.381774) (xy 283.943025 -97.349323)
			(xy 283.902876 -97.310614) (xy 283.86879 -97.266471) (xy 283.841494 -97.217836) (xy 283.821571 -97.165745)
			(xy 283.809445 -97.111308) (xy 283.805374 -97.055686) (xy 271.62125 -97.055686) (xy 271.036796 -97.64014)
			(xy 306.118004 -97.64014) (xy 306.122075 -97.584518) (xy 306.134201 -97.530081) (xy 306.154124 -97.47799)
			(xy 306.18142 -97.429355) (xy 306.215506 -97.385212) (xy 306.255655 -97.346503) (xy 306.301013 -97.314052)
			(xy 306.350613 -97.288551) (xy 306.403397 -97.270544) (xy 306.45824 -97.260414) (xy 306.513974 -97.258377)
			(xy 306.569411 -97.264477) (xy 306.623368 -97.278583) (xy 306.674697 -97.300395) (xy 306.722303 -97.329449)
			(xy 306.765171 -97.365124) (xy 306.802388 -97.406661) (xy 306.833161 -97.453174) (xy 306.856833 -97.503671)
			(xy 306.872901 -97.557078) (xy 306.881021 -97.612254) (xy 306.88153 -97.64014) (xy 306.881021 -97.668026)
			(xy 306.872901 -97.723202) (xy 306.856833 -97.776609) (xy 306.833161 -97.827106) (xy 306.802388 -97.873619)
			(xy 306.765171 -97.915156) (xy 306.722303 -97.950831) (xy 306.674697 -97.979885) (xy 306.623368 -98.001697)
			(xy 306.569411 -98.015803) (xy 306.513974 -98.021903) (xy 306.45824 -98.019866) (xy 306.403397 -98.009736)
			(xy 306.350613 -97.991729) (xy 306.301013 -97.966228) (xy 306.255655 -97.933777) (xy 306.215506 -97.895068)
			(xy 306.18142 -97.850925) (xy 306.154124 -97.80229) (xy 306.134201 -97.750199) (xy 306.122075 -97.695762)
			(xy 306.118004 -97.64014) (xy 271.036796 -97.64014) (xy 270.505936 -98.171) (xy 307.763924 -98.171)
			(xy 307.767995 -98.115378) (xy 307.780121 -98.060941) (xy 307.800044 -98.00885) (xy 307.82734 -97.960215)
			(xy 307.861426 -97.916072) (xy 307.901575 -97.877363) (xy 307.946933 -97.844912) (xy 307.996533 -97.819411)
			(xy 308.049317 -97.801404) (xy 308.10416 -97.791274) (xy 308.159894 -97.789237) (xy 308.215331 -97.795337)
			(xy 308.269288 -97.809443) (xy 308.320617 -97.831255) (xy 308.368223 -97.860309) (xy 308.411091 -97.895984)
			(xy 308.448308 -97.937521) (xy 308.479081 -97.984034) (xy 308.502753 -98.034531) (xy 308.518821 -98.087938)
			(xy 308.526941 -98.143114) (xy 308.52745 -98.171) (xy 308.526941 -98.198886) (xy 308.518821 -98.254062)
			(xy 308.502753 -98.307469) (xy 308.479081 -98.357966) (xy 308.448308 -98.404479) (xy 308.411091 -98.446016)
			(xy 308.368223 -98.481691) (xy 308.320617 -98.510745) (xy 308.269288 -98.532557) (xy 308.215331 -98.546663)
			(xy 308.159894 -98.552763) (xy 308.10416 -98.550726) (xy 308.049317 -98.540596) (xy 307.996533 -98.522589)
			(xy 307.946933 -98.497088) (xy 307.901575 -98.464637) (xy 307.861426 -98.425928) (xy 307.82734 -98.381785)
			(xy 307.800044 -98.33315) (xy 307.780121 -98.281059) (xy 307.767995 -98.226622) (xy 307.763924 -98.171)
			(xy 270.505936 -98.171) (xy 270.232886 -98.44405) (xy 270.214105 -98.462162) (xy 270.171907 -98.492846)
			(xy 270.125426 -98.516546) (xy 270.075809 -98.532678) (xy 270.024277 -98.540844) (xy 269.99819 -98.541332)
			(xy 269.4686 -98.541332) (xy 269.463774 -98.546412) (xy 269.461996 -98.547936) (xy 269.45971 -98.549714)
			(xy 267.83157 -100.177854) (xy 269.509748 -100.177854) (xy 269.509748 -99.314254) (xy 269.510238 -99.28427)
			(xy 269.518066 -99.224814) (xy 269.533587 -99.166889) (xy 269.556536 -99.111485) (xy 269.58652 -99.059551)
			(xy 269.623026 -99.011975) (xy 269.665431 -98.96957) (xy 269.713007 -98.933064) (xy 269.764941 -98.90308)
			(xy 269.820345 -98.880131) (xy 269.87827 -98.86461) (xy 269.937726 -98.856782) (xy 269.997694 -98.856782)
			(xy 270.05715 -98.86461) (xy 270.115075 -98.880131) (xy 270.170479 -98.90308) (xy 270.222413 -98.933064)
			(xy 270.269989 -98.96957) (xy 270.312394 -99.011975) (xy 270.3489 -99.059551) (xy 270.378884 -99.111485)
			(xy 270.401833 -99.166889) (xy 270.417354 -99.224814) (xy 270.425182 -99.28427) (xy 270.425672 -99.314254)
			(xy 270.425672 -100.177854) (xy 270.425182 -100.207838) (xy 270.417354 -100.267294) (xy 270.401833 -100.325219)
			(xy 270.378884 -100.380623) (xy 270.3489 -100.432557) (xy 270.312394 -100.480133) (xy 270.269989 -100.522538)
			(xy 270.222413 -100.559044) (xy 270.170479 -100.589028) (xy 270.115075 -100.611977) (xy 270.05715 -100.627498)
			(xy 269.997694 -100.635326) (xy 269.937726 -100.635326) (xy 269.87827 -100.627498) (xy 269.820345 -100.611977)
			(xy 269.764941 -100.589028) (xy 269.713007 -100.559044) (xy 269.665431 -100.522538) (xy 269.623026 -100.480133)
			(xy 269.58652 -100.432557) (xy 269.556536 -100.380623) (xy 269.533587 -100.325219) (xy 269.518066 -100.267294)
			(xy 269.510238 -100.207838) (xy 269.509748 -100.177854) (xy 267.83157 -100.177854) (xy 266.025122 -101.984302)
			(xy 267.47724 -101.984302) (xy 267.47724 -101.120702) (xy 267.47773 -101.090718) (xy 267.485558 -101.031262)
			(xy 267.501079 -100.973337) (xy 267.524028 -100.917933) (xy 267.554012 -100.865999) (xy 267.590518 -100.818423)
			(xy 267.632923 -100.776018) (xy 267.680499 -100.739512) (xy 267.732433 -100.709528) (xy 267.787837 -100.686579)
			(xy 267.845762 -100.671058) (xy 267.905218 -100.66323) (xy 267.965186 -100.66323) (xy 268.024642 -100.671058)
			(xy 268.082567 -100.686579) (xy 268.137971 -100.709528) (xy 268.189905 -100.739512) (xy 268.237481 -100.776018)
			(xy 268.279886 -100.818423) (xy 268.316392 -100.865999) (xy 268.346376 -100.917933) (xy 268.369325 -100.973337)
			(xy 268.384846 -101.031262) (xy 268.392674 -101.090718) (xy 268.393164 -101.120702) (xy 268.393164 -101.984302)
			(xy 268.392674 -102.014286) (xy 268.384846 -102.073742) (xy 268.369325 -102.131667) (xy 268.346376 -102.187071)
			(xy 268.316392 -102.239005) (xy 268.279886 -102.286581) (xy 268.237481 -102.328986) (xy 268.189905 -102.365492)
			(xy 268.137971 -102.395476) (xy 268.082567 -102.418425) (xy 268.024642 -102.433946) (xy 267.965186 -102.441774)
			(xy 267.905218 -102.441774) (xy 267.845762 -102.433946) (xy 267.787837 -102.418425) (xy 267.732433 -102.395476)
			(xy 267.680499 -102.365492) (xy 267.632923 -102.328986) (xy 267.590518 -102.286581) (xy 267.554012 -102.239005)
			(xy 267.524028 -102.187071) (xy 267.501079 -102.131667) (xy 267.485558 -102.073742) (xy 267.47773 -102.014286)
			(xy 267.47724 -101.984302) (xy 266.025122 -101.984302) (xy 264.231628 -103.777796) (xy 269.509748 -103.777796)
			(xy 269.509748 -102.914196) (xy 269.510238 -102.884212) (xy 269.518066 -102.824756) (xy 269.533587 -102.766831)
			(xy 269.556536 -102.711427) (xy 269.58652 -102.659493) (xy 269.623026 -102.611917) (xy 269.665431 -102.569512)
			(xy 269.713007 -102.533006) (xy 269.764941 -102.503022) (xy 269.820345 -102.480073) (xy 269.87827 -102.464552)
			(xy 269.937726 -102.456724) (xy 269.997694 -102.456724) (xy 270.05715 -102.464552) (xy 270.115075 -102.480073)
			(xy 270.170479 -102.503022) (xy 270.222413 -102.533006) (xy 270.269989 -102.569512) (xy 270.312394 -102.611917)
			(xy 270.3489 -102.659493) (xy 270.378884 -102.711427) (xy 270.401833 -102.766831) (xy 270.417354 -102.824756)
			(xy 270.425182 -102.884212) (xy 270.425672 -102.914196) (xy 270.425672 -103.777796) (xy 270.425182 -103.80778)
			(xy 270.417354 -103.867236) (xy 270.401833 -103.925161) (xy 270.378884 -103.980565) (xy 270.3489 -104.032499)
			(xy 270.312394 -104.080075) (xy 270.269989 -104.12248) (xy 270.222413 -104.158986) (xy 270.170479 -104.18897)
			(xy 270.115075 -104.211919) (xy 270.05715 -104.22744) (xy 269.997694 -104.235268) (xy 269.937726 -104.235268)
			(xy 269.87827 -104.22744) (xy 269.820345 -104.211919) (xy 269.764941 -104.18897) (xy 269.713007 -104.158986)
			(xy 269.665431 -104.12248) (xy 269.623026 -104.080075) (xy 269.58652 -104.032499) (xy 269.556536 -103.980565)
			(xy 269.533587 -103.925161) (xy 269.518066 -103.867236) (xy 269.510238 -103.80778) (xy 269.509748 -103.777796)
			(xy 264.231628 -103.777796) (xy 262.424926 -105.584498) (xy 266.86764 -105.584498) (xy 266.86764 -104.720898)
			(xy 266.86813 -104.690914) (xy 266.875958 -104.631458) (xy 266.891479 -104.573533) (xy 266.914428 -104.518129)
			(xy 266.944412 -104.466195) (xy 266.980918 -104.418619) (xy 267.023323 -104.376214) (xy 267.070899 -104.339708)
			(xy 267.122833 -104.309724) (xy 267.178237 -104.286775) (xy 267.236162 -104.271254) (xy 267.295618 -104.263426)
			(xy 267.355586 -104.263426) (xy 267.415042 -104.271254) (xy 267.472967 -104.286775) (xy 267.528371 -104.309724)
			(xy 267.580305 -104.339708) (xy 267.627881 -104.376214) (xy 267.670286 -104.418619) (xy 267.706792 -104.466195)
			(xy 267.736776 -104.518129) (xy 267.759725 -104.573533) (xy 267.775246 -104.631458) (xy 267.783074 -104.690914)
			(xy 267.783564 -104.720898) (xy 267.783564 -105.584498) (xy 267.783074 -105.614482) (xy 267.775246 -105.673938)
			(xy 267.759725 -105.731863) (xy 267.736776 -105.787267) (xy 267.706792 -105.839201) (xy 267.670286 -105.886777)
			(xy 267.627881 -105.929182) (xy 267.580305 -105.965688) (xy 267.528371 -105.995672) (xy 267.472967 -106.018621)
			(xy 267.415042 -106.034142) (xy 267.355586 -106.04197) (xy 267.295618 -106.04197) (xy 267.236162 -106.034142)
			(xy 267.178237 -106.018621) (xy 267.122833 -105.995672) (xy 267.070899 -105.965688) (xy 267.023323 -105.929182)
			(xy 266.980918 -105.886777) (xy 266.944412 -105.839201) (xy 266.914428 -105.787267) (xy 266.891479 -105.731863)
			(xy 266.875958 -105.673938) (xy 266.86813 -105.614482) (xy 266.86764 -105.584498) (xy 262.424926 -105.584498)
			(xy 256.958592 -111.050832) (xy 256.955889 -111.053685) (xy 256.951303 -111.060067) (xy 256.949448 -111.063532)
			(xy 256.946861 -111.068958) (xy 256.944033 -111.080638) (xy 256.94386 -111.086646) (xy 256.94386 -112.046258)
			(xy 256.944876 -112.055656) (xy 256.944876 -112.056164) (xy 256.946577 -112.063325) (xy 256.953404 -112.076357)
			(xy 256.958338 -112.081818) (xy 256.96037 -112.08385) (xy 257.017774 -112.136682) (xy 257.021349 -112.139444)
			(xy 257.029271 -112.143786) (xy 257.033522 -112.145318) (xy 257.039618 -112.146842) (xy 257.05181 -112.147604)
			(xy 257.052826 -112.147604) (xy 257.06451 -112.146842) (xy 257.069844 -112.146588) (xy 257.07213 -112.146588)
			(xy 257.091434 -112.14608) (xy 257.092958 -112.14608) (xy 257.095752 -112.14608) (xy 257.096006 -112.14608)
			(xy 257.127608 -112.146595) (xy 257.190273 -112.154835) (xy 257.251329 -112.171172) (xy 257.309734 -112.195329)
			(xy 257.364492 -112.226893) (xy 257.414669 -112.265326) (xy 257.437382 -112.287304) (xy 258.14528 -112.995456)
			(xy 258.152692 -113.00214) (xy 258.171125 -113.009737) (xy 258.191063 -113.009737) (xy 258.209496 -113.00214)
			(xy 258.216908 -112.995456) (xy 261.89305 -109.319314) (xy 261.90045 -109.312474) (xy 261.919049 -109.304755)
			(xy 261.929118 -109.304328) (xy 266.279122 -109.304328) (xy 266.286488 -109.30382) (xy 266.292268 -109.302775)
			(xy 266.303171 -109.298413) (xy 266.308078 -109.295184) (xy 266.314428 -109.290866) (xy 266.323572 -109.278928)
			(xy 266.326366 -109.271308) (xy 266.326874 -109.269784) (xy 266.327636 -109.267752) (xy 266.32789 -109.266482)
			(xy 266.336452 -109.241098) (xy 266.359691 -109.192829) (xy 266.389448 -109.148283) (xy 266.425139 -109.108333)
			(xy 266.466064 -109.073765) (xy 266.51142 -109.045256) (xy 266.560314 -109.023366) (xy 266.611789 -109.008526)
			(xy 266.664833 -109.001027) (xy 266.691618 -109.000544) (xy 266.705703 -109.000657) (xy 266.733798 -109.002694)
			(xy 266.747752 -109.004608) (xy 266.750038 -109.005116) (xy 266.7508 -109.005116) (xy 266.757658 -109.00537)
			(xy 266.7663 -109.005104) (xy 266.782647 -108.999505) (xy 266.789662 -108.994448) (xy 266.801854 -108.984288)
			(xy 266.802616 -108.983526) (xy 266.849606 -108.943648) (xy 266.854432 -108.938822) (xy 266.85494 -108.938314)
			(xy 266.860711 -108.931155) (xy 266.867214 -108.913971) (xy 266.86764 -108.904786) (xy 266.86764 -108.32084)
			(xy 266.86813 -108.290856) (xy 266.875958 -108.2314) (xy 266.891479 -108.173475) (xy 266.914428 -108.118071)
			(xy 266.944412 -108.066137) (xy 266.980918 -108.018561) (xy 267.023323 -107.976156) (xy 267.070899 -107.93965)
			(xy 267.122833 -107.909666) (xy 267.178237 -107.886717) (xy 267.236162 -107.871196) (xy 267.295618 -107.863368)
			(xy 267.355586 -107.863368) (xy 267.415042 -107.871196) (xy 267.472967 -107.886717) (xy 267.528371 -107.909666)
			(xy 267.580305 -107.93965) (xy 267.627881 -107.976156) (xy 267.670286 -108.018561) (xy 267.706792 -108.066137)
			(xy 267.736776 -108.118071) (xy 267.759725 -108.173475) (xy 267.775246 -108.2314) (xy 267.783074 -108.290856)
			(xy 267.783564 -108.32084) (xy 267.783564 -108.820204) (xy 267.784275 -108.829412) (xy 267.791405 -108.846431)
			(xy 267.804114 -108.859809) (xy 267.812266 -108.864146) (xy 267.839444 -108.864146) (xy 267.847572 -108.863384)
			(xy 267.84808 -108.863384) (xy 267.855602 -108.861789) (xy 267.869298 -108.854821) (xy 267.875004 -108.849668)
			(xy 267.993368 -108.731304) (xy 268.028103 -108.697326) (xy 268.103171 -108.635618) (xy 268.143228 -108.608114)
			(xy 269.535148 -107.677966) (xy 269.543276 -107.672378) (xy 269.54861 -107.664758) (xy 269.551395 -107.660628)
			(xy 269.555482 -107.651545) (xy 269.556738 -107.646724) (xy 269.558516 -107.63885) (xy 269.558516 -107.638342)
			(xy 269.56385 -107.616498) (xy 269.56385 -107.604306) (xy 269.562326 -107.59821) (xy 269.561818 -107.595924)
			(xy 269.558516 -107.583478) (xy 269.55623 -107.578906) (xy 269.541595 -107.547455) (xy 269.520912 -107.481244)
			(xy 269.510429 -107.412675) (xy 269.509748 -107.377992) (xy 269.509748 -106.514138) (xy 269.510238 -106.484154)
			(xy 269.518066 -106.424698) (xy 269.533587 -106.366773) (xy 269.556536 -106.311369) (xy 269.58652 -106.259435)
			(xy 269.623026 -106.211859) (xy 269.665431 -106.169454) (xy 269.713007 -106.132948) (xy 269.764941 -106.102964)
			(xy 269.820345 -106.080015) (xy 269.87827 -106.064494) (xy 269.937726 -106.056666) (xy 269.997694 -106.056666)
			(xy 270.05715 -106.064494) (xy 270.115075 -106.080015) (xy 270.170479 -106.102964) (xy 270.222413 -106.132948)
			(xy 270.269989 -106.169454) (xy 270.312394 -106.211859) (xy 270.3489 -106.259435) (xy 270.378884 -106.311369)
			(xy 270.401833 -106.366773) (xy 270.417354 -106.424698) (xy 270.425182 -106.484154) (xy 270.425672 -106.514138)
			(xy 270.425672 -106.98861) (xy 270.426434 -106.998008) (xy 270.428901 -107.008306) (xy 270.440841 -107.025764)
			(xy 270.449548 -107.03179) (xy 270.464788 -107.039918) (xy 270.478504 -107.03941) (xy 270.484877 -107.038948)
			(xy 270.497097 -107.035232) (xy 270.502634 -107.032044) (xy 270.526256 -107.016296) (xy 270.618712 -106.954828)
			(xy 270.620744 -106.953558) (xy 274.402042 -103.941372) (xy 274.405852 -103.938324) (xy 275.636228 -102.707948)
			(xy 275.643626 -102.701101) (xy 275.662224 -102.693369) (xy 275.672296 -102.692962) (xy 275.953474 -102.692962)
			(xy 275.961398 -102.692311) (xy 275.976286 -102.686758) (xy 275.982684 -102.68204) (xy 275.982938 -102.681786)
			(xy 276.389592 -102.35819) (xy 276.412049 -102.340573) (xy 276.458688 -102.307662) (xy 276.48281 -102.292404)
			(xy 276.51329 -102.274116) (xy 276.564344 -102.246938) (xy 280.24074 -100.413058) (xy 280.247598 -100.407216)
			(xy 281.412442 -99.242372) (xy 281.419839 -99.235524) (xy 281.438438 -99.227794) (xy 281.44851 -99.227386)
			(xy 282.60675 -99.227386) (xy 282.615894 -99.22637) (xy 283.441648 -98.81362) (xy 283.447142 -98.8077)
			(xy 283.454512 -98.79334) (xy 283.456126 -98.785426) (xy 283.456126 -98.785172) (xy 283.460798 -98.758601)
			(xy 283.476646 -98.707031) (xy 283.499603 -98.65821) (xy 283.529212 -98.613112) (xy 283.564882 -98.572637)
			(xy 283.6059 -98.537593) (xy 283.651447 -98.508679) (xy 283.700615 -98.486474) (xy 283.752422 -98.47142)
			(xy 283.805833 -98.463818) (xy 283.832808 -98.463354) (xy 283.833316 -98.463354) (xy 283.867352 -98.465132)
			(xy 283.87802 -98.466148) (xy 283.905716 -98.469914) (xy 283.959672 -98.484502) (xy 284.010923 -98.506803)
			(xy 284.058374 -98.53634) (xy 284.10101 -98.572481) (xy 284.119828 -98.593148) (xy 284.123471 -98.597071)
			(xy 284.132048 -98.603474) (xy 284.136846 -98.605848) (xy 284.137862 -98.606356) (xy 285.38297 -98.606356)
			(xy 285.390336 -98.603308) (xy 285.397194 -98.596196) (xy 285.402528 -98.590862) (xy 285.420675 -98.571231)
			(xy 285.461507 -98.536727) (xy 285.506748 -98.508247) (xy 285.555514 -98.486346) (xy 285.606856 -98.471451)
			(xy 285.659772 -98.463852) (xy 285.6865 -98.463354) (xy 285.687262 -98.463354) (xy 285.688024 -98.463354)
			(xy 285.688786 -98.463354) (xy 285.702685 -98.463539) (xy 285.730399 -98.465696) (xy 285.744158 -98.467672)
			(xy 285.745936 -98.467926) (xy 285.754355 -98.468593) (xy 285.770837 -98.46496) (xy 285.778194 -98.460814)
			(xy 285.819053 -98.436599) (xy 285.90451 -98.395137) (xy 285.993519 -98.361979) (xy 286.085276 -98.337426)
			(xy 286.132016 -98.328988) (xy 286.172924 -98.322559) (xy 286.255454 -98.31569) (xy 286.296862 -98.315272)
			(xy 286.343847 -98.315829) (xy 286.437398 -98.324696) (xy 286.529701 -98.342317) (xy 286.619939 -98.368537)
			(xy 286.707313 -98.403123) (xy 286.79105 -98.445769) (xy 286.831024 -98.470466) (xy 286.834326 -98.470212)
			(xy 286.846296 -98.468012) (xy 286.870445 -98.464961) (xy 286.882586 -98.464116) (xy 286.902398 -98.463354)
			(xy 286.905446 -98.463354) (xy 286.907224 -98.463354) (xy 286.934442 -98.463889) (xy 286.988314 -98.471729)
			(xy 287.040524 -98.487146) (xy 287.090013 -98.509828) (xy 287.135775 -98.539313) (xy 287.176882 -98.575004)
			(xy 287.212498 -98.616175) (xy 287.241901 -98.66199) (xy 287.264494 -98.71152) (xy 287.279818 -98.763757)
			(xy 287.287561 -98.817643) (xy 287.28797 -98.844862) (xy 287.28797 -98.845878) (xy 287.287496 -98.873042)
			(xy 287.279792 -98.926819) (xy 287.264522 -98.978956) (xy 287.25368 -99.003866) (xy 287.25114 -99.009454)
			(xy 287.249616 -99.017074) (xy 287.249616 -99.017582) (xy 287.263729 -99.065236) (xy 287.283556 -99.16263)
			(xy 287.293614 -99.261511) (xy 287.29432 -99.311206) (xy 287.29432 -99.31273) (xy 287.293887 -99.354677)
			(xy 287.28684 -99.438275) (xy 287.272799 -99.520986) (xy 287.251862 -99.602226) (xy 287.224179 -99.681422)
			(xy 287.207452 -99.719892) (xy 287.205674 -99.723956) (xy 287.202086 -99.739704) (xy 302.321974 -99.739704)
			(xy 302.326045 -99.684082) (xy 302.338171 -99.629645) (xy 302.358094 -99.577554) (xy 302.38539 -99.528919)
			(xy 302.419476 -99.484776) (xy 302.459625 -99.446067) (xy 302.504983 -99.413616) (xy 302.554583 -99.388115)
			(xy 302.607367 -99.370108) (xy 302.66221 -99.359978) (xy 302.717944 -99.357941) (xy 302.773381 -99.364041)
			(xy 302.827338 -99.378147) (xy 302.878667 -99.399959) (xy 302.926273 -99.429013) (xy 302.939456 -99.439984)
			(xy 307.509924 -99.439984) (xy 307.513995 -99.384362) (xy 307.526121 -99.329925) (xy 307.546044 -99.277834)
			(xy 307.57334 -99.229199) (xy 307.607426 -99.185056) (xy 307.647575 -99.146347) (xy 307.692933 -99.113896)
			(xy 307.742533 -99.088395) (xy 307.795317 -99.070388) (xy 307.85016 -99.060258) (xy 307.905894 -99.058221)
			(xy 307.961331 -99.064321) (xy 308.015288 -99.078427) (xy 308.066617 -99.100239) (xy 308.114223 -99.129293)
			(xy 308.157091 -99.164968) (xy 308.194308 -99.206505) (xy 308.225081 -99.253018) (xy 308.248753 -99.303515)
			(xy 308.264821 -99.356922) (xy 308.272941 -99.412098) (xy 308.27345 -99.439984) (xy 308.272941 -99.46787)
			(xy 308.264821 -99.523046) (xy 308.248753 -99.576453) (xy 308.225081 -99.62695) (xy 308.194308 -99.673463)
			(xy 308.157091 -99.715) (xy 308.114223 -99.750675) (xy 308.066617 -99.779729) (xy 308.015288 -99.801541)
			(xy 307.961331 -99.815647) (xy 307.905894 -99.821747) (xy 307.85016 -99.81971) (xy 307.795317 -99.80958)
			(xy 307.742533 -99.791573) (xy 307.692933 -99.766072) (xy 307.647575 -99.733621) (xy 307.607426 -99.694912)
			(xy 307.57334 -99.650769) (xy 307.546044 -99.602134) (xy 307.526121 -99.550043) (xy 307.513995 -99.495606)
			(xy 307.509924 -99.439984) (xy 302.939456 -99.439984) (xy 302.969141 -99.464688) (xy 303.006358 -99.506225)
			(xy 303.037131 -99.552738) (xy 303.060803 -99.603235) (xy 303.076871 -99.656642) (xy 303.084991 -99.711818)
			(xy 303.0855 -99.739704) (xy 303.084991 -99.76759) (xy 303.076871 -99.822766) (xy 303.060803 -99.876173)
			(xy 303.037131 -99.92667) (xy 303.006358 -99.973183) (xy 302.969141 -100.01472) (xy 302.938846 -100.039932)
			(xy 306.076856 -100.039932) (xy 306.080927 -99.98431) (xy 306.093053 -99.929873) (xy 306.112976 -99.877782)
			(xy 306.140272 -99.829147) (xy 306.174358 -99.785004) (xy 306.214507 -99.746295) (xy 306.259865 -99.713844)
			(xy 306.309465 -99.688343) (xy 306.362249 -99.670336) (xy 306.417092 -99.660206) (xy 306.472826 -99.658169)
			(xy 306.528263 -99.664269) (xy 306.58222 -99.678375) (xy 306.633549 -99.700187) (xy 306.681155 -99.729241)
			(xy 306.724023 -99.764916) (xy 306.76124 -99.806453) (xy 306.792013 -99.852966) (xy 306.815685 -99.903463)
			(xy 306.831753 -99.95687) (xy 306.839873 -100.012046) (xy 306.840382 -100.039932) (xy 306.839873 -100.067818)
			(xy 306.831753 -100.122994) (xy 306.815685 -100.176401) (xy 306.792013 -100.226898) (xy 306.76124 -100.273411)
			(xy 306.724023 -100.314948) (xy 306.681155 -100.350623) (xy 306.633549 -100.379677) (xy 306.58222 -100.401489)
			(xy 306.528263 -100.415595) (xy 306.472826 -100.421695) (xy 306.417092 -100.419658) (xy 306.362249 -100.409528)
			(xy 306.309465 -100.391521) (xy 306.259865 -100.36602) (xy 306.214507 -100.333569) (xy 306.174358 -100.29486)
			(xy 306.140272 -100.250717) (xy 306.112976 -100.202082) (xy 306.093053 -100.149991) (xy 306.080927 -100.095554)
			(xy 306.076856 -100.039932) (xy 302.938846 -100.039932) (xy 302.926273 -100.050395) (xy 302.878667 -100.079449)
			(xy 302.827338 -100.101261) (xy 302.773381 -100.115367) (xy 302.717944 -100.121467) (xy 302.66221 -100.11943)
			(xy 302.607367 -100.1093) (xy 302.554583 -100.091293) (xy 302.504983 -100.065792) (xy 302.459625 -100.033341)
			(xy 302.419476 -99.994632) (xy 302.38539 -99.950489) (xy 302.358094 -99.901854) (xy 302.338171 -99.849763)
			(xy 302.326045 -99.795326) (xy 302.321974 -99.739704) (xy 287.202086 -99.739704) (xy 287.201102 -99.744022)
			(xy 287.201102 -99.745038) (xy 287.204658 -99.760278) (xy 287.207706 -99.76993) (xy 287.224384 -99.808333)
			(xy 287.251991 -99.887384) (xy 287.272867 -99.968472) (xy 287.286866 -100.051026) (xy 287.293889 -100.134464)
			(xy 287.29432 -100.17633) (xy 287.293955 -100.213108) (xy 287.288492 -100.286462) (xy 287.283398 -100.322888)
			(xy 287.283398 -100.323396) (xy 287.280858 -100.341176) (xy 287.285684 -100.350828) (xy 287.287588 -100.354532)
			(xy 287.292434 -100.361303) (xy 287.295336 -100.36429) (xy 287.57372 -100.642674) (xy 287.580563 -100.650073)
			(xy 287.588283 -100.668672) (xy 287.588706 -100.678742) (xy 287.588706 -100.766372) (xy 289.797742 -100.766372)
			(xy 289.801813 -100.71075) (xy 289.813939 -100.656313) (xy 289.833862 -100.604222) (xy 289.861158 -100.555587)
			(xy 289.895244 -100.511444) (xy 289.935393 -100.472735) (xy 289.980751 -100.440284) (xy 290.030351 -100.414783)
			(xy 290.083135 -100.396776) (xy 290.137978 -100.386646) (xy 290.193712 -100.384609) (xy 290.249149 -100.390709)
			(xy 290.303106 -100.404815) (xy 290.354435 -100.426627) (xy 290.402041 -100.455681) (xy 290.444909 -100.491356)
			(xy 290.482126 -100.532893) (xy 290.512899 -100.579406) (xy 290.536571 -100.629903) (xy 290.552639 -100.68331)
			(xy 290.560759 -100.738486) (xy 290.561268 -100.766372) (xy 290.560759 -100.794258) (xy 290.552639 -100.849434)
			(xy 290.536571 -100.902841) (xy 290.512899 -100.953338) (xy 290.482126 -100.999851) (xy 290.444909 -101.041388)
			(xy 290.402041 -101.077063) (xy 290.354435 -101.106117) (xy 290.303106 -101.127929) (xy 290.249149 -101.142035)
			(xy 290.193712 -101.148135) (xy 290.137978 -101.146098) (xy 290.083135 -101.135968) (xy 290.030351 -101.117961)
			(xy 289.980751 -101.09246) (xy 289.935393 -101.060009) (xy 289.895244 -101.0213) (xy 289.861158 -100.977157)
			(xy 289.833862 -100.928522) (xy 289.813939 -100.876431) (xy 289.801813 -100.821994) (xy 289.797742 -100.766372)
			(xy 287.588706 -100.766372) (xy 287.588706 -101.240082) (xy 306.493924 -101.240082) (xy 306.497995 -101.18446)
			(xy 306.510121 -101.130023) (xy 306.530044 -101.077932) (xy 306.55734 -101.029297) (xy 306.591426 -100.985154)
			(xy 306.631575 -100.946445) (xy 306.676933 -100.913994) (xy 306.726533 -100.888493) (xy 306.779317 -100.870486)
			(xy 306.83416 -100.860356) (xy 306.889894 -100.858319) (xy 306.945331 -100.864419) (xy 306.999288 -100.878525)
			(xy 307.050617 -100.900337) (xy 307.098223 -100.929391) (xy 307.141091 -100.965066) (xy 307.178308 -101.006603)
			(xy 307.209081 -101.053116) (xy 307.216831 -101.069648) (xy 307.786276 -101.069648) (xy 307.790347 -101.014026)
			(xy 307.802473 -100.959589) (xy 307.822396 -100.907498) (xy 307.849692 -100.858863) (xy 307.883778 -100.81472)
			(xy 307.923927 -100.776011) (xy 307.969285 -100.74356) (xy 308.018885 -100.718059) (xy 308.071669 -100.700052)
			(xy 308.126512 -100.689922) (xy 308.182246 -100.687885) (xy 308.237683 -100.693985) (xy 308.29164 -100.708091)
			(xy 308.342969 -100.729903) (xy 308.390575 -100.758957) (xy 308.433443 -100.794632) (xy 308.47066 -100.836169)
			(xy 308.501433 -100.882682) (xy 308.525105 -100.933179) (xy 308.541173 -100.986586) (xy 308.549293 -101.041762)
			(xy 308.549802 -101.069648) (xy 308.549293 -101.097534) (xy 308.541173 -101.15271) (xy 308.525105 -101.206117)
			(xy 308.501433 -101.256614) (xy 308.47066 -101.303127) (xy 308.433443 -101.344664) (xy 308.390575 -101.380339)
			(xy 308.342969 -101.409393) (xy 308.29164 -101.431205) (xy 308.237683 -101.445311) (xy 308.182246 -101.451411)
			(xy 308.126512 -101.449374) (xy 308.071669 -101.439244) (xy 308.018885 -101.421237) (xy 307.969285 -101.395736)
			(xy 307.923927 -101.363285) (xy 307.883778 -101.324576) (xy 307.849692 -101.280433) (xy 307.822396 -101.231798)
			(xy 307.802473 -101.179707) (xy 307.790347 -101.12527) (xy 307.786276 -101.069648) (xy 307.216831 -101.069648)
			(xy 307.232753 -101.103613) (xy 307.248821 -101.15702) (xy 307.256941 -101.212196) (xy 307.25745 -101.240082)
			(xy 307.256941 -101.267968) (xy 307.248821 -101.323144) (xy 307.232753 -101.376551) (xy 307.209081 -101.427048)
			(xy 307.178308 -101.473561) (xy 307.141091 -101.515098) (xy 307.098223 -101.550773) (xy 307.050617 -101.579827)
			(xy 306.999288 -101.601639) (xy 306.945331 -101.615745) (xy 306.889894 -101.621845) (xy 306.83416 -101.619808)
			(xy 306.779317 -101.609678) (xy 306.726533 -101.591671) (xy 306.676933 -101.56617) (xy 306.631575 -101.533719)
			(xy 306.591426 -101.49501) (xy 306.55734 -101.450867) (xy 306.530044 -101.402232) (xy 306.510121 -101.350141)
			(xy 306.497995 -101.295704) (xy 306.493924 -101.240082) (xy 287.588706 -101.240082) (xy 287.588706 -102.489)
			(xy 307.001924 -102.489) (xy 307.005995 -102.433378) (xy 307.018121 -102.378941) (xy 307.038044 -102.32685)
			(xy 307.06534 -102.278215) (xy 307.099426 -102.234072) (xy 307.139575 -102.195363) (xy 307.184933 -102.162912)
			(xy 307.234533 -102.137411) (xy 307.287317 -102.119404) (xy 307.34216 -102.109274) (xy 307.397894 -102.107237)
			(xy 307.453331 -102.113337) (xy 307.507288 -102.127443) (xy 307.558617 -102.149255) (xy 307.606223 -102.178309)
			(xy 307.649091 -102.213984) (xy 307.686308 -102.255521) (xy 307.717081 -102.302034) (xy 307.740753 -102.352531)
			(xy 307.756821 -102.405938) (xy 307.764941 -102.461114) (xy 307.76545 -102.489) (xy 307.764941 -102.516886)
			(xy 307.756821 -102.572062) (xy 307.740753 -102.625469) (xy 307.717081 -102.675966) (xy 307.686308 -102.722479)
			(xy 307.649091 -102.764016) (xy 307.606223 -102.799691) (xy 307.558617 -102.828745) (xy 307.507288 -102.850557)
			(xy 307.453331 -102.864663) (xy 307.397894 -102.870763) (xy 307.34216 -102.868726) (xy 307.287317 -102.858596)
			(xy 307.234533 -102.840589) (xy 307.184933 -102.815088) (xy 307.139575 -102.782637) (xy 307.099426 -102.743928)
			(xy 307.06534 -102.699785) (xy 307.038044 -102.65115) (xy 307.018121 -102.599059) (xy 307.005995 -102.544622)
			(xy 307.001924 -102.489) (xy 287.588706 -102.489) (xy 287.588706 -103.886) (xy 307.509924 -103.886)
			(xy 307.513995 -103.830378) (xy 307.526121 -103.775941) (xy 307.546044 -103.72385) (xy 307.57334 -103.675215)
			(xy 307.607426 -103.631072) (xy 307.647575 -103.592363) (xy 307.692933 -103.559912) (xy 307.742533 -103.534411)
			(xy 307.795317 -103.516404) (xy 307.85016 -103.506274) (xy 307.905894 -103.504237) (xy 307.961331 -103.510337)
			(xy 308.015288 -103.524443) (xy 308.066617 -103.546255) (xy 308.114223 -103.575309) (xy 308.157091 -103.610984)
			(xy 308.194308 -103.652521) (xy 308.225081 -103.699034) (xy 308.248753 -103.749531) (xy 308.264821 -103.802938)
			(xy 308.272941 -103.858114) (xy 308.27345 -103.886) (xy 308.272941 -103.913886) (xy 308.264821 -103.969062)
			(xy 308.248753 -104.022469) (xy 308.225081 -104.072966) (xy 308.194308 -104.119479) (xy 308.157091 -104.161016)
			(xy 308.114223 -104.196691) (xy 308.066617 -104.225745) (xy 308.015288 -104.247557) (xy 307.961331 -104.261663)
			(xy 307.905894 -104.267763) (xy 307.85016 -104.265726) (xy 307.795317 -104.255596) (xy 307.742533 -104.237589)
			(xy 307.692933 -104.212088) (xy 307.647575 -104.179637) (xy 307.607426 -104.140928) (xy 307.57334 -104.096785)
			(xy 307.546044 -104.04815) (xy 307.526121 -103.996059) (xy 307.513995 -103.941622) (xy 307.509924 -103.886)
			(xy 287.588706 -103.886) (xy 287.588706 -107.210352) (xy 297.165012 -107.210352) (xy 297.169083 -107.15473)
			(xy 297.181209 -107.100293) (xy 297.201132 -107.048202) (xy 297.228428 -106.999567) (xy 297.262514 -106.955424)
			(xy 297.302663 -106.916715) (xy 297.348021 -106.884264) (xy 297.397621 -106.858763) (xy 297.450405 -106.840756)
			(xy 297.505248 -106.830626) (xy 297.560982 -106.828589) (xy 297.616419 -106.834689) (xy 297.670376 -106.848795)
			(xy 297.721705 -106.870607) (xy 297.769311 -106.899661) (xy 297.812179 -106.935336) (xy 297.849396 -106.976873)
			(xy 297.880169 -107.023386) (xy 297.903841 -107.073883) (xy 297.919909 -107.12729) (xy 297.928029 -107.182466)
			(xy 297.928538 -107.210352) (xy 297.928029 -107.238238) (xy 297.919909 -107.293414) (xy 297.903841 -107.346821)
			(xy 297.880169 -107.397318) (xy 297.849396 -107.443831) (xy 297.812179 -107.485368) (xy 297.769311 -107.521043)
			(xy 297.721705 -107.550097) (xy 297.670376 -107.571909) (xy 297.616419 -107.586015) (xy 297.560982 -107.592115)
			(xy 297.505248 -107.590078) (xy 297.450405 -107.579948) (xy 297.397621 -107.561941) (xy 297.348021 -107.53644)
			(xy 297.302663 -107.503989) (xy 297.262514 -107.46528) (xy 297.228428 -107.421137) (xy 297.201132 -107.372502)
			(xy 297.181209 -107.320411) (xy 297.169083 -107.265974) (xy 297.165012 -107.210352) (xy 287.588706 -107.210352)
			(xy 287.588706 -115.774216) (xy 288.047174 -115.774216) (xy 288.051245 -115.718594) (xy 288.063371 -115.664157)
			(xy 288.083294 -115.612066) (xy 288.11059 -115.563431) (xy 288.144676 -115.519288) (xy 288.184825 -115.480579)
			(xy 288.230183 -115.448128) (xy 288.279783 -115.422627) (xy 288.332567 -115.40462) (xy 288.38741 -115.39449)
			(xy 288.443144 -115.392453) (xy 288.498581 -115.398553) (xy 288.552538 -115.412659) (xy 288.603867 -115.434471)
			(xy 288.651473 -115.463525) (xy 288.694341 -115.4992) (xy 288.731558 -115.540737) (xy 288.762331 -115.58725)
			(xy 288.786003 -115.637747) (xy 288.802071 -115.691154) (xy 288.810191 -115.74633) (xy 288.8107 -115.774216)
			(xy 288.810191 -115.802102) (xy 288.802071 -115.857278) (xy 288.786003 -115.910685) (xy 288.762331 -115.961182)
			(xy 288.731558 -116.007695) (xy 288.694341 -116.049232) (xy 288.651473 -116.084907) (xy 288.603867 -116.113961)
			(xy 288.552538 -116.135773) (xy 288.498581 -116.149879) (xy 288.443144 -116.155979) (xy 288.38741 -116.153942)
			(xy 288.332567 -116.143812) (xy 288.279783 -116.125805) (xy 288.230183 -116.100304) (xy 288.184825 -116.067853)
			(xy 288.144676 -116.029144) (xy 288.11059 -115.985001) (xy 288.083294 -115.936366) (xy 288.063371 -115.884275)
			(xy 288.051245 -115.829838) (xy 288.047174 -115.774216) (xy 287.588706 -115.774216) (xy 287.588706 -118.249954)
			(xy 287.813748 -118.249954) (xy 287.817819 -118.194332) (xy 287.829945 -118.139895) (xy 287.849868 -118.087804)
			(xy 287.877164 -118.039169) (xy 287.91125 -117.995026) (xy 287.951399 -117.956317) (xy 287.996757 -117.923866)
			(xy 288.046357 -117.898365) (xy 288.099141 -117.880358) (xy 288.153984 -117.870228) (xy 288.209718 -117.868191)
			(xy 288.265155 -117.874291) (xy 288.319112 -117.888397) (xy 288.370441 -117.910209) (xy 288.418047 -117.939263)
			(xy 288.460915 -117.974938) (xy 288.498132 -118.016475) (xy 288.528905 -118.062988) (xy 288.552577 -118.113485)
			(xy 288.568645 -118.166892) (xy 288.576765 -118.222068) (xy 288.577274 -118.249954) (xy 288.576765 -118.27784)
			(xy 288.568645 -118.333016) (xy 288.552577 -118.386423) (xy 288.528905 -118.43692) (xy 288.498132 -118.483433)
			(xy 288.460915 -118.52497) (xy 288.418047 -118.560645) (xy 288.370441 -118.589699) (xy 288.319112 -118.611511)
			(xy 288.265155 -118.625617) (xy 288.209718 -118.631717) (xy 288.153984 -118.62968) (xy 288.099141 -118.61955)
			(xy 288.046357 -118.601543) (xy 287.996757 -118.576042) (xy 287.951399 -118.543591) (xy 287.91125 -118.504882)
			(xy 287.877164 -118.460739) (xy 287.849868 -118.412104) (xy 287.829945 -118.360013) (xy 287.817819 -118.305576)
			(xy 287.813748 -118.249954) (xy 287.588706 -118.249954) (xy 287.588706 -134.62) (xy 289.094924 -134.62)
			(xy 289.098995 -134.564378) (xy 289.111121 -134.509941) (xy 289.131044 -134.45785) (xy 289.15834 -134.409215)
			(xy 289.192426 -134.365072) (xy 289.232575 -134.326363) (xy 289.277933 -134.293912) (xy 289.327533 -134.268411)
			(xy 289.380317 -134.250404) (xy 289.43516 -134.240274) (xy 289.490894 -134.238237) (xy 289.546331 -134.244337)
			(xy 289.600288 -134.258443) (xy 289.651617 -134.280255) (xy 289.699223 -134.309309) (xy 289.742091 -134.344984)
			(xy 289.779308 -134.386521) (xy 289.810081 -134.433034) (xy 289.833753 -134.483531) (xy 289.849821 -134.536938)
			(xy 289.857941 -134.592114) (xy 289.85845 -134.62) (xy 289.857941 -134.647886) (xy 289.849821 -134.703062)
			(xy 289.833753 -134.756469) (xy 289.810081 -134.806966) (xy 289.779308 -134.853479) (xy 289.742091 -134.895016)
			(xy 289.699223 -134.930691) (xy 289.651617 -134.959745) (xy 289.600288 -134.981557) (xy 289.546331 -134.995663)
			(xy 289.490894 -135.001763) (xy 289.43516 -134.999726) (xy 289.380317 -134.989596) (xy 289.327533 -134.971589)
			(xy 289.277933 -134.946088) (xy 289.232575 -134.913637) (xy 289.192426 -134.874928) (xy 289.15834 -134.830785)
			(xy 289.131044 -134.78215) (xy 289.111121 -134.730059) (xy 289.098995 -134.675622) (xy 289.094924 -134.62)
			(xy 287.588706 -134.62) (xy 287.588706 -137.287) (xy 288.967924 -137.287) (xy 288.971995 -137.231378)
			(xy 288.984121 -137.176941) (xy 289.004044 -137.12485) (xy 289.03134 -137.076215) (xy 289.065426 -137.032072)
			(xy 289.105575 -136.993363) (xy 289.150933 -136.960912) (xy 289.200533 -136.935411) (xy 289.253317 -136.917404)
			(xy 289.30816 -136.907274) (xy 289.363894 -136.905237) (xy 289.419331 -136.911337) (xy 289.473288 -136.925443)
			(xy 289.524617 -136.947255) (xy 289.572223 -136.976309) (xy 289.615091 -137.011984) (xy 289.652308 -137.053521)
			(xy 289.683081 -137.100034) (xy 289.706753 -137.150531) (xy 289.722821 -137.203938) (xy 289.730941 -137.259114)
			(xy 289.73145 -137.287) (xy 289.730941 -137.314886) (xy 289.722821 -137.370062) (xy 289.706753 -137.423469)
			(xy 289.683081 -137.473966) (xy 289.652308 -137.520479) (xy 289.615091 -137.562016) (xy 289.572223 -137.597691)
			(xy 289.524617 -137.626745) (xy 289.473288 -137.648557) (xy 289.419331 -137.662663) (xy 289.363894 -137.668763)
			(xy 289.30816 -137.666726) (xy 289.253317 -137.656596) (xy 289.200533 -137.638589) (xy 289.150933 -137.613088)
			(xy 289.105575 -137.580637) (xy 289.065426 -137.541928) (xy 289.03134 -137.497785) (xy 289.004044 -137.44915)
			(xy 288.984121 -137.397059) (xy 288.971995 -137.342622) (xy 288.967924 -137.287) (xy 287.588706 -137.287)
			(xy 287.588706 -138.95705) (xy 288.714434 -138.95705) (xy 288.71492 -138.929799) (xy 288.722676 -138.875851)
			(xy 288.738031 -138.823556) (xy 288.760673 -138.773979) (xy 288.790139 -138.728129) (xy 288.82583 -138.686938)
			(xy 288.867021 -138.651247) (xy 288.912871 -138.621781) (xy 288.962448 -138.599139) (xy 289.014743 -138.583784)
			(xy 289.068691 -138.576028) (xy 289.123193 -138.576028) (xy 289.177141 -138.583784) (xy 289.229436 -138.599139)
			(xy 289.279013 -138.621781) (xy 289.324863 -138.651247) (xy 289.366054 -138.686938) (xy 289.401745 -138.728129)
			(xy 289.431211 -138.773979) (xy 289.453853 -138.823556) (xy 289.469208 -138.875851) (xy 289.476964 -138.929799)
			(xy 289.47745 -138.95705) (xy 289.476953 -138.98483) (xy 289.468879 -139.039801) (xy 289.45291 -139.093017)
			(xy 289.429384 -139.143351) (xy 289.398799 -139.189735) (xy 289.380676 -139.210796) (xy 289.380422 -139.21105)
			(xy 289.374119 -139.218931) (xy 289.367701 -139.238047) (xy 289.367976 -139.248134) (xy 289.37331 -139.321286)
			(xy 289.374479 -139.331363) (xy 289.383651 -139.34944) (xy 289.39109 -139.356338) (xy 289.391344 -139.356592)
			(xy 289.412369 -139.3748) (xy 289.449409 -139.416293) (xy 289.480036 -139.46272) (xy 289.503604 -139.5131)
			(xy 289.519614 -139.566366) (xy 289.527726 -139.621391) (xy 289.52825 -139.6492) (xy 289.527764 -139.676451)
			(xy 289.520008 -139.730399) (xy 289.504653 -139.782694) (xy 289.482011 -139.832271) (xy 289.452545 -139.878121)
			(xy 289.416854 -139.919312) (xy 289.375663 -139.955003) (xy 289.329813 -139.984469) (xy 289.280236 -140.007111)
			(xy 289.227941 -140.022466) (xy 289.173993 -140.030222) (xy 289.119491 -140.030222) (xy 289.065543 -140.022466)
			(xy 289.013248 -140.007111) (xy 288.963671 -139.984469) (xy 288.917821 -139.955003) (xy 288.87663 -139.919312)
			(xy 288.840939 -139.878121) (xy 288.811473 -139.832271) (xy 288.788831 -139.782694) (xy 288.773476 -139.730399)
			(xy 288.76572 -139.676451) (xy 288.765234 -139.6492) (xy 288.765765 -139.621421) (xy 288.773832 -139.566452)
			(xy 288.789793 -139.513237) (xy 288.813312 -139.462903) (xy 288.843889 -139.416516) (xy 288.862008 -139.395454)
			(xy 288.862262 -139.3952) (xy 288.868587 -139.387334) (xy 288.874992 -139.368207) (xy 288.874708 -139.358116)
			(xy 288.869374 -139.284964) (xy 288.868234 -139.274881) (xy 288.859041 -139.256807) (xy 288.851594 -139.249912)
			(xy 288.85134 -139.249658) (xy 288.830335 -139.231427) (xy 288.793295 -139.189938) (xy 288.762666 -139.143516)
			(xy 288.739094 -139.093141) (xy 288.72308 -139.039879) (xy 288.714962 -138.984858) (xy 288.714434 -138.95705)
			(xy 287.588706 -138.95705) (xy 287.588706 -139.475464) (xy 287.588272 -139.485529) (xy 287.580542 -139.504117)
			(xy 287.57372 -139.511532) (xy 285.150052 -141.9352) (xy 288.724084 -141.9352) (xy 288.728155 -141.879578)
			(xy 288.740281 -141.825141) (xy 288.760204 -141.77305) (xy 288.7875 -141.724415) (xy 288.821586 -141.680272)
			(xy 288.861735 -141.641563) (xy 288.907093 -141.609112) (xy 288.956693 -141.583611) (xy 289.009477 -141.565604)
			(xy 289.06432 -141.555474) (xy 289.120054 -141.553437) (xy 289.175491 -141.559537) (xy 289.229448 -141.573643)
			(xy 289.280777 -141.595455) (xy 289.328383 -141.624509) (xy 289.371251 -141.660184) (xy 289.408468 -141.701721)
			(xy 289.439241 -141.748234) (xy 289.462913 -141.798731) (xy 289.478981 -141.852138) (xy 289.487101 -141.907314)
			(xy 289.48761 -141.9352) (xy 289.487101 -141.963086) (xy 289.478981 -142.018262) (xy 289.462913 -142.071669)
			(xy 289.439241 -142.122166) (xy 289.408468 -142.168679) (xy 289.371251 -142.210216) (xy 289.328383 -142.245891)
			(xy 289.280777 -142.274945) (xy 289.229448 -142.296757) (xy 289.175491 -142.310863) (xy 289.120054 -142.316963)
			(xy 289.06432 -142.314926) (xy 289.009477 -142.304796) (xy 288.956693 -142.286789) (xy 288.907093 -142.261288)
			(xy 288.861735 -142.228837) (xy 288.821586 -142.190128) (xy 288.7875 -142.145985) (xy 288.760204 -142.09735)
			(xy 288.740281 -142.045259) (xy 288.728155 -141.990822) (xy 288.724084 -141.9352) (xy 285.150052 -141.9352)
			(xy 284.579568 -142.505684) (xy 284.573893 -142.511852) (xy 284.566513 -142.526888) (xy 284.56509 -142.535148)
			(xy 284.56509 -142.547848) (xy 284.565598 -142.55115) (xy 284.567021 -142.563037) (xy 284.568544 -142.586931)
			(xy 284.568646 -142.598902) (xy 284.568646 -142.601696) (xy 284.568092 -142.628902) (xy 284.560221 -142.682744)
			(xy 284.54478 -142.734921) (xy 284.522083 -142.784376) (xy 284.49259 -142.830104) (xy 284.4569 -142.871178)
			(xy 284.415736 -142.906765) (xy 284.369934 -142.936143) (xy 284.336908 -142.9512) (xy 288.74034 -142.9512)
			(xy 288.744411 -142.895578) (xy 288.756537 -142.841141) (xy 288.77646 -142.78905) (xy 288.803756 -142.740415)
			(xy 288.837842 -142.696272) (xy 288.877991 -142.657563) (xy 288.923349 -142.625112) (xy 288.972949 -142.599611)
			(xy 289.025733 -142.581604) (xy 289.080576 -142.571474) (xy 289.13631 -142.569437) (xy 289.191747 -142.575537)
			(xy 289.245704 -142.589643) (xy 289.297033 -142.611455) (xy 289.344639 -142.640509) (xy 289.387507 -142.676184)
			(xy 289.424724 -142.717721) (xy 289.455497 -142.764234) (xy 289.479169 -142.814731) (xy 289.495237 -142.868138)
			(xy 289.503357 -142.923314) (xy 289.503866 -142.9512) (xy 289.503357 -142.979086) (xy 289.495237 -143.034262)
			(xy 289.479169 -143.087669) (xy 289.455497 -143.138166) (xy 289.424724 -143.184679) (xy 289.387507 -143.226216)
			(xy 289.344639 -143.261891) (xy 289.297033 -143.290945) (xy 289.245704 -143.312757) (xy 289.191747 -143.326863)
			(xy 289.13631 -143.332963) (xy 289.080576 -143.330926) (xy 289.025733 -143.320796) (xy 288.972949 -143.302789)
			(xy 288.923349 -143.277288) (xy 288.877991 -143.244837) (xy 288.837842 -143.206128) (xy 288.803756 -143.161985)
			(xy 288.77646 -143.11335) (xy 288.756537 -143.061259) (xy 288.744411 -143.006822) (xy 288.74034 -142.9512)
			(xy 284.336908 -142.9512) (xy 284.320423 -142.958716) (xy 284.268207 -142.974026) (xy 284.214345 -142.981762)
			(xy 284.187138 -142.982188) (xy 284.186884 -142.982188) (xy 284.173888 -142.98207) (xy 284.147958 -142.980293)
			(xy 284.135068 -142.978632) (xy 284.122876 -142.976854) (xy 284.111954 -142.980664) (xy 284.106512 -142.982722)
			(xy 284.096639 -142.988875) (xy 284.092396 -142.992856) (xy 283.729684 -143.355568) (xy 283.72181 -143.365728)
			(xy 283.718508 -143.371316) (xy 283.71673 -143.377666) (xy 283.708673 -143.405438) (xy 283.689738 -143.460083)
			(xy 283.678884 -143.486886) (xy 283.50972 -143.895572) (xy 283.493569 -143.933454) (xy 283.455829 -144.006658)
			(xy 283.412132 -144.076469) (xy 283.3878 -144.109694) (xy 283.37807 -144.122619) (xy 283.357874 -144.147898)
			(xy 283.347414 -144.16024) (xy 283.346906 -144.160748) (xy 283.339032 -144.169638) (xy 283.338778 -144.169892)
			(xy 283.335222 -144.173702) (xy 283.332174 -144.177258) (xy 283.32811 -144.18818) (xy 283.325824 -144.19961)
			(xy 283.32557 -144.203928) (xy 283.32557 -145.608802) (xy 283.325146 -145.618871) (xy 283.317428 -145.637473)
			(xy 283.310584 -145.64487) (xy 282.159456 -146.795998) (xy 282.743654 -146.795998) (xy 282.747725 -146.740376)
			(xy 282.759851 -146.685939) (xy 282.779774 -146.633848) (xy 282.80707 -146.585213) (xy 282.841156 -146.54107)
			(xy 282.881305 -146.502361) (xy 282.926663 -146.46991) (xy 282.976263 -146.444409) (xy 283.029047 -146.426402)
			(xy 283.08389 -146.416272) (xy 283.139624 -146.414235) (xy 283.195061 -146.420335) (xy 283.249018 -146.434441)
			(xy 283.300347 -146.456253) (xy 283.347953 -146.485307) (xy 283.390821 -146.520982) (xy 283.428038 -146.562519)
			(xy 283.458811 -146.609032) (xy 283.482483 -146.659529) (xy 283.498551 -146.712936) (xy 283.506671 -146.768112)
			(xy 283.50718 -146.795998) (xy 283.506671 -146.823884) (xy 283.498551 -146.87906) (xy 283.482483 -146.932467)
			(xy 283.458811 -146.982964) (xy 283.428038 -147.029477) (xy 283.390821 -147.071014) (xy 283.347953 -147.106689)
			(xy 283.300347 -147.135743) (xy 283.249018 -147.157555) (xy 283.195061 -147.171661) (xy 283.139624 -147.177761)
			(xy 283.08389 -147.175724) (xy 283.029047 -147.165594) (xy 282.976263 -147.147587) (xy 282.926663 -147.122086)
			(xy 282.881305 -147.089635) (xy 282.841156 -147.050926) (xy 282.80707 -147.006783) (xy 282.779774 -146.958148)
			(xy 282.759851 -146.906057) (xy 282.747725 -146.85162) (xy 282.743654 -146.795998) (xy 282.159456 -146.795998)
			(xy 281.634946 -147.320508) (xy 281.627544 -147.327345) (xy 281.608946 -147.335059) (xy 281.598878 -147.335494)
			(xy 280.662634 -147.335494) (xy 280.65788 -147.335589) (xy 280.648543 -147.337377) (xy 280.644092 -147.33905)
			(xy 280.635456 -147.342352) (xy 280.628598 -147.348702) (xy 280.62682 -147.350226) (xy 280.425906 -147.55114)
			(xy 280.396498 -147.579946) (xy 280.333642 -147.633115) (xy 280.266585 -147.680876) (xy 280.19579 -147.7229)
			(xy 280.121748 -147.758894) (xy 280.083514 -147.774152) (xy 280.073354 -147.777962) (xy 279.444958 -148.406358)
			(xy 279.316688 -148.534374) (xy 279.311263 -148.540617) (xy 279.304395 -148.55565) (xy 279.303226 -148.563838)
			(xy 279.301194 -148.590508) (xy 279.301194 -148.591016) (xy 279.280366 -148.847048) (xy 279.280112 -148.851112)
			(xy 279.280112 -148.87194) (xy 279.28189 -148.878544) (xy 279.282652 -148.881084) (xy 279.282652 -148.881338)
			(xy 279.285192 -148.889212) (xy 279.29747 -148.926834) (xy 279.316685 -149.00361) (xy 279.329693 -149.081679)
			(xy 279.336411 -149.160538) (xy 279.337008 -149.200108) (xy 279.337008 -149.204934) (xy 279.33689 -149.22496)
			(xy 279.335237 -149.264977) (xy 279.333706 -149.284944) (xy 279.297892 -149.725888) (xy 279.293331 -149.774452)
			(xy 279.275843 -149.870421) (xy 279.248989 -149.9642) (xy 279.21303 -150.054879) (xy 279.191212 -150.098506)
			(xy 279.187148 -150.10638) (xy 279.186132 -150.114762) (xy 279.185779 -150.11781) (xy 284.581092 -150.11781)
			(xy 284.581705 -150.079563) (xy 284.591707 -150.003724) (xy 284.611504 -149.929835) (xy 284.640757 -149.859154)
			(xy 284.659324 -149.82571) (xy 284.663477 -149.817833) (xy 284.666574 -149.800309) (xy 284.663483 -149.782784)
			(xy 284.659324 -149.77491) (xy 284.640779 -149.741457) (xy 284.611556 -149.67077) (xy 284.591768 -149.596884)
			(xy 284.581749 -149.521054) (xy 284.581092 -149.48281) (xy 284.581541 -149.449929) (xy 284.588907 -149.384582)
			(xy 284.603547 -149.320471) (xy 284.625278 -149.258403) (xy 284.653825 -149.199161) (xy 284.688829 -149.14349)
			(xy 284.72985 -149.092091) (xy 284.752796 -149.068536) (xy 288.996374 -144.824958) (xy 289.002846 -144.817858)
			(xy 289.010471 -144.800241) (xy 289.011132 -144.781055) (xy 289.008312 -144.771872) (xy 288.97199 -144.671288)
			(xy 288.948622 -144.653254) (xy 288.93389 -144.651984) (xy 288.905839 -144.648829) (xy 288.851016 -144.635402)
			(xy 288.798767 -144.614047) (xy 288.750234 -144.585229) (xy 288.706474 -144.549578) (xy 288.668442 -144.507871)
			(xy 288.636967 -144.461018) (xy 288.612736 -144.410039) (xy 288.596277 -144.356048) (xy 288.58795 -144.300222)
			(xy 288.587434 -144.272) (xy 288.587855 -144.244745) (xy 288.595614 -144.190791) (xy 288.610972 -144.138489)
			(xy 288.633617 -144.088907) (xy 288.663089 -144.043051) (xy 288.698787 -144.001858) (xy 288.739985 -143.966164)
			(xy 288.785843 -143.936697) (xy 288.835429 -143.914057) (xy 288.887732 -143.898705) (xy 288.941687 -143.890952)
			(xy 288.968942 -143.890492) (xy 288.997171 -143.890967) (xy 289.053016 -143.899266) (xy 289.107028 -143.915707)
			(xy 289.158026 -143.939929) (xy 289.204897 -143.971404) (xy 289.246616 -144.009445) (xy 289.282272 -144.053219)
			(xy 289.311085 -144.101771) (xy 289.332428 -144.15404) (xy 289.345832 -144.208884) (xy 289.348926 -144.236948)
			(xy 289.350196 -144.25168) (xy 289.36823 -144.275048) (xy 289.468814 -144.31137) (xy 289.477984 -144.3143)
			(xy 289.497213 -144.313685) (xy 289.514842 -144.305982) (xy 289.5219 -144.299432) (xy 290.30549 -143.516096)
			(xy 290.312323 -143.50869) (xy 290.320047 -143.490095) (xy 290.320476 -143.480028) (xy 290.320476 -112.505744)
			(xy 290.320924 -112.47289) (xy 290.328293 -112.407597) (xy 290.34292 -112.343538) (xy 290.364621 -112.281518)
			(xy 290.393126 -112.222314) (xy 290.428074 -112.166672) (xy 290.469028 -112.115288) (xy 290.491926 -112.091724)
			(xy 292.990524 -109.593126) (xy 293.014081 -109.570219) (xy 293.065459 -109.529256) (xy 293.121101 -109.494303)
			(xy 293.180305 -109.465798) (xy 293.242329 -109.444102) (xy 293.306393 -109.429486) (xy 293.371689 -109.422134)
			(xy 293.404544 -109.421676) (xy 296.483024 -109.421676) (xy 296.494168 -109.421055) (xy 296.514341 -109.411566)
			(xy 296.528631 -109.394455) (xy 296.532046 -109.38383) (xy 296.539663 -109.357051) (xy 296.561588 -109.305876)
			(xy 296.590712 -109.258429) (xy 296.626419 -109.215714) (xy 296.667952 -109.178638) (xy 296.714428 -109.147988)
			(xy 296.764864 -109.124413) (xy 296.818188 -109.108412) (xy 296.873271 -109.100326) (xy 296.928945 -109.100326)
			(xy 296.984028 -109.108412) (xy 297.037352 -109.124413) (xy 297.087788 -109.147988) (xy 297.134264 -109.178638)
			(xy 297.175797 -109.215714) (xy 297.211504 -109.258429) (xy 297.240628 -109.305876) (xy 297.262553 -109.357051)
			(xy 297.27017 -109.38383) (xy 297.273526 -109.394492) (xy 297.287804 -109.411656) (xy 297.308028 -109.421116)
			(xy 297.319192 -109.421676) (xy 297.6372 -109.421676) (xy 297.670053 -109.422161) (xy 297.735345 -109.429523)
			(xy 297.799403 -109.444144) (xy 297.861423 -109.46584) (xy 297.920627 -109.494338) (xy 297.97627 -109.529281)
			(xy 298.027655 -109.570231) (xy 298.05122 -109.593126) (xy 298.988226 -110.530132) (xy 302.62906 -110.530132)
			(xy 302.633131 -110.47451) (xy 302.645257 -110.420073) (xy 302.66518 -110.367982) (xy 302.692476 -110.319347)
			(xy 302.726562 -110.275204) (xy 302.766711 -110.236495) (xy 302.812069 -110.204044) (xy 302.861669 -110.178543)
			(xy 302.914453 -110.160536) (xy 302.969296 -110.150406) (xy 303.02503 -110.148369) (xy 303.080467 -110.154469)
			(xy 303.134424 -110.168575) (xy 303.185753 -110.190387) (xy 303.233359 -110.219441) (xy 303.276227 -110.255116)
			(xy 303.313444 -110.296653) (xy 303.344217 -110.343166) (xy 303.367889 -110.393663) (xy 303.383957 -110.44707)
			(xy 303.392077 -110.502246) (xy 303.392586 -110.530132) (xy 303.392077 -110.558018) (xy 303.383957 -110.613194)
			(xy 303.367889 -110.666601) (xy 303.344217 -110.717098) (xy 303.313444 -110.763611) (xy 303.276227 -110.805148)
			(xy 303.233359 -110.840823) (xy 303.185753 -110.869877) (xy 303.134424 -110.891689) (xy 303.080467 -110.905795)
			(xy 303.02503 -110.911895) (xy 302.969296 -110.909858) (xy 302.914453 -110.899728) (xy 302.861669 -110.881721)
			(xy 302.812069 -110.85622) (xy 302.766711 -110.823769) (xy 302.726562 -110.78506) (xy 302.692476 -110.740917)
			(xy 302.66518 -110.692282) (xy 302.645257 -110.640191) (xy 302.633131 -110.585754) (xy 302.62906 -110.530132)
			(xy 298.988226 -110.530132) (xy 299.647356 -111.189262) (xy 299.673901 -111.216631) (xy 299.720383 -111.277067)
			(xy 299.758614 -111.343033) (xy 299.773848 -111.377984) (xy 299.777425 -111.3858) (xy 299.788935 -111.398555)
			(xy 299.804028 -111.406765) (xy 299.812456 -111.408464) (xy 299.838869 -111.413257) (xy 299.890065 -111.429404)
			(xy 299.938494 -111.452565) (xy 299.9832 -111.482284) (xy 300.0233 -111.517974) (xy 300.058004 -111.558931)
			(xy 300.086627 -111.604346) (xy 300.108603 -111.653324) (xy 300.1235 -111.704898) (xy 300.131023 -111.758051)
			(xy 300.13148 -111.784892) (xy 300.131034 -111.812237) (xy 300.123226 -111.866367) (xy 300.11797 -111.884206)
			(xy 302.56429 -111.884206) (xy 302.568361 -111.828584) (xy 302.580487 -111.774147) (xy 302.60041 -111.722056)
			(xy 302.627706 -111.673421) (xy 302.661792 -111.629278) (xy 302.701941 -111.590569) (xy 302.747299 -111.558118)
			(xy 302.796899 -111.532617) (xy 302.849683 -111.51461) (xy 302.904526 -111.50448) (xy 302.96026 -111.502443)
			(xy 303.015697 -111.508543) (xy 303.069654 -111.522649) (xy 303.120983 -111.544461) (xy 303.168589 -111.573515)
			(xy 303.211457 -111.60919) (xy 303.248674 -111.650727) (xy 303.279447 -111.69724) (xy 303.303119 -111.747737)
			(xy 303.319187 -111.801144) (xy 303.327307 -111.85632) (xy 303.327816 -111.884206) (xy 303.327307 -111.912092)
			(xy 303.319187 -111.967268) (xy 303.315138 -111.980726) (xy 306.101496 -111.980726) (xy 306.102037 -111.951988)
			(xy 306.110655 -111.895161) (xy 306.127701 -111.840271) (xy 306.152789 -111.788559) (xy 306.185351 -111.741195)
			(xy 306.20462 -111.719868) (xy 306.211224 -111.71301) (xy 306.218336 -111.694976) (xy 306.218336 -111.606076)
			(xy 306.211224 -111.588042) (xy 306.20462 -111.581184) (xy 306.185375 -111.559835) (xy 306.152809 -111.512476)
			(xy 306.127717 -111.460768) (xy 306.110665 -111.405881) (xy 306.10204 -111.349056) (xy 306.102037 -111.291581)
			(xy 306.110656 -111.234756) (xy 306.127703 -111.179867) (xy 306.15279 -111.128157) (xy 306.185351 -111.080795)
			(xy 306.20462 -111.059468) (xy 306.211224 -111.05261) (xy 306.218336 -111.034576) (xy 306.218336 -110.945676)
			(xy 306.211224 -110.927642) (xy 306.20462 -110.920784) (xy 306.185375 -110.899435) (xy 306.152809 -110.852076)
			(xy 306.127717 -110.800368) (xy 306.110665 -110.745481) (xy 306.10204 -110.688656) (xy 306.102037 -110.631181)
			(xy 306.110656 -110.574356) (xy 306.127703 -110.519467) (xy 306.15279 -110.467757) (xy 306.185351 -110.420395)
			(xy 306.20462 -110.399068) (xy 306.211224 -110.39221) (xy 306.218336 -110.374176) (xy 306.218336 -110.285276)
			(xy 306.211224 -110.267242) (xy 306.20462 -110.260384) (xy 306.185375 -110.239035) (xy 306.152809 -110.191676)
			(xy 306.127717 -110.139968) (xy 306.110665 -110.085081) (xy 306.10204 -110.028256) (xy 306.102037 -109.970781)
			(xy 306.110656 -109.913956) (xy 306.127703 -109.859067) (xy 306.15279 -109.807357) (xy 306.185351 -109.759995)
			(xy 306.20462 -109.738668) (xy 306.211224 -109.73181) (xy 306.218336 -109.713776) (xy 306.218336 -109.624876)
			(xy 306.211224 -109.606842) (xy 306.20462 -109.599984) (xy 306.185359 -109.578649) (xy 306.152792 -109.531289)
			(xy 306.127698 -109.479579) (xy 306.110645 -109.42469) (xy 306.102019 -109.367864) (xy 306.101496 -109.339126)
			(xy 306.10198 -109.311874) (xy 306.109733 -109.257923) (xy 306.125086 -109.205625) (xy 306.147726 -109.156045)
			(xy 306.177191 -109.110192) (xy 306.212883 -109.068999) (xy 306.254074 -109.033305) (xy 306.299926 -109.003836)
			(xy 306.349505 -108.981194) (xy 306.401802 -108.965838) (xy 306.455752 -108.958081) (xy 306.483004 -108.957618)
			(xy 306.509318 -108.958077) (xy 306.561447 -108.965313) (xy 306.612091 -108.979633) (xy 306.66029 -109.000767)
			(xy 306.705133 -109.028315) (xy 306.745772 -109.061755) (xy 306.763928 -109.080808) (xy 306.771436 -109.088225)
			(xy 306.790727 -109.09674) (xy 306.801266 -109.097318) (xy 306.875942 -109.097318) (xy 306.886489 -109.096766)
			(xy 306.905784 -109.088246) (xy 306.91328 -109.080808) (xy 306.931454 -109.061771) (xy 306.972079 -109.028312)
			(xy 307.016916 -109.00075) (xy 307.065113 -108.979608) (xy 307.115757 -108.965287) (xy 307.167889 -108.958059)
			(xy 307.194204 -108.957618) (xy 307.221458 -108.958052) (xy 307.275411 -108.96581) (xy 307.327711 -108.981168)
			(xy 307.377293 -109.003813) (xy 307.423148 -109.033283) (xy 307.464341 -109.06898) (xy 307.500035 -109.110176)
			(xy 307.529502 -109.156033) (xy 307.552143 -109.205617) (xy 307.567496 -109.257918) (xy 307.57525 -109.311872)
			(xy 307.575712 -109.339126) (xy 307.575201 -109.367865) (xy 307.566575 -109.424693) (xy 307.549522 -109.479584)
			(xy 307.524427 -109.531295) (xy 307.49186 -109.578657) (xy 307.472588 -109.599984) (xy 307.465984 -109.606842)
			(xy 307.458872 -109.624876) (xy 307.458872 -109.713776) (xy 307.465984 -109.73181) (xy 307.472588 -109.738668)
			(xy 307.491884 -109.759973) (xy 307.524447 -109.807339) (xy 307.549537 -109.859055) (xy 307.566584 -109.913949)
			(xy 307.575204 -109.970779) (xy 307.575201 -110.028259) (xy 307.566576 -110.085088) (xy 307.549523 -110.139981)
			(xy 307.524428 -110.191694) (xy 307.49186 -110.239057) (xy 307.472588 -110.260384) (xy 307.465984 -110.267242)
			(xy 307.458872 -110.285276) (xy 307.458872 -110.374176) (xy 307.465984 -110.39221) (xy 307.472588 -110.399068)
			(xy 307.491884 -110.420373) (xy 307.524447 -110.467739) (xy 307.549537 -110.519455) (xy 307.566584 -110.574349)
			(xy 307.575204 -110.631179) (xy 307.575201 -110.688659) (xy 307.566576 -110.745488) (xy 307.549523 -110.800381)
			(xy 307.524428 -110.852094) (xy 307.49186 -110.899457) (xy 307.472588 -110.920784) (xy 307.465984 -110.927642)
			(xy 307.458872 -110.945676) (xy 307.458872 -111.034576) (xy 307.465984 -111.05261) (xy 307.472588 -111.059468)
			(xy 307.491884 -111.080773) (xy 307.524447 -111.128139) (xy 307.549537 -111.179855) (xy 307.566584 -111.234749)
			(xy 307.575204 -111.291579) (xy 307.575201 -111.349059) (xy 307.566576 -111.405888) (xy 307.549523 -111.460781)
			(xy 307.524428 -111.512494) (xy 307.49186 -111.559857) (xy 307.472588 -111.581184) (xy 307.465984 -111.588042)
			(xy 307.458872 -111.606076) (xy 307.458872 -111.694976) (xy 307.465984 -111.71301) (xy 307.472588 -111.719868)
			(xy 307.491875 -111.741181) (xy 307.524438 -111.788547) (xy 307.549527 -111.840262) (xy 307.566574 -111.895156)
			(xy 307.575193 -111.951986) (xy 307.575712 -111.980726) (xy 307.575246 -112.007978) (xy 307.567486 -112.061926)
			(xy 307.552128 -112.114221) (xy 307.529484 -112.163798) (xy 307.500016 -112.209648) (xy 307.464322 -112.250838)
			(xy 307.42313 -112.286529) (xy 307.377279 -112.315995) (xy 307.3277 -112.338636) (xy 307.275404 -112.353991)
			(xy 307.221456 -112.361748) (xy 307.194204 -112.362234) (xy 307.167891 -112.361753) (xy 307.115763 -112.354519)
			(xy 307.065121 -112.340202) (xy 307.016922 -112.319072) (xy 306.972078 -112.291529) (xy 306.931438 -112.258094)
			(xy 306.91328 -112.239044) (xy 306.905762 -112.231638) (xy 306.886479 -112.223115) (xy 306.875942 -112.222534)
			(xy 306.801266 -112.222534) (xy 306.790717 -112.223075) (xy 306.771421 -112.231601) (xy 306.763928 -112.239044)
			(xy 306.74576 -112.258087) (xy 306.705132 -112.291544) (xy 306.660294 -112.319103) (xy 306.612096 -112.340244)
			(xy 306.561451 -112.354564) (xy 306.509319 -112.361793) (xy 306.483004 -112.362234) (xy 306.455754 -112.361719)
			(xy 306.401809 -112.353963) (xy 306.349516 -112.33861) (xy 306.299941 -112.315971) (xy 306.254091 -112.286508)
			(xy 306.212902 -112.250819) (xy 306.17721 -112.209633) (xy 306.147743 -112.163786) (xy 306.125101 -112.114212)
			(xy 306.109743 -112.061921) (xy 306.101984 -112.007976) (xy 306.101496 -111.980726) (xy 303.315138 -111.980726)
			(xy 303.303119 -112.020675) (xy 303.279447 -112.071172) (xy 303.248674 -112.117685) (xy 303.211457 -112.159222)
			(xy 303.168589 -112.194897) (xy 303.120983 -112.223951) (xy 303.069654 -112.245763) (xy 303.015697 -112.259869)
			(xy 302.96026 -112.265969) (xy 302.904526 -112.263932) (xy 302.849683 -112.253802) (xy 302.796899 -112.235795)
			(xy 302.747299 -112.210294) (xy 302.701941 -112.177843) (xy 302.661792 -112.139134) (xy 302.627706 -112.094991)
			(xy 302.60041 -112.046356) (xy 302.580487 -111.994265) (xy 302.568361 -111.939828) (xy 302.56429 -111.884206)
			(xy 300.11797 -111.884206) (xy 300.107768 -111.918827) (xy 300.084978 -111.968542) (xy 300.055322 -112.014493)
			(xy 300.019408 -112.055739) (xy 299.977973 -112.091434) (xy 299.931865 -112.120846) (xy 299.88203 -112.143373)
			(xy 299.85589 -112.151414) (xy 299.845453 -112.154902) (xy 299.828756 -112.169207) (xy 299.819583 -112.189188)
			(xy 299.81906 -112.200182) (xy 299.81906 -112.421924) (xy 301.65497 -112.421924) (xy 301.659041 -112.366302)
			(xy 301.671167 -112.311865) (xy 301.69109 -112.259774) (xy 301.718386 -112.211139) (xy 301.752472 -112.166996)
			(xy 301.792621 -112.128287) (xy 301.837979 -112.095836) (xy 301.887579 -112.070335) (xy 301.940363 -112.052328)
			(xy 301.995206 -112.042198) (xy 302.05094 -112.040161) (xy 302.106377 -112.046261) (xy 302.160334 -112.060367)
			(xy 302.211663 -112.082179) (xy 302.259269 -112.111233) (xy 302.302137 -112.146908) (xy 302.339354 -112.188445)
			(xy 302.370127 -112.234958) (xy 302.393799 -112.285455) (xy 302.409867 -112.338862) (xy 302.417987 -112.394038)
			(xy 302.418496 -112.421924) (xy 302.417987 -112.44981) (xy 302.409867 -112.504986) (xy 302.393799 -112.558393)
			(xy 302.370127 -112.60889) (xy 302.339354 -112.655403) (xy 302.302137 -112.69694) (xy 302.259269 -112.732615)
			(xy 302.211663 -112.761669) (xy 302.160334 -112.783481) (xy 302.106377 -112.797587) (xy 302.05094 -112.803687)
			(xy 301.995206 -112.80165) (xy 301.940363 -112.79152) (xy 301.887579 -112.773513) (xy 301.837979 -112.748012)
			(xy 301.792621 -112.715561) (xy 301.752472 -112.676852) (xy 301.718386 -112.632709) (xy 301.69109 -112.584074)
			(xy 301.671167 -112.531983) (xy 301.659041 -112.477546) (xy 301.65497 -112.421924) (xy 299.81906 -112.421924)
			(xy 299.81906 -112.485424) (xy 299.81842 -112.523341) (xy 299.80858 -112.598536) (xy 299.789119 -112.671832)
			(xy 299.760363 -112.742004) (xy 299.742098 -112.775238) (xy 299.737409 -112.784412) (xy 299.73505 -112.804861)
			(xy 299.737526 -112.814862) (xy 299.758354 -112.88522) (xy 299.761649 -112.894779) (xy 299.7745 -112.91037)
			(xy 299.783246 -112.915446) (xy 299.783246 -112.9157) (xy 299.783754 -112.9157) (xy 299.814944 -112.93262)
			(xy 299.873412 -112.972826) (xy 299.892421 -112.989614) (xy 302.639982 -112.989614) (xy 302.644053 -112.933992)
			(xy 302.656179 -112.879555) (xy 302.676102 -112.827464) (xy 302.703398 -112.778829) (xy 302.737484 -112.734686)
			(xy 302.777633 -112.695977) (xy 302.822991 -112.663526) (xy 302.872591 -112.638025) (xy 302.925375 -112.620018)
			(xy 302.980218 -112.609888) (xy 303.035952 -112.607851) (xy 303.091389 -112.613951) (xy 303.145346 -112.628057)
			(xy 303.196675 -112.649869) (xy 303.244281 -112.678923) (xy 303.287149 -112.714598) (xy 303.324366 -112.756135)
			(xy 303.355139 -112.802648) (xy 303.378811 -112.853145) (xy 303.394879 -112.906552) (xy 303.402999 -112.961728)
			(xy 303.403508 -112.989614) (xy 303.402999 -113.0175) (xy 303.394879 -113.072676) (xy 303.378811 -113.126083)
			(xy 303.355139 -113.17658) (xy 303.324366 -113.223093) (xy 303.287149 -113.26463) (xy 303.244281 -113.300305)
			(xy 303.196675 -113.329359) (xy 303.145346 -113.351171) (xy 303.091389 -113.365277) (xy 303.035952 -113.371377)
			(xy 302.980218 -113.36934) (xy 302.925375 -113.35921) (xy 302.872591 -113.341203) (xy 302.822991 -113.315702)
			(xy 302.777633 -113.283251) (xy 302.737484 -113.244542) (xy 302.703398 -113.200399) (xy 302.676102 -113.151764)
			(xy 302.656179 -113.099673) (xy 302.644053 -113.045236) (xy 302.639982 -112.989614) (xy 299.892421 -112.989614)
			(xy 299.926598 -113.019797) (xy 299.973724 -113.072847) (xy 300.014099 -113.131198) (xy 300.047134 -113.193997)
			(xy 300.072345 -113.260326) (xy 300.089363 -113.329213) (xy 300.097939 -113.399651) (xy 300.09846 -113.43513)
			(xy 300.098421 -113.437924) (xy 301.557688 -113.437924) (xy 301.561759 -113.382302) (xy 301.573885 -113.327865)
			(xy 301.593808 -113.275774) (xy 301.621104 -113.227139) (xy 301.65519 -113.182996) (xy 301.695339 -113.144287)
			(xy 301.740697 -113.111836) (xy 301.790297 -113.086335) (xy 301.843081 -113.068328) (xy 301.897924 -113.058198)
			(xy 301.953658 -113.056161) (xy 302.009095 -113.062261) (xy 302.063052 -113.076367) (xy 302.114381 -113.098179)
			(xy 302.161987 -113.127233) (xy 302.204855 -113.162908) (xy 302.242072 -113.204445) (xy 302.272845 -113.250958)
			(xy 302.296517 -113.301455) (xy 302.312585 -113.354862) (xy 302.320705 -113.410038) (xy 302.321214 -113.437924)
			(xy 302.320705 -113.46581) (xy 302.312585 -113.520986) (xy 302.296517 -113.574393) (xy 302.272845 -113.62489)
			(xy 302.242072 -113.671403) (xy 302.204855 -113.71294) (xy 302.161987 -113.748615) (xy 302.114381 -113.777669)
			(xy 302.063052 -113.799481) (xy 302.009095 -113.813587) (xy 301.953658 -113.819687) (xy 301.897924 -113.81765)
			(xy 301.843081 -113.80752) (xy 301.790297 -113.789513) (xy 301.740697 -113.764012) (xy 301.695339 -113.731561)
			(xy 301.65519 -113.692852) (xy 301.621104 -113.648709) (xy 301.593808 -113.600074) (xy 301.573885 -113.547983)
			(xy 301.561759 -113.493546) (xy 301.557688 -113.437924) (xy 300.098421 -113.437924) (xy 300.097972 -113.470534)
			(xy 300.089436 -113.540827) (xy 300.072492 -113.609578) (xy 300.047386 -113.675787) (xy 300.014485 -113.738488)
			(xy 299.974268 -113.796767) (xy 299.927322 -113.849776) (xy 299.87433 -113.896741) (xy 299.816064 -113.936978)
			(xy 299.753375 -113.969901) (xy 299.687175 -113.99503) (xy 299.61843 -114.011999) (xy 299.54814 -114.02056)
			(xy 299.512736 -114.021108) (xy 299.109384 -114.021108) (xy 299.076503 -114.020676) (xy 299.011154 -114.013307)
			(xy 298.947043 -113.998664) (xy 298.884976 -113.976931) (xy 298.825734 -113.948381) (xy 298.770063 -113.913374)
			(xy 298.718664 -113.872351) (xy 298.69511 -113.849404) (xy 297.738292 -112.892586) (xy 297.73089 -112.885748)
			(xy 297.712292 -112.878028) (xy 297.702224 -112.8776) (xy 297.434 -112.8776) (xy 297.425321 -112.877893)
			(xy 297.408944 -112.883646) (xy 297.395422 -112.894528) (xy 297.390566 -112.90173) (xy 297.345354 -112.975136)
			(xy 297.341132 -112.982693) (xy 297.337441 -112.999592) (xy 297.339541 -113.016762) (xy 297.343068 -113.024666)
			(xy 297.355803 -113.051094) (xy 297.375751 -113.106267) (xy 297.389205 -113.163371) (xy 297.395983 -113.221646)
			(xy 297.396408 -113.25098) (xy 297.396408 -113.251742) (xy 297.396048 -113.282461) (xy 297.388637 -113.343452)
			(xy 297.373929 -113.403104) (xy 297.352138 -113.460549) (xy 297.323581 -113.514948) (xy 297.288675 -113.565508)
			(xy 297.24793 -113.611492) (xy 297.201939 -113.65223) (xy 297.151372 -113.687127) (xy 297.096968 -113.715674)
			(xy 297.03952 -113.737455) (xy 296.979865 -113.752153) (xy 296.918874 -113.759554) (xy 296.888154 -113.759996)
			(xy 294.586914 -113.759996) (xy 294.576842 -113.760403) (xy 294.558243 -113.768134) (xy 294.550846 -113.774982)
			(xy 293.906702 -114.41938) (xy 293.899879 -114.426793) (xy 293.892149 -114.445382) (xy 293.891716 -114.455448)
			(xy 293.891716 -114.581432) (xy 298.499528 -114.581432) (xy 298.503599 -114.52581) (xy 298.515725 -114.471373)
			(xy 298.535648 -114.419282) (xy 298.562944 -114.370647) (xy 298.59703 -114.326504) (xy 298.637179 -114.287795)
			(xy 298.682537 -114.255344) (xy 298.732137 -114.229843) (xy 298.784921 -114.211836) (xy 298.839764 -114.201706)
			(xy 298.895498 -114.199669) (xy 298.950935 -114.205769) (xy 299.004892 -114.219875) (xy 299.056221 -114.241687)
			(xy 299.103827 -114.270741) (xy 299.127082 -114.290094) (xy 302.560226 -114.290094) (xy 302.564297 -114.234472)
			(xy 302.576423 -114.180035) (xy 302.596346 -114.127944) (xy 302.623642 -114.079309) (xy 302.657728 -114.035166)
			(xy 302.697877 -113.996457) (xy 302.743235 -113.964006) (xy 302.792835 -113.938505) (xy 302.845619 -113.920498)
			(xy 302.900462 -113.910368) (xy 302.956196 -113.908331) (xy 303.011633 -113.914431) (xy 303.06559 -113.928537)
			(xy 303.116919 -113.950349) (xy 303.164525 -113.979403) (xy 303.207393 -114.015078) (xy 303.24461 -114.056615)
			(xy 303.275383 -114.103128) (xy 303.299055 -114.153625) (xy 303.315123 -114.207032) (xy 303.323243 -114.262208)
			(xy 303.323752 -114.290094) (xy 303.323243 -114.31798) (xy 303.315123 -114.373156) (xy 303.299055 -114.426563)
			(xy 303.275383 -114.47706) (xy 303.24461 -114.523573) (xy 303.207393 -114.56511) (xy 303.164525 -114.600785)
			(xy 303.116919 -114.629839) (xy 303.06559 -114.651651) (xy 303.011633 -114.665757) (xy 302.956196 -114.671857)
			(xy 302.900462 -114.66982) (xy 302.845619 -114.65969) (xy 302.792835 -114.641683) (xy 302.743235 -114.616182)
			(xy 302.697877 -114.583731) (xy 302.657728 -114.545022) (xy 302.623642 -114.500879) (xy 302.596346 -114.452244)
			(xy 302.576423 -114.400153) (xy 302.564297 -114.345716) (xy 302.560226 -114.290094) (xy 299.127082 -114.290094)
			(xy 299.146695 -114.306416) (xy 299.183912 -114.347953) (xy 299.214685 -114.394466) (xy 299.238357 -114.444963)
			(xy 299.254425 -114.49837) (xy 299.262545 -114.553546) (xy 299.263054 -114.581432) (xy 299.262545 -114.609318)
			(xy 299.254425 -114.664494) (xy 299.238357 -114.717901) (xy 299.214685 -114.768398) (xy 299.183912 -114.814911)
			(xy 299.146695 -114.856448) (xy 299.103827 -114.892123) (xy 299.056221 -114.921177) (xy 299.004892 -114.942989)
			(xy 298.950935 -114.957095) (xy 298.895498 -114.963195) (xy 298.839764 -114.961158) (xy 298.784921 -114.951028)
			(xy 298.732137 -114.933021) (xy 298.682537 -114.90752) (xy 298.637179 -114.875069) (xy 298.59703 -114.83636)
			(xy 298.562944 -114.792217) (xy 298.535648 -114.743582) (xy 298.515725 -114.691491) (xy 298.503599 -114.637054)
			(xy 298.499528 -114.581432) (xy 293.891716 -114.581432) (xy 293.891716 -115.285774) (xy 299.130718 -115.285774)
			(xy 299.134789 -115.230152) (xy 299.146915 -115.175715) (xy 299.166838 -115.123624) (xy 299.194134 -115.074989)
			(xy 299.22822 -115.030846) (xy 299.268369 -114.992137) (xy 299.313727 -114.959686) (xy 299.363327 -114.934185)
			(xy 299.416111 -114.916178) (xy 299.470954 -114.906048) (xy 299.526688 -114.904011) (xy 299.582125 -114.910111)
			(xy 299.636082 -114.924217) (xy 299.687411 -114.946029) (xy 299.735017 -114.975083) (xy 299.777885 -115.010758)
			(xy 299.815102 -115.052295) (xy 299.845875 -115.098808) (xy 299.869547 -115.149305) (xy 299.885615 -115.202712)
			(xy 299.893735 -115.257888) (xy 299.894244 -115.285774) (xy 299.893735 -115.31366) (xy 299.886774 -115.360958)
			(xy 306.318412 -115.360958) (xy 306.318909 -115.333589) (xy 306.326719 -115.279411) (xy 306.342201 -115.226908)
			(xy 306.365036 -115.177161) (xy 306.394754 -115.131193) (xy 306.412392 -115.11026) (xy 306.412646 -115.110006)
			(xy 306.418242 -115.102926) (xy 306.424482 -115.086004) (xy 306.424838 -115.076986) (xy 306.424838 -115.00993)
			(xy 306.424458 -115.000916) (xy 306.418226 -114.983999) (xy 306.412646 -114.97691) (xy 306.412392 -114.97691)
			(xy 306.412392 -114.976656) (xy 306.394764 -114.955715) (xy 306.365051 -114.909744) (xy 306.342213 -114.859999)
			(xy 306.326719 -114.807501) (xy 306.318888 -114.753327) (xy 306.318412 -114.725958) (xy 306.318839 -114.698705)
			(xy 306.326602 -114.644754) (xy 306.341963 -114.592457) (xy 306.364611 -114.542878) (xy 306.394083 -114.497027)
			(xy 306.429781 -114.455837) (xy 306.470977 -114.420146) (xy 306.516833 -114.390681) (xy 306.566415 -114.368041)
			(xy 306.618715 -114.352688) (xy 306.672667 -114.344934) (xy 306.69992 -114.34445) (xy 306.727291 -114.344892)
			(xy 306.781472 -114.352714) (xy 306.833976 -114.368208) (xy 306.883722 -114.391055) (xy 306.929688 -114.420786)
			(xy 306.950618 -114.43843) (xy 306.950872 -114.438684) (xy 306.957964 -114.444263) (xy 306.974876 -114.450515)
			(xy 306.983892 -114.450876) (xy 307.050948 -114.450876) (xy 307.059963 -114.450499) (xy 307.07688 -114.444266)
			(xy 307.083968 -114.438684) (xy 307.083968 -114.43843) (xy 307.084222 -114.43843) (xy 307.105177 -114.420819)
			(xy 307.151143 -114.391102) (xy 307.200884 -114.36826) (xy 307.25338 -114.352762) (xy 307.307552 -114.344927)
			(xy 307.33492 -114.34445) (xy 307.36217 -114.344959) (xy 307.416115 -114.352717) (xy 307.468406 -114.368073)
			(xy 307.517981 -114.390713) (xy 307.563829 -114.420178) (xy 307.605018 -114.455866) (xy 307.640709 -114.497053)
			(xy 307.670176 -114.5429) (xy 307.69282 -114.592473) (xy 307.708178 -114.644764) (xy 307.715939 -114.698708)
			(xy 307.716428 -114.725958) (xy 307.715955 -114.753328) (xy 307.708141 -114.807508) (xy 307.692655 -114.860011)
			(xy 307.669814 -114.909758) (xy 307.64009 -114.955725) (xy 307.622448 -114.976656) (xy 307.622194 -114.97691)
			(xy 307.616596 -114.983989) (xy 307.610357 -115.000912) (xy 307.610002 -115.00993) (xy 307.610002 -115.076986)
			(xy 307.610365 -115.086002) (xy 307.616608 -115.102919) (xy 307.622194 -115.110006) (xy 307.622448 -115.110006)
			(xy 307.622448 -115.11026) (xy 307.640074 -115.131203) (xy 307.669789 -115.177172) (xy 307.692629 -115.226917)
			(xy 307.708123 -115.279415) (xy 307.715953 -115.333589) (xy 307.716428 -115.360958) (xy 307.715906 -115.388209)
			(xy 307.708155 -115.442157) (xy 307.692805 -115.494452) (xy 307.670169 -115.544031) (xy 307.640707 -115.589883)
			(xy 307.60502 -115.631076) (xy 307.563833 -115.66677) (xy 307.517985 -115.696239) (xy 307.46841 -115.718884)
			(xy 307.416117 -115.734242) (xy 307.362171 -115.742001) (xy 307.33492 -115.742466) (xy 307.30755 -115.741996)
			(xy 307.253371 -115.734181) (xy 307.200867 -115.718693) (xy 307.15112 -115.695852) (xy 307.105153 -115.666127)
			(xy 307.084222 -115.648486) (xy 307.083968 -115.648232) (xy 307.076872 -115.64266) (xy 307.059962 -115.636406)
			(xy 307.050948 -115.63604) (xy 306.983892 -115.63604) (xy 306.974874 -115.636384) (xy 306.957956 -115.64264)
			(xy 306.950872 -115.648232) (xy 306.950872 -115.648486) (xy 306.950618 -115.648486) (xy 306.929688 -115.666128)
			(xy 306.883715 -115.69584) (xy 306.833967 -115.718675) (xy 306.781466 -115.734166) (xy 306.727289 -115.741993)
			(xy 306.69992 -115.742466) (xy 306.672666 -115.742026) (xy 306.618712 -115.734271) (xy 306.566411 -115.718915)
			(xy 306.516828 -115.696272) (xy 306.470973 -115.666802) (xy 306.429779 -115.631106) (xy 306.394085 -115.58991)
			(xy 306.364618 -115.544053) (xy 306.341977 -115.494468) (xy 306.326625 -115.442167) (xy 306.318872 -115.388212)
			(xy 306.318412 -115.360958) (xy 299.886774 -115.360958) (xy 299.885615 -115.368836) (xy 299.869547 -115.422243)
			(xy 299.845875 -115.47274) (xy 299.815102 -115.519253) (xy 299.777885 -115.56079) (xy 299.735017 -115.596465)
			(xy 299.687411 -115.625519) (xy 299.636082 -115.647331) (xy 299.582125 -115.661437) (xy 299.526688 -115.667537)
			(xy 299.470954 -115.6655) (xy 299.416111 -115.65537) (xy 299.363327 -115.637363) (xy 299.313727 -115.611862)
			(xy 299.268369 -115.579411) (xy 299.22822 -115.540702) (xy 299.194134 -115.496559) (xy 299.166838 -115.447924)
			(xy 299.146915 -115.395833) (xy 299.134789 -115.341396) (xy 299.130718 -115.285774) (xy 293.891716 -115.285774)
			(xy 293.891716 -115.902486) (xy 296.391074 -115.902486) (xy 296.395145 -115.846864) (xy 296.407271 -115.792427)
			(xy 296.427194 -115.740336) (xy 296.45449 -115.691701) (xy 296.488576 -115.647558) (xy 296.528725 -115.608849)
			(xy 296.574083 -115.576398) (xy 296.623683 -115.550897) (xy 296.676467 -115.53289) (xy 296.73131 -115.52276)
			(xy 296.787044 -115.520723) (xy 296.842481 -115.526823) (xy 296.896438 -115.540929) (xy 296.947767 -115.562741)
			(xy 296.995373 -115.591795) (xy 297.038241 -115.62747) (xy 297.075458 -115.669007) (xy 297.106231 -115.71552)
			(xy 297.129903 -115.766017) (xy 297.145971 -115.819424) (xy 297.154091 -115.8746) (xy 297.1546 -115.902486)
			(xy 297.154091 -115.930372) (xy 297.145971 -115.985548) (xy 297.129903 -116.038955) (xy 297.106231 -116.089452)
			(xy 297.075458 -116.135965) (xy 297.038241 -116.177502) (xy 296.995373 -116.213177) (xy 296.947767 -116.242231)
			(xy 296.896438 -116.264043) (xy 296.842481 -116.278149) (xy 296.787044 -116.284249) (xy 296.73131 -116.282212)
			(xy 296.676467 -116.272082) (xy 296.623683 -116.254075) (xy 296.574083 -116.228574) (xy 296.528725 -116.196123)
			(xy 296.488576 -116.157414) (xy 296.45449 -116.113271) (xy 296.427194 -116.064636) (xy 296.407271 -116.012545)
			(xy 296.395145 -115.958108) (xy 296.391074 -115.902486) (xy 293.891716 -115.902486) (xy 293.891716 -116.44757)
			(xy 298.357034 -116.44757) (xy 298.361105 -116.391948) (xy 298.373231 -116.337511) (xy 298.393154 -116.28542)
			(xy 298.42045 -116.236785) (xy 298.454536 -116.192642) (xy 298.494685 -116.153933) (xy 298.540043 -116.121482)
			(xy 298.589643 -116.095981) (xy 298.642427 -116.077974) (xy 298.69727 -116.067844) (xy 298.753004 -116.065807)
			(xy 298.808441 -116.071907) (xy 298.862398 -116.086013) (xy 298.913727 -116.107825) (xy 298.961333 -116.136879)
			(xy 299.004201 -116.172554) (xy 299.041418 -116.214091) (xy 299.072191 -116.260604) (xy 299.095863 -116.311101)
			(xy 299.111931 -116.364508) (xy 299.120051 -116.419684) (xy 299.12056 -116.44757) (xy 299.120051 -116.475456)
			(xy 299.119781 -116.477288) (xy 303.504344 -116.477288) (xy 303.508415 -116.421666) (xy 303.520541 -116.367229)
			(xy 303.540464 -116.315138) (xy 303.56776 -116.266503) (xy 303.601846 -116.22236) (xy 303.641995 -116.183651)
			(xy 303.687353 -116.1512) (xy 303.736953 -116.125699) (xy 303.789737 -116.107692) (xy 303.84458 -116.097562)
			(xy 303.900314 -116.095525) (xy 303.955751 -116.101625) (xy 304.009708 -116.115731) (xy 304.061037 -116.137543)
			(xy 304.108643 -116.166597) (xy 304.151511 -116.202272) (xy 304.188728 -116.243809) (xy 304.219501 -116.290322)
			(xy 304.243173 -116.340819) (xy 304.259241 -116.394226) (xy 304.267361 -116.449402) (xy 304.26787 -116.477288)
			(xy 304.267361 -116.505174) (xy 304.259241 -116.56035) (xy 304.243173 -116.613757) (xy 304.219501 -116.664254)
			(xy 304.188728 -116.710767) (xy 304.151511 -116.752304) (xy 304.108643 -116.787979) (xy 304.061037 -116.817033)
			(xy 304.009708 -116.838845) (xy 303.955751 -116.852951) (xy 303.900314 -116.859051) (xy 303.84458 -116.857014)
			(xy 303.789737 -116.846884) (xy 303.736953 -116.828877) (xy 303.687353 -116.803376) (xy 303.641995 -116.770925)
			(xy 303.601846 -116.732216) (xy 303.56776 -116.688073) (xy 303.540464 -116.639438) (xy 303.520541 -116.587347)
			(xy 303.508415 -116.53291) (xy 303.504344 -116.477288) (xy 299.119781 -116.477288) (xy 299.111931 -116.530632)
			(xy 299.095863 -116.584039) (xy 299.072191 -116.634536) (xy 299.041418 -116.681049) (xy 299.004201 -116.722586)
			(xy 298.961333 -116.758261) (xy 298.913727 -116.787315) (xy 298.862398 -116.809127) (xy 298.808441 -116.823233)
			(xy 298.753004 -116.829333) (xy 298.69727 -116.827296) (xy 298.642427 -116.817166) (xy 298.589643 -116.799159)
			(xy 298.540043 -116.773658) (xy 298.494685 -116.741207) (xy 298.454536 -116.702498) (xy 298.42045 -116.658355)
			(xy 298.393154 -116.60972) (xy 298.373231 -116.557629) (xy 298.361105 -116.503192) (xy 298.357034 -116.44757)
			(xy 293.891716 -116.44757) (xy 293.891716 -118.331996) (xy 295.095674 -118.331996) (xy 295.099745 -118.276374)
			(xy 295.111871 -118.221937) (xy 295.131794 -118.169846) (xy 295.15909 -118.121211) (xy 295.193176 -118.077068)
			(xy 295.233325 -118.038359) (xy 295.278683 -118.005908) (xy 295.328283 -117.980407) (xy 295.381067 -117.9624)
			(xy 295.43591 -117.95227) (xy 295.491644 -117.950233) (xy 295.547081 -117.956333) (xy 295.601038 -117.970439)
			(xy 295.652367 -117.992251) (xy 295.699973 -118.021305) (xy 295.742841 -118.05698) (xy 295.780058 -118.098517)
			(xy 295.810831 -118.14503) (xy 295.834503 -118.195527) (xy 295.850571 -118.248934) (xy 295.858691 -118.30411)
			(xy 295.8592 -118.331996) (xy 295.858691 -118.359882) (xy 295.850571 -118.415058) (xy 295.834503 -118.468465)
			(xy 295.810831 -118.518962) (xy 295.780058 -118.565475) (xy 295.742841 -118.607012) (xy 295.699973 -118.642687)
			(xy 295.652367 -118.671741) (xy 295.601038 -118.693553) (xy 295.547081 -118.707659) (xy 295.491644 -118.713759)
			(xy 295.43591 -118.711722) (xy 295.381067 -118.701592) (xy 295.328283 -118.683585) (xy 295.278683 -118.658084)
			(xy 295.233325 -118.625633) (xy 295.193176 -118.586924) (xy 295.15909 -118.542781) (xy 295.131794 -118.494146)
			(xy 295.111871 -118.442055) (xy 295.099745 -118.387618) (xy 295.095674 -118.331996) (xy 293.891716 -118.331996)
			(xy 293.891716 -137.848848) (xy 294.139872 -137.848848) (xy 294.143943 -137.793226) (xy 294.156069 -137.738789)
			(xy 294.175992 -137.686698) (xy 294.203288 -137.638063) (xy 294.237374 -137.59392) (xy 294.277523 -137.555211)
			(xy 294.322881 -137.52276) (xy 294.372481 -137.497259) (xy 294.425265 -137.479252) (xy 294.480108 -137.469122)
			(xy 294.535842 -137.467085) (xy 294.591279 -137.473185) (xy 294.645236 -137.487291) (xy 294.696565 -137.509103)
			(xy 294.744171 -137.538157) (xy 294.787039 -137.573832) (xy 294.824256 -137.615369) (xy 294.855029 -137.661882)
			(xy 294.878701 -137.712379) (xy 294.894769 -137.765786) (xy 294.902889 -137.820962) (xy 294.903398 -137.848848)
			(xy 294.902889 -137.876734) (xy 294.894769 -137.93191) (xy 294.878701 -137.985317) (xy 294.855029 -138.035814)
			(xy 294.824256 -138.082327) (xy 294.787039 -138.123864) (xy 294.744171 -138.159539) (xy 294.696565 -138.188593)
			(xy 294.645236 -138.210405) (xy 294.591279 -138.224511) (xy 294.535842 -138.230611) (xy 294.480108 -138.228574)
			(xy 294.425265 -138.218444) (xy 294.372481 -138.200437) (xy 294.322881 -138.174936) (xy 294.277523 -138.142485)
			(xy 294.237374 -138.103776) (xy 294.203288 -138.059633) (xy 294.175992 -138.010998) (xy 294.156069 -137.958907)
			(xy 294.143943 -137.90447) (xy 294.139872 -137.848848) (xy 293.891716 -137.848848) (xy 293.891716 -138.864848)
			(xy 294.139872 -138.864848) (xy 294.143943 -138.809226) (xy 294.156069 -138.754789) (xy 294.175992 -138.702698)
			(xy 294.203288 -138.654063) (xy 294.237374 -138.60992) (xy 294.277523 -138.571211) (xy 294.322881 -138.53876)
			(xy 294.372481 -138.513259) (xy 294.425265 -138.495252) (xy 294.480108 -138.485122) (xy 294.535842 -138.483085)
			(xy 294.591279 -138.489185) (xy 294.645236 -138.503291) (xy 294.696565 -138.525103) (xy 294.744171 -138.554157)
			(xy 294.787039 -138.589832) (xy 294.824256 -138.631369) (xy 294.855029 -138.677882) (xy 294.878701 -138.728379)
			(xy 294.894769 -138.781786) (xy 294.902889 -138.836962) (xy 294.903398 -138.864848) (xy 294.902889 -138.892734)
			(xy 294.894769 -138.94791) (xy 294.878701 -139.001317) (xy 294.855029 -139.051814) (xy 294.824256 -139.098327)
			(xy 294.787039 -139.139864) (xy 294.744171 -139.175539) (xy 294.696565 -139.204593) (xy 294.645236 -139.226405)
			(xy 294.591279 -139.240511) (xy 294.535842 -139.246611) (xy 294.480108 -139.244574) (xy 294.425265 -139.234444)
			(xy 294.372481 -139.216437) (xy 294.322881 -139.190936) (xy 294.277523 -139.158485) (xy 294.237374 -139.119776)
			(xy 294.203288 -139.075633) (xy 294.175992 -139.026998) (xy 294.156069 -138.974907) (xy 294.143943 -138.92047)
			(xy 294.139872 -138.864848) (xy 293.891716 -138.864848) (xy 293.891716 -140.565451) (xy 295.630578 -140.565451)
			(xy 295.630578 -140.510949) (xy 295.638334 -140.457001) (xy 295.653689 -140.404706) (xy 295.676331 -140.355129)
			(xy 295.705797 -140.309279) (xy 295.741488 -140.268088) (xy 295.782679 -140.232397) (xy 295.828529 -140.202931)
			(xy 295.878106 -140.180289) (xy 295.930401 -140.164934) (xy 295.984349 -140.157178) (xy 296.0116 -140.156692)
			(xy 296.03897 -140.15716) (xy 296.093149 -140.164978) (xy 296.145652 -140.180466) (xy 296.195399 -140.203308)
			(xy 296.241366 -140.233031) (xy 296.262298 -140.250672) (xy 296.262552 -140.250926) (xy 296.269646 -140.256502)
			(xy 296.286557 -140.262754) (xy 296.295572 -140.263118) (xy 296.362628 -140.263118) (xy 296.371646 -140.262771)
			(xy 296.388563 -140.256516) (xy 296.395648 -140.250926) (xy 296.395648 -140.250672) (xy 296.395902 -140.250672)
			(xy 296.416819 -140.233014) (xy 296.462796 -140.203306) (xy 296.512548 -140.180474) (xy 296.565052 -140.164987)
			(xy 296.61923 -140.157164) (xy 296.6466 -140.156692) (xy 296.673851 -140.157178) (xy 296.727799 -140.164934)
			(xy 296.780094 -140.180289) (xy 296.829671 -140.202931) (xy 296.875521 -140.232397) (xy 296.916712 -140.268088)
			(xy 296.952403 -140.309279) (xy 296.981869 -140.355129) (xy 297.004511 -140.404706) (xy 297.019866 -140.457001)
			(xy 297.027622 -140.510949) (xy 297.027622 -140.565451) (xy 297.019866 -140.619399) (xy 297.004511 -140.671694)
			(xy 296.981869 -140.721271) (xy 296.952403 -140.767121) (xy 296.916712 -140.808312) (xy 296.875521 -140.844003)
			(xy 296.829671 -140.873469) (xy 296.780094 -140.896111) (xy 296.727799 -140.911466) (xy 296.673851 -140.919222)
			(xy 296.6466 -140.919708) (xy 296.61923 -140.91924) (xy 296.565051 -140.911422) (xy 296.512548 -140.895934)
			(xy 296.462801 -140.873092) (xy 296.416834 -140.843369) (xy 296.395902 -140.825728) (xy 296.395648 -140.825474)
			(xy 296.388554 -140.819898) (xy 296.371643 -140.813646) (xy 296.362628 -140.813282) (xy 296.295572 -140.813282)
			(xy 296.286554 -140.813629) (xy 296.269637 -140.819884) (xy 296.262552 -140.825474) (xy 296.262552 -140.825728)
			(xy 296.262298 -140.825728) (xy 296.241381 -140.843386) (xy 296.195404 -140.873094) (xy 296.145652 -140.895926)
			(xy 296.093148 -140.911413) (xy 296.03897 -140.919236) (xy 296.0116 -140.919708) (xy 295.984349 -140.919222)
			(xy 295.930401 -140.911466) (xy 295.878106 -140.896111) (xy 295.828529 -140.873469) (xy 295.782679 -140.844003)
			(xy 295.741488 -140.808312) (xy 295.705797 -140.767121) (xy 295.676331 -140.721271) (xy 295.653689 -140.671694)
			(xy 295.638334 -140.619399) (xy 295.630578 -140.565451) (xy 293.891716 -140.565451) (xy 293.891716 -142.229586)
			(xy 293.892145 -142.239655) (xy 293.899863 -142.258253) (xy 293.906702 -142.265654) (xy 295.367964 -143.72717)
			(xy 295.391108 -143.751088) (xy 295.431616 -143.803896) (xy 295.464887 -143.861538) (xy 295.490352 -143.923029)
			(xy 295.507576 -143.987317) (xy 295.516263 -144.053302) (xy 295.516808 -144.08658) (xy 295.516808 -160.045146)
			(xy 295.51726 -160.055212) (xy 295.524962 -160.07381) (xy 295.531794 -160.081214) (xy 296.996866 -161.546286)
			(xy 297.02004 -161.570189) (xy 297.060606 -161.622979) (xy 297.093931 -161.680614) (xy 297.119444 -161.742107)
			(xy 297.136709 -161.806406) (xy 297.145429 -161.872408) (xy 297.145964 -161.905696) (xy 297.145964 -171.278042)
			(xy 297.146351 -171.288116) (xy 297.154097 -171.306714) (xy 297.16095 -171.31411) (xy 297.65752 -171.810934)
			(xy 297.680656 -171.834858) (xy 297.721164 -171.887666) (xy 297.754435 -171.945307) (xy 297.779901 -172.006796)
			(xy 297.797126 -172.071083) (xy 297.805817 -172.137067) (xy 297.806364 -172.170344) (xy 297.805986 -172.201068)
			(xy 297.798577 -172.262067) (xy 297.783871 -172.321729) (xy 297.762083 -172.379185) (xy 297.73353 -172.433596)
			(xy 297.698629 -172.48417) (xy 297.657888 -172.530171) (xy 297.611901 -172.570927) (xy 297.561338 -172.605844)
			(xy 297.506936 -172.634414) (xy 297.449488 -172.656221) (xy 297.389831 -172.670947) (xy 297.328834 -172.678376)
			(xy 297.29811 -172.678852) (xy 297.264826 -172.678262) (xy 297.198833 -172.669529) (xy 297.134542 -172.652262)
			(xy 297.073053 -172.626758) (xy 297.015415 -172.593451) (xy 296.962615 -172.552911) (xy 296.9387 -172.529754)
			(xy 296.278046 -171.8691) (xy 296.254849 -171.845218) (xy 296.214289 -171.792422) (xy 296.180969 -171.734782)
			(xy 296.15546 -171.673285) (xy 296.138199 -171.608983) (xy 296.129482 -171.542979) (xy 296.128948 -171.50969)
			(xy 296.128948 -167.082978) (xy 296.128524 -167.073459) (xy 296.121576 -167.055733) (xy 296.108643 -167.04176)
			(xy 296.100246 -167.037258) (xy 296.004234 -166.99103) (xy 295.975786 -166.994332) (xy 295.964102 -167.003476)
			(xy 295.943743 -167.019238) (xy 295.899573 -167.045699) (xy 295.852244 -167.065976) (xy 295.802617 -167.0797)
			(xy 295.751595 -167.086622) (xy 295.72585 -167.087042) (xy 295.698604 -167.086484) (xy 295.644666 -167.078723)
			(xy 295.592382 -167.063365) (xy 295.542816 -167.040723) (xy 295.496976 -167.011258) (xy 295.455795 -166.97557)
			(xy 295.420112 -166.934384) (xy 295.390653 -166.88854) (xy 295.368018 -166.838971) (xy 295.352667 -166.786685)
			(xy 295.344912 -166.732747) (xy 295.344912 -166.678253) (xy 295.352667 -166.624315) (xy 295.368018 -166.572029)
			(xy 295.390653 -166.52246) (xy 295.420112 -166.476616) (xy 295.455795 -166.43543) (xy 295.496976 -166.399742)
			(xy 295.542816 -166.370277) (xy 295.592382 -166.347635) (xy 295.644666 -166.332277) (xy 295.698604 -166.324516)
			(xy 295.72585 -166.324026) (xy 295.751593 -166.324476) (xy 295.802609 -166.331404) (xy 295.852232 -166.345128)
			(xy 295.899559 -166.365399) (xy 295.943731 -166.391848) (xy 295.964102 -166.407592) (xy 295.975786 -166.416736)
			(xy 296.004234 -166.420038) (xy 296.100246 -166.37381) (xy 296.108652 -166.369316) (xy 296.121601 -166.355347)
			(xy 296.128554 -166.337614) (xy 296.128948 -166.32809) (xy 296.128948 -162.137344) (xy 296.128513 -162.127275)
			(xy 296.120801 -162.108677) (xy 296.113962 -162.101276) (xy 294.649144 -160.636204) (xy 294.625989 -160.612297)
			(xy 294.585482 -160.559487) (xy 294.552212 -160.501842) (xy 294.526749 -160.440349) (xy 294.509528 -160.37606)
			(xy 294.500843 -160.310072) (xy 294.5003 -160.276794) (xy 294.5003 -144.318228) (xy 294.499886 -144.308157)
			(xy 294.49216 -144.289558) (xy 294.485314 -144.28216) (xy 293.118286 -142.915386) (xy 293.110886 -142.908546)
			(xy 293.092287 -142.900827) (xy 293.082218 -142.9004) (xy 292.058344 -142.9004) (xy 292.048326 -142.900856)
			(xy 292.02981 -142.908511) (xy 292.015636 -142.922673) (xy 292.007964 -142.941182) (xy 292.007544 -142.9512)
			(xy 292.007544 -144.311624) (xy 292.007069 -144.344477) (xy 291.999704 -144.409769) (xy 291.985082 -144.473827)
			(xy 291.963384 -144.535847) (xy 291.934884 -144.595051) (xy 291.89994 -144.650694) (xy 291.85899 -144.702079)
			(xy 291.836094 -144.725644) (xy 286.180784 -150.380954) (xy 286.173867 -150.388589) (xy 286.166197 -150.407688)
			(xy 286.166594 -150.428266) (xy 286.17037 -150.43785) (xy 286.181119 -150.462697) (xy 286.196279 -150.514668)
			(xy 286.203934 -150.568261) (xy 286.204406 -150.59533) (xy 286.204406 -150.595838) (xy 286.203958 -150.62309)
			(xy 286.196196 -150.677039) (xy 286.180836 -150.729335) (xy 286.15819 -150.778912) (xy 286.12872 -150.824763)
			(xy 286.093024 -150.865953) (xy 286.051831 -150.901644) (xy 286.005977 -150.931109) (xy 285.956397 -150.95375)
			(xy 285.9041 -150.969104) (xy 285.85015 -150.97686) (xy 285.822898 -150.977346) (xy 285.794402 -150.976798)
			(xy 285.738042 -150.968332) (xy 285.683569 -150.951575) (xy 285.632196 -150.926898) (xy 285.585066 -150.894852)
			(xy 285.54323 -150.85615) (xy 285.507618 -150.811654) (xy 285.479023 -150.762354) (xy 285.46806 -150.736046)
			(xy 285.463991 -150.726703) (xy 285.449773 -150.712122) (xy 285.431 -150.704226) (xy 285.420816 -150.703788)
			(xy 285.16707 -150.703788) (xy 285.131657 -150.703272) (xy 285.061348 -150.694731) (xy 284.99258 -150.677779)
			(xy 284.926357 -150.652661) (xy 284.863645 -150.619745) (xy 284.805357 -150.579509) (xy 284.752344 -150.532542)
			(xy 284.705378 -150.479527) (xy 284.665145 -150.421238) (xy 284.632231 -150.358524) (xy 284.607115 -150.292301)
			(xy 284.590165 -150.223533) (xy 284.581627 -150.153223) (xy 284.581092 -150.11781) (xy 279.185779 -150.11781)
			(xy 279.185647 -150.118949) (xy 279.185906 -150.127375) (xy 279.18664 -150.131526) (xy 279.411116 -151.257)
			(xy 284.776924 -151.257) (xy 284.780995 -151.201378) (xy 284.793121 -151.146941) (xy 284.813044 -151.09485)
			(xy 284.84034 -151.046215) (xy 284.874426 -151.002072) (xy 284.914575 -150.963363) (xy 284.959933 -150.930912)
			(xy 285.009533 -150.905411) (xy 285.062317 -150.887404) (xy 285.11716 -150.877274) (xy 285.172894 -150.875237)
			(xy 285.228331 -150.881337) (xy 285.282288 -150.895443) (xy 285.333617 -150.917255) (xy 285.381223 -150.946309)
			(xy 285.424091 -150.981984) (xy 285.461308 -151.023521) (xy 285.492081 -151.070034) (xy 285.515753 -151.120531)
			(xy 285.531821 -151.173938) (xy 285.539941 -151.229114) (xy 285.54045 -151.257) (xy 285.539941 -151.284886)
			(xy 285.531821 -151.340062) (xy 285.515753 -151.393469) (xy 285.492081 -151.443966) (xy 285.461308 -151.490479)
			(xy 285.424091 -151.532016) (xy 285.381223 -151.567691) (xy 285.333617 -151.596745) (xy 285.282288 -151.618557)
			(xy 285.228331 -151.632663) (xy 285.172894 -151.638763) (xy 285.11716 -151.636726) (xy 285.062317 -151.626596)
			(xy 285.009533 -151.608589) (xy 284.959933 -151.583088) (xy 284.914575 -151.550637) (xy 284.874426 -151.511928)
			(xy 284.84034 -151.467785) (xy 284.813044 -151.41915) (xy 284.793121 -151.367059) (xy 284.780995 -151.312622)
			(xy 284.776924 -151.257) (xy 279.411116 -151.257) (xy 279.870452 -153.560018) (xy 284.649924 -153.560018)
			(xy 284.653995 -153.504396) (xy 284.666121 -153.449959) (xy 284.686044 -153.397868) (xy 284.71334 -153.349233)
			(xy 284.747426 -153.30509) (xy 284.787575 -153.266381) (xy 284.832933 -153.23393) (xy 284.882533 -153.208429)
			(xy 284.935317 -153.190422) (xy 284.99016 -153.180292) (xy 285.045894 -153.178255) (xy 285.101331 -153.184355)
			(xy 285.155288 -153.198461) (xy 285.206617 -153.220273) (xy 285.254223 -153.249327) (xy 285.297091 -153.285002)
			(xy 285.334308 -153.326539) (xy 285.365081 -153.373052) (xy 285.388753 -153.423549) (xy 285.404821 -153.476956)
			(xy 285.412941 -153.532132) (xy 285.41345 -153.560018) (xy 285.412941 -153.587904) (xy 285.404821 -153.64308)
			(xy 285.388753 -153.696487) (xy 285.365081 -153.746984) (xy 285.334308 -153.793497) (xy 285.297091 -153.835034)
			(xy 285.254223 -153.870709) (xy 285.206617 -153.899763) (xy 285.155288 -153.921575) (xy 285.101331 -153.935681)
			(xy 285.045894 -153.941781) (xy 284.99016 -153.939744) (xy 284.935317 -153.929614) (xy 284.882533 -153.911607)
			(xy 284.832933 -153.886106) (xy 284.787575 -153.853655) (xy 284.747426 -153.814946) (xy 284.71334 -153.770803)
			(xy 284.686044 -153.722168) (xy 284.666121 -153.670077) (xy 284.653995 -153.61564) (xy 284.649924 -153.560018)
			(xy 279.870452 -153.560018) (xy 279.990112 -154.159966) (xy 283.506924 -154.159966) (xy 283.510995 -154.104344)
			(xy 283.523121 -154.049907) (xy 283.543044 -153.997816) (xy 283.57034 -153.949181) (xy 283.604426 -153.905038)
			(xy 283.644575 -153.866329) (xy 283.689933 -153.833878) (xy 283.739533 -153.808377) (xy 283.792317 -153.79037)
			(xy 283.84716 -153.78024) (xy 283.902894 -153.778203) (xy 283.958331 -153.784303) (xy 284.012288 -153.798409)
			(xy 284.063617 -153.820221) (xy 284.111223 -153.849275) (xy 284.154091 -153.88495) (xy 284.191308 -153.926487)
			(xy 284.222081 -153.973) (xy 284.245753 -154.023497) (xy 284.261821 -154.076904) (xy 284.269941 -154.13208)
			(xy 284.27045 -154.159966) (xy 284.269941 -154.187852) (xy 284.261821 -154.243028) (xy 284.245753 -154.296435)
			(xy 284.222081 -154.346932) (xy 284.191308 -154.393445) (xy 284.154091 -154.434982) (xy 284.111223 -154.470657)
			(xy 284.063617 -154.499711) (xy 284.012288 -154.521523) (xy 283.958331 -154.535629) (xy 283.902894 -154.541729)
			(xy 283.84716 -154.539692) (xy 283.792317 -154.529562) (xy 283.739533 -154.511555) (xy 283.689933 -154.486054)
			(xy 283.644575 -154.453603) (xy 283.604426 -154.414894) (xy 283.57034 -154.370751) (xy 283.543044 -154.322116)
			(xy 283.523121 -154.270025) (xy 283.510995 -154.215588) (xy 283.506924 -154.159966) (xy 279.990112 -154.159966)
			(xy 280.165954 -155.0416) (xy 280.363674 -155.0416) (xy 280.367745 -154.985978) (xy 280.379871 -154.931541)
			(xy 280.399794 -154.87945) (xy 280.42709 -154.830815) (xy 280.461176 -154.786672) (xy 280.501325 -154.747963)
			(xy 280.546683 -154.715512) (xy 280.596283 -154.690011) (xy 280.649067 -154.672004) (xy 280.70391 -154.661874)
			(xy 280.759644 -154.659837) (xy 280.815081 -154.665937) (xy 280.869038 -154.680043) (xy 280.920367 -154.701855)
			(xy 280.967973 -154.730909) (xy 281.010841 -154.766584) (xy 281.048058 -154.808121) (xy 281.078831 -154.854634)
			(xy 281.102503 -154.905131) (xy 281.118496 -154.958288) (xy 284.944056 -154.958288) (xy 284.948127 -154.902666)
			(xy 284.960253 -154.848229) (xy 284.980176 -154.796138) (xy 285.007472 -154.747503) (xy 285.041558 -154.70336)
			(xy 285.081707 -154.664651) (xy 285.127065 -154.6322) (xy 285.176665 -154.606699) (xy 285.229449 -154.588692)
			(xy 285.284292 -154.578562) (xy 285.340026 -154.576525) (xy 285.395463 -154.582625) (xy 285.44942 -154.596731)
			(xy 285.500749 -154.618543) (xy 285.548355 -154.647597) (xy 285.591223 -154.683272) (xy 285.62844 -154.724809)
			(xy 285.659213 -154.771322) (xy 285.682885 -154.821819) (xy 285.698953 -154.875226) (xy 285.707073 -154.930402)
			(xy 285.707582 -154.958288) (xy 285.707073 -154.986174) (xy 285.698953 -155.04135) (xy 285.682885 -155.094757)
			(xy 285.659213 -155.145254) (xy 285.62844 -155.191767) (xy 285.591223 -155.233304) (xy 285.548355 -155.268979)
			(xy 285.500749 -155.298033) (xy 285.44942 -155.319845) (xy 285.395463 -155.333951) (xy 285.340026 -155.340051)
			(xy 285.284292 -155.338014) (xy 285.229449 -155.327884) (xy 285.176665 -155.309877) (xy 285.127065 -155.284376)
			(xy 285.081707 -155.251925) (xy 285.041558 -155.213216) (xy 285.007472 -155.169073) (xy 284.980176 -155.120438)
			(xy 284.960253 -155.068347) (xy 284.948127 -155.01391) (xy 284.944056 -154.958288) (xy 281.118496 -154.958288)
			(xy 281.118571 -154.958538) (xy 281.126691 -155.013714) (xy 281.1272 -155.0416) (xy 281.126691 -155.069486)
			(xy 281.118571 -155.124662) (xy 281.102503 -155.178069) (xy 281.078831 -155.228566) (xy 281.048058 -155.275079)
			(xy 281.010841 -155.316616) (xy 280.967973 -155.352291) (xy 280.920367 -155.381345) (xy 280.869038 -155.403157)
			(xy 280.815081 -155.417263) (xy 280.759644 -155.423363) (xy 280.70391 -155.421326) (xy 280.649067 -155.411196)
			(xy 280.596283 -155.393189) (xy 280.546683 -155.367688) (xy 280.501325 -155.335237) (xy 280.461176 -155.296528)
			(xy 280.42709 -155.252385) (xy 280.399794 -155.20375) (xy 280.379871 -155.151659) (xy 280.367745 -155.097222)
			(xy 280.363674 -155.0416) (xy 280.165954 -155.0416) (xy 280.277002 -155.598368) (xy 283.568138 -155.598368)
			(xy 283.572209 -155.542746) (xy 283.584335 -155.488309) (xy 283.604258 -155.436218) (xy 283.631554 -155.387583)
			(xy 283.66564 -155.34344) (xy 283.705789 -155.304731) (xy 283.751147 -155.27228) (xy 283.800747 -155.246779)
			(xy 283.853531 -155.228772) (xy 283.908374 -155.218642) (xy 283.964108 -155.216605) (xy 284.019545 -155.222705)
			(xy 284.073502 -155.236811) (xy 284.124831 -155.258623) (xy 284.172437 -155.287677) (xy 284.215305 -155.323352)
			(xy 284.252522 -155.364889) (xy 284.283295 -155.411402) (xy 284.306967 -155.461899) (xy 284.323035 -155.515306)
			(xy 284.331155 -155.570482) (xy 284.331664 -155.598368) (xy 284.331155 -155.626254) (xy 284.323035 -155.68143)
			(xy 284.306967 -155.734837) (xy 284.283295 -155.785334) (xy 284.252522 -155.831847) (xy 284.215305 -155.873384)
			(xy 284.172437 -155.909059) (xy 284.124831 -155.938113) (xy 284.073502 -155.959925) (xy 284.019545 -155.974031)
			(xy 283.964108 -155.980131) (xy 283.908374 -155.978094) (xy 283.853531 -155.967964) (xy 283.800747 -155.949957)
			(xy 283.751147 -155.924456) (xy 283.705789 -155.892005) (xy 283.66564 -155.853296) (xy 283.631554 -155.809153)
			(xy 283.604258 -155.760518) (xy 283.584335 -155.708427) (xy 283.572209 -155.65399) (xy 283.568138 -155.598368)
			(xy 280.277002 -155.598368) (xy 280.465712 -156.544518) (xy 284.9278 -156.544518) (xy 284.931871 -156.488896)
			(xy 284.943997 -156.434459) (xy 284.96392 -156.382368) (xy 284.991216 -156.333733) (xy 285.025302 -156.28959)
			(xy 285.065451 -156.250881) (xy 285.110809 -156.21843) (xy 285.160409 -156.192929) (xy 285.213193 -156.174922)
			(xy 285.268036 -156.164792) (xy 285.32377 -156.162755) (xy 285.379207 -156.168855) (xy 285.433164 -156.182961)
			(xy 285.484493 -156.204773) (xy 285.532099 -156.233827) (xy 285.574967 -156.269502) (xy 285.612184 -156.311039)
			(xy 285.642957 -156.357552) (xy 285.666629 -156.408049) (xy 285.682697 -156.461456) (xy 285.690817 -156.516632)
			(xy 285.691326 -156.544518) (xy 285.690817 -156.572404) (xy 285.682697 -156.62758) (xy 285.666629 -156.680987)
			(xy 285.642957 -156.731484) (xy 285.612184 -156.777997) (xy 285.574967 -156.819534) (xy 285.532099 -156.855209)
			(xy 285.484493 -156.884263) (xy 285.433164 -156.906075) (xy 285.379207 -156.920181) (xy 285.32377 -156.926281)
			(xy 285.268036 -156.924244) (xy 285.213193 -156.914114) (xy 285.160409 -156.896107) (xy 285.110809 -156.870606)
			(xy 285.065451 -156.838155) (xy 285.025302 -156.799446) (xy 284.991216 -156.755303) (xy 284.96392 -156.706668)
			(xy 284.943997 -156.654577) (xy 284.931871 -156.60014) (xy 284.9278 -156.544518) (xy 280.465712 -156.544518)
			(xy 280.571237 -157.0736) (xy 283.496764 -157.0736) (xy 283.500835 -157.017978) (xy 283.512961 -156.963541)
			(xy 283.532884 -156.91145) (xy 283.56018 -156.862815) (xy 283.594266 -156.818672) (xy 283.634415 -156.779963)
			(xy 283.679773 -156.747512) (xy 283.729373 -156.722011) (xy 283.782157 -156.704004) (xy 283.837 -156.693874)
			(xy 283.892734 -156.691837) (xy 283.948171 -156.697937) (xy 284.002128 -156.712043) (xy 284.053457 -156.733855)
			(xy 284.101063 -156.762909) (xy 284.143931 -156.798584) (xy 284.181148 -156.840121) (xy 284.211921 -156.886634)
			(xy 284.235593 -156.937131) (xy 284.251661 -156.990538) (xy 284.259698 -157.045152) (xy 293.610536 -157.045152)
			(xy 293.614607 -156.98953) (xy 293.626733 -156.935093) (xy 293.646656 -156.883002) (xy 293.673952 -156.834367)
			(xy 293.708038 -156.790224) (xy 293.748187 -156.751515) (xy 293.793545 -156.719064) (xy 293.843145 -156.693563)
			(xy 293.895929 -156.675556) (xy 293.950772 -156.665426) (xy 294.006506 -156.663389) (xy 294.061943 -156.669489)
			(xy 294.1159 -156.683595) (xy 294.167229 -156.705407) (xy 294.214835 -156.734461) (xy 294.257703 -156.770136)
			(xy 294.29492 -156.811673) (xy 294.325693 -156.858186) (xy 294.349365 -156.908683) (xy 294.365433 -156.96209)
			(xy 294.373553 -157.017266) (xy 294.374062 -157.045152) (xy 294.373553 -157.073038) (xy 294.365433 -157.128214)
			(xy 294.349365 -157.181621) (xy 294.325693 -157.232118) (xy 294.29492 -157.278631) (xy 294.257703 -157.320168)
			(xy 294.214835 -157.355843) (xy 294.167229 -157.384897) (xy 294.1159 -157.406709) (xy 294.061943 -157.420815)
			(xy 294.006506 -157.426915) (xy 293.950772 -157.424878) (xy 293.895929 -157.414748) (xy 293.843145 -157.396741)
			(xy 293.793545 -157.37124) (xy 293.748187 -157.338789) (xy 293.708038 -157.30008) (xy 293.673952 -157.255937)
			(xy 293.646656 -157.207302) (xy 293.626733 -157.155211) (xy 293.614607 -157.100774) (xy 293.610536 -157.045152)
			(xy 284.259698 -157.045152) (xy 284.259781 -157.045714) (xy 284.26029 -157.0736) (xy 284.259781 -157.101486)
			(xy 284.251661 -157.156662) (xy 284.235593 -157.210069) (xy 284.211921 -157.260566) (xy 284.181148 -157.307079)
			(xy 284.143931 -157.348616) (xy 284.101063 -157.384291) (xy 284.053457 -157.413345) (xy 284.002128 -157.435157)
			(xy 283.948171 -157.449263) (xy 283.892734 -157.455363) (xy 283.837 -157.453326) (xy 283.782157 -157.443196)
			(xy 283.729373 -157.425189) (xy 283.679773 -157.399688) (xy 283.634415 -157.367237) (xy 283.594266 -157.328528)
			(xy 283.56018 -157.284385) (xy 283.532884 -157.23575) (xy 283.512961 -157.183659) (xy 283.500835 -157.129222)
			(xy 283.496764 -157.0736) (xy 280.571237 -157.0736) (xy 281.305254 -160.753806) (xy 281.308109 -160.765172)
			(xy 281.322349 -160.78375) (xy 281.343335 -160.794122) (xy 281.355038 -160.7947) (xy 281.469592 -160.7947)
			(xy 281.513043 -160.795186) (xy 281.599573 -160.803204) (xy 281.684995 -160.819171) (xy 281.768579 -160.842952)
			(xy 281.849613 -160.874344) (xy 281.927404 -160.913079) (xy 282.001289 -160.958827) (xy 282.070638 -161.011197)
			(xy 282.134858 -161.069742) (xy 282.193403 -161.133962) (xy 282.245773 -161.203311) (xy 282.291521 -161.277196)
			(xy 282.330256 -161.354987) (xy 282.361648 -161.436021) (xy 282.385429 -161.519605) (xy 282.401396 -161.605027)
			(xy 282.409414 -161.691557) (xy 282.4099 -161.735008) (xy 282.409392 -161.768282) (xy 282.409138 -161.77514)
			(xy 282.406734 -161.819604) (xy 282.39457 -161.907821) (xy 282.374116 -161.994492) (xy 282.345556 -162.07884)
			(xy 282.309145 -162.160108) (xy 282.265211 -162.237568) (xy 282.214147 -162.310524) (xy 282.156411 -162.378324)
			(xy 282.092521 -162.440358) (xy 282.023049 -162.496071) (xy 281.948619 -162.544964) (xy 281.869899 -162.586596)
			(xy 281.787593 -162.620596) (xy 281.745182 -162.634168) (xy 281.737054 -162.636708) (xy 281.727402 -162.643566)
			(xy 281.720036 -162.650932) (xy 281.715464 -162.656774) (xy 281.706574 -162.668204) (xy 281.706066 -162.668712)
			(xy 281.705304 -162.669982) (xy 281.704796 -162.67049) (xy 281.698734 -162.679352) (xy 281.693985 -162.700271)
			(xy 281.695652 -162.710876) (xy 281.828494 -163.378134) (xy 281.99207 -164.198046) (xy 282.909262 -164.198046)
			(xy 282.913333 -164.142424) (xy 282.925459 -164.087987) (xy 282.945382 -164.035896) (xy 282.972678 -163.987261)
			(xy 283.006764 -163.943118) (xy 283.046913 -163.904409) (xy 283.092271 -163.871958) (xy 283.141871 -163.846457)
			(xy 283.194655 -163.82845) (xy 283.249498 -163.81832) (xy 283.305232 -163.816283) (xy 283.360669 -163.822383)
			(xy 283.414626 -163.836489) (xy 283.465955 -163.858301) (xy 283.513561 -163.887355) (xy 283.556429 -163.92303)
			(xy 283.593646 -163.964567) (xy 283.624419 -164.01108) (xy 283.648091 -164.061577) (xy 283.664159 -164.114984)
			(xy 283.672279 -164.17016) (xy 283.672788 -164.198046) (xy 283.672279 -164.225932) (xy 283.664159 -164.281108)
			(xy 283.648091 -164.334515) (xy 283.624419 -164.385012) (xy 283.593646 -164.431525) (xy 283.556429 -164.473062)
			(xy 283.513561 -164.508737) (xy 283.465955 -164.537791) (xy 283.414626 -164.559603) (xy 283.360669 -164.573709)
			(xy 283.305232 -164.579809) (xy 283.249498 -164.577772) (xy 283.194655 -164.567642) (xy 283.141871 -164.549635)
			(xy 283.092271 -164.524134) (xy 283.046913 -164.491683) (xy 283.006764 -164.452974) (xy 282.972678 -164.408831)
			(xy 282.945382 -164.360196) (xy 282.925459 -164.308105) (xy 282.913333 -164.253668) (xy 282.909262 -164.198046)
			(xy 281.99207 -164.198046) (xy 282.178044 -165.130226) (xy 282.866336 -165.130226) (xy 282.870407 -165.074604)
			(xy 282.882533 -165.020167) (xy 282.902456 -164.968076) (xy 282.929752 -164.919441) (xy 282.963838 -164.875298)
			(xy 283.003987 -164.836589) (xy 283.049345 -164.804138) (xy 283.098945 -164.778637) (xy 283.151729 -164.76063)
			(xy 283.206572 -164.7505) (xy 283.262306 -164.748463) (xy 283.317743 -164.754563) (xy 283.3717 -164.768669)
			(xy 283.423029 -164.790481) (xy 283.470635 -164.819535) (xy 283.513503 -164.85521) (xy 283.55072 -164.896747)
			(xy 283.581493 -164.94326) (xy 283.605165 -164.993757) (xy 283.621233 -165.047164) (xy 283.629353 -165.10234)
			(xy 283.629862 -165.130226) (xy 283.629353 -165.158112) (xy 283.621233 -165.213288) (xy 283.605165 -165.266695)
			(xy 283.581493 -165.317192) (xy 283.55072 -165.363705) (xy 283.513503 -165.405242) (xy 283.470635 -165.440917)
			(xy 283.423029 -165.469971) (xy 283.3717 -165.491783) (xy 283.317743 -165.505889) (xy 283.262306 -165.511989)
			(xy 283.206572 -165.509952) (xy 283.151729 -165.499822) (xy 283.098945 -165.481815) (xy 283.049345 -165.456314)
			(xy 283.003987 -165.423863) (xy 282.963838 -165.385154) (xy 282.929752 -165.341011) (xy 282.902456 -165.292376)
			(xy 282.882533 -165.240285) (xy 282.870407 -165.185848) (xy 282.866336 -165.130226) (xy 282.178044 -165.130226)
			(xy 282.492325 -166.705534) (xy 293.311832 -166.705534) (xy 293.315903 -166.649912) (xy 293.328029 -166.595475)
			(xy 293.347952 -166.543384) (xy 293.375248 -166.494749) (xy 293.409334 -166.450606) (xy 293.449483 -166.411897)
			(xy 293.494841 -166.379446) (xy 293.544441 -166.353945) (xy 293.597225 -166.335938) (xy 293.652068 -166.325808)
			(xy 293.707802 -166.323771) (xy 293.763239 -166.329871) (xy 293.817196 -166.343977) (xy 293.868525 -166.365789)
			(xy 293.916131 -166.394843) (xy 293.958999 -166.430518) (xy 293.996216 -166.472055) (xy 294.026989 -166.518568)
			(xy 294.050661 -166.569065) (xy 294.066729 -166.622472) (xy 294.074849 -166.677648) (xy 294.075358 -166.705534)
			(xy 294.327832 -166.705534) (xy 294.331903 -166.649912) (xy 294.344029 -166.595475) (xy 294.363952 -166.543384)
			(xy 294.391248 -166.494749) (xy 294.425334 -166.450606) (xy 294.465483 -166.411897) (xy 294.510841 -166.379446)
			(xy 294.560441 -166.353945) (xy 294.613225 -166.335938) (xy 294.668068 -166.325808) (xy 294.723802 -166.323771)
			(xy 294.779239 -166.329871) (xy 294.833196 -166.343977) (xy 294.884525 -166.365789) (xy 294.932131 -166.394843)
			(xy 294.974999 -166.430518) (xy 295.012216 -166.472055) (xy 295.042989 -166.518568) (xy 295.066661 -166.569065)
			(xy 295.082729 -166.622472) (xy 295.090849 -166.677648) (xy 295.091358 -166.705534) (xy 295.090849 -166.73342)
			(xy 295.082729 -166.788596) (xy 295.066661 -166.842003) (xy 295.042989 -166.8925) (xy 295.012216 -166.939013)
			(xy 294.974999 -166.98055) (xy 294.932131 -167.016225) (xy 294.884525 -167.045279) (xy 294.833196 -167.067091)
			(xy 294.779239 -167.081197) (xy 294.723802 -167.087297) (xy 294.668068 -167.08526) (xy 294.613225 -167.07513)
			(xy 294.560441 -167.057123) (xy 294.510841 -167.031622) (xy 294.465483 -166.999171) (xy 294.425334 -166.960462)
			(xy 294.391248 -166.916319) (xy 294.363952 -166.867684) (xy 294.344029 -166.815593) (xy 294.331903 -166.761156)
			(xy 294.327832 -166.705534) (xy 294.075358 -166.705534) (xy 294.074849 -166.73342) (xy 294.066729 -166.788596)
			(xy 294.050661 -166.842003) (xy 294.026989 -166.8925) (xy 293.996216 -166.939013) (xy 293.958999 -166.98055)
			(xy 293.916131 -167.016225) (xy 293.868525 -167.045279) (xy 293.817196 -167.067091) (xy 293.763239 -167.081197)
			(xy 293.707802 -167.087297) (xy 293.652068 -167.08526) (xy 293.597225 -167.07513) (xy 293.544441 -167.057123)
			(xy 293.494841 -167.031622) (xy 293.449483 -166.999171) (xy 293.409334 -166.960462) (xy 293.375248 -166.916319)
			(xy 293.347952 -166.867684) (xy 293.328029 -166.815593) (xy 293.315903 -166.761156) (xy 293.311832 -166.705534)
			(xy 282.492325 -166.705534) (xy 282.769056 -168.092628) (xy 282.770729 -168.098267) (xy 282.776252 -168.108649)
			(xy 282.779978 -168.113202) (xy 282.789122 -168.121584) (xy 282.79344 -168.124378) (xy 282.801822 -168.128188)
			(xy 282.843732 -168.140126) (xy 282.84424 -168.140126) (xy 282.886912 -168.152064) (xy 282.89203 -168.154201)
			(xy 282.901254 -168.160357) (xy 282.9052 -168.164256) (xy 282.93695 -168.144698) (xy 282.942792 -168.138856)
			(xy 282.945332 -168.136062) (xy 282.964885 -168.115938) (xy 283.008851 -168.081078) (xy 283.057453 -168.053042)
			(xy 283.109642 -168.032437) (xy 283.136848 -168.025572) (xy 283.157764 -168.021018) (xy 283.200282 -168.016052)
			(xy 283.221684 -168.015666) (xy 283.229812 -168.015666) (xy 283.256781 -168.016558) (xy 283.310076 -168.025003)
			(xy 283.361648 -168.040873) (xy 283.41047 -168.063852) (xy 283.455567 -168.093482) (xy 283.496038 -168.129171)
			(xy 283.531077 -168.170206) (xy 283.559983 -168.21577) (xy 283.582181 -168.264952) (xy 283.597226 -168.316772)
			(xy 283.60482 -168.370194) (xy 283.605224 -168.397174) (xy 283.604763 -168.424429) (xy 283.597009 -168.478383)
			(xy 283.581655 -168.530685) (xy 283.559015 -168.58027) (xy 283.529548 -168.626127) (xy 283.493854 -168.667324)
			(xy 283.452661 -168.703022) (xy 283.406807 -168.732494) (xy 283.357225 -168.755141) (xy 283.304924 -168.7705)
			(xy 283.25097 -168.77826) (xy 283.223716 -168.778682) (xy 283.19697 -168.778236) (xy 283.144003 -168.770758)
			(xy 283.092606 -168.755933) (xy 283.068014 -168.745408) (xy 283.063188 -168.743376) (xy 283.051758 -168.740836)
			(xy 283.040605 -168.738992) (xy 283.018585 -168.743986) (xy 283.00934 -168.750488) (xy 282.948126 -168.798748)
			(xy 282.947618 -168.799256) (xy 282.940252 -168.805098) (xy 282.933224 -168.810941) (xy 282.923484 -168.826394)
			(xy 282.919726 -168.844269) (xy 282.920694 -168.853358) (xy 282.921202 -168.855136) (xy 282.921202 -168.85539)
			(xy 283.510482 -171.80941) (xy 283.513589 -171.822724) (xy 283.525853 -171.847146) (xy 283.544152 -171.867443)
			(xy 283.567177 -171.882164) (xy 283.59328 -171.890253) (xy 283.620595 -171.891134) (xy 283.647165 -171.884742)
			(xy 283.659326 -171.878498) (xy 283.680698 -171.86704) (xy 283.725717 -171.849014) (xy 283.772653 -171.836821)
			(xy 283.820753 -171.830656) (xy 283.845 -171.830238) (xy 283.874295 -171.830772) (xy 283.932196 -171.839729)
			(xy 283.988047 -171.857431) (xy 284.040536 -171.883462) (xy 284.088429 -171.917211) (xy 284.1306 -171.957885)
			(xy 284.148784 -171.98086) (xy 284.15753 -171.991633) (xy 284.179611 -172.008416) (xy 284.205398 -172.018628)
			(xy 284.232983 -172.021514) (xy 284.260325 -172.016859) (xy 284.285401 -172.005008) (xy 284.306357 -171.986838)
			(xy 284.314392 -171.975526) (xy 284.329616 -171.953384) (xy 284.365292 -171.913203) (xy 284.406255 -171.878427)
			(xy 284.451694 -171.849745) (xy 284.500709 -171.827725) (xy 284.552329 -171.812803) (xy 284.605533 -171.805274)
			(xy 284.6324 -171.804838) (xy 284.659669 -171.805324) (xy 284.713653 -171.813086) (xy 284.765983 -171.828451)
			(xy 284.815593 -171.851108) (xy 284.861474 -171.880594) (xy 284.902691 -171.916309) (xy 284.938406 -171.957526)
			(xy 284.967892 -172.003407) (xy 284.990549 -172.053017) (xy 285.005914 -172.105347) (xy 285.013676 -172.159331)
			(xy 285.013676 -172.213869) (xy 285.005914 -172.267853) (xy 284.990549 -172.320183) (xy 284.986363 -172.329348)
			(xy 294.047924 -172.329348) (xy 294.051995 -172.273726) (xy 294.064121 -172.219289) (xy 294.084044 -172.167198)
			(xy 294.11134 -172.118563) (xy 294.145426 -172.07442) (xy 294.185575 -172.035711) (xy 294.230933 -172.00326)
			(xy 294.280533 -171.977759) (xy 294.333317 -171.959752) (xy 294.38816 -171.949622) (xy 294.443894 -171.947585)
			(xy 294.499331 -171.953685) (xy 294.553288 -171.967791) (xy 294.604617 -171.989603) (xy 294.652223 -172.018657)
			(xy 294.695091 -172.054332) (xy 294.732308 -172.095869) (xy 294.763081 -172.142382) (xy 294.786753 -172.192879)
			(xy 294.802821 -172.246286) (xy 294.810941 -172.301462) (xy 294.81145 -172.329348) (xy 294.811186 -172.343826)
			(xy 294.985184 -172.343826) (xy 294.989255 -172.288204) (xy 295.001381 -172.233767) (xy 295.021304 -172.181676)
			(xy 295.0486 -172.133041) (xy 295.082686 -172.088898) (xy 295.122835 -172.050189) (xy 295.168193 -172.017738)
			(xy 295.217793 -171.992237) (xy 295.270577 -171.97423) (xy 295.32542 -171.9641) (xy 295.381154 -171.962063)
			(xy 295.436591 -171.968163) (xy 295.490548 -171.982269) (xy 295.541877 -172.004081) (xy 295.589483 -172.033135)
			(xy 295.632351 -172.06881) (xy 295.669568 -172.110347) (xy 295.700341 -172.15686) (xy 295.724013 -172.207357)
			(xy 295.740081 -172.260764) (xy 295.748201 -172.31594) (xy 295.74871 -172.343826) (xy 295.748201 -172.371712)
			(xy 295.740081 -172.426888) (xy 295.724013 -172.480295) (xy 295.700341 -172.530792) (xy 295.669568 -172.577305)
			(xy 295.632351 -172.618842) (xy 295.589483 -172.654517) (xy 295.541877 -172.683571) (xy 295.490548 -172.705383)
			(xy 295.436591 -172.719489) (xy 295.381154 -172.725589) (xy 295.32542 -172.723552) (xy 295.270577 -172.713422)
			(xy 295.217793 -172.695415) (xy 295.168193 -172.669914) (xy 295.122835 -172.637463) (xy 295.082686 -172.598754)
			(xy 295.0486 -172.554611) (xy 295.021304 -172.505976) (xy 295.001381 -172.453885) (xy 294.989255 -172.399448)
			(xy 294.985184 -172.343826) (xy 294.811186 -172.343826) (xy 294.810941 -172.357234) (xy 294.802821 -172.41241)
			(xy 294.786753 -172.465817) (xy 294.763081 -172.516314) (xy 294.732308 -172.562827) (xy 294.695091 -172.604364)
			(xy 294.652223 -172.640039) (xy 294.604617 -172.669093) (xy 294.553288 -172.690905) (xy 294.499331 -172.705011)
			(xy 294.443894 -172.711111) (xy 294.38816 -172.709074) (xy 294.333317 -172.698944) (xy 294.280533 -172.680937)
			(xy 294.230933 -172.655436) (xy 294.185575 -172.622985) (xy 294.145426 -172.584276) (xy 294.11134 -172.540133)
			(xy 294.084044 -172.491498) (xy 294.064121 -172.439407) (xy 294.051995 -172.38497) (xy 294.047924 -172.329348)
			(xy 284.986363 -172.329348) (xy 284.967892 -172.369793) (xy 284.938406 -172.415674) (xy 284.902691 -172.456891)
			(xy 284.861474 -172.492606) (xy 284.815593 -172.522092) (xy 284.765983 -172.544749) (xy 284.713653 -172.560114)
			(xy 284.659669 -172.567876) (xy 284.6324 -172.568362) (xy 284.603105 -172.567828) (xy 284.545204 -172.558871)
			(xy 284.489353 -172.541169) (xy 284.436864 -172.515138) (xy 284.388971 -172.481389) (xy 284.3468 -172.440715)
			(xy 284.328616 -172.41774) (xy 284.31987 -172.406967) (xy 284.297789 -172.390184) (xy 284.272002 -172.379972)
			(xy 284.244417 -172.377086) (xy 284.217075 -172.381741) (xy 284.191999 -172.393592) (xy 284.171043 -172.411762)
			(xy 284.163008 -172.423074) (xy 284.147784 -172.445216) (xy 284.112108 -172.485397) (xy 284.071145 -172.520173)
			(xy 284.025706 -172.548855) (xy 283.976691 -172.570875) (xy 283.925071 -172.585797) (xy 283.871867 -172.593326)
			(xy 283.845 -172.593762) (xy 283.834116 -172.593671) (xy 283.812386 -172.592399) (xy 283.801566 -172.591222)
			(xy 283.787911 -172.590078) (xy 283.760841 -172.59426) (xy 283.735861 -172.6055) (xy 283.714776 -172.622985)
			(xy 283.699108 -172.645453) (xy 283.689988 -172.671281) (xy 283.688075 -172.698606) (xy 283.690314 -172.712126)
			(xy 284.45123 -176.525682) (xy 296.609006 -176.525682) (xy 296.613077 -176.47006) (xy 296.625203 -176.415623)
			(xy 296.645126 -176.363532) (xy 296.672422 -176.314897) (xy 296.706508 -176.270754) (xy 296.746657 -176.232045)
			(xy 296.792015 -176.199594) (xy 296.841615 -176.174093) (xy 296.894399 -176.156086) (xy 296.949242 -176.145956)
			(xy 297.004976 -176.143919) (xy 297.060413 -176.150019) (xy 297.11437 -176.164125) (xy 297.165699 -176.185937)
			(xy 297.213305 -176.214991) (xy 297.256173 -176.250666) (xy 297.29339 -176.292203) (xy 297.324163 -176.338716)
			(xy 297.347835 -176.389213) (xy 297.363903 -176.44262) (xy 297.372023 -176.497796) (xy 297.372532 -176.525682)
			(xy 297.372023 -176.553568) (xy 297.363903 -176.608744) (xy 297.347835 -176.662151) (xy 297.324163 -176.712648)
			(xy 297.29339 -176.759161) (xy 297.256173 -176.800698) (xy 297.213305 -176.836373) (xy 297.165699 -176.865427)
			(xy 297.11437 -176.887239) (xy 297.060413 -176.901345) (xy 297.004976 -176.907445) (xy 296.949242 -176.905408)
			(xy 296.894399 -176.895278) (xy 296.841615 -176.877271) (xy 296.792015 -176.85177) (xy 296.746657 -176.819319)
			(xy 296.706508 -176.78061) (xy 296.672422 -176.736467) (xy 296.645126 -176.687832) (xy 296.625203 -176.635741)
			(xy 296.613077 -176.581304) (xy 296.609006 -176.525682) (xy 284.45123 -176.525682) (xy 284.685131 -177.697949)
			(xy 293.026092 -177.697949) (xy 293.026092 -177.643451) (xy 293.033848 -177.589506) (xy 293.049202 -177.537215)
			(xy 293.071841 -177.48764) (xy 293.101305 -177.441793) (xy 293.136993 -177.400604) (xy 293.17818 -177.364914)
			(xy 293.224026 -177.335449) (xy 293.2736 -177.312807) (xy 293.325891 -177.297451) (xy 293.379835 -177.289693)
			(xy 293.407084 -177.289206) (xy 293.434454 -177.28968) (xy 293.488633 -177.297496) (xy 293.541136 -177.312983)
			(xy 293.590883 -177.335823) (xy 293.63685 -177.365546) (xy 293.657782 -177.383186) (xy 293.658036 -177.38344)
			(xy 293.665133 -177.389011) (xy 293.682042 -177.395266) (xy 293.691056 -177.395632) (xy 293.758112 -177.395632)
			(xy 293.767129 -177.395274) (xy 293.784045 -177.389026) (xy 293.791132 -177.38344) (xy 293.791132 -177.383186)
			(xy 293.791386 -177.383186) (xy 293.812319 -177.365545) (xy 293.858287 -177.335821) (xy 293.908033 -177.312975)
			(xy 293.960535 -177.297479) (xy 294.014713 -177.28965) (xy 294.069455 -177.28965) (xy 294.123633 -177.297479)
			(xy 294.176135 -177.312975) (xy 294.225881 -177.335821) (xy 294.271849 -177.365545) (xy 294.292782 -177.383186)
			(xy 294.293036 -177.38344) (xy 294.300133 -177.389011) (xy 294.317042 -177.395266) (xy 294.326056 -177.395632)
			(xy 294.393112 -177.395632) (xy 294.402129 -177.395274) (xy 294.419045 -177.389026) (xy 294.426132 -177.38344)
			(xy 294.426132 -177.383186) (xy 294.426386 -177.383186) (xy 294.447319 -177.365545) (xy 294.493287 -177.335821)
			(xy 294.543033 -177.312975) (xy 294.595535 -177.297479) (xy 294.649713 -177.28965) (xy 294.704455 -177.28965)
			(xy 294.758633 -177.297479) (xy 294.811135 -177.312975) (xy 294.860881 -177.335821) (xy 294.906849 -177.365545)
			(xy 294.927782 -177.383186) (xy 294.928036 -177.38344) (xy 294.935133 -177.389011) (xy 294.952042 -177.395266)
			(xy 294.961056 -177.395632) (xy 295.028112 -177.395632) (xy 295.037129 -177.395274) (xy 295.054045 -177.389026)
			(xy 295.061132 -177.38344) (xy 295.061132 -177.383186) (xy 295.061386 -177.383186) (xy 295.082311 -177.365538)
			(xy 295.128286 -177.335828) (xy 295.178035 -177.312994) (xy 295.230537 -177.297505) (xy 295.284714 -177.289679)
			(xy 295.312084 -177.289206) (xy 295.339339 -177.28964) (xy 295.393293 -177.297395) (xy 295.445595 -177.31275)
			(xy 295.495179 -177.335393) (xy 295.541036 -177.364862) (xy 295.582232 -177.400557) (xy 295.617929 -177.441751)
			(xy 295.647399 -177.487607) (xy 295.670044 -177.53719) (xy 295.685401 -177.589491) (xy 295.693159 -177.643445)
			(xy 295.693159 -177.697955) (xy 295.685401 -177.751909) (xy 295.670044 -177.80421) (xy 295.647399 -177.853793)
			(xy 295.617929 -177.899649) (xy 295.582232 -177.940843) (xy 295.541036 -177.976538) (xy 295.495179 -178.006007)
			(xy 295.445595 -178.02865) (xy 295.393293 -178.044005) (xy 295.339339 -178.05176) (xy 295.312084 -178.052222)
			(xy 295.284713 -178.051784) (xy 295.230531 -178.043963) (xy 295.178027 -178.028468) (xy 295.128281 -178.005619)
			(xy 295.082316 -177.975887) (xy 295.061386 -177.958242) (xy 295.061132 -177.957988) (xy 295.054041 -177.952407)
			(xy 295.037128 -177.946157) (xy 295.028112 -177.945796) (xy 294.961056 -177.945796) (xy 294.952042 -177.946181)
			(xy 294.935125 -177.952409) (xy 294.928036 -177.957988) (xy 294.927782 -177.958242) (xy 294.906849 -177.975883)
			(xy 294.860881 -178.005607) (xy 294.811135 -178.028453) (xy 294.758633 -178.043949) (xy 294.704455 -178.051778)
			(xy 294.649713 -178.051778) (xy 294.595535 -178.043949) (xy 294.543033 -178.028453) (xy 294.493287 -178.005607)
			(xy 294.447319 -177.975883) (xy 294.426386 -177.958242) (xy 294.426132 -177.957988) (xy 294.419041 -177.952407)
			(xy 294.402128 -177.946157) (xy 294.393112 -177.945796) (xy 294.326056 -177.945796) (xy 294.317042 -177.946181)
			(xy 294.300125 -177.952409) (xy 294.293036 -177.957988) (xy 294.293036 -177.958242) (xy 294.292782 -177.958242)
			(xy 294.271849 -177.975883) (xy 294.225881 -178.005607) (xy 294.176135 -178.028453) (xy 294.123633 -178.043949)
			(xy 294.069455 -178.051778) (xy 294.014713 -178.051778) (xy 293.960535 -178.043949) (xy 293.908033 -178.028453)
			(xy 293.858287 -178.005607) (xy 293.812319 -177.975883) (xy 293.791386 -177.958242) (xy 293.791132 -177.957988)
			(xy 293.784041 -177.952407) (xy 293.767128 -177.946157) (xy 293.758112 -177.945796) (xy 293.691056 -177.945796)
			(xy 293.682042 -177.946181) (xy 293.665125 -177.952409) (xy 293.658036 -177.957988) (xy 293.658036 -177.958242)
			(xy 293.657782 -177.958242) (xy 293.636836 -177.975863) (xy 293.590866 -178.005576) (xy 293.541122 -178.028415)
			(xy 293.488625 -178.043911) (xy 293.434452 -178.051745) (xy 293.407084 -178.052222) (xy 293.379835 -178.051707)
			(xy 293.325891 -178.043949) (xy 293.2736 -178.028593) (xy 293.224026 -178.005951) (xy 293.17818 -177.976486)
			(xy 293.136993 -177.940796) (xy 293.101305 -177.899607) (xy 293.071841 -177.85376) (xy 293.049202 -177.804185)
			(xy 293.033848 -177.751894) (xy 293.026092 -177.697949) (xy 284.685131 -177.697949) (xy 284.745176 -177.998882)
			(xy 284.747208 -178.00574) (xy 284.974284 -178.55438) (xy 285.142432 -178.960526) (xy 285.145734 -178.9684)
			(xy 285.145734 -178.968908) (xy 285.155998 -178.997485) (xy 285.167125 -179.05717) (xy 285.167832 -179.087526)
			(xy 285.167832 -180.1114) (xy 285.168848 -180.121306) (xy 285.381519 -181.190138) (xy 295.216578 -181.190138)
			(xy 295.220649 -181.134516) (xy 295.232775 -181.080079) (xy 295.252698 -181.027988) (xy 295.279994 -180.979353)
			(xy 295.31408 -180.93521) (xy 295.354229 -180.896501) (xy 295.399587 -180.86405) (xy 295.449187 -180.838549)
			(xy 295.501971 -180.820542) (xy 295.556814 -180.810412) (xy 295.612548 -180.808375) (xy 295.667985 -180.814475)
			(xy 295.721942 -180.828581) (xy 295.773271 -180.850393) (xy 295.820877 -180.879447) (xy 295.863745 -180.915122)
			(xy 295.900962 -180.956659) (xy 295.931735 -181.003172) (xy 295.955407 -181.053669) (xy 295.971475 -181.107076)
			(xy 295.979595 -181.162252) (xy 295.980104 -181.190138) (xy 295.979595 -181.218024) (xy 295.971475 -181.2732)
			(xy 295.955407 -181.326607) (xy 295.931735 -181.377104) (xy 295.900962 -181.423617) (xy 295.863745 -181.465154)
			(xy 295.820877 -181.500829) (xy 295.773271 -181.529883) (xy 295.721942 -181.551695) (xy 295.667985 -181.565801)
			(xy 295.612548 -181.571901) (xy 295.556814 -181.569864) (xy 295.501971 -181.559734) (xy 295.449187 -181.541727)
			(xy 295.399587 -181.516226) (xy 295.354229 -181.483775) (xy 295.31408 -181.445066) (xy 295.279994 -181.400923)
			(xy 295.252698 -181.352288) (xy 295.232775 -181.300197) (xy 295.220649 -181.24576) (xy 295.216578 -181.190138)
			(xy 285.381519 -181.190138) (xy 285.39567 -181.261258) (xy 285.640992 -182.491126) (xy 295.811192 -182.491126)
			(xy 295.815263 -182.435504) (xy 295.827389 -182.381067) (xy 295.847312 -182.328976) (xy 295.874608 -182.280341)
			(xy 295.908694 -182.236198) (xy 295.948843 -182.197489) (xy 295.994201 -182.165038) (xy 296.043801 -182.139537)
			(xy 296.096585 -182.12153) (xy 296.151428 -182.1114) (xy 296.207162 -182.109363) (xy 296.262599 -182.115463)
			(xy 296.316556 -182.129569) (xy 296.367885 -182.151381) (xy 296.415491 -182.180435) (xy 296.458359 -182.21611)
			(xy 296.495576 -182.257647) (xy 296.526349 -182.30416) (xy 296.550021 -182.354657) (xy 296.566089 -182.408064)
			(xy 296.574209 -182.46324) (xy 296.574718 -182.491126) (xy 296.574209 -182.519012) (xy 296.566089 -182.574188)
			(xy 296.550021 -182.627595) (xy 296.526349 -182.678092) (xy 296.495576 -182.724605) (xy 296.458359 -182.766142)
			(xy 296.415491 -182.801817) (xy 296.367885 -182.830871) (xy 296.316556 -182.852683) (xy 296.262599 -182.866789)
			(xy 296.207162 -182.872889) (xy 296.151428 -182.870852) (xy 296.096585 -182.860722) (xy 296.043801 -182.842715)
			(xy 295.994201 -182.817214) (xy 295.948843 -182.784763) (xy 295.908694 -182.746054) (xy 295.874608 -182.701911)
			(xy 295.847312 -182.653276) (xy 295.827389 -182.601185) (xy 295.815263 -182.546748) (xy 295.811192 -182.491126)
			(xy 285.640992 -182.491126) (xy 286.103568 -184.810146) (xy 286.105329 -184.817113) (xy 286.112173 -184.829741)
			(xy 286.11703 -184.835038) (xy 286.331914 -185.049922) (xy 292.35603 -185.049922) (xy 292.360101 -184.9943)
			(xy 292.372227 -184.939863) (xy 292.39215 -184.887772) (xy 292.419446 -184.839137) (xy 292.453532 -184.794994)
			(xy 292.493681 -184.756285) (xy 292.539039 -184.723834) (xy 292.588639 -184.698333) (xy 292.641423 -184.680326)
			(xy 292.696266 -184.670196) (xy 292.752 -184.668159) (xy 292.807437 -184.674259) (xy 292.861394 -184.688365)
			(xy 292.912723 -184.710177) (xy 292.960329 -184.739231) (xy 293.003197 -184.774906) (xy 293.040414 -184.816443)
			(xy 293.071187 -184.862956) (xy 293.094859 -184.913453) (xy 293.110927 -184.96686) (xy 293.119047 -185.022036)
			(xy 293.119556 -185.049922) (xy 293.119047 -185.077808) (xy 293.110927 -185.132984) (xy 293.094859 -185.186391)
			(xy 293.071187 -185.236888) (xy 293.040414 -185.283401) (xy 293.003197 -185.324938) (xy 292.960329 -185.360613)
			(xy 292.912723 -185.389667) (xy 292.861394 -185.411479) (xy 292.807437 -185.425585) (xy 292.752 -185.431685)
			(xy 292.696266 -185.429648) (xy 292.641423 -185.419518) (xy 292.588639 -185.401511) (xy 292.539039 -185.37601)
			(xy 292.493681 -185.343559) (xy 292.453532 -185.30485) (xy 292.419446 -185.260707) (xy 292.39215 -185.212072)
			(xy 292.372227 -185.159981) (xy 292.360101 -185.105544) (xy 292.35603 -185.049922) (xy 286.331914 -185.049922)
			(xy 286.982408 -185.700416) (xy 286.993076 -185.706766) (xy 286.998918 -185.708544) (xy 287.024485 -185.716991)
			(xy 287.073133 -185.740069) (xy 287.118056 -185.769754) (xy 287.158362 -185.805458) (xy 287.19325 -185.846471)
			(xy 287.222028 -185.89198) (xy 287.244126 -185.941081) (xy 287.259104 -185.9928) (xy 287.266666 -186.046112)
			(xy 287.267142 -186.073034) (xy 287.266654 -186.100285) (xy 287.258894 -186.15423) (xy 287.243536 -186.206523)
			(xy 287.220893 -186.256098) (xy 287.191427 -186.301947) (xy 287.155736 -186.343136) (xy 287.114547 -186.378827)
			(xy 287.082103 -186.399678) (xy 297.289218 -186.399678) (xy 297.293289 -186.344056) (xy 297.305415 -186.289619)
			(xy 297.325338 -186.237528) (xy 297.352634 -186.188893) (xy 297.38672 -186.14475) (xy 297.426869 -186.106041)
			(xy 297.472227 -186.07359) (xy 297.521827 -186.048089) (xy 297.574611 -186.030082) (xy 297.629454 -186.019952)
			(xy 297.685188 -186.017915) (xy 297.740625 -186.024015) (xy 297.794582 -186.038121) (xy 297.845911 -186.059933)
			(xy 297.893517 -186.088987) (xy 297.936385 -186.124662) (xy 297.973602 -186.166199) (xy 298.004375 -186.212712)
			(xy 298.028047 -186.263209) (xy 298.044115 -186.316616) (xy 298.052235 -186.371792) (xy 298.052744 -186.399678)
			(xy 298.052235 -186.427564) (xy 298.044115 -186.48274) (xy 298.028047 -186.536147) (xy 298.004375 -186.586644)
			(xy 297.973602 -186.633157) (xy 297.936385 -186.674694) (xy 297.893517 -186.710369) (xy 297.845911 -186.739423)
			(xy 297.794582 -186.761235) (xy 297.740625 -186.775341) (xy 297.685188 -186.781441) (xy 297.629454 -186.779404)
			(xy 297.574611 -186.769274) (xy 297.521827 -186.751267) (xy 297.472227 -186.725766) (xy 297.426869 -186.693315)
			(xy 297.38672 -186.654606) (xy 297.352634 -186.610463) (xy 297.325338 -186.561828) (xy 297.305415 -186.509737)
			(xy 297.293289 -186.4553) (xy 297.289218 -186.399678) (xy 287.082103 -186.399678) (xy 287.068698 -186.408293)
			(xy 287.019123 -186.430936) (xy 286.96683 -186.446294) (xy 286.912885 -186.454054) (xy 286.885634 -186.454542)
			(xy 286.885634 -186.454796) (xy 286.8587 -186.454335) (xy 286.805365 -186.446764) (xy 286.753626 -186.431768)
			(xy 286.70451 -186.409644) (xy 286.658994 -186.380832) (xy 286.617982 -186.345905) (xy 286.582289 -186.305558)
			(xy 286.552626 -186.260592) (xy 286.529581 -186.211901) (xy 286.521144 -186.186318) (xy 286.521144 -186.186064)
			(xy 286.519136 -186.180228) (xy 286.512718 -186.169689) (xy 286.508444 -186.165236) (xy 286.45866 -186.115452)
			(xy 286.451425 -186.108848) (xy 286.433406 -186.101209) (xy 286.413838 -186.100889) (xy 286.404558 -186.104022)
			(xy 286.381952 -186.11596) (xy 286.37738 -186.124088) (xy 286.373877 -186.131507) (xy 286.371277 -186.147698)
			(xy 286.3723 -186.155838) (xy 287.099556 -189.802262) (xy 291.45433 -189.802262) (xy 291.458401 -189.74664)
			(xy 291.470527 -189.692203) (xy 291.49045 -189.640112) (xy 291.517746 -189.591477) (xy 291.551832 -189.547334)
			(xy 291.591981 -189.508625) (xy 291.637339 -189.476174) (xy 291.686939 -189.450673) (xy 291.739723 -189.432666)
			(xy 291.794566 -189.422536) (xy 291.8503 -189.420499) (xy 291.905737 -189.426599) (xy 291.959694 -189.440705)
			(xy 292.011023 -189.462517) (xy 292.058629 -189.491571) (xy 292.101497 -189.527246) (xy 292.138714 -189.568783)
			(xy 292.169487 -189.615296) (xy 292.193159 -189.665793) (xy 292.209227 -189.7192) (xy 292.217347 -189.774376)
			(xy 292.217856 -189.802262) (xy 292.217347 -189.830148) (xy 292.209227 -189.885324) (xy 292.193159 -189.938731)
			(xy 292.169487 -189.989228) (xy 292.138714 -190.035741) (xy 292.101497 -190.077278) (xy 292.058629 -190.112953)
			(xy 292.011023 -190.142007) (xy 291.959694 -190.163819) (xy 291.905737 -190.177925) (xy 291.8503 -190.184025)
			(xy 291.794566 -190.181988) (xy 291.739723 -190.171858) (xy 291.686939 -190.153851) (xy 291.637339 -190.12835)
			(xy 291.591981 -190.095899) (xy 291.551832 -190.05719) (xy 291.517746 -190.013047) (xy 291.49045 -189.964412)
			(xy 291.470527 -189.912321) (xy 291.458401 -189.857884) (xy 291.45433 -189.802262) (xy 287.099556 -189.802262)
			(xy 287.975901 -194.196208) (xy 292.349172 -194.196208) (xy 292.353243 -194.140586) (xy 292.365369 -194.086149)
			(xy 292.385292 -194.034058) (xy 292.412588 -193.985423) (xy 292.446674 -193.94128) (xy 292.486823 -193.902571)
			(xy 292.532181 -193.87012) (xy 292.581781 -193.844619) (xy 292.634565 -193.826612) (xy 292.689408 -193.816482)
			(xy 292.745142 -193.814445) (xy 292.800579 -193.820545) (xy 292.854536 -193.834651) (xy 292.905865 -193.856463)
			(xy 292.953471 -193.885517) (xy 292.996339 -193.921192) (xy 293.033556 -193.962729) (xy 293.064329 -194.009242)
			(xy 293.088001 -194.059739) (xy 293.104069 -194.113146) (xy 293.112189 -194.168322) (xy 293.112698 -194.196208)
			(xy 293.112189 -194.224094) (xy 293.104069 -194.27927) (xy 293.090238 -194.32524) (xy 297.568618 -194.32524)
			(xy 297.572689 -194.269618) (xy 297.584815 -194.215181) (xy 297.604738 -194.16309) (xy 297.632034 -194.114455)
			(xy 297.66612 -194.070312) (xy 297.706269 -194.031603) (xy 297.751627 -193.999152) (xy 297.801227 -193.973651)
			(xy 297.854011 -193.955644) (xy 297.908854 -193.945514) (xy 297.964588 -193.943477) (xy 298.020025 -193.949577)
			(xy 298.073982 -193.963683) (xy 298.125311 -193.985495) (xy 298.172917 -194.014549) (xy 298.215785 -194.050224)
			(xy 298.253002 -194.091761) (xy 298.283775 -194.138274) (xy 298.307447 -194.188771) (xy 298.323515 -194.242178)
			(xy 298.331635 -194.297354) (xy 298.332144 -194.32524) (xy 298.331635 -194.353126) (xy 298.323515 -194.408302)
			(xy 298.307447 -194.461709) (xy 298.283775 -194.512206) (xy 298.253002 -194.558719) (xy 298.215785 -194.600256)
			(xy 298.172917 -194.635931) (xy 298.125311 -194.664985) (xy 298.073982 -194.686797) (xy 298.020025 -194.700903)
			(xy 297.964588 -194.707003) (xy 297.908854 -194.704966) (xy 297.854011 -194.694836) (xy 297.801227 -194.676829)
			(xy 297.751627 -194.651328) (xy 297.706269 -194.618877) (xy 297.66612 -194.580168) (xy 297.632034 -194.536025)
			(xy 297.604738 -194.48739) (xy 297.584815 -194.435299) (xy 297.572689 -194.380862) (xy 297.568618 -194.32524)
			(xy 293.090238 -194.32524) (xy 293.088001 -194.332677) (xy 293.064329 -194.383174) (xy 293.033556 -194.429687)
			(xy 292.996339 -194.471224) (xy 292.953471 -194.506899) (xy 292.905865 -194.535953) (xy 292.854536 -194.557765)
			(xy 292.800579 -194.571871) (xy 292.745142 -194.577971) (xy 292.689408 -194.575934) (xy 292.634565 -194.565804)
			(xy 292.581781 -194.547797) (xy 292.532181 -194.522296) (xy 292.486823 -194.489845) (xy 292.446674 -194.451136)
			(xy 292.412588 -194.406993) (xy 292.385292 -194.358358) (xy 292.365369 -194.306267) (xy 292.353243 -194.25183)
			(xy 292.349172 -194.196208) (xy 287.975901 -194.196208) (xy 288.053966 -194.587622) (xy 291.074854 -194.587622)
			(xy 291.078925 -194.532) (xy 291.091051 -194.477563) (xy 291.110974 -194.425472) (xy 291.13827 -194.376837)
			(xy 291.172356 -194.332694) (xy 291.212505 -194.293985) (xy 291.257863 -194.261534) (xy 291.307463 -194.236033)
			(xy 291.360247 -194.218026) (xy 291.41509 -194.207896) (xy 291.470824 -194.205859) (xy 291.526261 -194.211959)
			(xy 291.580218 -194.226065) (xy 291.631547 -194.247877) (xy 291.679153 -194.276931) (xy 291.722021 -194.312606)
			(xy 291.759238 -194.354143) (xy 291.790011 -194.400656) (xy 291.813683 -194.451153) (xy 291.829751 -194.50456)
			(xy 291.837871 -194.559736) (xy 291.83838 -194.587622) (xy 291.837871 -194.615508) (xy 291.829751 -194.670684)
			(xy 291.813683 -194.724091) (xy 291.790011 -194.774588) (xy 291.759238 -194.821101) (xy 291.722021 -194.862638)
			(xy 291.679153 -194.898313) (xy 291.631547 -194.927367) (xy 291.580218 -194.949179) (xy 291.526261 -194.963285)
			(xy 291.470824 -194.969385) (xy 291.41509 -194.967348) (xy 291.360247 -194.957218) (xy 291.307463 -194.939211)
			(xy 291.257863 -194.91371) (xy 291.212505 -194.881259) (xy 291.172356 -194.84255) (xy 291.13827 -194.798407)
			(xy 291.110974 -194.749772) (xy 291.091051 -194.697681) (xy 291.078925 -194.643244) (xy 291.074854 -194.587622)
			(xy 288.053966 -194.587622) (xy 288.340238 -196.022976) (xy 297.965112 -196.022976) (xy 297.969183 -195.967354)
			(xy 297.981309 -195.912917) (xy 298.001232 -195.860826) (xy 298.028528 -195.812191) (xy 298.062614 -195.768048)
			(xy 298.102763 -195.729339) (xy 298.148121 -195.696888) (xy 298.197721 -195.671387) (xy 298.250505 -195.65338)
			(xy 298.305348 -195.64325) (xy 298.361082 -195.641213) (xy 298.416519 -195.647313) (xy 298.470476 -195.661419)
			(xy 298.521805 -195.683231) (xy 298.569411 -195.712285) (xy 298.612279 -195.74796) (xy 298.649496 -195.789497)
			(xy 298.680269 -195.83601) (xy 298.703941 -195.886507) (xy 298.720009 -195.939914) (xy 298.728129 -195.99509)
			(xy 298.728638 -196.022976) (xy 298.728129 -196.050862) (xy 298.720009 -196.106038) (xy 298.703941 -196.159445)
			(xy 298.680269 -196.209942) (xy 298.649496 -196.256455) (xy 298.612279 -196.297992) (xy 298.569411 -196.333667)
			(xy 298.521805 -196.362721) (xy 298.470476 -196.384533) (xy 298.416519 -196.398639) (xy 298.361082 -196.404739)
			(xy 298.305348 -196.402702) (xy 298.250505 -196.392572) (xy 298.197721 -196.374565) (xy 298.148121 -196.349064)
			(xy 298.102763 -196.316613) (xy 298.062614 -196.277904) (xy 298.028528 -196.233761) (xy 298.001232 -196.185126)
			(xy 297.981309 -196.133035) (xy 297.969183 -196.078598) (xy 297.965112 -196.022976) (xy 288.340238 -196.022976)
			(xy 289.008375 -199.372982) (xy 298.448982 -199.372982) (xy 298.453053 -199.31736) (xy 298.465179 -199.262923)
			(xy 298.485102 -199.210832) (xy 298.512398 -199.162197) (xy 298.546484 -199.118054) (xy 298.586633 -199.079345)
			(xy 298.631991 -199.046894) (xy 298.681591 -199.021393) (xy 298.734375 -199.003386) (xy 298.789218 -198.993256)
			(xy 298.844952 -198.991219) (xy 298.900389 -198.997319) (xy 298.954346 -199.011425) (xy 299.005675 -199.033237)
			(xy 299.053281 -199.062291) (xy 299.096149 -199.097966) (xy 299.133366 -199.139503) (xy 299.164139 -199.186016)
			(xy 299.187811 -199.236513) (xy 299.203879 -199.28992) (xy 299.211999 -199.345096) (xy 299.212508 -199.372982)
			(xy 299.211999 -199.400868) (xy 299.203879 -199.456044) (xy 299.187811 -199.509451) (xy 299.164139 -199.559948)
			(xy 299.133366 -199.606461) (xy 299.096149 -199.647998) (xy 299.053281 -199.683673) (xy 299.005675 -199.712727)
			(xy 298.954346 -199.734539) (xy 298.900389 -199.748645) (xy 298.844952 -199.754745) (xy 298.789218 -199.752708)
			(xy 298.734375 -199.742578) (xy 298.681591 -199.724571) (xy 298.631991 -199.69907) (xy 298.586633 -199.666619)
			(xy 298.546484 -199.62791) (xy 298.512398 -199.583767) (xy 298.485102 -199.535132) (xy 298.465179 -199.483041)
			(xy 298.453053 -199.428604) (xy 298.448982 -199.372982) (xy 289.008375 -199.372982) (xy 289.318558 -200.928224)
			(xy 292.89959 -200.928224) (xy 292.903661 -200.872602) (xy 292.915787 -200.818165) (xy 292.93571 -200.766074)
			(xy 292.963006 -200.717439) (xy 292.997092 -200.673296) (xy 293.037241 -200.634587) (xy 293.082599 -200.602136)
			(xy 293.132199 -200.576635) (xy 293.184983 -200.558628) (xy 293.239826 -200.548498) (xy 293.29556 -200.546461)
			(xy 293.350997 -200.552561) (xy 293.404954 -200.566667) (xy 293.456283 -200.588479) (xy 293.503889 -200.617533)
			(xy 293.546757 -200.653208) (xy 293.583974 -200.694745) (xy 293.614747 -200.741258) (xy 293.638419 -200.791755)
			(xy 293.654487 -200.845162) (xy 293.662607 -200.900338) (xy 293.663116 -200.928224) (xy 293.662607 -200.95611)
			(xy 293.654487 -201.011286) (xy 293.638419 -201.064693) (xy 293.636785 -201.068178) (xy 295.508932 -201.068178)
			(xy 295.513003 -201.012556) (xy 295.525129 -200.958119) (xy 295.545052 -200.906028) (xy 295.572348 -200.857393)
			(xy 295.606434 -200.81325) (xy 295.646583 -200.774541) (xy 295.691941 -200.74209) (xy 295.741541 -200.716589)
			(xy 295.794325 -200.698582) (xy 295.849168 -200.688452) (xy 295.904902 -200.686415) (xy 295.960339 -200.692515)
			(xy 296.014296 -200.706621) (xy 296.065625 -200.728433) (xy 296.113231 -200.757487) (xy 296.156099 -200.793162)
			(xy 296.193316 -200.834699) (xy 296.224089 -200.881212) (xy 296.247761 -200.931709) (xy 296.263829 -200.985116)
			(xy 296.271949 -201.040292) (xy 296.272458 -201.068178) (xy 296.271949 -201.096064) (xy 296.263829 -201.15124)
			(xy 296.263754 -201.15149) (xy 296.72102 -201.15149) (xy 296.725091 -201.095868) (xy 296.737217 -201.041431)
			(xy 296.75714 -200.98934) (xy 296.784436 -200.940705) (xy 296.818522 -200.896562) (xy 296.858671 -200.857853)
			(xy 296.904029 -200.825402) (xy 296.953629 -200.799901) (xy 297.006413 -200.781894) (xy 297.061256 -200.771764)
			(xy 297.11699 -200.769727) (xy 297.172427 -200.775827) (xy 297.226384 -200.789933) (xy 297.277713 -200.811745)
			(xy 297.325319 -200.840799) (xy 297.368187 -200.876474) (xy 297.405404 -200.918011) (xy 297.436177 -200.964524)
			(xy 297.459849 -201.015021) (xy 297.475917 -201.068428) (xy 297.484037 -201.123604) (xy 297.484546 -201.15149)
			(xy 297.484037 -201.179376) (xy 297.475917 -201.234552) (xy 297.459849 -201.287959) (xy 297.436177 -201.338456)
			(xy 297.405404 -201.384969) (xy 297.368187 -201.426506) (xy 297.325319 -201.462181) (xy 297.277713 -201.491235)
			(xy 297.226384 -201.513047) (xy 297.172427 -201.527153) (xy 297.11699 -201.533253) (xy 297.061256 -201.531216)
			(xy 297.006413 -201.521086) (xy 296.953629 -201.503079) (xy 296.904029 -201.477578) (xy 296.858671 -201.445127)
			(xy 296.818522 -201.406418) (xy 296.784436 -201.362275) (xy 296.75714 -201.31364) (xy 296.737217 -201.261549)
			(xy 296.725091 -201.207112) (xy 296.72102 -201.15149) (xy 296.263754 -201.15149) (xy 296.247761 -201.204647)
			(xy 296.224089 -201.255144) (xy 296.193316 -201.301657) (xy 296.156099 -201.343194) (xy 296.113231 -201.378869)
			(xy 296.065625 -201.407923) (xy 296.014296 -201.429735) (xy 295.960339 -201.443841) (xy 295.904902 -201.449941)
			(xy 295.849168 -201.447904) (xy 295.794325 -201.437774) (xy 295.741541 -201.419767) (xy 295.691941 -201.394266)
			(xy 295.646583 -201.361815) (xy 295.606434 -201.323106) (xy 295.572348 -201.278963) (xy 295.545052 -201.230328)
			(xy 295.525129 -201.178237) (xy 295.513003 -201.1238) (xy 295.508932 -201.068178) (xy 293.636785 -201.068178)
			(xy 293.614747 -201.11519) (xy 293.583974 -201.161703) (xy 293.546757 -201.20324) (xy 293.503889 -201.238915)
			(xy 293.456283 -201.267969) (xy 293.404954 -201.289781) (xy 293.350997 -201.303887) (xy 293.29556 -201.309987)
			(xy 293.239826 -201.30795) (xy 293.184983 -201.29782) (xy 293.132199 -201.279813) (xy 293.082599 -201.254312)
			(xy 293.037241 -201.221861) (xy 292.997092 -201.183152) (xy 292.963006 -201.139009) (xy 292.93571 -201.090374)
			(xy 292.915787 -201.038283) (xy 292.903661 -200.983846) (xy 292.89959 -200.928224) (xy 289.318558 -200.928224)
			(xy 289.48634 -201.769472) (xy 289.487102 -201.77252) (xy 290.11331 -204.125068) (xy 290.679122 -204.125068)
			(xy 290.683193 -204.069446) (xy 290.695319 -204.015009) (xy 290.715242 -203.962918) (xy 290.742538 -203.914283)
			(xy 290.776624 -203.87014) (xy 290.816773 -203.831431) (xy 290.862131 -203.79898) (xy 290.911731 -203.773479)
			(xy 290.964515 -203.755472) (xy 291.019358 -203.745342) (xy 291.075092 -203.743305) (xy 291.130529 -203.749405)
			(xy 291.184486 -203.763511) (xy 291.235815 -203.785323) (xy 291.283421 -203.814377) (xy 291.326289 -203.850052)
			(xy 291.363506 -203.891589) (xy 291.392781 -203.935838) (xy 292.984172 -203.935838) (xy 292.988243 -203.880216)
			(xy 293.000369 -203.825779) (xy 293.020292 -203.773688) (xy 293.047588 -203.725053) (xy 293.081674 -203.68091)
			(xy 293.121823 -203.642201) (xy 293.167181 -203.60975) (xy 293.216781 -203.584249) (xy 293.269565 -203.566242)
			(xy 293.324408 -203.556112) (xy 293.380142 -203.554075) (xy 293.435579 -203.560175) (xy 293.489536 -203.574281)
			(xy 293.540865 -203.596093) (xy 293.588471 -203.625147) (xy 293.631339 -203.660822) (xy 293.668556 -203.702359)
			(xy 293.699329 -203.748872) (xy 293.712199 -203.776326) (xy 295.45991 -203.776326) (xy 295.463981 -203.720704)
			(xy 295.476107 -203.666267) (xy 295.49603 -203.614176) (xy 295.523326 -203.565541) (xy 295.557412 -203.521398)
			(xy 295.597561 -203.482689) (xy 295.642919 -203.450238) (xy 295.692519 -203.424737) (xy 295.745303 -203.40673)
			(xy 295.800146 -203.3966) (xy 295.85588 -203.394563) (xy 295.911317 -203.400663) (xy 295.965274 -203.414769)
			(xy 296.016603 -203.436581) (xy 296.064209 -203.465635) (xy 296.107077 -203.50131) (xy 296.144294 -203.542847)
			(xy 296.175067 -203.58936) (xy 296.198739 -203.639857) (xy 296.214807 -203.693264) (xy 296.222927 -203.74844)
			(xy 296.223436 -203.776326) (xy 296.222927 -203.804212) (xy 296.214807 -203.859388) (xy 296.202352 -203.900786)
			(xy 297.59097 -203.900786) (xy 297.595041 -203.845164) (xy 297.607167 -203.790727) (xy 297.62709 -203.738636)
			(xy 297.654386 -203.690001) (xy 297.688472 -203.645858) (xy 297.728621 -203.607149) (xy 297.773979 -203.574698)
			(xy 297.823579 -203.549197) (xy 297.876363 -203.53119) (xy 297.931206 -203.52106) (xy 297.98694 -203.519023)
			(xy 298.042377 -203.525123) (xy 298.096334 -203.539229) (xy 298.147663 -203.561041) (xy 298.195269 -203.590095)
			(xy 298.238137 -203.62577) (xy 298.275354 -203.667307) (xy 298.306127 -203.71382) (xy 298.329799 -203.764317)
			(xy 298.345867 -203.817724) (xy 298.353987 -203.8729) (xy 298.354496 -203.900786) (xy 298.353987 -203.928672)
			(xy 298.345867 -203.983848) (xy 298.329799 -204.037255) (xy 298.306127 -204.087752) (xy 298.275354 -204.134265)
			(xy 298.238137 -204.175802) (xy 298.195269 -204.211477) (xy 298.147663 -204.240531) (xy 298.096334 -204.262343)
			(xy 298.042377 -204.276449) (xy 297.98694 -204.282549) (xy 297.931206 -204.280512) (xy 297.876363 -204.270382)
			(xy 297.823579 -204.252375) (xy 297.773979 -204.226874) (xy 297.728621 -204.194423) (xy 297.688472 -204.155714)
			(xy 297.654386 -204.111571) (xy 297.62709 -204.062936) (xy 297.607167 -204.010845) (xy 297.595041 -203.956408)
			(xy 297.59097 -203.900786) (xy 296.202352 -203.900786) (xy 296.198739 -203.912795) (xy 296.175067 -203.963292)
			(xy 296.144294 -204.009805) (xy 296.107077 -204.051342) (xy 296.064209 -204.087017) (xy 296.016603 -204.116071)
			(xy 295.965274 -204.137883) (xy 295.911317 -204.151989) (xy 295.85588 -204.158089) (xy 295.800146 -204.156052)
			(xy 295.745303 -204.145922) (xy 295.692519 -204.127915) (xy 295.642919 -204.102414) (xy 295.597561 -204.069963)
			(xy 295.557412 -204.031254) (xy 295.523326 -203.987111) (xy 295.49603 -203.938476) (xy 295.476107 -203.886385)
			(xy 295.463981 -203.831948) (xy 295.45991 -203.776326) (xy 293.712199 -203.776326) (xy 293.723001 -203.799369)
			(xy 293.739069 -203.852776) (xy 293.747189 -203.907952) (xy 293.747698 -203.935838) (xy 293.747189 -203.963724)
			(xy 293.739069 -204.0189) (xy 293.723001 -204.072307) (xy 293.699329 -204.122804) (xy 293.668556 -204.169317)
			(xy 293.631339 -204.210854) (xy 293.588471 -204.246529) (xy 293.540865 -204.275583) (xy 293.489536 -204.297395)
			(xy 293.435579 -204.311501) (xy 293.380142 -204.317601) (xy 293.324408 -204.315564) (xy 293.269565 -204.305434)
			(xy 293.216781 -204.287427) (xy 293.167181 -204.261926) (xy 293.121823 -204.229475) (xy 293.081674 -204.190766)
			(xy 293.047588 -204.146623) (xy 293.020292 -204.097988) (xy 293.000369 -204.045897) (xy 292.988243 -203.99146)
			(xy 292.984172 -203.935838) (xy 291.392781 -203.935838) (xy 291.394279 -203.938102) (xy 291.417951 -203.988599)
			(xy 291.434019 -204.042006) (xy 291.442139 -204.097182) (xy 291.442648 -204.125068) (xy 291.442139 -204.152954)
			(xy 291.434019 -204.20813) (xy 291.417951 -204.261537) (xy 291.394279 -204.312034) (xy 291.363506 -204.358547)
			(xy 291.326289 -204.400084) (xy 291.283421 -204.435759) (xy 291.235815 -204.464813) (xy 291.184486 -204.486625)
			(xy 291.130529 -204.500731) (xy 291.075092 -204.506831) (xy 291.019358 -204.504794) (xy 290.964515 -204.494664)
			(xy 290.911731 -204.476657) (xy 290.862131 -204.451156) (xy 290.816773 -204.418705) (xy 290.776624 -204.379996)
			(xy 290.742538 -204.335853) (xy 290.715242 -204.287218) (xy 290.695319 -204.235127) (xy 290.683193 -204.18069)
			(xy 290.679122 -204.125068) (xy 290.11331 -204.125068) (xy 290.755609 -206.538068) (xy 292.603172 -206.538068)
			(xy 292.607243 -206.482446) (xy 292.619369 -206.428009) (xy 292.639292 -206.375918) (xy 292.666588 -206.327283)
			(xy 292.700674 -206.28314) (xy 292.740823 -206.244431) (xy 292.786181 -206.21198) (xy 292.835781 -206.186479)
			(xy 292.888565 -206.168472) (xy 292.943408 -206.158342) (xy 292.999142 -206.156305) (xy 293.054579 -206.162405)
			(xy 293.108536 -206.176511) (xy 293.159865 -206.198323) (xy 293.207471 -206.227377) (xy 293.250339 -206.263052)
			(xy 293.287556 -206.304589) (xy 293.318329 -206.351102) (xy 293.342001 -206.401599) (xy 293.358069 -206.455006)
			(xy 293.366189 -206.510182) (xy 293.366698 -206.538068) (xy 293.366189 -206.565954) (xy 293.358069 -206.62113)
			(xy 293.342001 -206.674537) (xy 293.318329 -206.725034) (xy 293.287556 -206.771547) (xy 293.250339 -206.813084)
			(xy 293.207471 -206.848759) (xy 293.159865 -206.877813) (xy 293.108536 -206.899625) (xy 293.054579 -206.913731)
			(xy 292.999142 -206.919831) (xy 292.943408 -206.917794) (xy 292.888565 -206.907664) (xy 292.835781 -206.889657)
			(xy 292.786181 -206.864156) (xy 292.740823 -206.831705) (xy 292.700674 -206.792996) (xy 292.666588 -206.748853)
			(xy 292.639292 -206.700218) (xy 292.619369 -206.648127) (xy 292.607243 -206.59369) (xy 292.603172 -206.538068)
			(xy 290.755609 -206.538068) (xy 292.776148 -214.128858) (xy 292.778255 -214.135623) (xy 292.78561 -214.147728)
			(xy 292.790626 -214.152734) (xy 292.795706 -214.15756) (xy 292.807644 -214.16391) (xy 292.81501 -214.165434)
			(xy 292.843275 -214.171844) (xy 292.89759 -214.192056) (xy 292.948222 -214.220253) (xy 292.994006 -214.255786)
			(xy 293.033887 -214.297837) (xy 293.066947 -214.345437) (xy 293.092425 -214.39749) (xy 293.098974 -214.418418)
			(xy 294.647872 -214.418418) (xy 294.651943 -214.362796) (xy 294.664069 -214.308359) (xy 294.683992 -214.256268)
			(xy 294.711288 -214.207633) (xy 294.745374 -214.16349) (xy 294.785523 -214.124781) (xy 294.830881 -214.09233)
			(xy 294.880481 -214.066829) (xy 294.933265 -214.048822) (xy 294.988108 -214.038692) (xy 295.043842 -214.036655)
			(xy 295.099279 -214.042755) (xy 295.153236 -214.056861) (xy 295.204565 -214.078673) (xy 295.252171 -214.107727)
			(xy 295.295039 -214.143402) (xy 295.332256 -214.184939) (xy 295.363029 -214.231452) (xy 295.386701 -214.281949)
			(xy 295.402769 -214.335356) (xy 295.410889 -214.390532) (xy 295.411398 -214.418418) (xy 295.411022 -214.438992)
			(xy 300.739046 -214.438992) (xy 300.743117 -214.38337) (xy 300.755243 -214.328933) (xy 300.775166 -214.276842)
			(xy 300.802462 -214.228207) (xy 300.836548 -214.184064) (xy 300.876697 -214.145355) (xy 300.922055 -214.112904)
			(xy 300.971655 -214.087403) (xy 301.024439 -214.069396) (xy 301.079282 -214.059266) (xy 301.135016 -214.057229)
			(xy 301.190453 -214.063329) (xy 301.24441 -214.077435) (xy 301.295739 -214.099247) (xy 301.343345 -214.128301)
			(xy 301.386213 -214.163976) (xy 301.42343 -214.205513) (xy 301.454203 -214.252026) (xy 301.477875 -214.302523)
			(xy 301.493943 -214.35593) (xy 301.502063 -214.411106) (xy 301.502572 -214.438992) (xy 301.502063 -214.466878)
			(xy 301.493943 -214.522054) (xy 301.477875 -214.575461) (xy 301.454203 -214.625958) (xy 301.42343 -214.672471)
			(xy 301.386213 -214.714008) (xy 301.343345 -214.749683) (xy 301.295739 -214.778737) (xy 301.24441 -214.800549)
			(xy 301.190453 -214.814655) (xy 301.135016 -214.820755) (xy 301.079282 -214.818718) (xy 301.024439 -214.808588)
			(xy 300.971655 -214.790581) (xy 300.922055 -214.76508) (xy 300.876697 -214.732629) (xy 300.836548 -214.69392)
			(xy 300.802462 -214.649777) (xy 300.775166 -214.601142) (xy 300.755243 -214.549051) (xy 300.743117 -214.494614)
			(xy 300.739046 -214.438992) (xy 295.411022 -214.438992) (xy 295.410889 -214.446304) (xy 295.402769 -214.50148)
			(xy 295.386701 -214.554887) (xy 295.363029 -214.605384) (xy 295.332256 -214.651897) (xy 295.295039 -214.693434)
			(xy 295.252171 -214.729109) (xy 295.204565 -214.758163) (xy 295.153236 -214.779975) (xy 295.099279 -214.794081)
			(xy 295.043842 -214.800181) (xy 294.988108 -214.798144) (xy 294.933265 -214.788014) (xy 294.880481 -214.770007)
			(xy 294.830881 -214.744506) (xy 294.785523 -214.712055) (xy 294.745374 -214.673346) (xy 294.711288 -214.629203)
			(xy 294.683992 -214.580568) (xy 294.664069 -214.528477) (xy 294.651943 -214.47404) (xy 294.647872 -214.418418)
			(xy 293.098974 -214.418418) (xy 293.109734 -214.452799) (xy 293.118477 -214.510091) (xy 293.119048 -214.539068)
			(xy 293.118579 -214.566466) (xy 293.110752 -214.620701) (xy 293.095256 -214.673261) (xy 293.072407 -214.723067)
			(xy 293.042675 -214.769097) (xy 293.006671 -214.810405) (xy 292.986206 -214.828628) (xy 292.985952 -214.828882)
			(xy 292.985444 -214.82939) (xy 292.983412 -214.831168) (xy 292.979602 -214.83447) (xy 292.975538 -214.848186)
			(xy 292.973724 -214.854911) (xy 292.973465 -214.868831) (xy 292.97503 -214.875618) (xy 292.978586 -214.888826)
			(xy 293.050468 -215.159082) (xy 293.052092 -215.164646) (xy 293.057476 -215.174907) (xy 293.061136 -215.179402)
			(xy 293.068248 -215.18753) (xy 293.078662 -215.192356) (xy 293.103882 -215.204401) (xy 293.150797 -215.234773)
			(xy 293.192778 -215.271665) (xy 293.228927 -215.314287) (xy 293.258471 -215.361729) (xy 293.280776 -215.412973)
			(xy 293.295365 -215.466923) (xy 293.299134 -215.494616) (xy 293.300658 -215.508586) (xy 293.301928 -215.539574)
			(xy 293.301429 -215.567663) (xy 293.293184 -215.623232) (xy 293.276869 -215.676988) (xy 293.252839 -215.727766)
			(xy 293.237666 -215.75141) (xy 293.233348 -215.757506) (xy 293.22903 -215.771984) (xy 293.22903 -215.822276)
			(xy 293.230808 -215.83523) (xy 293.300379 -216.096596) (xy 295.167048 -216.096596) (xy 295.171119 -216.040974)
			(xy 295.183245 -215.986537) (xy 295.203168 -215.934446) (xy 295.230464 -215.885811) (xy 295.26455 -215.841668)
			(xy 295.304699 -215.802959) (xy 295.350057 -215.770508) (xy 295.399657 -215.745007) (xy 295.452441 -215.727)
			(xy 295.507284 -215.71687) (xy 295.563018 -215.714833) (xy 295.618455 -215.720933) (xy 295.672412 -215.735039)
			(xy 295.723741 -215.756851) (xy 295.771347 -215.785905) (xy 295.814215 -215.82158) (xy 295.851432 -215.863117)
			(xy 295.882205 -215.90963) (xy 295.905877 -215.960127) (xy 295.921945 -216.013534) (xy 295.930065 -216.06871)
			(xy 295.930574 -216.096596) (xy 295.930065 -216.124482) (xy 295.92303 -216.172288) (xy 300.440342 -216.172288)
			(xy 300.444413 -216.116666) (xy 300.456539 -216.062229) (xy 300.476462 -216.010138) (xy 300.503758 -215.961503)
			(xy 300.537844 -215.91736) (xy 300.577993 -215.878651) (xy 300.623351 -215.8462) (xy 300.672951 -215.820699)
			(xy 300.725735 -215.802692) (xy 300.780578 -215.792562) (xy 300.836312 -215.790525) (xy 300.891749 -215.796625)
			(xy 300.945706 -215.810731) (xy 300.997035 -215.832543) (xy 301.044641 -215.861597) (xy 301.087509 -215.897272)
			(xy 301.124726 -215.938809) (xy 301.155499 -215.985322) (xy 301.179171 -216.035819) (xy 301.195239 -216.089226)
			(xy 301.203359 -216.144402) (xy 301.203868 -216.172288) (xy 301.203359 -216.200174) (xy 301.195239 -216.25535)
			(xy 301.179171 -216.308757) (xy 301.155499 -216.359254) (xy 301.124726 -216.405767) (xy 301.087509 -216.447304)
			(xy 301.044641 -216.482979) (xy 300.997035 -216.512033) (xy 300.945706 -216.533845) (xy 300.891749 -216.547951)
			(xy 300.836312 -216.554051) (xy 300.780578 -216.552014) (xy 300.725735 -216.541884) (xy 300.672951 -216.523877)
			(xy 300.623351 -216.498376) (xy 300.577993 -216.465925) (xy 300.537844 -216.427216) (xy 300.503758 -216.383073)
			(xy 300.476462 -216.334438) (xy 300.456539 -216.282347) (xy 300.444413 -216.22791) (xy 300.440342 -216.172288)
			(xy 295.92303 -216.172288) (xy 295.921945 -216.179658) (xy 295.905877 -216.233065) (xy 295.882205 -216.283562)
			(xy 295.851432 -216.330075) (xy 295.814215 -216.371612) (xy 295.771347 -216.407287) (xy 295.723741 -216.436341)
			(xy 295.672412 -216.458153) (xy 295.618455 -216.472259) (xy 295.563018 -216.478359) (xy 295.507284 -216.476322)
			(xy 295.452441 -216.466192) (xy 295.399657 -216.448185) (xy 295.350057 -216.422684) (xy 295.304699 -216.390233)
			(xy 295.26455 -216.351524) (xy 295.230464 -216.307381) (xy 295.203168 -216.258746) (xy 295.183245 -216.206655)
			(xy 295.171119 -216.152218) (xy 295.167048 -216.096596) (xy 293.300379 -216.096596) (xy 293.691098 -217.564462)
			(xy 300.10303 -217.564462) (xy 300.107101 -217.50884) (xy 300.119227 -217.454403) (xy 300.13915 -217.402312)
			(xy 300.166446 -217.353677) (xy 300.200532 -217.309534) (xy 300.240681 -217.270825) (xy 300.286039 -217.238374)
			(xy 300.335639 -217.212873) (xy 300.388423 -217.194866) (xy 300.443266 -217.184736) (xy 300.499 -217.182699)
			(xy 300.554437 -217.188799) (xy 300.608394 -217.202905) (xy 300.659723 -217.224717) (xy 300.707329 -217.253771)
			(xy 300.750197 -217.289446) (xy 300.787414 -217.330983) (xy 300.818187 -217.377496) (xy 300.841859 -217.427993)
			(xy 300.857927 -217.4814) (xy 300.866047 -217.536576) (xy 300.866556 -217.564462) (xy 300.866047 -217.592348)
			(xy 300.857927 -217.647524) (xy 300.841859 -217.700931) (xy 300.818187 -217.751428) (xy 300.787414 -217.797941)
			(xy 300.750197 -217.839478) (xy 300.707329 -217.875153) (xy 300.659723 -217.904207) (xy 300.608394 -217.926019)
			(xy 300.554437 -217.940125) (xy 300.499 -217.946225) (xy 300.443266 -217.944188) (xy 300.388423 -217.934058)
			(xy 300.335639 -217.916051) (xy 300.286039 -217.89055) (xy 300.240681 -217.858099) (xy 300.200532 -217.81939)
			(xy 300.166446 -217.775247) (xy 300.13915 -217.726612) (xy 300.119227 -217.674521) (xy 300.107101 -217.620084)
			(xy 300.10303 -217.564462) (xy 293.691098 -217.564462) (xy 294.420544 -220.304868) (xy 294.423385 -220.314014)
			(xy 294.434753 -220.329407) (xy 294.442642 -220.33484) (xy 294.449246 -220.338904) (xy 294.502078 -220.371924)
			(xy 294.506032 -220.374307) (xy 294.514595 -220.377757) (xy 294.519096 -220.378782) (xy 294.527732 -220.38056)
			(xy 294.537892 -220.378528) (xy 294.556059 -220.375188) (xy 294.592828 -220.371631) (xy 294.611298 -220.371416)
			(xy 294.614092 -220.371416) (xy 294.641212 -220.372092) (xy 294.694857 -220.38017) (xy 294.746816 -220.395765)
			(xy 294.796041 -220.418564) (xy 294.841541 -220.448107) (xy 294.882397 -220.483797) (xy 294.917784 -220.524915)
			(xy 294.94699 -220.570631) (xy 294.9518 -220.58122) (xy 299.398688 -220.58122) (xy 299.402759 -220.525598)
			(xy 299.414885 -220.471161) (xy 299.434808 -220.41907) (xy 299.462104 -220.370435) (xy 299.49619 -220.326292)
			(xy 299.536339 -220.287583) (xy 299.581697 -220.255132) (xy 299.631297 -220.229631) (xy 299.684081 -220.211624)
			(xy 299.738924 -220.201494) (xy 299.794658 -220.199457) (xy 299.850095 -220.205557) (xy 299.904052 -220.219663)
			(xy 299.955381 -220.241475) (xy 300.002987 -220.270529) (xy 300.045855 -220.306204) (xy 300.083072 -220.347741)
			(xy 300.113845 -220.394254) (xy 300.137517 -220.444751) (xy 300.153585 -220.498158) (xy 300.161705 -220.553334)
			(xy 300.161797 -220.55836) (xy 301.225456 -220.55836) (xy 301.229527 -220.502738) (xy 301.241653 -220.448301)
			(xy 301.261576 -220.39621) (xy 301.288872 -220.347575) (xy 301.322958 -220.303432) (xy 301.363107 -220.264723)
			(xy 301.408465 -220.232272) (xy 301.458065 -220.206771) (xy 301.510849 -220.188764) (xy 301.565692 -220.178634)
			(xy 301.621426 -220.176597) (xy 301.676863 -220.182697) (xy 301.73082 -220.196803) (xy 301.782149 -220.218615)
			(xy 301.829755 -220.247669) (xy 301.872623 -220.283344) (xy 301.90984 -220.324881) (xy 301.940613 -220.371394)
			(xy 301.964285 -220.421891) (xy 301.980353 -220.475298) (xy 301.988473 -220.530474) (xy 301.988982 -220.55836)
			(xy 301.988473 -220.586246) (xy 301.980353 -220.641422) (xy 301.964285 -220.694829) (xy 301.940613 -220.745326)
			(xy 301.90984 -220.791839) (xy 301.872623 -220.833376) (xy 301.829755 -220.869051) (xy 301.782149 -220.898105)
			(xy 301.73082 -220.919917) (xy 301.676863 -220.934023) (xy 301.621426 -220.940123) (xy 301.565692 -220.938086)
			(xy 301.510849 -220.927956) (xy 301.458065 -220.909949) (xy 301.408465 -220.884448) (xy 301.363107 -220.851997)
			(xy 301.322958 -220.813288) (xy 301.288872 -220.769145) (xy 301.261576 -220.72051) (xy 301.241653 -220.668419)
			(xy 301.229527 -220.613982) (xy 301.225456 -220.55836) (xy 300.161797 -220.55836) (xy 300.162214 -220.58122)
			(xy 300.161705 -220.609106) (xy 300.153585 -220.664282) (xy 300.137517 -220.717689) (xy 300.113845 -220.768186)
			(xy 300.083072 -220.814699) (xy 300.045855 -220.856236) (xy 300.002987 -220.891911) (xy 299.955381 -220.920965)
			(xy 299.904052 -220.942777) (xy 299.850095 -220.956883) (xy 299.794658 -220.962983) (xy 299.738924 -220.960946)
			(xy 299.684081 -220.950816) (xy 299.631297 -220.932809) (xy 299.581697 -220.907308) (xy 299.536339 -220.874857)
			(xy 299.49619 -220.836148) (xy 299.462104 -220.792005) (xy 299.434808 -220.74337) (xy 299.414885 -220.691279)
			(xy 299.402759 -220.636842) (xy 299.398688 -220.58122) (xy 294.9518 -220.58122) (xy 294.969425 -220.620024)
			(xy 294.984637 -220.672097) (xy 294.992319 -220.725799) (xy 294.992806 -220.752924) (xy 294.99236 -220.779297)
			(xy 294.985096 -220.831539) (xy 294.97071 -220.882285) (xy 294.949476 -220.930567) (xy 294.921799 -220.975467)
			(xy 294.888204 -221.01613) (xy 294.849331 -221.051781) (xy 294.805922 -221.081742) (xy 294.758801 -221.105443)
			(xy 294.73398 -221.114366) (xy 294.724836 -221.117414) (xy 294.71747 -221.12351) (xy 294.713869 -221.126723)
			(xy 294.707852 -221.134265) (xy 294.705532 -221.138496) (xy 294.672766 -221.199456) (xy 294.670734 -221.204028)
			(xy 294.668499 -221.209985) (xy 294.666692 -221.222576) (xy 294.667178 -221.22892) (xy 294.668448 -221.23654)
			(xy 295.69543 -225.094038) (xy 299.26915 -225.094038) (xy 299.269601 -225.066885) (xy 299.277321 -225.013131)
			(xy 299.292582 -224.961014) (xy 299.315076 -224.911586) (xy 299.344348 -224.865845) (xy 299.379808 -224.824715)
			(xy 299.39996 -224.80651) (xy 299.407416 -224.799438) (xy 299.416318 -224.780934) (xy 299.417232 -224.770696)
			(xy 299.421296 -224.686876) (xy 299.414184 -224.667572) (xy 299.407072 -224.659952) (xy 299.38752 -224.638591)
			(xy 299.354484 -224.591033) (xy 299.329019 -224.539025) (xy 299.311712 -224.483765) (xy 299.30296 -224.426523)
			(xy 299.302424 -224.39757) (xy 299.30291 -224.370319) (xy 299.310666 -224.316371) (xy 299.326021 -224.264076)
			(xy 299.348663 -224.214499) (xy 299.378129 -224.168649) (xy 299.41382 -224.127458) (xy 299.455011 -224.091767)
			(xy 299.500861 -224.062301) (xy 299.550438 -224.039659) (xy 299.602733 -224.024304) (xy 299.656681 -224.016548)
			(xy 299.711183 -224.016548) (xy 299.765131 -224.024304) (xy 299.817426 -224.039659) (xy 299.867003 -224.062301)
			(xy 299.912853 -224.091767) (xy 299.954044 -224.127458) (xy 299.989735 -224.168649) (xy 300.019201 -224.214499)
			(xy 300.041843 -224.264076) (xy 300.057198 -224.316371) (xy 300.064954 -224.370319) (xy 300.06544 -224.39757)
			(xy 300.065344 -224.40265) (xy 300.622714 -224.40265) (xy 300.626785 -224.347028) (xy 300.638911 -224.292591)
			(xy 300.658834 -224.2405) (xy 300.68613 -224.191865) (xy 300.720216 -224.147722) (xy 300.760365 -224.109013)
			(xy 300.805723 -224.076562) (xy 300.855323 -224.051061) (xy 300.908107 -224.033054) (xy 300.96295 -224.022924)
			(xy 301.018684 -224.020887) (xy 301.074121 -224.026987) (xy 301.128078 -224.041093) (xy 301.179407 -224.062905)
			(xy 301.227013 -224.091959) (xy 301.269881 -224.127634) (xy 301.307098 -224.169171) (xy 301.337871 -224.215684)
			(xy 301.361543 -224.266181) (xy 301.377611 -224.319588) (xy 301.385731 -224.374764) (xy 301.38624 -224.40265)
			(xy 301.385731 -224.430536) (xy 301.377611 -224.485712) (xy 301.361543 -224.539119) (xy 301.337871 -224.589616)
			(xy 301.307098 -224.636129) (xy 301.269881 -224.677666) (xy 301.227013 -224.713341) (xy 301.179407 -224.742395)
			(xy 301.128078 -224.764207) (xy 301.074121 -224.778313) (xy 301.018684 -224.784413) (xy 300.96295 -224.782376)
			(xy 300.908107 -224.772246) (xy 300.855323 -224.754239) (xy 300.805723 -224.728738) (xy 300.760365 -224.696287)
			(xy 300.720216 -224.657578) (xy 300.68613 -224.613435) (xy 300.658834 -224.5648) (xy 300.638911 -224.512709)
			(xy 300.626785 -224.458272) (xy 300.622714 -224.40265) (xy 300.065344 -224.40265) (xy 300.064929 -224.424721)
			(xy 300.057222 -224.478472) (xy 300.041973 -224.530589) (xy 300.019491 -224.580017) (xy 299.990228 -224.625759)
			(xy 299.954777 -224.666892) (xy 299.93463 -224.685098) (xy 299.927185 -224.692181) (xy 299.918273 -224.710676)
			(xy 299.917358 -224.720912) (xy 299.913294 -224.804732) (xy 299.920406 -224.824036) (xy 299.927518 -224.831656)
			(xy 299.947072 -224.853015) (xy 299.980108 -224.900574) (xy 300.005573 -224.952582) (xy 300.022879 -225.007842)
			(xy 300.031631 -225.065084) (xy 300.032166 -225.094038) (xy 300.03168 -225.121289) (xy 300.023924 -225.175237)
			(xy 300.008569 -225.227532) (xy 299.985927 -225.277109) (xy 299.956461 -225.322959) (xy 299.92077 -225.36415)
			(xy 299.879579 -225.399841) (xy 299.833729 -225.429307) (xy 299.784152 -225.451949) (xy 299.731857 -225.467304)
			(xy 299.677909 -225.47506) (xy 299.623407 -225.47506) (xy 299.569459 -225.467304) (xy 299.517164 -225.451949)
			(xy 299.467587 -225.429307) (xy 299.421737 -225.399841) (xy 299.380546 -225.36415) (xy 299.344855 -225.322959)
			(xy 299.315389 -225.277109) (xy 299.292747 -225.227532) (xy 299.277392 -225.175237) (xy 299.269636 -225.121289)
			(xy 299.26915 -225.094038) (xy 295.69543 -225.094038) (xy 296.268462 -227.246434) (xy 299.758098 -227.246434)
			(xy 299.762169 -227.190812) (xy 299.774295 -227.136375) (xy 299.794218 -227.084284) (xy 299.821514 -227.035649)
			(xy 299.8556 -226.991506) (xy 299.895749 -226.952797) (xy 299.941107 -226.920346) (xy 299.990707 -226.894845)
			(xy 300.043491 -226.876838) (xy 300.098334 -226.866708) (xy 300.154068 -226.864671) (xy 300.209505 -226.870771)
			(xy 300.263462 -226.884877) (xy 300.314791 -226.906689) (xy 300.362397 -226.935743) (xy 300.405265 -226.971418)
			(xy 300.442482 -227.012955) (xy 300.473255 -227.059468) (xy 300.496927 -227.109965) (xy 300.512995 -227.163372)
			(xy 300.521115 -227.218548) (xy 300.521624 -227.246434) (xy 300.521115 -227.27432) (xy 300.512995 -227.329496)
			(xy 300.496927 -227.382903) (xy 300.473255 -227.4334) (xy 300.442482 -227.479913) (xy 300.405265 -227.52145)
			(xy 300.362397 -227.557125) (xy 300.314791 -227.586179) (xy 300.263462 -227.607991) (xy 300.209505 -227.622097)
			(xy 300.154068 -227.628197) (xy 300.098334 -227.62616) (xy 300.043491 -227.61603) (xy 299.990707 -227.598023)
			(xy 299.941107 -227.572522) (xy 299.895749 -227.540071) (xy 299.8556 -227.501362) (xy 299.821514 -227.457219)
			(xy 299.794218 -227.408584) (xy 299.774295 -227.356493) (xy 299.762169 -227.302056) (xy 299.758098 -227.246434)
			(xy 296.268462 -227.246434) (xy 296.690291 -228.830886) (xy 301.931322 -228.830886) (xy 301.935393 -228.775264)
			(xy 301.947519 -228.720827) (xy 301.967442 -228.668736) (xy 301.994738 -228.620101) (xy 302.028824 -228.575958)
			(xy 302.068973 -228.537249) (xy 302.114331 -228.504798) (xy 302.163931 -228.479297) (xy 302.216715 -228.46129)
			(xy 302.271558 -228.45116) (xy 302.327292 -228.449123) (xy 302.382729 -228.455223) (xy 302.436686 -228.469329)
			(xy 302.488015 -228.491141) (xy 302.535621 -228.520195) (xy 302.578489 -228.55587) (xy 302.615706 -228.597407)
			(xy 302.646479 -228.64392) (xy 302.670151 -228.694417) (xy 302.686219 -228.747824) (xy 302.694339 -228.803)
			(xy 302.694848 -228.830886) (xy 302.694339 -228.858772) (xy 302.686219 -228.913948) (xy 302.670151 -228.967355)
			(xy 302.646479 -229.017852) (xy 302.615706 -229.064365) (xy 302.578489 -229.105902) (xy 302.535621 -229.141577)
			(xy 302.488015 -229.170631) (xy 302.436686 -229.192443) (xy 302.382729 -229.206549) (xy 302.327292 -229.212649)
			(xy 302.271558 -229.210612) (xy 302.216715 -229.200482) (xy 302.163931 -229.182475) (xy 302.114331 -229.156974)
			(xy 302.068973 -229.124523) (xy 302.028824 -229.085814) (xy 301.994738 -229.041671) (xy 301.967442 -228.993036)
			(xy 301.947519 -228.940945) (xy 301.935393 -228.886508) (xy 301.931322 -228.830886) (xy 296.690291 -228.830886)
			(xy 296.884773 -229.56139) (xy 302.4792 -229.56139) (xy 302.483271 -229.505768) (xy 302.495397 -229.451331)
			(xy 302.51532 -229.39924) (xy 302.542616 -229.350605) (xy 302.576702 -229.306462) (xy 302.616851 -229.267753)
			(xy 302.662209 -229.235302) (xy 302.711809 -229.209801) (xy 302.764593 -229.191794) (xy 302.819436 -229.181664)
			(xy 302.87517 -229.179627) (xy 302.930607 -229.185727) (xy 302.984564 -229.199833) (xy 303.035893 -229.221645)
			(xy 303.083499 -229.250699) (xy 303.126367 -229.286374) (xy 303.163584 -229.327911) (xy 303.194357 -229.374424)
			(xy 303.218029 -229.424921) (xy 303.234097 -229.478328) (xy 303.242217 -229.533504) (xy 303.242726 -229.56139)
			(xy 303.242217 -229.589276) (xy 303.234097 -229.644452) (xy 303.218029 -229.697859) (xy 303.194357 -229.748356)
			(xy 303.163584 -229.794869) (xy 303.126367 -229.836406) (xy 303.083499 -229.872081) (xy 303.035893 -229.901135)
			(xy 302.984564 -229.922947) (xy 302.930607 -229.937053) (xy 302.87517 -229.943153) (xy 302.819436 -229.941116)
			(xy 302.764593 -229.930986) (xy 302.711809 -229.912979) (xy 302.662209 -229.887478) (xy 302.616851 -229.855027)
			(xy 302.576702 -229.816318) (xy 302.542616 -229.772175) (xy 302.51532 -229.72354) (xy 302.495397 -229.671449)
			(xy 302.483271 -229.617012) (xy 302.4792 -229.56139) (xy 296.884773 -229.56139) (xy 297.610361 -232.28681)
			(xy 297.931076 -232.28681) (xy 297.935147 -232.231188) (xy 297.947273 -232.176751) (xy 297.967196 -232.12466)
			(xy 297.994492 -232.076025) (xy 298.028578 -232.031882) (xy 298.068727 -231.993173) (xy 298.114085 -231.960722)
			(xy 298.163685 -231.935221) (xy 298.216469 -231.917214) (xy 298.271312 -231.907084) (xy 298.327046 -231.905047)
			(xy 298.382483 -231.911147) (xy 298.43644 -231.925253) (xy 298.487769 -231.947065) (xy 298.535375 -231.976119)
			(xy 298.578243 -232.011794) (xy 298.61546 -232.053331) (xy 298.646233 -232.099844) (xy 298.669905 -232.150341)
			(xy 298.685973 -232.203748) (xy 298.694093 -232.258924) (xy 298.694602 -232.28681) (xy 298.694093 -232.314696)
			(xy 298.685973 -232.369872) (xy 298.669905 -232.423279) (xy 298.646233 -232.473776) (xy 298.61546 -232.520289)
			(xy 298.578243 -232.561826) (xy 298.535375 -232.597501) (xy 298.487769 -232.626555) (xy 298.43644 -232.648367)
			(xy 298.382483 -232.662473) (xy 298.327046 -232.668573) (xy 298.271312 -232.666536) (xy 298.216469 -232.656406)
			(xy 298.163685 -232.638399) (xy 298.114085 -232.612898) (xy 298.068727 -232.580447) (xy 298.028578 -232.541738)
			(xy 297.994492 -232.497595) (xy 297.967196 -232.44896) (xy 297.947273 -232.396869) (xy 297.935147 -232.342432)
			(xy 297.931076 -232.28681) (xy 297.610361 -232.28681) (xy 297.941238 -233.529632) (xy 298.048886 -233.934)
			(xy 301.154336 -233.934) (xy 301.158407 -233.878378) (xy 301.170533 -233.823941) (xy 301.190456 -233.77185)
			(xy 301.217752 -233.723215) (xy 301.251838 -233.679072) (xy 301.291987 -233.640363) (xy 301.337345 -233.607912)
			(xy 301.386945 -233.582411) (xy 301.439729 -233.564404) (xy 301.494572 -233.554274) (xy 301.550306 -233.552237)
			(xy 301.605743 -233.558337) (xy 301.6597 -233.572443) (xy 301.711029 -233.594255) (xy 301.758635 -233.623309)
			(xy 301.801503 -233.658984) (xy 301.83872 -233.700521) (xy 301.869493 -233.747034) (xy 301.893165 -233.797531)
			(xy 301.909233 -233.850938) (xy 301.917353 -233.906114) (xy 301.917862 -233.934) (xy 301.917353 -233.961886)
			(xy 301.909233 -234.017062) (xy 301.893165 -234.070469) (xy 301.869493 -234.120966) (xy 301.83872 -234.167479)
			(xy 301.801503 -234.209016) (xy 301.758635 -234.244691) (xy 301.711029 -234.273745) (xy 301.6597 -234.295557)
			(xy 301.605743 -234.309663) (xy 301.550306 -234.315763) (xy 301.494572 -234.313726) (xy 301.439729 -234.303596)
			(xy 301.386945 -234.285589) (xy 301.337345 -234.260088) (xy 301.291987 -234.227637) (xy 301.251838 -234.188928)
			(xy 301.217752 -234.144785) (xy 301.190456 -234.09615) (xy 301.170533 -234.044059) (xy 301.158407 -233.989622)
			(xy 301.154336 -233.934) (xy 298.048886 -233.934) (xy 299.096968 -237.871) (xy 299.845982 -237.871)
			(xy 299.850053 -237.815378) (xy 299.862179 -237.760941) (xy 299.882102 -237.70885) (xy 299.909398 -237.660215)
			(xy 299.943484 -237.616072) (xy 299.983633 -237.577363) (xy 300.028991 -237.544912) (xy 300.078591 -237.519411)
			(xy 300.131375 -237.501404) (xy 300.186218 -237.491274) (xy 300.241952 -237.489237) (xy 300.297389 -237.495337)
			(xy 300.351346 -237.509443) (xy 300.402675 -237.531255) (xy 300.450281 -237.560309) (xy 300.493149 -237.595984)
			(xy 300.530366 -237.637521) (xy 300.561139 -237.684034) (xy 300.584811 -237.734531) (xy 300.600879 -237.787938)
			(xy 300.605477 -237.819184) (xy 302.170336 -237.819184) (xy 302.174407 -237.763562) (xy 302.186533 -237.709125)
			(xy 302.206456 -237.657034) (xy 302.233752 -237.608399) (xy 302.267838 -237.564256) (xy 302.307987 -237.525547)
			(xy 302.353345 -237.493096) (xy 302.402945 -237.467595) (xy 302.455729 -237.449588) (xy 302.510572 -237.439458)
			(xy 302.566306 -237.437421) (xy 302.621743 -237.443521) (xy 302.6757 -237.457627) (xy 302.727029 -237.479439)
			(xy 302.774635 -237.508493) (xy 302.817503 -237.544168) (xy 302.85472 -237.585705) (xy 302.885493 -237.632218)
			(xy 302.909165 -237.682715) (xy 302.925233 -237.736122) (xy 302.933353 -237.791298) (xy 302.933862 -237.819184)
			(xy 302.933353 -237.84707) (xy 302.925233 -237.902246) (xy 302.909165 -237.955653) (xy 302.885493 -238.00615)
			(xy 302.85472 -238.052663) (xy 302.817503 -238.0942) (xy 302.774635 -238.129875) (xy 302.727029 -238.158929)
			(xy 302.6757 -238.180741) (xy 302.621743 -238.194847) (xy 302.566306 -238.200947) (xy 302.510572 -238.19891)
			(xy 302.455729 -238.18878) (xy 302.402945 -238.170773) (xy 302.353345 -238.145272) (xy 302.307987 -238.112821)
			(xy 302.267838 -238.074112) (xy 302.233752 -238.029969) (xy 302.206456 -237.981334) (xy 302.186533 -237.929243)
			(xy 302.174407 -237.874806) (xy 302.170336 -237.819184) (xy 300.605477 -237.819184) (xy 300.608999 -237.843114)
			(xy 300.609508 -237.871) (xy 300.608999 -237.898886) (xy 300.600879 -237.954062) (xy 300.584811 -238.007469)
			(xy 300.561139 -238.057966) (xy 300.530366 -238.104479) (xy 300.493149 -238.146016) (xy 300.450281 -238.181691)
			(xy 300.402675 -238.210745) (xy 300.351346 -238.232557) (xy 300.297389 -238.246663) (xy 300.241952 -238.252763)
			(xy 300.186218 -238.250726) (xy 300.131375 -238.240596) (xy 300.078591 -238.222589) (xy 300.028991 -238.197088)
			(xy 299.983633 -238.164637) (xy 299.943484 -238.125928) (xy 299.909398 -238.081785) (xy 299.882102 -238.03315)
			(xy 299.862179 -237.981059) (xy 299.850053 -237.926622) (xy 299.845982 -237.871) (xy 299.096968 -237.871)
			(xy 299.381167 -238.938562) (xy 301.679608 -238.938562) (xy 301.683679 -238.88294) (xy 301.695805 -238.828503)
			(xy 301.715728 -238.776412) (xy 301.743024 -238.727777) (xy 301.77711 -238.683634) (xy 301.817259 -238.644925)
			(xy 301.862617 -238.612474) (xy 301.912217 -238.586973) (xy 301.965001 -238.568966) (xy 302.019844 -238.558836)
			(xy 302.075578 -238.556799) (xy 302.131015 -238.562899) (xy 302.184972 -238.577005) (xy 302.236301 -238.598817)
			(xy 302.283907 -238.627871) (xy 302.326775 -238.663546) (xy 302.363992 -238.705083) (xy 302.394765 -238.751596)
			(xy 302.418437 -238.802093) (xy 302.434505 -238.8555) (xy 302.442625 -238.910676) (xy 302.443134 -238.938562)
			(xy 302.695608 -238.938562) (xy 302.699679 -238.88294) (xy 302.711805 -238.828503) (xy 302.731728 -238.776412)
			(xy 302.759024 -238.727777) (xy 302.79311 -238.683634) (xy 302.833259 -238.644925) (xy 302.878617 -238.612474)
			(xy 302.928217 -238.586973) (xy 302.981001 -238.568966) (xy 303.035844 -238.558836) (xy 303.091578 -238.556799)
			(xy 303.147015 -238.562899) (xy 303.200972 -238.577005) (xy 303.252301 -238.598817) (xy 303.299907 -238.627871)
			(xy 303.342775 -238.663546) (xy 303.379992 -238.705083) (xy 303.410765 -238.751596) (xy 303.434437 -238.802093)
			(xy 303.450505 -238.8555) (xy 303.458625 -238.910676) (xy 303.459134 -238.938562) (xy 303.458625 -238.966448)
			(xy 303.450505 -239.021624) (xy 303.434437 -239.075031) (xy 303.410765 -239.125528) (xy 303.379992 -239.172041)
			(xy 303.342775 -239.213578) (xy 303.299907 -239.249253) (xy 303.252301 -239.278307) (xy 303.200972 -239.300119)
			(xy 303.147015 -239.314225) (xy 303.091578 -239.320325) (xy 303.035844 -239.318288) (xy 302.981001 -239.308158)
			(xy 302.928217 -239.290151) (xy 302.878617 -239.26465) (xy 302.833259 -239.232199) (xy 302.79311 -239.19349)
			(xy 302.759024 -239.149347) (xy 302.731728 -239.100712) (xy 302.711805 -239.048621) (xy 302.699679 -238.994184)
			(xy 302.695608 -238.938562) (xy 302.443134 -238.938562) (xy 302.442625 -238.966448) (xy 302.434505 -239.021624)
			(xy 302.418437 -239.075031) (xy 302.394765 -239.125528) (xy 302.363992 -239.172041) (xy 302.326775 -239.213578)
			(xy 302.283907 -239.249253) (xy 302.236301 -239.278307) (xy 302.184972 -239.300119) (xy 302.131015 -239.314225)
			(xy 302.075578 -239.320325) (xy 302.019844 -239.318288) (xy 301.965001 -239.308158) (xy 301.912217 -239.290151)
			(xy 301.862617 -239.26465) (xy 301.817259 -239.232199) (xy 301.77711 -239.19349) (xy 301.743024 -239.149347)
			(xy 301.715728 -239.100712) (xy 301.695805 -239.048621) (xy 301.683679 -238.994184) (xy 301.679608 -238.938562)
			(xy 299.381167 -238.938562) (xy 300.964854 -244.887496) (xy 300.965616 -244.89029) (xy 300.967649 -244.895901)
			(xy 300.973942 -244.906038) (xy 300.978062 -244.910356) (xy 301.036228 -244.968522) (xy 301.041658 -244.973503)
			(xy 301.054697 -244.980351) (xy 301.061882 -244.981984) (xy 301.06239 -244.981984) (xy 301.071788 -244.983)
			(xy 304.088292 -244.983) (xy 304.09642 -244.982238) (xy 304.096928 -244.982238) (xy 304.104448 -244.980639)
			(xy 304.11814 -244.973667) (xy 304.123852 -244.968522) (xy 304.545238 -244.547136) (xy 304.552053 -244.539658)
			(xy 304.559654 -244.520926) (xy 304.55997 -244.510814) (xy 304.364898 -241.729514) (xy 304.364207 -241.723021)
			(xy 304.359966 -241.710674) (xy 304.356516 -241.70513) (xy 304.34915 -241.69624) (xy 304.330354 -241.680492)
			(xy 304.323496 -241.681254) (xy 304.320956 -241.681508) (xy 304.320702 -241.681508) (xy 304.26025 -241.687858)
			(xy 304.249582 -241.690906) (xy 304.221388 -241.7191) (xy 304.217832 -241.72672) (xy 304.205842 -241.750754)
			(xy 304.176124 -241.795493) (xy 304.140429 -241.835626) (xy 304.099463 -241.870361) (xy 304.054033 -241.899013)
			(xy 304.005037 -241.921015) (xy 303.953441 -241.935934) (xy 303.900263 -241.943476) (xy 303.873408 -241.94389)
			(xy 303.846155 -241.943427) (xy 303.792204 -241.935671) (xy 303.739907 -241.920316) (xy 303.690327 -241.897673)
			(xy 303.644474 -241.868205) (xy 303.603282 -241.832511) (xy 303.567589 -241.791318) (xy 303.538122 -241.745465)
			(xy 303.515481 -241.695884) (xy 303.500127 -241.643586) (xy 303.492372 -241.589635) (xy 303.4919 -241.562382)
			(xy 303.492399 -241.534642) (xy 303.500433 -241.479747) (xy 303.516331 -241.426593) (xy 303.539756 -241.376301)
			(xy 303.570215 -241.32993) (xy 303.607067 -241.288457) (xy 303.649534 -241.252756) (xy 303.696723 -241.22358)
			(xy 303.747638 -241.201542) (xy 303.801208 -241.187108) (xy 303.828704 -241.183414) (xy 303.84242 -241.18189)
			(xy 303.869305 -241.180165) (xy 303.923081 -241.183386) (xy 303.975871 -241.194134) (xy 304.026625 -241.212197)
			(xy 304.074336 -241.237215) (xy 304.118055 -241.268693) (xy 304.156916 -241.306004) (xy 304.17389 -241.326924)
			(xy 304.17516 -241.328702) (xy 304.179732 -241.334544) (xy 304.192432 -241.34445) (xy 304.19692 -241.347592)
			(xy 304.206911 -241.352085) (xy 304.212244 -241.35334) (xy 304.221896 -241.354356) (xy 304.2285 -241.354356)
			(xy 304.31232 -241.344958) (xy 304.31896 -241.344016) (xy 304.331441 -241.339121) (xy 304.336958 -241.335306)
			(xy 304.309018 -240.937288) (xy 304.263552 -240.288318) (xy 304.201068 -239.396778) (xy 304.199619 -239.388433)
			(xy 304.192097 -239.37327) (xy 304.186336 -239.36706) (xy 304.184812 -239.365536) (xy 304.117502 -239.304576)
			(xy 304.10531 -239.30483) (xy 304.083466 -239.305338) (xy 304.081942 -239.305338) (xy 304.054686 -239.304878)
			(xy 304.000729 -239.297126) (xy 303.948425 -239.281774) (xy 303.898837 -239.259134) (xy 303.852977 -239.229668)
			(xy 303.811776 -239.193975) (xy 303.776075 -239.152781) (xy 303.7466 -239.106926) (xy 303.723951 -239.057343)
			(xy 303.708589 -239.005041) (xy 303.700827 -238.951086) (xy 303.700434 -238.92383) (xy 303.700925 -238.895822)
			(xy 303.70911 -238.840406) (xy 303.72531 -238.786783) (xy 303.749176 -238.736104) (xy 303.780195 -238.68946)
			(xy 303.817701 -238.647852) (xy 303.860887 -238.612175) (xy 303.908825 -238.583195) (xy 303.960485 -238.561536)
			(xy 304.014757 -238.547662) (xy 304.042572 -238.544354) (xy 304.052478 -238.543338) (xy 304.061114 -238.538766)
			(xy 304.065406 -238.536373) (xy 304.073082 -238.53024) (xy 304.076354 -238.526574) (xy 304.122582 -238.47171)
			(xy 304.12826 -238.464) (xy 304.133893 -238.445716) (xy 304.133504 -238.43615) (xy 303.186338 -224.942146)
			(xy 303.186338 -224.941892) (xy 303.185329 -224.932576) (xy 303.177384 -224.915618) (xy 303.163839 -224.902686)
			(xy 303.15535 -224.898712) (xy 303.134268 -224.891092) (xy 303.13376 -224.890838) (xy 303.126736 -224.888607)
			(xy 303.112023 -224.887831) (xy 303.104804 -224.889314) (xy 303.102772 -224.890076) (xy 303.101502 -224.89033)
			(xy 303.095701 -224.892321) (xy 303.08518 -224.898615) (xy 303.080674 -224.902776) (xy 303.079404 -224.904046)
			(xy 303.061393 -224.921873) (xy 303.02148 -224.953098) (xy 302.977784 -224.978764) (xy 302.931076 -224.99842)
			(xy 302.882176 -225.011719) (xy 302.831946 -225.018429) (xy 302.806608 -225.018854) (xy 302.779351 -225.018392)
			(xy 302.725393 -225.010635) (xy 302.673088 -224.995277) (xy 302.623501 -224.972633) (xy 302.577641 -224.943161)
			(xy 302.536442 -224.907463) (xy 302.500744 -224.866265) (xy 302.471271 -224.820406) (xy 302.448625 -224.77082)
			(xy 302.433267 -224.718515) (xy 302.425509 -224.664557) (xy 302.425509 -224.610043) (xy 302.433267 -224.556085)
			(xy 302.448625 -224.50378) (xy 302.471271 -224.454194) (xy 302.500744 -224.408335) (xy 302.536442 -224.367137)
			(xy 302.577641 -224.331439) (xy 302.623501 -224.301967) (xy 302.673088 -224.279323) (xy 302.725393 -224.263965)
			(xy 302.779351 -224.256208) (xy 302.806608 -224.255838) (xy 302.837228 -224.256448) (xy 302.897681 -224.266239)
			(xy 302.955792 -224.285567) (xy 303.010066 -224.313935) (xy 303.034954 -224.331784) (xy 303.036986 -224.333308)
			(xy 303.040796 -224.336102) (xy 303.054766 -224.341436) (xy 303.057052 -224.342198) (xy 303.067095 -224.34518)
			(xy 303.087963 -224.343617) (xy 303.097438 -224.33915) (xy 303.113186 -224.330768) (xy 303.121379 -224.325993)
			(xy 303.133752 -224.311641) (xy 303.14005 -224.293768) (xy 303.14011 -224.284286) (xy 303.082452 -223.462342)
			(xy 303.0093 -222.420434) (xy 302.911002 -221.020894) (xy 302.906122 -221.017537) (xy 302.895218 -221.012921)
			(xy 302.889412 -221.01175) (xy 302.87341 -221.010988) (xy 302.870108 -221.010988) (xy 302.841463 -221.009924)
			(xy 302.784962 -221.000263) (xy 302.730543 -220.982255) (xy 302.679432 -220.956305) (xy 302.632781 -220.922998)
			(xy 302.59164 -220.883084) (xy 302.556936 -220.837462) (xy 302.529451 -220.78716) (xy 302.509804 -220.733311)
			(xy 302.498438 -220.677128) (xy 302.496474 -220.64853) (xy 302.495625 -220.624138) (xy 302.499396 -220.575478)
			(xy 302.509353 -220.527698) (xy 302.525333 -220.481581) (xy 302.535844 -220.459554) (xy 302.546913 -220.438128)
			(xy 302.573663 -220.398001) (xy 302.589184 -220.379544) (xy 302.607065 -220.359609) (xy 302.647458 -220.324451)
			(xy 302.692373 -220.295291) (xy 302.740926 -220.272701) (xy 302.792162 -220.257128) (xy 302.818546 -220.252544)
			(xy 302.82007 -220.25229) (xy 302.822864 -220.251782) (xy 302.832516 -220.250004) (xy 302.836236 -220.249155)
			(xy 302.843383 -220.246482) (xy 302.84674 -220.24467) (xy 302.853852 -220.24086) (xy 302.856138 -220.238066)
			(xy 302.846994 -220.10624) (xy 302.69815 -217.985848) (xy 302.694594 -217.934794) (xy 302.693772 -217.927533)
			(xy 302.688608 -217.913869) (xy 302.684434 -217.90787) (xy 302.675798 -217.896186) (xy 302.67021 -217.8939)
			(xy 302.664114 -217.891868) (xy 302.641762 -217.883994) (xy 302.632621 -217.88117) (xy 302.613515 -217.881831)
			(xy 302.595993 -217.889475) (xy 302.58893 -217.895932) (xy 302.586898 -217.897964) (xy 302.568889 -217.915794)
			(xy 302.528978 -217.947024) (xy 302.485283 -217.972695) (xy 302.438574 -217.992355) (xy 302.389673 -218.005657)
			(xy 302.339441 -218.012367) (xy 302.314102 -218.012772) (xy 302.286852 -218.012309) (xy 302.232906 -218.004553)
			(xy 302.180612 -217.989198) (xy 302.131037 -217.966558) (xy 302.085188 -217.937093) (xy 302.043999 -217.901403)
			(xy 302.008308 -217.860214) (xy 301.978843 -217.814365) (xy 301.956202 -217.764789) (xy 301.940848 -217.712496)
			(xy 301.933091 -217.65855) (xy 301.933091 -217.60405) (xy 301.940848 -217.550104) (xy 301.956202 -217.497811)
			(xy 301.978843 -217.448235) (xy 302.008308 -217.402386) (xy 302.043999 -217.361197) (xy 302.085188 -217.325507)
			(xy 302.131037 -217.296042) (xy 302.180612 -217.273402) (xy 302.232906 -217.258047) (xy 302.286852 -217.250291)
			(xy 302.314102 -217.249756) (xy 302.31461 -217.249756) (xy 302.339542 -217.250155) (xy 302.388984 -217.256638)
			(xy 302.43716 -217.269504) (xy 302.48325 -217.288536) (xy 302.526469 -217.313408) (xy 302.546512 -217.328242)
			(xy 302.55083 -217.331544) (xy 302.559466 -217.335608) (xy 302.563983 -217.337634) (xy 302.573579 -217.340064)
			(xy 302.578516 -217.340434) (xy 302.582072 -217.340434) (xy 302.587953 -217.34022) (xy 302.599372 -217.337392)
			(xy 302.604678 -217.334846) (xy 302.62322 -217.324686) (xy 302.63121 -217.319642) (xy 302.64302 -217.30491)
			(xy 302.648645 -217.286886) (xy 302.648366 -217.277442) (xy 302.568864 -216.144856) (xy 302.556164 -215.962738)
			(xy 302.550056 -215.958307) (xy 302.53598 -215.952892) (xy 302.528478 -215.95207) (xy 302.505364 -215.95207)
			(xy 302.477651 -215.951535) (xy 302.422818 -215.943441) (xy 302.369733 -215.9275) (xy 302.319511 -215.904049)
			(xy 302.27321 -215.873579) (xy 302.231804 -215.836733) (xy 302.196162 -215.794285) (xy 302.167035 -215.747128)
			(xy 302.145036 -215.696254) (xy 302.130626 -215.642732) (xy 302.126904 -215.615266) (xy 302.12538 -215.602312)
			(xy 302.12411 -215.570562) (xy 302.124578 -215.543163) (xy 302.132406 -215.488928) (xy 302.147909 -215.436369)
			(xy 302.170769 -215.386567) (xy 302.200515 -215.340547) (xy 302.236537 -215.299253) (xy 302.278094 -215.263535)
			(xy 302.324332 -215.234127) (xy 302.3743 -215.211634) (xy 302.426971 -215.196517) (xy 302.454056 -215.192356)
			(xy 302.46955 -215.190324) (xy 302.480472 -215.1888) (xy 302.488092 -215.184736) (xy 302.496728 -215.180164)
			(xy 302.500792 -215.175338) (xy 301.822866 -205.51648) (xy 298.837858 -162.99561) (xy 298.837604 -162.992054)
			(xy 298.725336 -162.19551) (xy 298.35475 -159.566356) (xy 298.351702 -159.554672) (xy 298.34967 -159.549338)
			(xy 298.346114 -159.544258) (xy 298.319543 -159.505396) (xy 298.273016 -159.423549) (xy 298.234411 -159.33768)
			(xy 298.204073 -159.248554) (xy 298.182271 -159.156965) (xy 298.175172 -159.110426) (xy 298.106084 -158.619698)
			(xy 298.10154 -158.585144) (xy 298.096707 -158.515611) (xy 298.096432 -158.48076) (xy 298.096608 -158.45244)
			(xy 298.099783 -158.395891) (xy 298.102782 -158.36773) (xy 298.103544 -158.36138) (xy 298.094146 -158.29534)
			(xy 298.09048 -158.268292) (xy 298.085777 -158.213904) (xy 298.084748 -158.186628) (xy 298.084483 -158.181716)
			(xy 298.082307 -158.172125) (xy 298.08043 -158.167578) (xy 298.062348 -158.125387) (xy 298.03309 -158.038375)
			(xy 298.011941 -157.949046) (xy 298.004992 -157.903672) (xy 297.93565 -157.412944) (xy 297.931033 -157.378267)
			(xy 297.926076 -157.308479) (xy 297.925744 -157.273498) (xy 297.925986 -157.244473) (xy 297.929417 -157.186525)
			(xy 297.932602 -157.157674) (xy 297.933364 -157.15107) (xy 297.923204 -157.079188) (xy 297.921426 -157.06725)
			(xy 297.91533 -157.05836) (xy 297.911989 -157.053554) (xy 297.903517 -157.045482) (xy 297.898566 -157.042358)
			(xy 297.825668 -157.00121) (xy 297.812206 -156.997146) (xy 297.792902 -157.005274) (xy 297.778678 -157.011116)
			(xy 297.777662 -157.011624) (xy 297.7769 -157.011878) (xy 297.775884 -157.012386) (xy 297.730287 -157.030129)
			(xy 297.636393 -157.057667) (xy 297.540255 -157.075881) (xy 297.442796 -157.084596) (xy 297.393868 -157.084776)
			(xy 297.391836 -157.084776) (xy 297.347613 -157.083787) (xy 297.259593 -157.074938) (xy 297.172701 -157.058336)
			(xy 297.087619 -157.03411) (xy 297.046142 -157.018736) (xy 297.000027 -157.000411) (xy 296.911342 -156.95588)
			(xy 296.869104 -156.929836) (xy 296.867326 -156.93009) (xy 296.863008 -156.930344) (xy 296.84683 -156.933156)
			(xy 296.814146 -156.936339) (xy 296.79773 -156.936694) (xy 296.793412 -156.936694) (xy 296.766159 -156.936231)
			(xy 296.712207 -156.928476) (xy 296.659909 -156.913121) (xy 296.610328 -156.890479) (xy 296.564475 -156.861011)
			(xy 296.523282 -156.825317) (xy 296.487588 -156.784124) (xy 296.45812 -156.73827) (xy 296.435479 -156.688689)
			(xy 296.420124 -156.636391) (xy 296.412368 -156.582439) (xy 296.411904 -156.555186) (xy 296.411904 -156.554424)
			(xy 296.412395 -156.527127) (xy 296.420166 -156.473088) (xy 296.435541 -156.420702) (xy 296.446448 -156.395674)
			(xy 296.448734 -156.390594) (xy 296.450512 -156.382974) (xy 296.436333 -156.335162) (xy 296.416469 -156.237428)
			(xy 296.40645 -156.1382) (xy 296.405808 -156.088334) (xy 296.405808 -156.087318) (xy 296.406242 -156.044731)
			(xy 296.41348 -155.959866) (xy 296.427932 -155.875928) (xy 296.449491 -155.793529) (xy 296.478001 -155.713268)
			(xy 296.495216 -155.674314) (xy 296.498403 -155.665181) (xy 296.498409 -155.645852) (xy 296.495216 -155.636722)
			(xy 296.478007 -155.597766) (xy 296.449512 -155.517502) (xy 296.42796 -155.435102) (xy 296.413506 -155.351166)
			(xy 296.406256 -155.266304) (xy 296.405808 -155.223718) (xy 296.406181 -155.18327) (xy 296.412676 -155.102636)
			(xy 296.425691 -155.022794) (xy 296.435018 -154.983434) (xy 296.450512 -154.927554) (xy 296.450258 -154.926284)
			(xy 296.448988 -154.920442) (xy 296.437272 -154.894648) (xy 296.420739 -154.840464) (xy 296.412403 -154.78443)
			(xy 296.411904 -154.756104) (xy 296.411904 -154.755088) (xy 296.412391 -154.727838) (xy 296.420149 -154.673892)
			(xy 296.435505 -154.621599) (xy 296.458147 -154.572024) (xy 296.487614 -154.526177) (xy 296.523306 -154.484989)
			(xy 296.564496 -154.4493) (xy 296.610346 -154.419836) (xy 296.659922 -154.397197) (xy 296.712215 -154.381844)
			(xy 296.766162 -154.374089) (xy 296.793412 -154.37358) (xy 296.794174 -154.37358) (xy 296.794682 -154.37358)
			(xy 296.811926 -154.373807) (xy 296.846269 -154.376987) (xy 296.863262 -154.37993) (xy 296.869612 -154.380946)
			(xy 296.90954 -154.356318) (xy 296.993178 -154.313815) (xy 297.080435 -154.279346) (xy 297.170541 -154.253215)
			(xy 297.262702 -154.235653) (xy 297.356103 -154.226815) (xy 297.403012 -154.22626) (xy 297.4086 -154.22626)
			(xy 297.454993 -154.22706) (xy 297.547333 -154.236217) (xy 297.638424 -154.253911) (xy 297.727477 -154.27999)
			(xy 297.813723 -154.314228) (xy 297.896415 -154.356329) (xy 297.935904 -154.380692) (xy 297.941238 -154.380184)
			(xy 297.978576 -154.375104) (xy 297.979084 -154.375104) (xy 297.992038 -154.374088) (xy 297.996356 -154.373834)
			(xy 297.999658 -154.373834) (xy 298.00423 -154.37358) (xy 298.014136 -154.37358) (xy 298.043973 -154.374178)
			(xy 298.102916 -154.383494) (xy 298.131484 -154.392122) (xy 298.13377 -154.392884) (xy 298.142152 -154.394916)
			(xy 298.152486 -154.396361) (xy 298.172825 -154.391789) (xy 298.181522 -154.386026) (xy 298.24807 -154.33802)
			(xy 298.250356 -154.335734) (xy 298.258484 -154.329384) (xy 298.260516 -154.325574) (xy 298.260008 -154.306524)
			(xy 298.260008 -154.28722) (xy 298.260442 -154.244633) (xy 298.26768 -154.159768) (xy 298.282132 -154.07583)
			(xy 298.303691 -153.99343) (xy 298.3322 -153.91317) (xy 298.349416 -153.874216) (xy 298.352603 -153.865083)
			(xy 298.352611 -153.845754) (xy 298.349416 -153.836624) (xy 298.332207 -153.797668) (xy 298.303712 -153.717404)
			(xy 298.282159 -153.635005) (xy 298.267706 -153.551068) (xy 298.260456 -153.466206) (xy 298.260008 -153.42362)
			(xy 298.260008 -153.405586) (xy 298.260008 -153.404062) (xy 298.260516 -153.38552) (xy 298.258029 -153.381911)
			(xy 298.252028 -153.375523) (xy 298.248578 -153.37282) (xy 298.219114 -153.351484) (xy 298.218606 -153.351484)
			(xy 298.18711 -153.32837) (xy 298.183554 -153.32583) (xy 298.177204 -153.32202) (xy 298.169867 -153.318018)
			(xy 298.153534 -153.314527) (xy 298.1452 -153.315162) (xy 298.13758 -153.315924) (xy 298.132754 -153.317448)
			(xy 298.131992 -153.317702) (xy 298.103144 -153.326582) (xy 298.043552 -153.336152) (xy 298.013374 -153.336752)
			(xy 298.005246 -153.336752) (xy 297.990049 -153.336351) (xy 297.959787 -153.333426) (xy 297.944794 -153.33091)
			(xy 297.937428 -153.329386) (xy 297.897442 -153.354106) (xy 297.813667 -153.39677) (xy 297.726249 -153.431365)
			(xy 297.635965 -153.457583) (xy 297.543616 -153.475193) (xy 297.450019 -153.484037) (xy 297.403012 -153.48458)
			(xy 297.356058 -153.484068) (xy 297.26256 -153.475293) (xy 297.170303 -153.457763) (xy 297.080103 -153.431634)
			(xy 296.992761 -153.397137) (xy 296.90905 -153.354577) (xy 296.869104 -153.329894) (xy 296.867072 -153.329894)
			(xy 296.86377 -153.330148) (xy 296.847472 -153.333049) (xy 296.814533 -153.336357) (xy 296.797984 -153.336752)
			(xy 296.793412 -153.336752) (xy 296.766401 -153.336284) (xy 296.71292 -153.328666) (xy 296.661047 -153.313581)
			(xy 296.611821 -153.29133) (xy 296.566225 -153.262358) (xy 296.525172 -153.227244) (xy 296.489482 -153.186691)
			(xy 296.459869 -153.14151) (xy 296.436925 -153.092603) (xy 296.421108 -153.040948) (xy 296.412735 -152.98758)
			(xy 296.411904 -152.960578) (xy 296.411904 -152.95499) (xy 296.412398 -152.926759) (xy 296.420685 -152.87091)
			(xy 296.437107 -152.81689) (xy 296.448734 -152.79116) (xy 296.450512 -152.78354) (xy 296.442379 -152.75665)
			(xy 296.428785 -152.702134) (xy 296.423334 -152.674574) (xy 296.415078 -152.628217) (xy 296.406299 -152.53446)
			(xy 296.405808 -152.487376) (xy 296.406244 -152.44479) (xy 296.413486 -152.359926) (xy 296.42794 -152.275989)
			(xy 296.449503 -152.193591) (xy 296.478015 -152.113333) (xy 296.495216 -152.074372) (xy 296.498395 -152.065239)
			(xy 296.498386 -152.045917) (xy 296.495216 -152.03678) (xy 296.478009 -151.997823) (xy 296.449517 -151.917559)
			(xy 296.427968 -151.83516) (xy 296.413518 -151.751223) (xy 296.406272 -151.666361) (xy 296.405808 -151.623776)
			(xy 296.406179 -151.583328) (xy 296.412669 -151.502692) (xy 296.425679 -151.422849) (xy 296.435018 -151.383492)
			(xy 296.450512 -151.327612) (xy 296.450258 -151.326342) (xy 296.448988 -151.3205) (xy 296.438102 -151.296569)
			(xy 296.422255 -151.24644) (xy 296.413413 -151.194615) (xy 296.412158 -151.168354) (xy 296.412158 -151.167846)
			(xy 296.411904 -151.15921) (xy 296.411904 -151.155146) (xy 296.412364 -151.128308) (xy 296.419892 -151.075161)
			(xy 296.434791 -151.023593) (xy 296.456768 -150.974622) (xy 296.485389 -150.929212) (xy 296.520091 -150.88826)
			(xy 296.560187 -150.852574) (xy 296.604887 -150.822857) (xy 296.65331 -150.799696) (xy 296.7045 -150.783548)
			(xy 296.757448 -150.77473) (xy 296.784268 -150.773638) (xy 296.79392 -150.773384) (xy 296.794174 -150.773384)
			(xy 296.810767 -150.773511) (xy 296.843836 -150.776306) (xy 296.860214 -150.778972) (xy 296.87012 -150.78075)
			(xy 296.910018 -150.756176) (xy 296.99359 -150.713776) (xy 297.08077 -150.679403) (xy 297.17079 -150.653359)
			(xy 297.262856 -150.635875) (xy 297.356156 -150.627104) (xy 297.403012 -150.626572) (xy 297.449743 -150.627106)
			(xy 297.542798 -150.635829) (xy 297.634627 -150.653226) (xy 297.724424 -150.679145) (xy 297.8114 -150.713356)
			(xy 297.894791 -150.755561) (xy 297.934634 -150.779988) (xy 297.94327 -150.779988) (xy 297.960451 -150.777013)
			(xy 297.995177 -150.773835) (xy 298.012612 -150.773638) (xy 298.020994 -150.773638) (xy 298.048984 -150.774766)
			(xy 298.104199 -150.784205) (xy 298.130976 -150.792434) (xy 298.13504 -150.793704) (xy 298.149518 -150.79599)
			(xy 298.16118 -150.796945) (xy 298.183302 -150.789407) (xy 298.191936 -150.781512) (xy 298.199556 -150.773892)
			(xy 298.205398 -150.768812) (xy 298.248832 -150.737316) (xy 298.252183 -150.734638) (xy 298.258047 -150.728378)
			(xy 298.260516 -150.72487) (xy 298.260008 -150.706328) (xy 298.260008 -150.687278) (xy 298.260444 -150.644692)
			(xy 298.267685 -150.559828) (xy 298.28214 -150.475891) (xy 298.303702 -150.393493) (xy 298.332214 -150.313234)
			(xy 298.349416 -150.274274) (xy 298.352595 -150.265141) (xy 298.352587 -150.245818) (xy 298.349416 -150.236682)
			(xy 298.332209 -150.197725) (xy 298.303717 -150.117461) (xy 298.282168 -150.035062) (xy 298.267718 -149.951126)
			(xy 298.260471 -149.866263) (xy 298.260008 -149.823678) (xy 298.260008 -149.805644) (xy 298.260008 -149.80412)
			(xy 298.260516 -149.785578) (xy 298.258027 -149.781971) (xy 298.252023 -149.775587) (xy 298.248578 -149.772878)
			(xy 298.219114 -149.751542) (xy 298.218606 -149.751542) (xy 298.18711 -149.728428) (xy 298.183554 -149.725888)
			(xy 298.177204 -149.722078) (xy 298.169868 -149.718072) (xy 298.153534 -149.714577) (xy 298.1452 -149.71522)
			(xy 298.13758 -149.715982) (xy 298.132754 -149.717506) (xy 298.131992 -149.71776) (xy 298.103144 -149.726638)
			(xy 298.043551 -149.736207) (xy 298.013374 -149.73681) (xy 298.012104 -149.73681) (xy 297.995766 -149.736636)
			(xy 297.963209 -149.733836) (xy 297.94708 -149.731222) (xy 297.937428 -149.729444) (xy 297.897448 -149.754184)
			(xy 297.81368 -149.796888) (xy 297.726266 -149.831523) (xy 297.635982 -149.857781) (xy 297.543629 -149.87543)
			(xy 297.450024 -149.884313) (xy 297.403012 -149.884892) (xy 297.351415 -149.884229) (xy 297.248776 -149.87354)
			(xy 297.147792 -149.852294) (xy 297.098466 -149.83714) (xy 297.058304 -149.823805) (xy 296.980181 -149.791257)
			(xy 296.905094 -149.752213) (xy 296.869104 -149.729952) (xy 296.867326 -149.730206) (xy 296.863008 -149.73046)
			(xy 296.84683 -149.733272) (xy 296.814146 -149.736456) (xy 296.79773 -149.73681) (xy 296.793412 -149.73681)
			(xy 296.766159 -149.736347) (xy 296.712206 -149.728592) (xy 296.659907 -149.713237) (xy 296.610325 -149.690595)
			(xy 296.56447 -149.661128) (xy 296.523276 -149.625434) (xy 296.487581 -149.584241) (xy 296.458112 -149.538387)
			(xy 296.435468 -149.488806) (xy 296.420111 -149.436507) (xy 296.412354 -149.382555) (xy 296.411904 -149.355302)
			(xy 296.411904 -149.35454) (xy 296.412401 -149.327244) (xy 296.420183 -149.273209) (xy 296.435568 -149.220829)
			(xy 296.446448 -149.19579) (xy 296.448734 -149.19071) (xy 296.450512 -149.18309) (xy 296.436332 -149.135278)
			(xy 296.416466 -149.037544) (xy 296.406446 -148.938316) (xy 296.405808 -148.88845) (xy 296.405808 -148.887434)
			(xy 296.406241 -148.844847) (xy 296.413478 -148.759982) (xy 296.427929 -148.676043) (xy 296.449487 -148.593643)
			(xy 296.477995 -148.513382) (xy 296.495216 -148.47443) (xy 296.498406 -148.465297) (xy 296.498418 -148.445966)
			(xy 296.495216 -148.436838) (xy 296.478006 -148.397882) (xy 296.44951 -148.317618) (xy 296.427957 -148.235219)
			(xy 296.413502 -148.151283) (xy 296.406251 -148.06642) (xy 296.405808 -148.023834) (xy 296.40618 -147.983386)
			(xy 296.412674 -147.902751) (xy 296.425688 -147.822909) (xy 296.435018 -147.78355) (xy 296.450512 -147.72767)
			(xy 296.450258 -147.7264) (xy 296.448988 -147.720558) (xy 296.437271 -147.694764) (xy 296.420735 -147.64058)
			(xy 296.412397 -147.584546) (xy 296.411904 -147.55622) (xy 296.411904 -147.555204) (xy 296.412367 -147.527951)
			(xy 296.420124 -147.474001) (xy 296.435479 -147.421703) (xy 296.458122 -147.372123) (xy 296.48759 -147.32627)
			(xy 296.523284 -147.285078) (xy 296.564477 -147.249385) (xy 296.61033 -147.219918) (xy 296.65991 -147.197277)
			(xy 296.712208 -147.181922) (xy 296.766159 -147.174167) (xy 296.793412 -147.173696) (xy 296.794174 -147.173696)
			(xy 296.794682 -147.173696) (xy 296.811926 -147.173923) (xy 296.846269 -147.177103) (xy 296.863262 -147.180046)
			(xy 296.869612 -147.181062) (xy 296.90954 -147.156433) (xy 296.993178 -147.113929) (xy 297.080435 -147.07946)
			(xy 297.170541 -147.053329) (xy 297.262701 -147.035767) (xy 297.356103 -147.026928) (xy 297.403012 -147.026376)
			(xy 297.4086 -147.026376) (xy 297.454993 -147.027176) (xy 297.547333 -147.036333) (xy 297.638423 -147.054027)
			(xy 297.727476 -147.080107) (xy 297.813722 -147.114345) (xy 297.896414 -147.156447) (xy 297.935904 -147.180808)
			(xy 297.941238 -147.1803) (xy 297.978576 -147.17522) (xy 297.979084 -147.17522) (xy 297.992038 -147.174204)
			(xy 297.996356 -147.17395) (xy 297.999658 -147.17395) (xy 298.00423 -147.173696) (xy 298.014136 -147.173696)
			(xy 298.043973 -147.174294) (xy 298.102916 -147.183608) (xy 298.131484 -147.192238) (xy 298.13377 -147.193)
			(xy 298.142152 -147.195032) (xy 298.152487 -147.196477) (xy 298.172826 -147.191906) (xy 298.181522 -147.186142)
			(xy 298.24807 -147.138136) (xy 298.250356 -147.13585) (xy 298.258484 -147.1295) (xy 298.260516 -147.12569)
			(xy 298.260008 -147.10664) (xy 298.260008 -147.087336) (xy 298.260441 -147.044749) (xy 298.267678 -146.959884)
			(xy 298.282128 -146.875945) (xy 298.303686 -146.793545) (xy 298.332194 -146.713284) (xy 298.349416 -146.674332)
			(xy 298.352606 -146.665199) (xy 298.352619 -146.645868) (xy 298.349416 -146.63674) (xy 298.332225 -146.597831)
			(xy 298.303755 -146.517666) (xy 298.28221 -146.435369) (xy 298.267746 -146.351537) (xy 298.260469 -146.266779)
			(xy 298.260008 -146.224244) (xy 298.260008 -146.18462) (xy 298.25788 -146.181592) (xy 298.25291 -146.176108)
			(xy 298.250102 -146.173698) (xy 298.219114 -146.151346) (xy 298.218606 -146.151346) (xy 298.18711 -146.128232)
			(xy 298.183554 -146.125692) (xy 298.177204 -146.121882) (xy 298.169868 -146.117876) (xy 298.153534 -146.11438)
			(xy 298.1452 -146.115024) (xy 298.13758 -146.115786) (xy 298.132754 -146.11731) (xy 298.131992 -146.117564)
			(xy 298.103144 -146.126442) (xy 298.043551 -146.136011) (xy 298.013374 -146.136614) (xy 298.012104 -146.136614)
			(xy 297.995766 -146.13644) (xy 297.963209 -146.13364) (xy 297.94708 -146.131026) (xy 297.937428 -146.129248)
			(xy 297.897448 -146.153988) (xy 297.81368 -146.196692) (xy 297.726266 -146.231326) (xy 297.635982 -146.257584)
			(xy 297.543629 -146.275233) (xy 297.450024 -146.284117) (xy 297.403012 -146.284696) (xy 297.351415 -146.284033)
			(xy 297.248776 -146.273344) (xy 297.147792 -146.252099) (xy 297.098466 -146.236944) (xy 297.058304 -146.22361)
			(xy 296.980181 -146.191061) (xy 296.905094 -146.152017) (xy 296.869104 -146.129756) (xy 296.867326 -146.13001)
			(xy 296.863008 -146.130264) (xy 296.84683 -146.133076) (xy 296.814146 -146.13626) (xy 296.79773 -146.136614)
			(xy 296.793412 -146.136614) (xy 296.766158 -146.136151) (xy 296.712206 -146.128396) (xy 296.659906 -146.113041)
			(xy 296.610324 -146.090399) (xy 296.564469 -146.060932) (xy 296.523275 -146.025238) (xy 296.487579 -145.984045)
			(xy 296.458109 -145.938192) (xy 296.435465 -145.888611) (xy 296.420108 -145.836312) (xy 296.41235 -145.78236)
			(xy 296.411904 -145.755106) (xy 296.411904 -145.754344) (xy 296.4124 -145.727048) (xy 296.420182 -145.673013)
			(xy 296.435566 -145.620633) (xy 296.446448 -145.595594) (xy 296.448734 -145.590514) (xy 296.450512 -145.582894)
			(xy 296.436332 -145.535082) (xy 296.416466 -145.437348) (xy 296.406445 -145.33812) (xy 296.405808 -145.288254)
			(xy 296.405808 -145.287238) (xy 296.406241 -145.244651) (xy 296.413478 -145.159786) (xy 296.427928 -145.075847)
			(xy 296.449486 -144.993446) (xy 296.477994 -144.913186) (xy 296.495216 -144.874234) (xy 296.498407 -144.865101)
			(xy 296.49842 -144.845769) (xy 296.495216 -144.836642) (xy 296.478006 -144.797686) (xy 296.44951 -144.717422)
			(xy 296.427956 -144.635023) (xy 296.4135 -144.551087) (xy 296.406249 -144.466224) (xy 296.405808 -144.423638)
			(xy 296.40618 -144.38319) (xy 296.412674 -144.302555) (xy 296.425687 -144.222713) (xy 296.435018 -144.183354)
			(xy 296.450512 -144.127474) (xy 296.450258 -144.126204) (xy 296.448988 -144.120362) (xy 296.437271 -144.094568)
			(xy 296.420735 -144.040384) (xy 296.412395 -143.98435) (xy 296.411904 -143.956024) (xy 296.411904 -143.955008)
			(xy 296.412367 -143.927755) (xy 296.420123 -143.873804) (xy 296.435478 -143.821506) (xy 296.458121 -143.771925)
			(xy 296.487589 -143.726072) (xy 296.523282 -143.68488) (xy 296.564475 -143.649186) (xy 296.610329 -143.619719)
			(xy 296.65991 -143.597077) (xy 296.712208 -143.581722) (xy 296.766159 -143.573967) (xy 296.793412 -143.5735)
			(xy 296.794174 -143.5735) (xy 296.794682 -143.5735) (xy 296.811926 -143.573727) (xy 296.846269 -143.576907)
			(xy 296.863262 -143.57985) (xy 296.869612 -143.580866) (xy 296.909539 -143.556237) (xy 296.993178 -143.513733)
			(xy 297.080435 -143.479264) (xy 297.170541 -143.453132) (xy 297.262701 -143.43557) (xy 297.356103 -143.426732)
			(xy 297.403012 -143.42618) (xy 297.4086 -143.42618) (xy 297.454993 -143.42698) (xy 297.547333 -143.436137)
			(xy 297.638423 -143.453832) (xy 297.727476 -143.479911) (xy 297.813722 -143.514149) (xy 297.896414 -143.556251)
			(xy 297.935904 -143.580612) (xy 297.941238 -143.580104) (xy 297.978576 -143.575024) (xy 297.979084 -143.575024)
			(xy 297.992038 -143.574008) (xy 297.996356 -143.573754) (xy 297.999658 -143.573754) (xy 298.00423 -143.5735)
			(xy 298.014136 -143.5735) (xy 298.043973 -143.574098) (xy 298.102916 -143.583412) (xy 298.131484 -143.592042)
			(xy 298.13377 -143.592804) (xy 298.142152 -143.594836) (xy 298.152487 -143.596282) (xy 298.172826 -143.591711)
			(xy 298.181522 -143.585946) (xy 298.24807 -143.53794) (xy 298.250356 -143.535654) (xy 298.258484 -143.529304)
			(xy 298.260516 -143.525494) (xy 298.260008 -143.506444) (xy 298.260008 -143.48714) (xy 298.260441 -143.444553)
			(xy 298.267678 -143.359687) (xy 298.282127 -143.275749) (xy 298.303685 -143.193348) (xy 298.332193 -143.113087)
			(xy 298.349416 -143.074136) (xy 298.352607 -143.065003) (xy 298.352621 -143.045671) (xy 298.349416 -143.036544)
			(xy 298.332206 -142.997588) (xy 298.30371 -142.917324) (xy 298.282155 -142.834925) (xy 298.2677 -142.750989)
			(xy 298.260448 -142.666126) (xy 298.260008 -142.62354) (xy 298.26038 -142.583092) (xy 298.266874 -142.502457)
			(xy 298.279886 -142.422615) (xy 298.289218 -142.383256) (xy 298.304712 -142.327376) (xy 298.304458 -142.326106)
			(xy 298.303188 -142.320264) (xy 298.29147 -142.29447) (xy 298.274934 -142.240286) (xy 298.266595 -142.184252)
			(xy 298.266104 -142.155926) (xy 298.266104 -142.15491) (xy 298.266567 -142.127657) (xy 298.274323 -142.073706)
			(xy 298.289678 -142.021407) (xy 298.31232 -141.971827) (xy 298.341788 -141.925973) (xy 298.377482 -141.88478)
			(xy 298.418675 -141.849087) (xy 298.464528 -141.819619) (xy 298.514109 -141.796977) (xy 298.566408 -141.781622)
			(xy 298.620359 -141.773867) (xy 298.647612 -141.773402) (xy 298.648882 -141.773402) (xy 298.666126 -141.773629)
			(xy 298.700469 -141.776809) (xy 298.717462 -141.779752) (xy 298.724574 -141.78026) (xy 298.765361 -141.755182)
			(xy 298.850854 -141.712056) (xy 298.895262 -141.694154) (xy 298.91863 -141.68501) (xy 298.922537 -141.679012)
			(xy 298.92717 -141.665474) (xy 298.927774 -141.65834) (xy 298.877228 -139.447524) (xy 298.822364 -137.047478)
			(xy 298.82211 -137.044684) (xy 298.820904 -137.035082) (xy 298.812339 -137.017744) (xy 298.798002 -137.004768)
			(xy 298.78909 -137.000996) (xy 298.785648 -136.999775) (xy 298.778506 -136.998244) (xy 298.774866 -136.997948)
			(xy 298.552616 -136.997948) (xy 298.497129 -136.996413) (xy 298.387011 -136.982409) (xy 298.332906 -136.970008)
			(xy 298.317551 -136.966247) (xy 298.287065 -136.957864) (xy 298.271946 -136.953244) (xy 298.260793 -136.950485)
			(xy 298.238109 -136.953931) (xy 298.228258 -136.959848) (xy 298.204829 -136.975296) (xy 298.154387 -136.999893)
			(xy 298.10089 -137.016845) (xy 298.045488 -137.025787) (xy 298.017438 -137.02665) (xy 298.012612 -137.02665)
			(xy 298.01185 -137.02665) (xy 298.007024 -137.02665) (xy 297.981624 -137.02538) (xy 297.980608 -137.02538)
			(xy 297.97883 -137.025126) (xy 297.978322 -137.025126) (xy 297.948604 -137.021316) (xy 297.94835 -137.021316)
			(xy 297.941238 -137.020046) (xy 297.93692 -137.019792) (xy 297.90072 -137.042208) (xy 297.825178 -137.081503)
			(xy 297.786044 -137.098278) (xy 297.745712 -137.114546) (xy 297.662806 -137.140834) (xy 297.577926 -137.159801)
			(xy 297.491716 -137.171304) (xy 297.404832 -137.175255) (xy 297.317935 -137.171623) (xy 297.231683 -137.160437)
			(xy 297.146734 -137.141782) (xy 297.063732 -137.115798) (xy 296.983309 -137.082684) (xy 296.906076 -137.042692)
			(xy 296.869104 -137.019792) (xy 296.862246 -137.020554) (xy 296.860214 -137.020808) (xy 296.843651 -137.023556)
			(xy 296.810201 -137.02648) (xy 296.793412 -137.02665) (xy 296.791126 -137.02665) (xy 296.763982 -137.026009)
			(xy 296.710284 -137.017991) (xy 296.658265 -137.002439) (xy 296.608977 -136.979668) (xy 296.563415 -136.950139)
			(xy 296.522501 -136.914448) (xy 296.48706 -136.873316) (xy 296.45781 -136.827575) (xy 296.435342 -136.778149)
			(xy 296.420108 -136.726036) (xy 296.412418 -136.672289) (xy 296.411904 -136.645142) (xy 296.411904 -136.64438)
			(xy 296.412398 -136.617083) (xy 296.420175 -136.563046) (xy 296.435555 -136.510664) (xy 296.446448 -136.48563)
			(xy 296.448734 -136.48055) (xy 296.450512 -136.47293) (xy 296.43633 -136.425119) (xy 296.416461 -136.327385)
			(xy 296.406436 -136.228156) (xy 296.405808 -136.17829) (xy 296.405808 -136.177274) (xy 296.406244 -136.134688)
			(xy 296.413486 -136.049824) (xy 296.427941 -135.965887) (xy 296.449503 -135.883489) (xy 296.478016 -135.803231)
			(xy 296.495216 -135.76427) (xy 296.498394 -135.755137) (xy 296.498385 -135.735815) (xy 296.495216 -135.726678)
			(xy 296.478009 -135.687721) (xy 296.449518 -135.607457) (xy 296.427969 -135.525058) (xy 296.413519 -135.441121)
			(xy 296.406273 -135.356259) (xy 296.405808 -135.313674) (xy 296.406179 -135.273226) (xy 296.41267 -135.19259)
			(xy 296.42568 -135.112747) (xy 296.435018 -135.07339) (xy 296.450512 -135.01751) (xy 296.450258 -135.01624)
			(xy 296.448988 -135.010398) (xy 296.437268 -134.984605) (xy 296.420727 -134.930421) (xy 296.412382 -134.874387)
			(xy 296.411904 -134.84606) (xy 296.411904 -134.845044) (xy 296.412364 -134.817789) (xy 296.420116 -134.763834)
			(xy 296.435469 -134.711532) (xy 296.458109 -134.661947) (xy 296.487576 -134.616089) (xy 296.52327 -134.574892)
			(xy 296.564464 -134.539195) (xy 296.610319 -134.509724) (xy 296.659902 -134.48708) (xy 296.712203 -134.471723)
			(xy 296.766157 -134.463967) (xy 296.793412 -134.463536) (xy 296.794174 -134.463536) (xy 296.794682 -134.463536)
			(xy 296.811926 -134.463763) (xy 296.846269 -134.466942) (xy 296.863262 -134.469886) (xy 296.869612 -134.470902)
			(xy 296.909539 -134.446272) (xy 296.993177 -134.403767) (xy 297.080434 -134.369296) (xy 297.17054 -134.343164)
			(xy 297.262701 -134.325601) (xy 297.356103 -134.316762) (xy 297.403012 -134.316216) (xy 297.4086 -134.316216)
			(xy 297.454993 -134.317016) (xy 297.547333 -134.326173) (xy 297.638424 -134.343866) (xy 297.727478 -134.369944)
			(xy 297.813725 -134.40418) (xy 297.896418 -134.44628) (xy 297.935904 -134.470648) (xy 297.941238 -134.47014)
			(xy 297.978576 -134.46506) (xy 297.979084 -134.46506) (xy 297.992038 -134.464044) (xy 297.996356 -134.46379)
			(xy 297.999658 -134.46379) (xy 298.00423 -134.463536) (xy 298.014136 -134.463536) (xy 298.043973 -134.464134)
			(xy 298.102916 -134.473449) (xy 298.131484 -134.482078) (xy 298.13377 -134.48284) (xy 298.142152 -134.484872)
			(xy 298.152486 -134.486318) (xy 298.172823 -134.481742) (xy 298.181522 -134.475982) (xy 298.24807 -134.427976)
			(xy 298.250356 -134.42569) (xy 298.258484 -134.41934) (xy 298.260516 -134.41553) (xy 298.260008 -134.39648)
			(xy 298.260008 -134.377176) (xy 298.260444 -134.33459) (xy 298.267686 -134.249726) (xy 298.28214 -134.165789)
			(xy 298.303703 -134.083391) (xy 298.332215 -134.003133) (xy 298.349416 -133.964172) (xy 298.352595 -133.955039)
			(xy 298.352586 -133.935717) (xy 298.349416 -133.92658) (xy 298.332209 -133.887623) (xy 298.303717 -133.807359)
			(xy 298.282168 -133.72496) (xy 298.267718 -133.641023) (xy 298.260472 -133.556161) (xy 298.260008 -133.513576)
			(xy 298.260008 -133.495542) (xy 298.260008 -133.494018) (xy 298.260516 -133.475476) (xy 298.258027 -133.471869)
			(xy 298.252023 -133.465486) (xy 298.248578 -133.462776) (xy 298.219114 -133.44144) (xy 298.218606 -133.44144)
			(xy 298.18711 -133.418326) (xy 298.183554 -133.415786) (xy 298.177204 -133.411976) (xy 298.169868 -133.40797)
			(xy 298.153534 -133.404475) (xy 298.1452 -133.405118) (xy 298.13758 -133.40588) (xy 298.132754 -133.407404)
			(xy 298.131992 -133.407658) (xy 298.103144 -133.416536) (xy 298.043551 -133.426105) (xy 298.013374 -133.426708)
			(xy 298.005246 -133.426708) (xy 297.990049 -133.426307) (xy 297.959787 -133.423382) (xy 297.944794 -133.420866)
			(xy 297.937428 -133.419342) (xy 297.897442 -133.444061) (xy 297.813666 -133.486723) (xy 297.726248 -133.521315)
			(xy 297.635964 -133.547532) (xy 297.543615 -133.565141) (xy 297.450019 -133.573985) (xy 297.403012 -133.574536)
			(xy 297.356057 -133.574024) (xy 297.26256 -133.565249) (xy 297.170302 -133.54772) (xy 297.080101 -133.521592)
			(xy 296.992758 -133.487097) (xy 296.909046 -133.44454) (xy 296.869104 -133.41985) (xy 296.867072 -133.41985)
			(xy 296.86377 -133.420104) (xy 296.847473 -133.423005) (xy 296.814533 -133.426313) (xy 296.797984 -133.426708)
			(xy 296.793412 -133.426708) (xy 296.7664 -133.42624) (xy 296.712915 -133.418623) (xy 296.66104 -133.403538)
			(xy 296.61181 -133.381288) (xy 296.566211 -133.352316) (xy 296.525153 -133.317204) (xy 296.489458 -133.276651)
			(xy 296.459839 -133.23147) (xy 296.436888 -133.182563) (xy 296.421064 -133.130908) (xy 296.412684 -133.077538)
			(xy 296.411904 -133.050534) (xy 296.411904 -133.044946) (xy 296.412394 -133.016714) (xy 296.420674 -132.960862)
			(xy 296.437089 -132.906838) (xy 296.448734 -132.881116) (xy 296.450512 -132.873496) (xy 296.442378 -132.846606)
			(xy 296.42878 -132.79209) (xy 296.423334 -132.76453) (xy 296.41508 -132.718173) (xy 296.406305 -132.624416)
			(xy 296.405808 -132.577332) (xy 296.406241 -132.534745) (xy 296.413479 -132.44988) (xy 296.427929 -132.365941)
			(xy 296.449487 -132.283541) (xy 296.477996 -132.20328) (xy 296.495216 -132.164328) (xy 296.498406 -132.155195)
			(xy 296.498417 -132.135864) (xy 296.495216 -132.126736) (xy 296.478007 -132.08778) (xy 296.449511 -132.007516)
			(xy 296.427957 -131.925117) (xy 296.413502 -131.841181) (xy 296.406251 -131.756318) (xy 296.405808 -131.713732)
			(xy 296.40618 -131.673284) (xy 296.412675 -131.592649) (xy 296.425688 -131.512807) (xy 296.435018 -131.473448)
			(xy 296.450512 -131.417568) (xy 296.450258 -131.416298) (xy 296.448988 -131.410456) (xy 296.438105 -131.386524)
			(xy 296.422263 -131.336395) (xy 296.413428 -131.28457) (xy 296.412158 -131.25831) (xy 296.412158 -131.257802)
			(xy 296.411904 -131.249166) (xy 296.411904 -131.245102) (xy 296.412367 -131.218266) (xy 296.4199 -131.165124)
			(xy 296.434803 -131.113561) (xy 296.456782 -131.064595) (xy 296.485405 -131.019191) (xy 296.520106 -130.978244)
			(xy 296.560202 -130.942563) (xy 296.6049 -130.91285) (xy 296.65332 -130.889692) (xy 296.704507 -130.873546)
			(xy 296.757451 -130.86473) (xy 296.784268 -130.863594) (xy 296.79392 -130.86334) (xy 296.794174 -130.86334)
			(xy 296.810767 -130.863467) (xy 296.843836 -130.866262) (xy 296.860214 -130.868928) (xy 296.87012 -130.870706)
			(xy 296.910019 -130.846133) (xy 296.99359 -130.803735) (xy 297.080771 -130.769363) (xy 297.17079 -130.743321)
			(xy 297.262856 -130.725837) (xy 297.356156 -130.717067) (xy 297.403012 -130.716528) (xy 297.449744 -130.717062)
			(xy 297.542798 -130.725785) (xy 297.634628 -130.743181) (xy 297.724425 -130.769099) (xy 297.811402 -130.803309)
			(xy 297.894794 -130.845512) (xy 297.934634 -130.869944) (xy 297.94327 -130.869944) (xy 297.960451 -130.866969)
			(xy 297.995177 -130.86379) (xy 298.012612 -130.863594) (xy 298.020994 -130.863594) (xy 298.048984 -130.864723)
			(xy 298.104199 -130.874162) (xy 298.130976 -130.88239) (xy 298.13504 -130.88366) (xy 298.149518 -130.885946)
			(xy 298.161181 -130.886902) (xy 298.183308 -130.87937) (xy 298.191936 -130.871468) (xy 298.199556 -130.863848)
			(xy 298.205398 -130.858768) (xy 298.248832 -130.827272) (xy 298.252185 -130.824596) (xy 298.258055 -130.81834)
			(xy 298.260516 -130.814826) (xy 298.260008 -130.796284) (xy 298.260008 -130.777234) (xy 298.260441 -130.734647)
			(xy 298.267678 -130.649782) (xy 298.282129 -130.565843) (xy 298.303687 -130.483443) (xy 298.332195 -130.403182)
			(xy 298.349416 -130.36423) (xy 298.352606 -130.355097) (xy 298.352618 -130.335766) (xy 298.349416 -130.326638)
			(xy 298.332206 -130.287682) (xy 298.30371 -130.207418) (xy 298.282157 -130.125019) (xy 298.267702 -130.041083)
			(xy 298.260451 -129.95622) (xy 298.260008 -129.913634) (xy 298.260572 -129.863512) (xy 298.270529 -129.763766)
			(xy 298.290457 -129.665525) (xy 298.304712 -129.61747) (xy 298.303188 -129.610104) (xy 298.297003 -129.596822)
			(xy 298.286449 -129.569487) (xy 298.282106 -129.555494) (xy 298.278843 -129.54434) (xy 298.273503 -129.521719)
			(xy 298.271438 -129.510282) (xy 298.26883 -129.494216) (xy 298.266028 -129.461787) (xy 298.26585 -129.445512)
			(xy 298.26585 -129.445004) (xy 298.26632 -129.417975) (xy 298.273952 -129.364459) (xy 298.289062 -129.312556)
			(xy 298.311348 -129.263307) (xy 298.340365 -129.217697) (xy 298.37553 -129.176641) (xy 298.416139 -129.14096)
			(xy 298.461379 -129.11137) (xy 298.510343 -129.088463) (xy 298.56205 -129.072699) (xy 298.588684 -129.068068)
			(xy 298.595034 -129.066798) (xy 298.602146 -129.062988) (xy 298.625514 -129.050542) (xy 298.625768 -129.050288)
			(xy 298.626276 -129.050034) (xy 298.631677 -129.043468) (xy 298.638164 -129.027763) (xy 298.638976 -129.0193)
			(xy 298.592748 -126.996698) (xy 298.563284 -125.710442) (xy 298.56251 -125.699947) (xy 298.553587 -125.680916)
			(xy 298.546012 -125.673612) (xy 298.31665 -125.673612) (xy 298.30903 -125.677168) (xy 298.302426 -125.684026)
			(xy 298.30141 -125.685042) (xy 298.299632 -125.687074) (xy 298.298108 -125.688598) (xy 298.28005 -125.708265)
			(xy 298.239382 -125.742862) (xy 298.194289 -125.771453) (xy 298.145652 -125.79348) (xy 298.094419 -125.808513)
			(xy 298.041591 -125.816259) (xy 298.014898 -125.816868) (xy 298.00677 -125.816614) (xy 298.006262 -125.816614)
			(xy 297.991647 -125.816266) (xy 297.962531 -125.813597) (xy 297.948096 -125.81128) (xy 297.944286 -125.810518)
			(xy 297.937428 -125.809248) (xy 297.897466 -125.833977) (xy 297.813738 -125.876665) (xy 297.726366 -125.911292)
			(xy 297.636126 -125.93755) (xy 297.543817 -125.955206) (xy 297.450257 -125.964106) (xy 297.403266 -125.964696)
			(xy 297.403012 -125.964696) (xy 297.354891 -125.964101) (xy 297.259097 -125.954803) (xy 297.164643 -125.936332)
			(xy 297.072405 -125.908857) (xy 297.0276 -125.89129) (xy 296.986852 -125.874164) (xy 296.908252 -125.833716)
			(xy 296.870628 -125.810518) (xy 296.86123 -125.810518) (xy 296.856912 -125.81128) (xy 296.841344 -125.813741)
			(xy 296.809935 -125.816409) (xy 296.794174 -125.816614) (xy 296.793412 -125.816614) (xy 296.766158 -125.816151)
			(xy 296.712206 -125.808396) (xy 296.659906 -125.793041) (xy 296.610324 -125.770399) (xy 296.564469 -125.740932)
			(xy 296.523275 -125.705238) (xy 296.487579 -125.664045) (xy 296.458109 -125.618192) (xy 296.435465 -125.568611)
			(xy 296.420108 -125.516312) (xy 296.41235 -125.46236) (xy 296.411904 -125.435106) (xy 296.411904 -125.434344)
			(xy 296.412394 -125.406112) (xy 296.420674 -125.35026) (xy 296.437089 -125.296237) (xy 296.448734 -125.270514)
			(xy 296.450512 -125.262894) (xy 296.436373 -125.215159) (xy 296.416524 -125.117596) (xy 296.406487 -125.018542)
			(xy 296.405808 -124.968762) (xy 296.405808 -124.968254) (xy 296.405808 -124.967238) (xy 296.406241 -124.924651)
			(xy 296.413478 -124.839786) (xy 296.427928 -124.755847) (xy 296.449486 -124.673446) (xy 296.477994 -124.593186)
			(xy 296.495216 -124.554234) (xy 296.498407 -124.545101) (xy 296.49842 -124.525769) (xy 296.495216 -124.516642)
			(xy 296.478006 -124.477686) (xy 296.44951 -124.397422) (xy 296.427956 -124.315023) (xy 296.4135 -124.231087)
			(xy 296.406249 -124.146224) (xy 296.405808 -124.103638) (xy 296.40618 -124.06319) (xy 296.412674 -123.982555)
			(xy 296.425687 -123.902713) (xy 296.435018 -123.863354) (xy 296.450512 -123.807474) (xy 296.450258 -123.806204)
			(xy 296.448988 -123.800362) (xy 296.437271 -123.774568) (xy 296.420735 -123.720384) (xy 296.412395 -123.66435)
			(xy 296.411904 -123.636024) (xy 296.411904 -123.635008) (xy 296.412367 -123.607755) (xy 296.420123 -123.553804)
			(xy 296.435478 -123.501506) (xy 296.458121 -123.451925) (xy 296.487589 -123.406072) (xy 296.523282 -123.36488)
			(xy 296.564475 -123.329186) (xy 296.610329 -123.299719) (xy 296.65991 -123.277077) (xy 296.712208 -123.261722)
			(xy 296.766159 -123.253967) (xy 296.793412 -123.2535) (xy 296.798238 -123.2535) (xy 296.814592 -123.253851)
			(xy 296.84715 -123.257027) (xy 296.863262 -123.25985) (xy 296.869612 -123.260866) (xy 296.909539 -123.236237)
			(xy 296.993178 -123.193733) (xy 297.080435 -123.159264) (xy 297.170541 -123.133132) (xy 297.262701 -123.11557)
			(xy 297.356103 -123.106732) (xy 297.403012 -123.10618) (xy 297.4086 -123.10618) (xy 297.454993 -123.10698)
			(xy 297.547333 -123.116137) (xy 297.638423 -123.133832) (xy 297.727476 -123.159911) (xy 297.813722 -123.194149)
			(xy 297.896414 -123.236251) (xy 297.935904 -123.260612) (xy 297.941238 -123.260104) (xy 297.978576 -123.255024)
			(xy 297.979084 -123.255024) (xy 297.992038 -123.254008) (xy 297.996356 -123.253754) (xy 297.999658 -123.253754)
			(xy 298.00423 -123.2535) (xy 298.014136 -123.2535) (xy 298.043973 -123.254098) (xy 298.102916 -123.263412)
			(xy 298.131484 -123.272042) (xy 298.13377 -123.272804) (xy 298.142152 -123.274836) (xy 298.152487 -123.276282)
			(xy 298.172826 -123.271711) (xy 298.181522 -123.265946) (xy 298.24807 -123.21794) (xy 298.250356 -123.215654)
			(xy 298.258484 -123.209304) (xy 298.260516 -123.205494) (xy 298.260008 -123.186444) (xy 298.260008 -123.16714)
			(xy 298.260441 -123.124553) (xy 298.267678 -123.039687) (xy 298.282127 -122.955749) (xy 298.303685 -122.873348)
			(xy 298.332193 -122.793087) (xy 298.349416 -122.754136) (xy 298.352607 -122.745003) (xy 298.352621 -122.725671)
			(xy 298.349416 -122.716544) (xy 298.332206 -122.677588) (xy 298.30371 -122.597324) (xy 298.282155 -122.514925)
			(xy 298.2677 -122.430989) (xy 298.260448 -122.346126) (xy 298.260008 -122.30354) (xy 298.260008 -122.285506)
			(xy 298.260008 -122.283982) (xy 298.260516 -122.26544) (xy 298.258025 -122.261835) (xy 298.252018 -122.255455)
			(xy 298.248578 -122.25274) (xy 298.219114 -122.231404) (xy 298.218606 -122.231404) (xy 298.18711 -122.20829)
			(xy 298.183554 -122.20575) (xy 298.177204 -122.20194) (xy 298.169867 -122.197937) (xy 298.153534 -122.194444)
			(xy 298.1452 -122.195082) (xy 298.13758 -122.195844) (xy 298.132754 -122.197368) (xy 298.131992 -122.197622)
			(xy 298.103144 -122.206501) (xy 298.043552 -122.216071) (xy 298.013374 -122.216672) (xy 298.005246 -122.216672)
			(xy 297.990049 -122.216271) (xy 297.959787 -122.213346) (xy 297.944794 -122.21083) (xy 297.937428 -122.209306)
			(xy 297.897442 -122.234026) (xy 297.813666 -122.276689) (xy 297.726249 -122.311283) (xy 297.635965 -122.337501)
			(xy 297.543615 -122.35511) (xy 297.450019 -122.363954) (xy 297.403012 -122.3645) (xy 297.356058 -122.363988)
			(xy 297.26256 -122.355213) (xy 297.170302 -122.337684) (xy 297.080102 -122.311555) (xy 296.99276 -122.277058)
			(xy 296.909049 -122.2345) (xy 296.869104 -122.209814) (xy 296.867072 -122.209814) (xy 296.86377 -122.210068)
			(xy 296.847472 -122.212968) (xy 296.814533 -122.216276) (xy 296.797984 -122.216672) (xy 296.793412 -122.216672)
			(xy 296.766401 -122.216204) (xy 296.712918 -122.208586) (xy 296.661044 -122.193501) (xy 296.611817 -122.17125)
			(xy 296.56622 -122.142279) (xy 296.525165 -122.107165) (xy 296.489473 -122.066613) (xy 296.459858 -122.021431)
			(xy 296.436912 -121.972524) (xy 296.421092 -121.92087) (xy 296.412717 -121.8675) (xy 296.411904 -121.840498)
			(xy 296.411904 -121.83491) (xy 296.412397 -121.806679) (xy 296.420681 -121.750829) (xy 296.437101 -121.696807)
			(xy 296.448734 -121.67108) (xy 296.450512 -121.66346) (xy 296.442379 -121.63657) (xy 296.428783 -121.582054)
			(xy 296.423334 -121.554494) (xy 296.415077 -121.508137) (xy 296.406296 -121.41438) (xy 296.405808 -121.367296)
			(xy 296.406243 -121.324709) (xy 296.413483 -121.239845) (xy 296.427936 -121.155907) (xy 296.449497 -121.073509)
			(xy 296.478008 -120.99325) (xy 296.495216 -120.954292) (xy 296.498399 -120.945159) (xy 296.498398 -120.925834)
			(xy 296.495216 -120.9167) (xy 296.478008 -120.877743) (xy 296.449515 -120.79748) (xy 296.427964 -120.71508)
			(xy 296.413512 -120.631144) (xy 296.406265 -120.546282) (xy 296.405808 -120.503696) (xy 296.406182 -120.463248)
			(xy 296.412679 -120.382614) (xy 296.425695 -120.302773) (xy 296.435018 -120.263412) (xy 296.450512 -120.207532)
			(xy 296.450258 -120.206262) (xy 296.448988 -120.20042) (xy 296.438107 -120.176488) (xy 296.42227 -120.126358)
			(xy 296.413439 -120.074533) (xy 296.412158 -120.048274) (xy 296.412158 -120.047766) (xy 296.411904 -120.03913)
			(xy 296.411904 -120.035066) (xy 296.412362 -120.008227) (xy 296.419888 -119.955078) (xy 296.434786 -119.903508)
			(xy 296.456762 -119.854534) (xy 296.485382 -119.809122) (xy 296.520083 -119.768168) (xy 296.56018 -119.732479)
			(xy 296.604881 -119.702761) (xy 296.653306 -119.679598) (xy 296.704497 -119.663448) (xy 296.757447 -119.65463)
			(xy 296.784268 -119.653558) (xy 296.79392 -119.653304) (xy 296.794174 -119.653304) (xy 296.810767 -119.653431)
			(xy 296.843836 -119.656226) (xy 296.860214 -119.658892) (xy 296.87012 -119.66067) (xy 296.910018 -119.636096)
			(xy 296.993589 -119.593695) (xy 297.080769 -119.559321) (xy 297.170789 -119.533277) (xy 297.262855 -119.515792)
			(xy 297.356156 -119.507021) (xy 297.403012 -119.506492) (xy 297.449744 -119.507026) (xy 297.542799 -119.515748)
			(xy 297.634628 -119.533144) (xy 297.724426 -119.559061) (xy 297.811404 -119.59327) (xy 297.894796 -119.635472)
			(xy 297.934634 -119.659908) (xy 297.94327 -119.659908) (xy 297.960451 -119.656933) (xy 297.995177 -119.653755)
			(xy 298.012612 -119.653558) (xy 298.020994 -119.653558) (xy 298.048984 -119.654686) (xy 298.104199 -119.664125)
			(xy 298.130976 -119.672354) (xy 298.13504 -119.673624) (xy 298.149518 -119.67591) (xy 298.16118 -119.676866)
			(xy 298.183304 -119.66933) (xy 298.191936 -119.661432) (xy 298.199556 -119.653812) (xy 298.205398 -119.648732)
			(xy 298.248832 -119.617236) (xy 298.252184 -119.614559) (xy 298.25805 -119.6083) (xy 298.260516 -119.60479)
			(xy 298.260008 -119.586248) (xy 298.260008 -119.567198) (xy 298.260443 -119.524611) (xy 298.267683 -119.439747)
			(xy 298.282136 -119.355809) (xy 298.303697 -119.273411) (xy 298.332208 -119.193151) (xy 298.349416 -119.154194)
			(xy 298.352599 -119.145061) (xy 298.352599 -119.125735) (xy 298.349416 -119.116602) (xy 298.332208 -119.077645)
			(xy 298.303715 -118.997382) (xy 298.282164 -118.914982) (xy 298.267712 -118.831046) (xy 298.260464 -118.746184)
			(xy 298.260008 -118.703598) (xy 298.260382 -118.66315) (xy 298.266879 -118.582516) (xy 298.279895 -118.502675)
			(xy 298.289218 -118.463314) (xy 298.304712 -118.407434) (xy 298.304458 -118.406164) (xy 298.303188 -118.400322)
			(xy 298.291473 -118.374528) (xy 298.274943 -118.320343) (xy 298.26661 -118.264309) (xy 298.266104 -118.235984)
			(xy 298.266104 -118.234968) (xy 298.266592 -118.207719) (xy 298.274353 -118.153775) (xy 298.289711 -118.101485)
			(xy 298.312354 -118.051913) (xy 298.341821 -118.006067) (xy 298.377513 -117.964882) (xy 298.418702 -117.929195)
			(xy 298.464551 -117.899733) (xy 298.514126 -117.877095) (xy 298.566418 -117.861743) (xy 298.620363 -117.853989)
			(xy 298.647612 -117.85346) (xy 298.652438 -117.85346) (xy 298.668792 -117.853811) (xy 298.70135 -117.856988)
			(xy 298.717462 -117.85981) (xy 298.723812 -117.860826) (xy 298.763739 -117.836196) (xy 298.847377 -117.793689)
			(xy 298.934634 -117.759218) (xy 299.02474 -117.733085) (xy 299.116901 -117.715521) (xy 299.210303 -117.706683)
			(xy 299.257212 -117.70614) (xy 299.295661 -117.706525) (xy 299.372327 -117.712487) (xy 299.448307 -117.724335)
			(xy 299.485812 -117.73281) (xy 299.524291 -117.742271) (xy 299.599738 -117.766519) (xy 299.673018 -117.796686)
			(xy 299.743669 -117.832582) (xy 299.777658 -117.852952) (xy 299.784932 -117.856258) (xy 299.800711 -117.858716)
			(xy 299.808646 -117.857778) (xy 299.809154 -117.857778) (xy 299.818044 -117.856508) (xy 299.832014 -117.854984)
			(xy 299.847 -117.853714) (xy 299.865034 -117.853206) (xy 299.866812 -117.853206) (xy 299.89538 -117.853763)
			(xy 299.951873 -117.862324) (xy 300.006459 -117.879209) (xy 300.057919 -117.90404) (xy 300.105104 -117.936263)
			(xy 300.1264 -117.955314) (xy 300.1365 -117.964861) (xy 300.155443 -117.9852) (xy 300.164246 -117.995954)
			(xy 300.173898 -118.001288) (xy 300.193153 -118.003116) (xy 300.231518 -118.008069) (xy 300.250606 -118.011194)
			(xy 300.296611 -118.019607) (xy 300.386929 -118.043906) (xy 300.430946 -118.059708) (xy 300.431708 -118.059962)
			(xy 300.438566 -118.062502) (xy 300.44517 -118.06301) (xy 300.448989 -118.063327) (xy 300.456643 -118.062949)
			(xy 300.46041 -118.062248) (xy 301.684182 -117.797072) (xy 301.689262 -117.795802) (xy 301.689516 -117.795802)
			(xy 301.70501 -117.791992) (xy 301.705518 -117.791992) (xy 301.835566 -117.758972) (xy 301.839897 -117.757787)
			(xy 301.848076 -117.754082) (xy 301.851822 -117.751606) (xy 301.85614 -117.748558) (xy 301.862236 -117.742462)
			(xy 301.873412 -117.729254) (xy 301.875922 -117.726062) (xy 301.880002 -117.719042) (xy 301.88154 -117.715284)
			(xy 301.884334 -117.707918) (xy 301.884842 -117.69979) (xy 301.886921 -117.67327) (xy 301.897433 -117.621124)
			(xy 301.914977 -117.570905) (xy 301.939224 -117.523557) (xy 301.969718 -117.47997) (xy 302.005886 -117.440962)
			(xy 302.047049 -117.407267) (xy 302.092434 -117.379518) (xy 302.141186 -117.358236) (xy 302.192391 -117.343821)
			(xy 302.245086 -117.336544) (xy 302.271684 -117.336062) (xy 302.300376 -117.336586) (xy 302.357132 -117.345056)
			(xy 302.41202 -117.361799) (xy 302.46384 -117.386448) (xy 302.511462 -117.418466) (xy 302.553845 -117.457153)
			(xy 302.590062 -117.501664) (xy 302.605186 -117.526054) (xy 302.606964 -117.529102) (xy 302.610266 -117.534436)
			(xy 302.620426 -117.54231) (xy 302.629178 -117.547944) (xy 302.649512 -117.55229) (xy 302.659796 -117.550692)
			(xy 309.553102 -115.809522) (xy 309.561414 -115.807063) (xy 309.575825 -115.797451) (xy 309.581296 -115.790726)
			(xy 309.581296 -108.340144) (xy 309.576216 -108.335318) (xy 309.574692 -108.33354) (xy 309.572914 -108.331254)
			(xy 308.76621 -107.52455) (xy 308.748656 -107.506334) (xy 308.718922 -107.465411) (xy 308.695961 -107.420337)
			(xy 308.680338 -107.372224) (xy 308.67244 -107.322259) (xy 308.671976 -107.296966) (xy 308.671976 -95.692722)
			(xy 308.671722 -95.687134) (xy 308.671236 -95.683469) (xy 308.669324 -95.676327) (xy 308.667912 -95.67291)
			(xy 308.664356 -95.664782) (xy 308.657752 -95.657924) (xy 308.655212 -95.654876) (xy 308.653434 -95.65259)
			(xy 306.950872 -93.950028) (xy 306.934588 -93.933117) (xy 306.90659 -93.895435) (xy 306.884351 -93.854091)
			(xy 306.875942 -93.832172) (xy 306.875942 -93.830902) (xy 306.869592 -93.814138) (xy 306.867814 -93.807534)
			(xy 306.867814 -93.80728) (xy 306.867306 -93.80474) (xy 306.866544 -93.801946) (xy 306.861962 -93.782393)
			(xy 306.857122 -93.742525) (xy 306.856892 -93.722444) (xy 306.856892 -91.667584) (xy 306.856821 -91.663576)
			(xy 306.85554 -91.655664) (xy 306.854352 -91.651836) (xy 306.853336 -91.648788) (xy 306.84978 -91.640152)
			(xy 306.842668 -91.632786) (xy 306.841652 -91.631516) (xy 306.840128 -91.629738) (xy 299.21708 -84.006944)
			(xy 299.197769 -83.986768) (xy 299.165707 -83.941045) (xy 299.153326 -83.916012) (xy 299.141388 -83.887056)
			(xy 299.138086 -83.87715) (xy 299.1358 -83.871054) (xy 299.135038 -83.868514) (xy 299.134022 -83.865974)
			(xy 299.133768 -83.865212) (xy 299.129371 -83.853086) (xy 299.122249 -83.828293) (xy 299.119544 -83.815682)
			(xy 299.116421 -83.799159) (xy 299.113116 -83.765694) (xy 299.11294 -83.74888) (xy 299.11294 -81.535016)
			(xy 299.108876 -81.530698) (xy 299.108114 -81.529682) (xy 299.106336 -81.52765) (xy 298.87926 -81.300574)
			(xy 298.872396 -81.294333) (xy 298.855469 -81.286777) (xy 298.84624 -81.285842) (xy 298.840398 -81.285842)
			(xy 298.80941 -81.28762) (xy 298.76496 -81.29016) (xy 298.751498 -81.292954) (xy 298.75099 -81.292954)
			(xy 298.744386 -81.295748) (xy 298.734988 -81.300574) (xy 298.72813 -81.308956) (xy 298.70994 -81.330577)
			(xy 298.668262 -81.368725) (xy 298.621404 -81.400294) (xy 298.570395 -81.424592) (xy 298.516355 -81.441084)
			(xy 298.460471 -81.449408) (xy 298.43222 -81.449926) (xy 298.431458 -81.449926) (xy 298.43095 -81.449926)
			(xy 298.400198 -81.449351) (xy 298.33949 -81.439499) (xy 298.281151 -81.420027) (xy 298.253658 -81.406238)
			(xy 298.248128 -81.403536) (xy 298.236187 -81.40057) (xy 298.230036 -81.400396) (xy 297.563032 -81.400396)
			(xy 297.550986 -81.400269) (xy 297.52696 -81.398487) (xy 297.515026 -81.39684) (xy 297.514518 -81.39684)
			(xy 297.487594 -81.391506) (xy 297.481752 -81.390236) (xy 296.924476 -81.390236) (xy 296.899186 -81.389739)
			(xy 296.84923 -81.381828) (xy 296.801124 -81.366204) (xy 296.756052 -81.343252) (xy 296.715123 -81.313536)
			(xy 296.696892 -81.296002) (xy 292.513004 -77.112114) (xy 292.506171 -77.104711) (xy 292.498467 -77.086113)
			(xy 292.498018 -77.076046) (xy 292.498018 -67.165474) (xy 292.497953 -67.161869) (xy 292.49693 -67.15473)
			(xy 292.495986 -67.15125) (xy 292.494462 -67.146678) (xy 292.490652 -67.137534) (xy 291.39261 -66.039492)
			(xy 291.389758 -66.036787) (xy 291.383379 -66.032197) (xy 291.37991 -66.030348) (xy 291.374483 -66.027768)
			(xy 291.362803 -66.024952) (xy 291.356796 -66.02476) (xy 282.419552 -66.02476) (xy 282.415947 -66.024826)
			(xy 282.408809 -66.025852) (xy 282.405328 -66.026792) (xy 282.400756 -66.028316) (xy 282.391612 -66.032126)
			(xy 282.379928 -66.04381) (xy 282.370784 -66.04762) (xy 282.366156 -66.049393) (xy 282.356435 -66.051311)
			(xy 282.35148 -66.05143) (xy 279.23109 -66.05143) (xy 279.22102 -66.051006) (xy 279.202415 -66.043292)
			(xy 279.195022 -66.036444) (xy 278.642318 -65.48374) (xy 278.632412 -65.47612) (xy 278.625554 -65.472056)
			(xy 278.618696 -65.470278) (xy 278.592137 -65.462889) (xy 278.541323 -65.441514) (xy 278.494113 -65.41305)
			(xy 278.45149 -65.37809) (xy 278.414341 -65.337359) (xy 278.38344 -65.291708) (xy 278.359429 -65.242085)
			(xy 278.342809 -65.189523) (xy 278.333925 -65.135117) (xy 278.332946 -65.107566) (xy 278.332692 -65.09766)
			(xy 278.327612 -65.085722) (xy 278.325721 -65.081953) (xy 278.32087 -65.075057) (xy 278.31796 -65.072006)
			(xy 278.14143 -64.895476) (xy 278.138581 -64.892767) (xy 278.132206 -64.888167) (xy 278.12873 -64.886332)
			(xy 278.123303 -64.88375) (xy 278.111623 -64.880931) (xy 278.105616 -64.880744) (xy 277.78329 -64.880744)
			(xy 277.779684 -64.880808) (xy 277.772545 -64.881828) (xy 277.769066 -64.882776) (xy 277.764494 -64.8843)
			(xy 277.75535 -64.88811) (xy 276.660356 -65.983104) (xy 276.643485 -65.999378) (xy 276.605889 -66.027372)
			(xy 276.564636 -66.04963) (xy 276.542754 -66.058034) (xy 276.532086 -66.06159) (xy 276.524466 -66.064384)
			(xy 276.517354 -66.066416) (xy 276.515576 -66.06667) (xy 276.512528 -66.067432) (xy 276.511258 -66.067686)
			(xy 276.492016 -66.0722) (xy 276.452789 -66.077045) (xy 276.433026 -66.077338) (xy 276.427184 -66.077338)
			(xy 276.424898 -66.077084) (xy 276.276308 -66.077084) (xy 276.270466 -66.078354) (xy 276.251689 -66.082502)
			(xy 276.213493 -66.08696) (xy 276.194266 -66.087244) (xy 273.117818 -66.087244) (xy 273.1135 -66.08953)
			(xy 273.085074 -66.104445) (xy 273.024473 -66.125603) (xy 272.96119 -66.13635) (xy 272.929096 -66.137028)
			(xy 272.928588 -66.137028) (xy 272.901336 -66.136541) (xy 272.847387 -66.128783) (xy 272.795091 -66.113426)
			(xy 272.745512 -66.090783) (xy 272.699661 -66.061315) (xy 272.65847 -66.025622) (xy 272.622778 -65.984429)
			(xy 272.593311 -65.938577) (xy 272.57067 -65.888998) (xy 272.555314 -65.836702) (xy 272.547558 -65.782752)
			(xy 272.547558 -65.728248) (xy 272.555314 -65.674298) (xy 272.57067 -65.622002) (xy 272.593311 -65.572423)
			(xy 272.622778 -65.526571) (xy 272.65847 -65.485378) (xy 272.699661 -65.449685) (xy 272.745512 -65.420217)
			(xy 272.795091 -65.397574) (xy 272.847387 -65.382217) (xy 272.901336 -65.374459) (xy 272.928588 -65.374012)
			(xy 272.928842 -65.374012) (xy 272.953089 -65.374408) (xy 273.00119 -65.380579) (xy 273.048126 -65.39278)
			(xy 273.093143 -65.410814) (xy 273.114516 -65.422272) (xy 273.11731 -65.423796) (xy 276.035516 -65.423796)
			(xy 276.046438 -65.422526) (xy 276.053405 -65.420766) (xy 276.066034 -65.413923) (xy 276.07133 -65.409064)
			(xy 277.706582 -63.773558) (xy 277.725362 -63.755444) (xy 277.767559 -63.724755) (xy 277.814039 -63.70105)
			(xy 277.863657 -63.684913) (xy 277.91519 -63.676742) (xy 277.941278 -63.676276) (xy 278.073612 -63.676276)
			(xy 278.081486 -63.672466) (xy 278.096101 -63.665104) (xy 278.126512 -63.653017) (xy 278.142192 -63.648336)
			(xy 278.144986 -63.647828) (xy 278.14778 -63.647066) (xy 278.167858 -63.642053) (xy 278.208878 -63.636574)
			(xy 278.229568 -63.636144) (xy 280.368248 -63.636144) (xy 280.3754 -63.635763) (xy 280.389071 -63.631513)
			(xy 280.395172 -63.627762) (xy 280.40203 -63.622936) (xy 280.406602 -63.618872) (xy 280.411119 -63.614054)
			(xy 280.417677 -63.602597) (xy 280.419556 -63.596266) (xy 280.423112 -63.583312) (xy 280.42743 -63.572898)
			(xy 280.432002 -63.56096) (xy 280.433765 -63.556817) (xy 280.43849 -63.549155) (xy 280.4414 -63.54572)
			(xy 280.442416 -63.54445) (xy 280.446722 -63.538999) (xy 280.452507 -63.526375) (xy 280.453846 -63.519558)
			(xy 280.454862 -63.5127) (xy 280.4541 -63.505842) (xy 280.453551 -63.502169) (xy 280.451506 -63.495029)
			(xy 280.450036 -63.491618) (xy 280.4414 -63.472314) (xy 280.4414 -63.471806) (xy 280.436828 -63.461392)
			(xy 280.430224 -63.454534) (xy 280.42997 -63.45428) (xy 280.429462 -63.453772) (xy 280.409229 -63.432376)
			(xy 280.374929 -63.384511) (xy 280.34839 -63.331944) (xy 280.330241 -63.275925) (xy 280.320914 -63.217782)
			(xy 280.320242 -63.188342) (xy 280.320242 -63.180214) (xy 280.321242 -63.151261) (xy 280.330913 -63.094144)
			(xy 280.349107 -63.039145) (xy 280.375408 -62.98753) (xy 280.40921 -62.940484) (xy 280.449736 -62.899089)
			(xy 280.496055 -62.864297) (xy 280.547101 -62.836907) (xy 280.601702 -62.81755) (xy 280.658601 -62.806671)
			(xy 280.687526 -62.805056) (xy 280.68778 -62.805056) (xy 280.70175 -62.804802) (xy 280.702258 -62.804802)
			(xy 280.727885 -62.80523) (xy 280.778673 -62.812124) (xy 280.828078 -62.825767) (xy 280.875207 -62.845911)
			(xy 280.919209 -62.872194) (xy 280.939494 -62.88786) (xy 280.946098 -62.89294) (xy 280.957274 -62.89675)
			(xy 280.970736 -62.898782) (xy 280.99258 -62.898782) (xy 280.996186 -62.898844) (xy 281.003326 -62.89986)
			(xy 281.006804 -62.900814) (xy 281.01036 -62.901576) (xy 281.064208 -62.901576) (xy 281.072809 -62.901234)
			(xy 281.089029 -62.895509) (xy 281.095958 -62.8904) (xy 281.096212 -62.890146) (xy 281.096974 -62.889638)
			(xy 281.101546 -62.886082) (xy 281.104086 -62.88405) (xy 281.104848 -62.883288) (xy 281.116532 -62.874906)
			(xy 281.11704 -62.874398) (xy 281.126692 -62.867794) (xy 281.1272 -62.867286) (xy 281.146524 -62.855005)
			(xy 281.187529 -62.834631) (xy 281.208988 -62.826646) (xy 281.20975 -62.826392) (xy 281.21356 -62.825122)
			(xy 281.234863 -62.818184) (xy 281.278665 -62.808768) (xy 281.300936 -62.806326) (xy 281.301444 -62.806326)
			(xy 281.315922 -62.80531) (xy 281.316684 -62.80531) (xy 281.320494 -62.805056) (xy 281.337258 -62.804294)
			(xy 281.349704 -62.805056) (xy 281.38007 -62.806677) (xy 281.439745 -62.818355) (xy 281.49681 -62.839357)
			(xy 281.549818 -62.86915) (xy 281.573986 -62.887606) (xy 281.57424 -62.88786) (xy 281.577288 -62.8904)
			(xy 281.583398 -62.894131) (xy 281.597064 -62.89838) (xy 281.604212 -62.898782) (xy 281.62758 -62.898782)
			(xy 281.633021 -62.898919) (xy 281.643657 -62.901216) (xy 281.648662 -62.903354) (xy 281.662378 -62.909704)
			(xy 281.667082 -62.911769) (xy 281.677063 -62.914201) (xy 281.68219 -62.91453) (xy 281.690826 -62.914022)
			(xy 281.698116 -62.912747) (xy 281.711551 -62.906559) (xy 281.717242 -62.90183) (xy 281.717496 -62.901576)
			(xy 281.738566 -62.883469) (xy 281.78496 -62.852909) (xy 281.835293 -62.829396) (xy 281.888503 -62.813427)
			(xy 281.943465 -62.805338) (xy 281.971242 -62.804802) (xy 281.97175 -62.804802) (xy 281.999005 -62.805262)
			(xy 282.052961 -62.813013) (xy 282.105264 -62.828365) (xy 282.15485 -62.851005) (xy 282.200708 -62.880472)
			(xy 282.241906 -62.916165) (xy 282.277604 -62.957359) (xy 282.307076 -63.003215) (xy 282.329721 -63.052798)
			(xy 282.345078 -63.1051) (xy 282.352835 -63.159055) (xy 282.353258 -63.18631) (xy 282.352688 -63.216036)
			(xy 282.34346 -63.274769) (xy 282.32523 -63.331358) (xy 282.298439 -63.384432) (xy 282.263735 -63.432706)
			(xy 282.243276 -63.45428) (xy 282.243022 -63.454534) (xy 282.236926 -63.460884) (xy 282.22829 -63.479426)
			(xy 282.227528 -63.48222) (xy 282.223718 -63.499238) (xy 282.223032 -63.505124) (xy 282.224061 -63.516926)
			(xy 282.22575 -63.522606) (xy 282.2448 -63.569342) (xy 282.2448 -63.56985) (xy 282.260294 -63.606934)
			(xy 282.267152 -63.617856) (xy 282.274756 -63.626111) (xy 282.295058 -63.635617) (xy 282.306268 -63.636144)
			(xy 283.403548 -63.636144) (xy 283.410152 -63.635636) (xy 283.596842 -63.4492) (xy 283.600128 -63.44579)
			(xy 283.605497 -63.437992) (xy 283.60751 -63.433706) (xy 283.609566 -63.428749) (xy 283.611754 -63.418244)
			(xy 283.611828 -63.412878) (xy 283.611828 -58.181494) (xy 283.611666 -58.175483) (xy 283.608853 -58.163795)
			(xy 283.60624 -58.15838) (xy 283.604402 -58.154905) (xy 283.59981 -58.148524) (xy 283.597096 -58.14568)
			(xy 283.275024 -57.823608) (xy 283.259569 -57.807641) (xy 283.232748 -57.77221) (xy 283.211054 -57.733429)
			(xy 283.202634 -57.712864) (xy 283.196792 -57.701942) (xy 283.195776 -57.700418) (xy 283.180138 -57.678708)
			(xy 283.155276 -57.631334) (xy 283.138334 -57.580586) (xy 283.12975 -57.527779) (xy 283.129228 -57.501028)
			(xy 283.129228 -56.577992) (xy 283.125157 -56.572851) (xy 283.114866 -56.564729) (xy 283.108908 -56.56199)
			(xy 283.016452 -56.528208) (xy 283.009078 -56.525734) (xy 282.993553 -56.524947) (xy 282.985972 -56.526684)
			(xy 282.978606 -56.528716) (xy 282.965398 -56.537098) (xy 282.960318 -56.543194) (xy 282.942062 -56.564011)
			(xy 282.900577 -56.600678) (xy 282.854235 -56.630976) (xy 282.804007 -56.654271) (xy 282.750944 -56.670076)
			(xy 282.696156 -56.67806) (xy 282.668472 -56.678576) (xy 282.641224 -56.678088) (xy 282.587284 -56.670329)
			(xy 282.534997 -56.654973) (xy 282.485428 -56.632332) (xy 282.439585 -56.602867) (xy 282.398401 -56.567179)
			(xy 282.362716 -56.525993) (xy 282.333255 -56.480148) (xy 282.310618 -56.430576) (xy 282.295265 -56.378288)
			(xy 282.28751 -56.324348) (xy 282.28751 -56.269852) (xy 282.295265 -56.215912) (xy 282.310618 -56.163624)
			(xy 282.333255 -56.114052) (xy 282.362716 -56.068207) (xy 282.398401 -56.027021) (xy 282.439585 -55.991333)
			(xy 282.485428 -55.961868) (xy 282.534997 -55.939227) (xy 282.587284 -55.923871) (xy 282.641224 -55.916112)
			(xy 282.668472 -55.91556) (xy 282.69545 -55.916023) (xy 282.748869 -55.92361) (xy 282.80069 -55.938638)
			(xy 282.84988 -55.960808) (xy 282.895462 -55.989678) (xy 282.936529 -56.024674) (xy 282.95473 -56.044592)
			(xy 282.960572 -56.051196) (xy 282.97632 -56.06161) (xy 282.985561 -56.066309) (xy 283.006138 -56.068684)
			(xy 283.016198 -56.066182) (xy 283.07284 -56.045608) (xy 283.106114 -56.033416) (xy 283.112917 -56.030668)
			(xy 283.124667 -56.021891) (xy 283.129228 -56.016144) (xy 283.129228 -55.113428) (xy 283.129712 -55.08734)
			(xy 283.137875 -55.035806) (xy 283.154003 -54.986185) (xy 283.1777 -54.9397) (xy 283.20838 -54.897497)
			(xy 283.22651 -54.878732) (xy 285.15056 -52.954682) (xy 285.15691 -52.944014) (xy 285.158688 -52.938172)
			(xy 285.167123 -52.912592) (xy 285.190181 -52.863915) (xy 285.219853 -52.818964) (xy 285.25555 -52.77863)
			(xy 285.296563 -52.743716) (xy 285.342077 -52.714913) (xy 285.391188 -52.692796) (xy 285.44292 -52.677802)
			(xy 285.496247 -52.67023) (xy 285.550109 -52.67023) (xy 285.603436 -52.677802) (xy 285.655168 -52.692796)
			(xy 285.704279 -52.714913) (xy 285.749793 -52.743716) (xy 285.790806 -52.77863) (xy 285.826503 -52.818964)
			(xy 285.856175 -52.863915) (xy 285.879233 -52.912592) (xy 285.887668 -52.938172) (xy 285.889446 -52.944014)
			(xy 285.895796 -52.954682) (xy 286.437669 -53.496555) (xy 290.333341 -53.496555) (xy 290.333341 -53.442045)
			(xy 290.341099 -53.388089) (xy 290.356457 -53.335787) (xy 290.379103 -53.286203) (xy 290.408575 -53.240347)
			(xy 290.444273 -53.199152) (xy 290.485471 -53.163457) (xy 290.531329 -53.133988) (xy 290.580915 -53.111347)
			(xy 290.633219 -53.095993) (xy 290.687175 -53.088239) (xy 290.71443 -53.087778) (xy 290.741802 -53.088207)
			(xy 290.795983 -53.096031) (xy 290.848487 -53.111528) (xy 290.898234 -53.134378) (xy 290.944198 -53.164112)
			(xy 290.965128 -53.181758) (xy 290.965382 -53.182012) (xy 290.972469 -53.187599) (xy 290.989385 -53.193845)
			(xy 290.998402 -53.194204) (xy 291.065458 -53.194204) (xy 291.074473 -53.193826) (xy 291.09139 -53.187593)
			(xy 291.098478 -53.182012) (xy 291.098478 -53.181758) (xy 291.098732 -53.181758) (xy 291.119673 -53.16413)
			(xy 291.165644 -53.134418) (xy 291.215389 -53.111581) (xy 291.267888 -53.096087) (xy 291.322062 -53.088254)
			(xy 291.34943 -53.087778) (xy 291.376679 -53.088294) (xy 291.430621 -53.096054) (xy 291.48291 -53.111411)
			(xy 291.532482 -53.134053) (xy 291.578327 -53.163519) (xy 291.619512 -53.199209) (xy 291.655199 -53.240397)
			(xy 291.684661 -53.286244) (xy 291.707299 -53.335818) (xy 291.722652 -53.388108) (xy 291.730408 -53.442051)
			(xy 291.730408 -53.496549) (xy 291.722652 -53.550492) (xy 291.707299 -53.602782) (xy 291.684661 -53.652356)
			(xy 291.655199 -53.698203) (xy 291.619512 -53.739391) (xy 291.578327 -53.775081) (xy 291.532482 -53.804547)
			(xy 291.48291 -53.827189) (xy 291.430621 -53.842546) (xy 291.376679 -53.850306) (xy 291.34943 -53.850794)
			(xy 291.32206 -53.850312) (xy 291.267882 -53.842498) (xy 291.215379 -53.827013) (xy 291.165632 -53.804175)
			(xy 291.119664 -53.774454) (xy 291.098732 -53.756814) (xy 291.098478 -53.75656) (xy 291.091405 -53.750953)
			(xy 291.074478 -53.74472) (xy 291.065458 -53.744368) (xy 290.998402 -53.744368) (xy 290.989386 -53.744733)
			(xy 290.97247 -53.750976) (xy 290.965382 -53.75656) (xy 290.965382 -53.756814) (xy 290.965128 -53.756814)
			(xy 290.944198 -53.774456) (xy 290.898224 -53.804167) (xy 290.848476 -53.827002) (xy 290.795975 -53.842492)
			(xy 290.741799 -53.85032) (xy 290.71443 -53.850794) (xy 290.687175 -53.850361) (xy 290.633219 -53.842607)
			(xy 290.580915 -53.827253) (xy 290.531329 -53.804612) (xy 290.485471 -53.775143) (xy 290.444273 -53.739448)
			(xy 290.408575 -53.698253) (xy 290.379103 -53.652397) (xy 290.356457 -53.602813) (xy 290.341099 -53.550511)
			(xy 290.333341 -53.496555) (xy 286.437669 -53.496555) (xy 286.51835 -53.577236) (xy 286.518604 -53.57749)
			(xy 286.532297 -53.591557) (xy 286.556621 -53.62237) (xy 286.567118 -53.638958) (xy 286.567626 -53.639974)
			(xy 286.572452 -53.64607) (xy 286.587679 -53.663844) (xy 286.613368 -53.702965) (xy 286.633127 -53.745391)
			(xy 286.646538 -53.79023) (xy 286.653319 -53.836537) (xy 286.653732 -53.859938) (xy 286.653732 -54.91353)
			(xy 286.654214 -54.924277) (xy 286.663038 -54.943874) (xy 286.67075 -54.951376) (xy 286.686498 -54.965346)
			(xy 286.71321 -54.989055) (xy 288.100945 -54.989055) (xy 288.100945 -54.934545) (xy 288.108703 -54.880591)
			(xy 288.12406 -54.82829) (xy 288.146705 -54.778707) (xy 288.176176 -54.732851) (xy 288.211874 -54.691657)
			(xy 288.25307 -54.655962) (xy 288.298928 -54.626494) (xy 288.348512 -54.603852) (xy 288.400814 -54.588498)
			(xy 288.454769 -54.580743) (xy 288.482024 -54.580282) (xy 288.510116 -54.580758) (xy 288.565694 -54.588988)
			(xy 288.619464 -54.605283) (xy 288.670261 -54.629289) (xy 288.716988 -54.660486) (xy 288.758632 -54.698201)
			(xy 288.794294 -54.741616) (xy 288.809176 -54.765448) (xy 288.81451 -54.774338) (xy 288.831528 -54.78653)
			(xy 288.924746 -54.80685) (xy 288.94532 -54.802532) (xy 288.953956 -54.79669) (xy 288.97803 -54.780705)
			(xy 289.029958 -54.755359) (xy 289.085113 -54.73813) (xy 289.142234 -54.729409) (xy 289.171126 -54.728872)
			(xy 289.198377 -54.729354) (xy 289.252324 -54.737113) (xy 289.304617 -54.752471) (xy 289.354193 -54.775113)
			(xy 289.400043 -54.80458) (xy 289.441232 -54.840272) (xy 289.476923 -54.881462) (xy 289.50639 -54.927312)
			(xy 289.529032 -54.976888) (xy 289.544388 -55.029182) (xy 289.552147 -55.083129) (xy 289.552634 -55.11038)
			(xy 289.552172 -55.137751) (xy 289.544356 -55.19193) (xy 289.528867 -55.244434) (xy 289.506024 -55.294181)
			(xy 289.476297 -55.340147) (xy 289.458654 -55.361078) (xy 289.4584 -55.361332) (xy 289.452836 -55.368434)
			(xy 289.446576 -55.385339) (xy 289.446208 -55.394352) (xy 289.446208 -55.461408) (xy 289.446559 -55.470425)
			(xy 289.452811 -55.487342) (xy 289.4584 -55.494428) (xy 289.458654 -55.494428) (xy 289.458654 -55.494682)
			(xy 289.476276 -55.51563) (xy 289.506003 -55.561595) (xy 289.528851 -55.611338) (xy 289.544349 -55.663838)
			(xy 289.55218 -55.718015) (xy 289.552182 -55.772755) (xy 289.544356 -55.826932) (xy 289.528861 -55.879433)
			(xy 289.506017 -55.929179) (xy 289.476294 -55.975146) (xy 289.458654 -55.996078) (xy 289.4584 -55.996332)
			(xy 289.452836 -56.003434) (xy 289.446576 -56.020339) (xy 289.446208 -56.029352) (xy 289.446208 -56.096408)
			(xy 289.446559 -56.105425) (xy 289.452811 -56.122342) (xy 289.4584 -56.129428) (xy 289.458654 -56.129428)
			(xy 289.458654 -56.129682) (xy 289.476291 -56.150616) (xy 289.506005 -56.196588) (xy 289.528842 -56.246334)
			(xy 289.544333 -56.298835) (xy 289.552161 -56.353011) (xy 289.552634 -56.38038) (xy 289.552148 -56.407631)
			(xy 289.544392 -56.461579) (xy 289.529037 -56.513874) (xy 289.506395 -56.563451) (xy 289.476929 -56.609301)
			(xy 289.441238 -56.650492) (xy 289.400047 -56.686183) (xy 289.354197 -56.715649) (xy 289.30462 -56.738291)
			(xy 289.252325 -56.753646) (xy 289.198377 -56.761402) (xy 289.143875 -56.761402) (xy 289.089927 -56.753646)
			(xy 289.037632 -56.738291) (xy 288.988055 -56.715649) (xy 288.942205 -56.686183) (xy 288.901014 -56.650492)
			(xy 288.865323 -56.609301) (xy 288.835857 -56.563451) (xy 288.813215 -56.513874) (xy 288.79786 -56.461579)
			(xy 288.790104 -56.407631) (xy 288.789618 -56.38038) (xy 288.790068 -56.353009) (xy 288.797889 -56.298829)
			(xy 288.813382 -56.246326) (xy 288.836227 -56.196579) (xy 288.865955 -56.150613) (xy 288.883598 -56.129682)
			(xy 288.883852 -56.129428) (xy 288.889439 -56.122342) (xy 288.895684 -56.105425) (xy 288.896044 -56.096408)
			(xy 288.896044 -56.029352) (xy 288.895674 -56.020336) (xy 288.889437 -56.003418) (xy 288.883852 -55.996332)
			(xy 288.883598 -55.996332) (xy 288.883598 -55.996078) (xy 288.865939 -55.975161) (xy 288.836217 -55.929189)
			(xy 288.813375 -55.87944) (xy 288.797881 -55.826936) (xy 288.790055 -55.772756) (xy 288.790057 -55.718014)
			(xy 288.797888 -55.663834) (xy 288.813385 -55.611331) (xy 288.836232 -55.561584) (xy 288.865957 -55.515615)
			(xy 288.883598 -55.494682) (xy 288.883852 -55.494428) (xy 288.889439 -55.487342) (xy 288.895684 -55.470425)
			(xy 288.896044 -55.461408) (xy 288.896044 -55.394352) (xy 288.895674 -55.385336) (xy 288.889437 -55.368418)
			(xy 288.883852 -55.361332) (xy 288.883598 -55.360824) (xy 288.872654 -55.348089) (xy 288.852813 -55.320998)
			(xy 288.843974 -55.306722) (xy 288.83864 -55.297832) (xy 288.821622 -55.28564) (xy 288.728404 -55.26532)
			(xy 288.70783 -55.269638) (xy 288.699194 -55.27548) (xy 288.675132 -55.291483) (xy 288.6232 -55.316825)
			(xy 288.568041 -55.33405) (xy 288.510917 -55.342764) (xy 288.482024 -55.343298) (xy 288.454769 -55.342857)
			(xy 288.400814 -55.335102) (xy 288.348512 -55.319748) (xy 288.298928 -55.297106) (xy 288.25307 -55.267638)
			(xy 288.211874 -55.231943) (xy 288.176176 -55.190749) (xy 288.146705 -55.144893) (xy 288.12406 -55.09531)
			(xy 288.108703 -55.043009) (xy 288.100945 -54.989055) (xy 286.71321 -54.989055) (xy 286.729424 -55.003446)
			(xy 286.732893 -55.006111) (xy 286.740556 -55.010327) (xy 286.744664 -55.011828) (xy 286.755078 -55.015384)
			(xy 286.762952 -55.014368) (xy 286.773586 -55.013274) (xy 286.794934 -55.012129) (xy 286.805624 -55.012082)
			(xy 286.80791 -55.012082) (xy 286.83827 -55.012853) (xy 286.898171 -55.022833) (xy 286.955737 -55.042173)
			(xy 287.009513 -55.070386) (xy 287.058142 -55.10676) (xy 287.07969 -55.12816) (xy 287.086802 -55.135526)
			(xy 287.116012 -55.148226) (xy 287.120166 -55.149783) (xy 287.128853 -55.151573) (xy 287.133284 -55.151782)
			(xy 287.187894 -55.151782) (xy 287.1978 -55.150004) (xy 287.207452 -55.147972) (xy 287.235646 -55.135526)
			(xy 287.242504 -55.128414) (xy 287.260533 -55.110346) (xy 287.300582 -55.078703) (xy 287.344495 -55.052685)
			(xy 287.391486 -55.032758) (xy 287.440715 -55.019278) (xy 287.491303 -55.012485) (xy 287.516824 -55.012082)
			(xy 287.544075 -55.012569) (xy 287.598021 -55.020329) (xy 287.650315 -55.035687) (xy 287.69989 -55.05833)
			(xy 287.745739 -55.087797) (xy 287.786927 -55.12349) (xy 287.822617 -55.164681) (xy 287.852082 -55.210531)
			(xy 287.874722 -55.260108) (xy 287.890076 -55.312402) (xy 287.897832 -55.366349) (xy 287.897832 -55.420851)
			(xy 287.890076 -55.474798) (xy 287.874722 -55.527092) (xy 287.852082 -55.576669) (xy 287.822617 -55.622519)
			(xy 287.786927 -55.66371) (xy 287.745739 -55.699403) (xy 287.69989 -55.72887) (xy 287.650315 -55.751513)
			(xy 287.598021 -55.766871) (xy 287.544075 -55.774631) (xy 287.516824 -55.775098) (xy 287.491337 -55.774669)
			(xy 287.440819 -55.767872) (xy 287.391655 -55.754411) (xy 287.344721 -55.734524) (xy 287.300852 -55.708566)
			(xy 287.26083 -55.676998) (xy 287.242758 -55.65902) (xy 287.235646 -55.651654) (xy 287.206436 -55.638954)
			(xy 287.202282 -55.637401) (xy 287.193594 -55.635621) (xy 287.189164 -55.635398) (xy 287.140142 -55.635398)
			(xy 287.129982 -55.636414) (xy 287.11906 -55.6387) (xy 287.113472 -55.639716) (xy 287.086802 -55.651654)
			(xy 287.079944 -55.65902) (xy 287.062284 -55.676678) (xy 287.023139 -55.707693) (xy 286.980279 -55.733328)
			(xy 286.957516 -55.743602) (xy 286.949642 -55.747158) (xy 286.9438 -55.752238) (xy 286.935164 -55.762398)
			(xy 286.92221 -55.785004) (xy 286.92221 -55.785258) (xy 286.919416 -55.790084) (xy 286.915773 -55.796929)
			(xy 286.912406 -55.812058) (xy 286.912812 -55.819802) (xy 286.913066 -55.824374) (xy 286.913828 -55.84825)
			(xy 286.913828 -55.884572) (xy 286.915098 -55.890414) (xy 286.920432 -55.917338) (xy 286.920432 -55.917846)
			(xy 286.922086 -55.929779) (xy 286.923866 -55.953806) (xy 286.923988 -55.965852) (xy 286.923988 -57.48528)
			(xy 288.805872 -57.48528) (xy 288.809943 -57.429658) (xy 288.822069 -57.375221) (xy 288.841992 -57.32313)
			(xy 288.869288 -57.274495) (xy 288.903374 -57.230352) (xy 288.943523 -57.191643) (xy 288.988881 -57.159192)
			(xy 289.038481 -57.133691) (xy 289.091265 -57.115684) (xy 289.146108 -57.105554) (xy 289.201842 -57.103517)
			(xy 289.257279 -57.109617) (xy 289.311236 -57.123723) (xy 289.362565 -57.145535) (xy 289.410171 -57.174589)
			(xy 289.453039 -57.210264) (xy 289.490256 -57.251801) (xy 289.521029 -57.298314) (xy 289.544701 -57.348811)
			(xy 289.560769 -57.402218) (xy 289.568889 -57.457394) (xy 289.569398 -57.48528) (xy 289.568889 -57.513166)
			(xy 289.560769 -57.568342) (xy 289.544701 -57.621749) (xy 289.521029 -57.672246) (xy 289.490256 -57.718759)
			(xy 289.453039 -57.760296) (xy 289.410171 -57.795971) (xy 289.362565 -57.825025) (xy 289.311236 -57.846837)
			(xy 289.257279 -57.860943) (xy 289.201842 -57.867043) (xy 289.146108 -57.865006) (xy 289.091265 -57.854876)
			(xy 289.038481 -57.836869) (xy 288.988881 -57.811368) (xy 288.943523 -57.778917) (xy 288.903374 -57.740208)
			(xy 288.869288 -57.696065) (xy 288.841992 -57.64743) (xy 288.822069 -57.595339) (xy 288.809943 -57.540902)
			(xy 288.805872 -57.48528) (xy 286.923988 -57.48528) (xy 286.923988 -58.561224) (xy 290.76218 -58.561224)
			(xy 290.766251 -58.505602) (xy 290.778377 -58.451165) (xy 290.7983 -58.399074) (xy 290.825596 -58.350439)
			(xy 290.859682 -58.306296) (xy 290.899831 -58.267587) (xy 290.945189 -58.235136) (xy 290.994789 -58.209635)
			(xy 291.047573 -58.191628) (xy 291.102416 -58.181498) (xy 291.15815 -58.179461) (xy 291.213587 -58.185561)
			(xy 291.267544 -58.199667) (xy 291.318873 -58.221479) (xy 291.366479 -58.250533) (xy 291.409347 -58.286208)
			(xy 291.446564 -58.327745) (xy 291.477337 -58.374258) (xy 291.501009 -58.424755) (xy 291.517077 -58.478162)
			(xy 291.525197 -58.533338) (xy 291.525706 -58.561224) (xy 291.525197 -58.58911) (xy 291.517077 -58.644286)
			(xy 291.501009 -58.697693) (xy 291.477337 -58.74819) (xy 291.446564 -58.794703) (xy 291.409347 -58.83624)
			(xy 291.366479 -58.871915) (xy 291.318873 -58.900969) (xy 291.267544 -58.922781) (xy 291.213587 -58.936887)
			(xy 291.15815 -58.942987) (xy 291.102416 -58.94095) (xy 291.047573 -58.93082) (xy 290.994789 -58.912813)
			(xy 290.945189 -58.887312) (xy 290.899831 -58.854861) (xy 290.859682 -58.816152) (xy 290.825596 -58.772009)
			(xy 290.7983 -58.723374) (xy 290.778377 -58.671283) (xy 290.766251 -58.616846) (xy 290.76218 -58.561224)
			(xy 286.923988 -58.561224) (xy 286.923988 -59.174634) (xy 289.293044 -59.174634) (xy 289.297115 -59.119012)
			(xy 289.309241 -59.064575) (xy 289.329164 -59.012484) (xy 289.35646 -58.963849) (xy 289.390546 -58.919706)
			(xy 289.430695 -58.880997) (xy 289.476053 -58.848546) (xy 289.525653 -58.823045) (xy 289.578437 -58.805038)
			(xy 289.63328 -58.794908) (xy 289.689014 -58.792871) (xy 289.744451 -58.798971) (xy 289.798408 -58.813077)
			(xy 289.849737 -58.834889) (xy 289.897343 -58.863943) (xy 289.940211 -58.899618) (xy 289.977428 -58.941155)
			(xy 290.008201 -58.987668) (xy 290.031873 -59.038165) (xy 290.047941 -59.091572) (xy 290.056061 -59.146748)
			(xy 290.05657 -59.174634) (xy 290.056061 -59.20252) (xy 290.047941 -59.257696) (xy 290.031873 -59.311103)
			(xy 290.008201 -59.3616) (xy 289.977428 -59.408113) (xy 289.940211 -59.44965) (xy 289.897343 -59.485325)
			(xy 289.849737 -59.514379) (xy 289.798408 -59.536191) (xy 289.744451 -59.550297) (xy 289.689014 -59.556397)
			(xy 289.63328 -59.55436) (xy 289.578437 -59.54423) (xy 289.525653 -59.526223) (xy 289.476053 -59.500722)
			(xy 289.430695 -59.468271) (xy 289.390546 -59.429562) (xy 289.35646 -59.385419) (xy 289.329164 -59.336784)
			(xy 289.309241 -59.284693) (xy 289.297115 -59.230256) (xy 289.293044 -59.174634) (xy 286.923988 -59.174634)
			(xy 286.923988 -60.633356) (xy 291.996874 -60.633356) (xy 292.000945 -60.577734) (xy 292.013071 -60.523297)
			(xy 292.032994 -60.471206) (xy 292.06029 -60.422571) (xy 292.094376 -60.378428) (xy 292.134525 -60.339719)
			(xy 292.179883 -60.307268) (xy 292.229483 -60.281767) (xy 292.282267 -60.26376) (xy 292.33711 -60.25363)
			(xy 292.392844 -60.251593) (xy 292.448281 -60.257693) (xy 292.502238 -60.271799) (xy 292.553567 -60.293611)
			(xy 292.601173 -60.322665) (xy 292.644041 -60.35834) (xy 292.681258 -60.399877) (xy 292.712031 -60.44639)
			(xy 292.735703 -60.496887) (xy 292.751771 -60.550294) (xy 292.759891 -60.60547) (xy 292.7604 -60.633356)
			(xy 292.759891 -60.661242) (xy 292.751771 -60.716418) (xy 292.735703 -60.769825) (xy 292.712031 -60.820322)
			(xy 292.681258 -60.866835) (xy 292.644041 -60.908372) (xy 292.601173 -60.944047) (xy 292.553567 -60.973101)
			(xy 292.502238 -60.994913) (xy 292.448281 -61.009019) (xy 292.392844 -61.015119) (xy 292.33711 -61.013082)
			(xy 292.282267 -61.002952) (xy 292.229483 -60.984945) (xy 292.179883 -60.959444) (xy 292.134525 -60.926993)
			(xy 292.094376 -60.888284) (xy 292.06029 -60.844141) (xy 292.032994 -60.795506) (xy 292.013071 -60.743415)
			(xy 292.000945 -60.688978) (xy 291.996874 -60.633356) (xy 286.923988 -60.633356) (xy 286.923988 -61.06668)
			(xy 286.925766 -61.068966) (xy 287.344484 -61.487812) (xy 290.50437 -61.487812) (xy 290.508441 -61.43219)
			(xy 290.520567 -61.377753) (xy 290.54049 -61.325662) (xy 290.567786 -61.277027) (xy 290.601872 -61.232884)
			(xy 290.642021 -61.194175) (xy 290.687379 -61.161724) (xy 290.736979 -61.136223) (xy 290.789763 -61.118216)
			(xy 290.844606 -61.108086) (xy 290.90034 -61.106049) (xy 290.955777 -61.112149) (xy 291.009734 -61.126255)
			(xy 291.061063 -61.148067) (xy 291.108669 -61.177121) (xy 291.151537 -61.212796) (xy 291.188754 -61.254333)
			(xy 291.219527 -61.300846) (xy 291.243199 -61.351343) (xy 291.259267 -61.40475) (xy 291.267387 -61.459926)
			(xy 291.267896 -61.487812) (xy 291.267387 -61.515698) (xy 291.259267 -61.570874) (xy 291.243199 -61.624281)
			(xy 291.219527 -61.674778) (xy 291.188754 -61.721291) (xy 291.151537 -61.762828) (xy 291.108669 -61.798503)
			(xy 291.061063 -61.827557) (xy 291.009734 -61.849369) (xy 290.955777 -61.863475) (xy 290.90034 -61.869575)
			(xy 290.844606 -61.867538) (xy 290.789763 -61.857408) (xy 290.736979 -61.839401) (xy 290.687379 -61.8139)
			(xy 290.642021 -61.781449) (xy 290.601872 -61.74274) (xy 290.567786 -61.698597) (xy 290.54049 -61.649962)
			(xy 290.520567 -61.597871) (xy 290.508441 -61.543434) (xy 290.50437 -61.487812) (xy 287.344484 -61.487812)
			(xy 287.758124 -61.901578) (xy 287.774408 -61.918489) (xy 287.802406 -61.956171) (xy 287.824644 -61.997515)
			(xy 287.833054 -62.019434) (xy 287.833054 -62.020704) (xy 287.839404 -62.037468) (xy 287.840928 -62.042548)
			(xy 287.841436 -62.045088) (xy 287.841944 -62.04712) (xy 287.846791 -62.067215) (xy 287.851886 -62.108238)
			(xy 287.852021 -62.121034) (xy 288.442144 -62.121034) (xy 288.446215 -62.065412) (xy 288.458341 -62.010975)
			(xy 288.478264 -61.958884) (xy 288.50556 -61.910249) (xy 288.539646 -61.866106) (xy 288.579795 -61.827397)
			(xy 288.625153 -61.794946) (xy 288.674753 -61.769445) (xy 288.727537 -61.751438) (xy 288.78238 -61.741308)
			(xy 288.838114 -61.739271) (xy 288.893551 -61.745371) (xy 288.947508 -61.759477) (xy 288.998837 -61.781289)
			(xy 289.046443 -61.810343) (xy 289.089311 -61.846018) (xy 289.126528 -61.887555) (xy 289.157301 -61.934068)
			(xy 289.180973 -61.984565) (xy 289.197041 -62.037972) (xy 289.205161 -62.093148) (xy 289.20567 -62.121034)
			(xy 289.205161 -62.14892) (xy 289.197041 -62.204096) (xy 289.180973 -62.257503) (xy 289.157301 -62.308)
			(xy 289.126528 -62.354513) (xy 289.089311 -62.39605) (xy 289.046443 -62.431725) (xy 288.998837 -62.460779)
			(xy 288.947508 -62.482591) (xy 288.893551 -62.496697) (xy 288.838114 -62.502797) (xy 288.78238 -62.50076)
			(xy 288.727537 -62.49063) (xy 288.674753 -62.472623) (xy 288.625153 -62.447122) (xy 288.579795 -62.414671)
			(xy 288.539646 -62.375962) (xy 288.50556 -62.331819) (xy 288.478264 -62.283184) (xy 288.458341 -62.231093)
			(xy 288.446215 -62.176656) (xy 288.442144 -62.121034) (xy 287.852021 -62.121034) (xy 287.852104 -62.128908)
			(xy 287.852104 -62.8396) (xy 287.853076 -62.84813) (xy 287.859936 -62.863857) (xy 287.871604 -62.876436)
			(xy 287.879028 -62.880748) (xy 287.946084 -62.923928) (xy 287.946592 -62.924182) (xy 287.948624 -62.925198)
			(xy 287.957768 -62.929262) (xy 287.962594 -62.930532) (xy 287.967685 -62.931527) (xy 287.978055 -62.931657)
			(xy 287.983168 -62.930786) (xy 287.984184 -62.930532) (xy 287.99663 -62.927992) (xy 288.00171 -62.925706)
			(xy 288.026488 -62.915035) (xy 288.078296 -62.899992) (xy 288.131708 -62.8924) (xy 288.158682 -62.891924)
			(xy 288.185935 -62.892386) (xy 288.239886 -62.900141) (xy 288.292184 -62.915496) (xy 288.341765 -62.938138)
			(xy 288.387618 -62.967606) (xy 288.42881 -63.0033) (xy 288.464502 -63.044494) (xy 288.493969 -63.090348)
			(xy 288.516609 -63.139929) (xy 288.531962 -63.192228) (xy 288.539715 -63.246179) (xy 288.54019 -63.273432)
			(xy 288.539719 -63.300442) (xy 288.532097 -63.353921) (xy 288.517008 -63.40579) (xy 288.494755 -63.455013)
			(xy 288.465782 -63.500606) (xy 288.430669 -63.541657) (xy 288.390117 -63.577346) (xy 288.344938 -63.606959)
			(xy 288.296034 -63.629904) (xy 288.244383 -63.645723) (xy 288.191017 -63.6541) (xy 288.164016 -63.65494)
			(xy 288.15665 -63.65494) (xy 288.130468 -63.654525) (xy 288.07859 -63.647398) (xy 288.028175 -63.633243)
			(xy 288.003996 -63.62319) (xy 287.994344 -63.618872) (xy 287.968182 -63.618872) (xy 287.961374 -63.619093)
			(xy 287.948244 -63.622703) (xy 287.942274 -63.625984) (xy 287.904682 -63.64986) (xy 287.880044 -63.665608)
			(xy 287.871662 -63.672466) (xy 287.860232 -63.683896) (xy 287.858454 -63.68669) (xy 287.858454 -63.687198)
			(xy 287.855561 -63.69281) (xy 287.852352 -63.705018) (xy 287.852104 -63.711328) (xy 287.852104 -64.02705)
			(xy 287.85312 -64.036448) (xy 287.85312 -64.036956) (xy 287.854822 -64.044117) (xy 287.861652 -64.057146)
			(xy 287.866582 -64.06261) (xy 288.45891 -64.654938) (xy 288.46434 -64.65992) (xy 288.477378 -64.66677)
			(xy 288.484564 -64.6684) (xy 288.485072 -64.6684) (xy 288.49447 -64.669416) (xy 291.077904 -64.669416)
			(xy 291.081968 -64.669162) (xy 291.082476 -64.669162) (xy 291.094548 -64.667443) (xy 291.115134 -64.654447)
			(xy 291.121846 -64.64427) (xy 291.135816 -64.61887) (xy 291.16528 -64.56553) (xy 291.168238 -64.559806)
			(xy 291.171454 -64.547333) (xy 291.17163 -64.540892) (xy 291.17163 -64.52616) (xy 291.16401 -64.513968)
			(xy 291.150352 -64.491169) (xy 291.128789 -64.442594) (xy 291.114178 -64.391496) (xy 291.106802 -64.338865)
			(xy 291.106352 -64.312292) (xy 291.106838 -64.285041) (xy 291.114594 -64.231093) (xy 291.129949 -64.178798)
			(xy 291.152591 -64.129221) (xy 291.182057 -64.083371) (xy 291.217748 -64.04218) (xy 291.258939 -64.006489)
			(xy 291.304789 -63.977023) (xy 291.354366 -63.954381) (xy 291.406661 -63.939026) (xy 291.460609 -63.93127)
			(xy 291.515111 -63.93127) (xy 291.569059 -63.939026) (xy 291.621354 -63.954381) (xy 291.670931 -63.977023)
			(xy 291.716781 -64.006489) (xy 291.757972 -64.04218) (xy 291.793663 -64.083371) (xy 291.823129 -64.129221)
			(xy 291.845771 -64.178798) (xy 291.861126 -64.231093) (xy 291.868882 -64.285041) (xy 291.869368 -64.312292)
			(xy 291.868909 -64.338865) (xy 291.861535 -64.391496) (xy 291.846928 -64.442595) (xy 291.825372 -64.491172)
			(xy 291.81171 -64.513968) (xy 291.807646 -64.520318) (xy 291.80409 -64.53251) (xy 291.80409 -64.54267)
			(xy 291.804454 -64.548513) (xy 291.80753 -64.559805) (xy 291.810186 -64.565022) (xy 291.824156 -64.590168)
			(xy 291.824156 -64.590676) (xy 291.85489 -64.64554) (xy 291.859733 -64.652611) (xy 291.873112 -64.663305)
			(xy 291.889255 -64.669031) (xy 291.897816 -64.669416) (xy 292.074092 -64.669416) (xy 292.08222 -64.668654)
			(xy 292.082728 -64.668654) (xy 292.090162 -64.667084) (xy 292.103721 -64.660242) (xy 292.109398 -64.655192)
			(xy 292.464236 -64.3001) (xy 292.470916 -64.292689) (xy 292.478493 -64.274253) (xy 292.478968 -64.264286)
			(xy 292.478968 -63.101982) (xy 292.478735 -63.09561) (xy 292.47552 -63.083276) (xy 292.472618 -63.077598)
			(xy 292.466522 -63.066422) (xy 292.459664 -63.06185) (xy 292.453442 -63.058083) (xy 292.439502 -63.053949)
			(xy 292.432232 -63.053722) (xy 292.405562 -63.053722) (xy 292.396164 -63.057786) (xy 292.372665 -63.067187)
			(xy 292.323813 -63.080418) (xy 292.273642 -63.087094) (xy 292.248336 -63.087504) (xy 292.246812 -63.087504)
			(xy 292.23081 -63.08725) (xy 292.221666 -63.086742) (xy 292.192988 -63.084302) (xy 292.136789 -63.071885)
			(xy 292.083092 -63.051169) (xy 292.033115 -63.022624) (xy 291.987991 -62.986897) (xy 291.948745 -62.944798)
			(xy 291.916267 -62.897284) (xy 291.891292 -62.84543) (xy 291.874388 -62.790414) (xy 291.865937 -62.733483)
			(xy 291.866133 -62.675929) (xy 291.874969 -62.619057) (xy 291.883084 -62.591442) (xy 291.891541 -62.566063)
			(xy 291.914568 -62.517778) (xy 291.944117 -62.473184) (xy 291.979607 -62.433157) (xy 292.020342 -62.398482)
			(xy 292.065522 -62.36984) (xy 292.114262 -62.347792) (xy 292.165605 -62.332771) (xy 292.218543 -62.325072)
			(xy 292.245288 -62.324488) (xy 292.247574 -62.324488) (xy 292.271958 -62.32525) (xy 292.27272 -62.32525)
			(xy 292.274498 -62.325504) (xy 292.276022 -62.325504) (xy 292.30701 -62.32906) (xy 292.332384 -62.333538)
			(xy 292.381705 -62.348446) (xy 292.405308 -62.358778) (xy 292.405562 -62.359032) (xy 292.405816 -62.359032)
			(xy 292.407086 -62.35954) (xy 292.417246 -62.364366) (xy 292.427914 -62.364366) (xy 292.435095 -62.364119)
			(xy 292.44889 -62.36012) (xy 292.455092 -62.356492) (xy 292.455346 -62.356238) (xy 292.462398 -62.351393)
			(xy 292.473035 -62.338005) (xy 292.47867 -62.321862) (xy 292.478968 -62.313312) (xy 292.478968 -62.254384)
			(xy 292.478793 -62.248232) (xy 292.47583 -62.236291) (xy 292.473126 -62.230762) (xy 292.459662 -62.203868)
			(xy 292.440423 -62.146887) (xy 292.430339 -62.087597) (xy 292.429438 -62.057534) (xy 292.429438 -62.048136)
			(xy 292.430134 -62.021188) (xy 292.438179 -61.967886) (xy 292.453647 -61.916247) (xy 292.476232 -61.8673)
			(xy 292.505481 -61.82202) (xy 292.540814 -61.781309) (xy 292.581527 -61.745977) (xy 292.626807 -61.716728)
			(xy 292.675755 -61.694145) (xy 292.727394 -61.678677) (xy 292.780696 -61.670633) (xy 292.807644 -61.66993)
			(xy 292.816788 -61.66993) (xy 292.846897 -61.670791) (xy 292.906283 -61.680841) (xy 292.96335 -61.700107)
			(xy 292.99027 -61.713618) (xy 292.995801 -61.716314) (xy 293.007742 -61.71927) (xy 293.013892 -61.71946)
			(xy 293.161466 -61.71946) (xy 293.17134 -61.718993) (xy 293.189632 -61.711544) (xy 293.197026 -61.704982)
			(xy 293.364666 -61.537342) (xy 293.70401 -61.198252) (xy 293.710683 -61.190971) (xy 293.71838 -61.172804)
			(xy 293.718996 -61.162946) (xy 293.718996 -58.840624) (xy 293.715867 -58.836628) (xy 293.708316 -58.829849)
			(xy 293.70401 -58.827162) (xy 293.67353 -58.809382) (xy 293.62908 -58.783474) (xy 293.620924 -58.779497)
			(xy 293.60296 -58.777042) (xy 293.594028 -58.778648) (xy 293.578026 -58.782458) (xy 293.572438 -58.785506)
			(xy 293.544435 -58.799875) (xy 293.484888 -58.820249) (xy 293.422804 -58.83057) (xy 293.391336 -58.831226)
			(xy 293.390828 -58.831226) (xy 293.363573 -58.830765) (xy 293.309616 -58.823011) (xy 293.257312 -58.807657)
			(xy 293.207726 -58.785015) (xy 293.161867 -58.755546) (xy 293.120669 -58.719851) (xy 293.084971 -58.678655)
			(xy 293.055499 -58.632798) (xy 293.032853 -58.583214) (xy 293.017495 -58.530911) (xy 293.009737 -58.476955)
			(xy 293.009737 -58.422445) (xy 293.017495 -58.368489) (xy 293.032853 -58.316186) (xy 293.055499 -58.266602)
			(xy 293.084971 -58.220745) (xy 293.120669 -58.179549) (xy 293.161867 -58.143854) (xy 293.207726 -58.114385)
			(xy 293.257312 -58.091743) (xy 293.309616 -58.076389) (xy 293.363573 -58.068635) (xy 293.390828 -58.06821)
			(xy 293.39159 -58.06821) (xy 293.423497 -58.068848) (xy 293.486422 -58.079462) (xy 293.546699 -58.100411)
			(xy 293.574978 -58.1152) (xy 293.576756 -58.116216) (xy 293.586154 -58.121804) (xy 293.596822 -58.123074)
			(xy 293.59733 -58.123074) (xy 293.60225 -58.123525) (xy 293.612099 -58.122761) (xy 293.616888 -58.12155)
			(xy 293.625016 -58.11901) (xy 293.63162 -58.114692) (xy 293.70401 -58.072274) (xy 293.708325 -58.069599)
			(xy 293.715877 -58.062818) (xy 293.718996 -58.058812) (xy 293.718996 -54.889146) (xy 293.718607 -54.879621)
			(xy 293.711658 -54.861883) (xy 293.698705 -54.847915) (xy 293.690294 -54.843426) (xy 293.687246 -54.842156)
			(xy 293.680075 -54.839449) (xy 293.664822 -54.83803) (xy 293.657274 -54.839362) (xy 293.65067 -54.840632)
			(xy 293.63797 -54.84749) (xy 290.618164 -57.867296) (xy 291.84295 -57.867296) (xy 291.847021 -57.811674)
			(xy 291.859147 -57.757237) (xy 291.87907 -57.705146) (xy 291.906366 -57.656511) (xy 291.940452 -57.612368)
			(xy 291.980601 -57.573659) (xy 292.025959 -57.541208) (xy 292.075559 -57.515707) (xy 292.128343 -57.4977)
			(xy 292.183186 -57.48757) (xy 292.23892 -57.485533) (xy 292.294357 -57.491633) (xy 292.348314 -57.505739)
			(xy 292.399643 -57.527551) (xy 292.447249 -57.556605) (xy 292.490117 -57.59228) (xy 292.527334 -57.633817)
			(xy 292.558107 -57.68033) (xy 292.581779 -57.730827) (xy 292.597847 -57.784234) (xy 292.605967 -57.83941)
			(xy 292.606476 -57.867296) (xy 292.605967 -57.895182) (xy 292.597847 -57.950358) (xy 292.581779 -58.003765)
			(xy 292.558107 -58.054262) (xy 292.527334 -58.100775) (xy 292.490117 -58.142312) (xy 292.447249 -58.177987)
			(xy 292.399643 -58.207041) (xy 292.348314 -58.228853) (xy 292.294357 -58.242959) (xy 292.23892 -58.249059)
			(xy 292.183186 -58.247022) (xy 292.128343 -58.236892) (xy 292.075559 -58.218885) (xy 292.025959 -58.193384)
			(xy 291.980601 -58.160933) (xy 291.940452 -58.122224) (xy 291.906366 -58.078081) (xy 291.87907 -58.029446)
			(xy 291.859147 -57.977355) (xy 291.847021 -57.922918) (xy 291.84295 -57.867296) (xy 290.618164 -57.867296)
			(xy 290.312602 -58.172858) (xy 290.306252 -58.183526) (xy 290.304474 -58.189368) (xy 290.296024 -58.214933)
			(xy 290.272943 -58.263577) (xy 290.243256 -58.308496) (xy 290.207551 -58.348798) (xy 290.166538 -58.383683)
			(xy 290.121031 -58.412459) (xy 290.071931 -58.434556) (xy 290.020214 -58.449534) (xy 289.966905 -58.457097)
			(xy 289.939984 -58.457592) (xy 289.912734 -58.457105) (xy 289.858789 -58.449346) (xy 289.806497 -58.43399)
			(xy 289.756923 -58.411347) (xy 289.711076 -58.38188) (xy 289.669889 -58.346189) (xy 289.6342 -58.304999)
			(xy 289.604737 -58.259149) (xy 289.582099 -58.209573) (xy 289.566747 -58.15728) (xy 289.558993 -58.103334)
			(xy 289.558476 -58.076084) (xy 289.558222 -58.076084) (xy 289.558679 -58.049148) (xy 289.566245 -57.99581)
			(xy 289.581237 -57.944066) (xy 289.603358 -57.894945) (xy 289.632168 -57.849424) (xy 289.667095 -57.808407)
			(xy 289.707443 -57.772711) (xy 289.752411 -57.743044) (xy 289.801105 -57.719998) (xy 289.8267 -57.711594)
			(xy 289.826954 -57.711594) (xy 289.832791 -57.709586) (xy 289.843331 -57.70317) (xy 289.847782 -57.698894)
			(xy 293.325804 -54.221126) (xy 293.330133 -54.216494) (xy 293.336557 -54.20557) (xy 293.338504 -54.199536)
			(xy 293.339453 -54.196057) (xy 293.340474 -54.188918) (xy 293.340536 -54.185312) (xy 293.340536 -46.1518)
			(xy 293.340363 -46.145792) (xy 293.337531 -46.134114) (xy 293.334948 -46.128686) (xy 293.333107 -46.125213)
			(xy 293.328511 -46.118837) (xy 293.325804 -46.115986) (xy 287.528254 -40.318436) (xy 287.525402 -40.315732)
			(xy 287.519021 -40.311144) (xy 287.515554 -40.309292) (xy 287.510127 -40.30671) (xy 287.498447 -40.303887)
			(xy 287.49244 -40.303704) (xy 284.666944 -40.303704) (xy 284.662626 -40.30599) (xy 284.6342 -40.320905)
			(xy 284.573599 -40.342064) (xy 284.510316 -40.352813) (xy 284.478222 -40.353488) (xy 284.477714 -40.353488)
			(xy 284.450462 -40.353026) (xy 284.396512 -40.345271) (xy 284.344216 -40.329917) (xy 284.294636 -40.307276)
			(xy 284.248784 -40.27781) (xy 284.207592 -40.242118) (xy 284.171898 -40.200927) (xy 284.142431 -40.155076)
			(xy 284.119788 -40.105498) (xy 284.104432 -40.053201) (xy 284.096675 -39.999252) (xy 284.096675 -39.944748)
			(xy 284.104432 -39.890799) (xy 284.119788 -39.838502) (xy 284.142431 -39.788924) (xy 284.171898 -39.743073)
			(xy 284.207592 -39.701882) (xy 284.248784 -39.66619) (xy 284.294636 -39.636724) (xy 284.344216 -39.614083)
			(xy 284.396512 -39.598729) (xy 284.450462 -39.590974) (xy 284.477714 -39.590472) (xy 284.477968 -39.590472)
			(xy 284.502215 -39.59087) (xy 284.550314 -39.597045) (xy 284.597247 -39.60925) (xy 284.642261 -39.627289)
			(xy 284.663642 -39.638732) (xy 284.666436 -39.640256) (xy 287.233868 -39.640256) (xy 287.243915 -39.639836)
			(xy 287.262474 -39.632133) (xy 287.276653 -39.617895) (xy 287.280858 -39.60876) (xy 287.282382 -39.605458)
			(xy 287.283906 -39.601648) (xy 287.28543 -39.586662) (xy 287.283906 -39.57955) (xy 287.282181 -39.57236)
			(xy 287.27521 -39.559326) (xy 287.27019 -39.553896) (xy 283.939742 -36.223448) (xy 283.936893 -36.22074)
			(xy 283.930517 -36.216141) (xy 283.927042 -36.214304) (xy 283.921615 -36.211722) (xy 283.909935 -36.208902)
			(xy 283.903928 -36.208716) (xy 282.938474 -36.208716) (xy 282.929584 -36.216844) (xy 282.897072 -36.261802)
			(xy 282.880562 -36.284916) (xy 282.876825 -36.291025) (xy 282.872559 -36.304689) (xy 282.87218 -36.31184)
			(xy 282.87218 -36.331906) (xy 282.874466 -36.339526) (xy 282.882629 -36.367329) (xy 282.891423 -36.424601)
			(xy 282.891992 -36.453572) (xy 282.891531 -36.480826) (xy 282.883777 -36.534779) (xy 282.868423 -36.587079)
			(xy 282.845782 -36.636662) (xy 282.816314 -36.682517) (xy 282.78062 -36.723712) (xy 282.739427 -36.759407)
			(xy 282.693572 -36.788876) (xy 282.64399 -36.811519) (xy 282.591691 -36.826874) (xy 282.537738 -36.83463)
			(xy 282.510484 -36.83508) (xy 282.483361 -36.834602) (xy 282.429663 -36.826915) (xy 282.377594 -36.811699)
			(xy 282.328207 -36.789261) (xy 282.282496 -36.760052) (xy 282.241384 -36.724663) (xy 282.205699 -36.683807)
			(xy 282.176162 -36.638308) (xy 282.153368 -36.589083) (xy 282.137777 -36.537126) (xy 282.129704 -36.483484)
			(xy 282.128976 -36.456366) (xy 282.128976 -36.45281) (xy 282.129537 -36.423839) (xy 282.138345 -36.366569)
			(xy 282.146502 -36.338764) (xy 282.147264 -36.336224) (xy 282.148788 -36.331398) (xy 282.150312 -36.318444)
			(xy 282.150582 -36.310291) (xy 282.146577 -36.294485) (xy 282.142438 -36.287456) (xy 282.123388 -36.260786)
			(xy 282.0924 -36.21786) (xy 282.083002 -36.208716) (xy 281.56027 -36.208716) (xy 281.554428 -36.211764)
			(xy 281.551126 -36.213288) (xy 281.523324 -36.227422) (xy 281.464262 -36.24745) (xy 281.40273 -36.257611)
			(xy 281.371548 -36.258246) (xy 281.370786 -36.258246) (xy 281.343533 -36.257759) (xy 281.289581 -36.25)
			(xy 281.237283 -36.234642) (xy 281.187702 -36.211998) (xy 281.141849 -36.182529) (xy 281.100657 -36.146834)
			(xy 281.064963 -36.10564) (xy 281.035495 -36.059785) (xy 281.012853 -36.010204) (xy 280.997497 -35.957905)
			(xy 280.98974 -35.903953) (xy 280.98974 -35.849447) (xy 280.997497 -35.795495) (xy 281.012853 -35.743196)
			(xy 281.035495 -35.693615) (xy 281.064963 -35.64776) (xy 281.100657 -35.606566) (xy 281.141849 -35.570871)
			(xy 281.187702 -35.541402) (xy 281.237283 -35.518758) (xy 281.289581 -35.5034) (xy 281.343533 -35.495641)
			(xy 281.370786 -35.49523) (xy 281.371548 -35.49523) (xy 281.40273 -35.495867) (xy 281.464262 -35.50603)
			(xy 281.523328 -35.526047) (xy 281.551126 -35.540188) (xy 281.554428 -35.541712) (xy 281.56027 -35.54476)
			(xy 283.64561 -35.54476) (xy 283.654707 -35.544347) (xy 283.671729 -35.537911) (xy 283.685425 -35.525928)
			(xy 283.69006 -35.51809) (xy 283.692092 -35.51301) (xy 283.694818 -35.505978) (xy 283.696381 -35.490984)
			(xy 283.69514 -35.483546) (xy 283.69387 -35.476942) (xy 283.686758 -35.463734) (xy 281.350212 -33.127188)
			(xy 281.332182 -33.108416) (xy 281.301607 -33.066298) (xy 281.277985 -33.019922) (xy 281.261897 -32.970425)
			(xy 281.253737 -32.919023) (xy 281.253184 -32.893) (xy 281.253184 -29.692092) (xy 281.253716 -29.66607)
			(xy 281.261891 -29.614672) (xy 281.277993 -29.565182) (xy 281.301627 -29.518813) (xy 281.332212 -29.476704)
			(xy 281.350212 -29.457904) (xy 281.920696 -28.88742) (xy 281.926811 -28.880735) (xy 281.934288 -28.864245)
			(xy 281.935552 -28.846184) (xy 281.933396 -28.837382) (xy 281.93111 -28.832048) (xy 281.928024 -28.825231)
			(xy 281.918603 -28.813612) (xy 281.912568 -28.809188) (xy 281.90698 -28.805378) (xy 281.892502 -28.80106)
			(xy 279.273254 -28.80106) (xy 279.247168 -28.80057) (xy 279.19564 -28.792397) (xy 279.146027 -28.77626)
			(xy 279.099551 -28.752556) (xy 279.057357 -28.72187) (xy 279.038558 -28.703778) (xy 278.014684 -27.67965)
			(xy 278.008708 -27.674201) (xy 277.994203 -27.66707) (xy 277.986236 -27.66568) (xy 277.979124 -27.665172)
			(xy 276.933406 -27.665172) (xy 276.907384 -27.664641) (xy 276.855983 -27.656469) (xy 276.80649 -27.640371)
			(xy 276.760117 -27.616741) (xy 276.718003 -27.586161) (xy 276.699218 -27.568144) (xy 275.746972 -26.615644)
			(xy 275.740365 -26.609699) (xy 275.724201 -26.602342) (xy 275.706496 -26.600951) (xy 275.689381 -26.605694)
			(xy 275.681948 -26.610564) (xy 275.669139 -26.620386) (xy 275.649986 -26.646347) (xy 275.639876 -26.676984)
			(xy 275.639276 -26.693114) (xy 275.639276 -27.342846) (xy 275.638786 -27.37283) (xy 275.630958 -27.432286)
			(xy 275.615437 -27.490211) (xy 275.592488 -27.545615) (xy 275.562504 -27.597549) (xy 275.525998 -27.645125)
			(xy 275.483593 -27.68753) (xy 275.436017 -27.724036) (xy 275.384083 -27.75402) (xy 275.328679 -27.776969)
			(xy 275.270754 -27.79249) (xy 275.211298 -27.800318) (xy 275.15133 -27.800318) (xy 275.091874 -27.79249)
			(xy 275.033949 -27.776969) (xy 274.978545 -27.75402) (xy 274.926611 -27.724036) (xy 274.879035 -27.68753)
			(xy 274.83663 -27.645125) (xy 274.800124 -27.597549) (xy 274.77014 -27.545615) (xy 274.747191 -27.490211)
			(xy 274.73167 -27.432286) (xy 274.723842 -27.37283) (xy 274.723352 -27.342846) (xy 274.723352 -26.479246)
			(xy 274.723883 -26.448026) (xy 274.732367 -26.386166) (xy 274.74917 -26.32603) (xy 274.773981 -26.268732)
			(xy 274.80634 -26.215332) (xy 274.84565 -26.166819) (xy 274.891181 -26.124092) (xy 274.94209 -26.087942)
			(xy 274.997436 -26.059037) (xy 275.026628 -26.047954) (xy 275.037042 -26.044144) (xy 275.052282 -26.029412)
			(xy 275.055584 -26.025602) (xy 275.058664 -26.021652) (xy 275.063407 -26.01283) (xy 275.064982 -26.008076)
			(xy 275.067776 -25.99563) (xy 275.067776 -25.995122) (xy 275.084032 -25.923494) (xy 275.085118 -25.915003)
			(xy 275.082267 -25.898133) (xy 275.078444 -25.890474) (xy 275.073364 -25.8826) (xy 274.67814 -25.487376)
			(xy 274.67306 -25.483058) (xy 274.630642 -25.453086) (xy 274.520914 -25.37587) (xy 274.514387 -25.371566)
			(xy 274.499516 -25.366772) (xy 274.491704 -25.366472) (xy 272.904966 -25.366472) (xy 272.901664 -25.366472)
			(xy 272.892642 -25.367416) (xy 272.876101 -25.37483) (xy 272.869406 -25.38095) (xy 272.795492 -25.455118)
			(xy 272.763742 -25.486868) (xy 272.757392 -25.497536) (xy 272.755614 -25.503378) (xy 272.747164 -25.528944)
			(xy 272.724083 -25.57759) (xy 272.694396 -25.622511) (xy 272.658692 -25.662815) (xy 272.61768 -25.697703)
			(xy 272.572173 -25.726483) (xy 272.523073 -25.748584) (xy 272.471356 -25.763567) (xy 272.418046 -25.771136)
			(xy 272.391124 -25.771602) (xy 272.36387 -25.77114) (xy 272.309917 -25.763386) (xy 272.257617 -25.748032)
			(xy 272.208034 -25.725391) (xy 272.162178 -25.695923) (xy 272.120983 -25.66023) (xy 272.085287 -25.619036)
			(xy 272.055818 -25.573182) (xy 272.033174 -25.5236) (xy 272.017818 -25.471301) (xy 272.010061 -25.417348)
			(xy 272.009616 -25.390094) (xy 272.009362 -25.390094) (xy 272.009819 -25.363158) (xy 272.017383 -25.30982)
			(xy 272.032376 -25.258077) (xy 272.054497 -25.208957) (xy 272.083308 -25.163437) (xy 272.118236 -25.122422)
			(xy 272.158586 -25.086729) (xy 272.203555 -25.057066) (xy 272.25225 -25.034023) (xy 272.27784 -25.025604)
			(xy 272.278094 -25.025604) (xy 272.283928 -25.023593) (xy 272.294464 -25.017171) (xy 272.298922 -25.012904)
			(xy 272.34134 -24.970486) (xy 272.341783 -24.96688) (xy 272.341789 -24.959613) (xy 272.34134 -24.956008)
			(xy 271.98955 -24.604218) (xy 271.964402 -24.578277) (xy 271.919983 -24.521292) (xy 271.882899 -24.459283)
			(xy 271.853713 -24.393189) (xy 271.832865 -24.324011) (xy 271.826228 -24.288496) (xy 271.822164 -24.263858)
			(xy 271.818111 -24.260147) (xy 271.80876 -24.254378) (xy 271.803622 -24.252428) (xy 271.736566 -24.231092)
			(xy 271.736058 -24.231092) (xy 271.723866 -24.227282) (xy 271.71523 -24.225504) (xy 271.708626 -24.224996)
			(xy 271.703038 -24.224996) (xy 271.693894 -24.228806) (xy 271.689327 -24.230809) (xy 271.681005 -24.2363)
			(xy 271.677384 -24.239728) (xy 271.492472 -24.42464) (xy 271.473701 -24.442671) (xy 271.431584 -24.473248)
			(xy 271.385207 -24.496871) (xy 271.33571 -24.51296) (xy 271.284307 -24.521119) (xy 271.258284 -24.521668)
			(xy 270.070072 -24.521668) (xy 270.065754 -24.523954) (xy 270.037329 -24.538872) (xy 269.976728 -24.560038)
			(xy 269.913445 -24.570792) (xy 269.88135 -24.571452) (xy 269.880842 -24.571452) (xy 269.853584 -24.570992)
			(xy 269.799622 -24.563239) (xy 269.747313 -24.547885) (xy 269.697722 -24.525242) (xy 269.651858 -24.495772)
			(xy 269.610656 -24.460074) (xy 269.574954 -24.418875) (xy 269.545478 -24.373015) (xy 269.52283 -24.323426)
			(xy 269.50747 -24.271119) (xy 269.499711 -24.217158) (xy 269.499711 -24.162642) (xy 269.50747 -24.108681)
			(xy 269.52283 -24.056374) (xy 269.545478 -24.006785) (xy 269.574954 -23.960925) (xy 269.610656 -23.919726)
			(xy 269.651858 -23.884028) (xy 269.697722 -23.854558) (xy 269.747313 -23.831915) (xy 269.799622 -23.816561)
			(xy 269.853584 -23.808808) (xy 269.880842 -23.808436) (xy 269.881096 -23.808436) (xy 269.905344 -23.808829)
			(xy 269.953447 -23.814996) (xy 270.000385 -23.827192) (xy 270.045405 -23.845222) (xy 270.06677 -23.856696)
			(xy 270.069564 -23.85822) (xy 271.09928 -23.85822) (xy 271.102582 -23.85822) (xy 271.1116 -23.857269)
			(xy 271.12813 -23.849843) (xy 271.13484 -23.843742) (xy 271.21485 -23.763478) (xy 271.253966 -23.724362)
			(xy 271.25422 -23.710646) (xy 271.252188 -23.701756) (xy 271.24279 -23.673562) (xy 271.24279 -23.673054)
			(xy 271.221454 -23.603712) (xy 271.214088 -23.597108) (xy 271.18945 -23.59279) (xy 271.156604 -23.586392)
			(xy 271.092532 -23.567072) (xy 271.031081 -23.540574) (xy 270.97305 -23.507244) (xy 270.919198 -23.467516)
			(xy 270.870225 -23.421908) (xy 270.82677 -23.371015) (xy 270.7894 -23.3155) (xy 270.758602 -23.256087)
			(xy 270.74622 -23.224998) (xy 270.737838 -23.203154) (xy 270.733804 -23.200575) (xy 270.724978 -23.196865)
			(xy 270.720312 -23.195788) (xy 270.671036 -23.185374) (xy 270.670528 -23.185374) (xy 270.634714 -23.177754)
			(xy 270.62049 -23.178008) (xy 270.35887 -23.439628) (xy 270.335284 -23.462565) (xy 270.283846 -23.503589)
			(xy 270.228139 -23.538597) (xy 270.168862 -23.567147) (xy 270.106762 -23.588882) (xy 270.042619 -23.603526)
			(xy 269.977239 -23.610897) (xy 269.944342 -23.611332) (xy 269.908911 -23.610821) (xy 269.838565 -23.602284)
			(xy 269.769761 -23.58533) (xy 269.703502 -23.560205) (xy 269.640755 -23.527277) (xy 269.582435 -23.487026)
			(xy 269.529392 -23.440037) (xy 269.4824 -23.386998) (xy 269.442144 -23.328681) (xy 269.409212 -23.265936)
			(xy 269.384083 -23.199679) (xy 269.367124 -23.130876) (xy 269.358582 -23.060531) (xy 269.35811 -23.0251)
			(xy 269.358554 -22.992203) (xy 269.365921 -22.926823) (xy 269.380563 -22.862679) (xy 269.402294 -22.800578)
			(xy 269.430843 -22.7413) (xy 269.465849 -22.685592) (xy 269.506873 -22.634155) (xy 269.529814 -22.610572)
			(xy 270.032734 -22.107652) (xy 270.056321 -22.084716) (xy 270.107759 -22.043693) (xy 270.163467 -22.008687)
			(xy 270.222743 -21.980138) (xy 270.284843 -21.958405) (xy 270.348986 -21.943761) (xy 270.414365 -21.936391)
			(xy 270.447262 -21.935948) (xy 270.468598 -21.936456) (xy 274.246594 -21.936456) (xy 274.255297 -21.936107)
			(xy 274.271703 -21.930295) (xy 274.285225 -21.919336) (xy 274.290028 -21.912072) (xy 274.301966 -21.892514)
			(xy 274.301966 -21.892006) (xy 274.31746 -21.866098) (xy 274.322286 -21.85416) (xy 274.32381 -21.842476)
			(xy 274.324064 -21.830792) (xy 274.318476 -21.818854) (xy 274.317968 -21.817838) (xy 274.304069 -21.790282)
			(xy 274.284387 -21.731792) (xy 274.274387 -21.670894) (xy 274.273772 -21.640038) (xy 274.273772 -21.63572)
			(xy 274.27454 -21.607318) (xy 274.283452 -21.551206) (xy 274.300592 -21.497037) (xy 274.325578 -21.44601)
			(xy 274.357859 -21.399256) (xy 274.376896 -21.378164) (xy 274.383754 -21.371052) (xy 274.38731 -21.362162)
			(xy 274.38985 -21.353018) (xy 274.390612 -21.344128) (xy 274.390612 -21.27377) (xy 274.390548 -21.269636)
			(xy 274.389279 -21.261468) (xy 274.388072 -21.257514) (xy 274.38731 -21.255736) (xy 274.384008 -21.2471)
			(xy 274.376896 -21.23948) (xy 274.357625 -21.218153) (xy 274.325059 -21.170789) (xy 274.299966 -21.119076)
			(xy 274.282914 -21.064184) (xy 274.274289 -21.007356) (xy 274.274287 -20.949876) (xy 274.282907 -20.893047)
			(xy 274.299954 -20.838154) (xy 274.325042 -20.786439) (xy 274.357605 -20.739073) (xy 274.376896 -20.717764)
			(xy 274.384008 -20.710144) (xy 274.38731 -20.701508) (xy 274.388072 -20.69973) (xy 274.389305 -20.695782)
			(xy 274.390584 -20.68761) (xy 274.390612 -20.683474) (xy 274.390612 -20.61337) (xy 274.390548 -20.609236)
			(xy 274.389279 -20.601068) (xy 274.388072 -20.597114) (xy 274.38731 -20.595336) (xy 274.384008 -20.5867)
			(xy 274.376896 -20.57908) (xy 274.357625 -20.557753) (xy 274.325059 -20.510389) (xy 274.299966 -20.458676)
			(xy 274.282914 -20.403784) (xy 274.274289 -20.346956) (xy 274.274287 -20.289476) (xy 274.282907 -20.232647)
			(xy 274.299954 -20.177754) (xy 274.325042 -20.126039) (xy 274.357605 -20.078673) (xy 274.376896 -20.057364)
			(xy 274.384008 -20.049744) (xy 274.38731 -20.041108) (xy 274.388072 -20.03933) (xy 274.389305 -20.035382)
			(xy 274.390584 -20.02721) (xy 274.390612 -20.023074) (xy 274.390612 -19.95297) (xy 274.390548 -19.948836)
			(xy 274.389279 -19.940668) (xy 274.388072 -19.936714) (xy 274.38731 -19.934936) (xy 274.384008 -19.9263)
			(xy 274.376896 -19.91868) (xy 274.357625 -19.897353) (xy 274.325059 -19.849989) (xy 274.299966 -19.798276)
			(xy 274.282914 -19.743384) (xy 274.274289 -19.686556) (xy 274.274287 -19.629076) (xy 274.282907 -19.572247)
			(xy 274.299954 -19.517354) (xy 274.325042 -19.465639) (xy 274.357605 -19.418273) (xy 274.376896 -19.396964)
			(xy 274.384008 -19.389344) (xy 274.38731 -19.380708) (xy 274.388072 -19.37893) (xy 274.389305 -19.374982)
			(xy 274.390584 -19.36681) (xy 274.390612 -19.362674) (xy 274.390612 -19.29257) (xy 274.390548 -19.288436)
			(xy 274.389279 -19.280268) (xy 274.388072 -19.276314) (xy 274.38731 -19.274536) (xy 274.384008 -19.2659)
			(xy 274.376896 -19.25828) (xy 274.357625 -19.236953) (xy 274.32506 -19.18959) (xy 274.299967 -19.137879)
			(xy 274.282915 -19.082988) (xy 274.27429 -19.026161) (xy 274.273772 -18.997422) (xy 274.274258 -18.970171)
			(xy 274.282014 -18.916223) (xy 274.297369 -18.863928) (xy 274.320011 -18.814351) (xy 274.349477 -18.768501)
			(xy 274.385168 -18.72731) (xy 274.426359 -18.691619) (xy 274.472209 -18.662153) (xy 274.521786 -18.639511)
			(xy 274.574081 -18.624156) (xy 274.628029 -18.6164) (xy 274.682531 -18.6164) (xy 274.736479 -18.624156)
			(xy 274.788774 -18.639511) (xy 274.838351 -18.662153) (xy 274.884201 -18.691619) (xy 274.925392 -18.72731)
			(xy 274.961083 -18.768501) (xy 274.990549 -18.814351) (xy 275.013191 -18.863928) (xy 275.028546 -18.916223)
			(xy 275.036302 -18.970171) (xy 275.036788 -18.997422) (xy 275.036265 -19.02616) (xy 275.02764 -19.082986)
			(xy 275.010587 -19.137875) (xy 274.985492 -19.189585) (xy 274.952925 -19.236944) (xy 274.933664 -19.25828)
			(xy 274.926552 -19.2659) (xy 274.92325 -19.274536) (xy 274.922488 -19.276314) (xy 274.92126 -19.280263)
			(xy 274.919989 -19.288434) (xy 274.919948 -19.29257) (xy 274.919948 -19.362674) (xy 274.920015 -19.366807)
			(xy 274.921289 -19.374974) (xy 274.922488 -19.37893) (xy 274.92325 -19.380708) (xy 274.926552 -19.389344)
			(xy 274.933664 -19.396964) (xy 274.952934 -19.41829) (xy 274.985497 -19.465652) (xy 275.010586 -19.517363)
			(xy 275.027634 -19.572252) (xy 275.036254 -19.629078) (xy 275.036251 -19.686554) (xy 275.027626 -19.743379)
			(xy 275.010574 -19.798267) (xy 274.98548 -19.849976) (xy 274.952914 -19.897335) (xy 274.933664 -19.91868)
			(xy 274.926552 -19.9263) (xy 274.92325 -19.934936) (xy 274.922488 -19.936714) (xy 274.92126 -19.940663)
			(xy 274.919989 -19.948834) (xy 274.919948 -19.95297) (xy 274.919948 -20.023074) (xy 274.920015 -20.027207)
			(xy 274.921289 -20.035374) (xy 274.922488 -20.03933) (xy 274.92325 -20.041108) (xy 274.926552 -20.049744)
			(xy 274.933664 -20.057364) (xy 274.952934 -20.07869) (xy 274.985497 -20.126052) (xy 275.010586 -20.177763)
			(xy 275.027634 -20.232652) (xy 275.036254 -20.289478) (xy 275.036251 -20.346954) (xy 275.027626 -20.403779)
			(xy 275.010574 -20.458667) (xy 274.98548 -20.510376) (xy 274.952914 -20.557735) (xy 274.933664 -20.57908)
			(xy 274.926552 -20.5867) (xy 274.92325 -20.595336) (xy 274.922488 -20.597114) (xy 274.92126 -20.601063)
			(xy 274.919989 -20.609234) (xy 274.919948 -20.61337) (xy 274.919948 -20.683474) (xy 274.920015 -20.687607)
			(xy 274.921289 -20.695774) (xy 274.922488 -20.69973) (xy 274.92325 -20.701508) (xy 274.926552 -20.710144)
			(xy 274.933664 -20.717764) (xy 274.952934 -20.73909) (xy 274.985497 -20.786452) (xy 275.010586 -20.838163)
			(xy 275.027634 -20.893052) (xy 275.036254 -20.949878) (xy 275.036251 -21.007354) (xy 275.027626 -21.064179)
			(xy 275.010574 -21.119067) (xy 274.98548 -21.170776) (xy 274.952914 -21.218135) (xy 274.933664 -21.23948)
			(xy 274.926552 -21.2471) (xy 274.92325 -21.255736) (xy 274.922488 -21.257514) (xy 274.92126 -21.261463)
			(xy 274.919989 -21.269634) (xy 274.919948 -21.27377) (xy 274.919948 -21.344128) (xy 274.92071 -21.353018)
			(xy 274.92325 -21.362162) (xy 274.926806 -21.371052) (xy 274.934172 -21.378672) (xy 274.953115 -21.399719)
			(xy 274.985211 -21.446367) (xy 275.01006 -21.497246) (xy 275.027116 -21.551239) (xy 275.036003 -21.607161)
			(xy 275.036788 -21.635466) (xy 275.036788 -21.63953) (xy 275.036187 -21.67047) (xy 275.026211 -21.731541)
			(xy 275.006523 -21.790206) (xy 274.992592 -21.817838) (xy 274.991068 -21.820632) (xy 274.988945 -21.825769)
			(xy 274.986758 -21.836664) (xy 274.98675 -21.842222) (xy 274.987004 -21.855684) (xy 275.008594 -21.892006)
			(xy 275.008594 -21.892514) (xy 275.020532 -21.912072) (xy 275.025348 -21.919334) (xy 275.038849 -21.930333)
			(xy 275.055259 -21.93616) (xy 275.063966 -21.936456) (xy 279.462738 -21.936456) (xy 279.470447 -21.936227)
			(xy 279.485185 -21.931703) (xy 279.491694 -21.927566) (xy 279.495758 -21.924264) (xy 279.828752 -21.59127)
			(xy 279.82926 -21.583904) (xy 279.82926 -21.567902) (xy 279.826212 -21.556218) (xy 279.821894 -21.547836)
			(xy 279.80836 -21.520574) (xy 279.789164 -21.46282) (xy 279.779377 -21.402751) (xy 279.778714 -21.372322)
			(xy 279.778714 -21.36394) (xy 279.779709 -21.337044) (xy 279.788329 -21.283919) (xy 279.80433 -21.232532)
			(xy 279.827396 -21.183905) (xy 279.857067 -21.139002) (xy 279.892755 -21.098716) (xy 279.933752 -21.063846)
			(xy 279.979243 -21.035085) (xy 280.028325 -21.013004) (xy 280.080023 -20.998041) (xy 280.133312 -20.990493)
			(xy 280.160222 -20.990052) (xy 280.160476 -20.990052) (xy 280.176478 -20.990306) (xy 280.187146 -20.990814)
			(xy 280.19629 -20.987258) (xy 280.200653 -20.985504) (xy 280.208701 -20.980643) (xy 280.212292 -20.977606)
			(xy 280.226008 -20.964652) (xy 280.226516 -20.964144) (xy 280.268426 -20.923758) (xy 280.272236 -20.919186)
			(xy 280.272236 -19.452844) (xy 280.272801 -19.417133) (xy 280.281548 -19.346248) (xy 280.298845 -19.276951)
			(xy 280.324434 -19.21027) (xy 280.357938 -19.147193) (xy 280.398859 -19.088656) (xy 280.446591 -19.035525)
			(xy 280.47315 -19.011646) (xy 280.483818 -19.002248) (xy 280.48585 -18.99793) (xy 280.487856 -18.993216)
			(xy 280.490155 -18.983234) (xy 280.490422 -18.978118) (xy 280.491946 -18.922238) (xy 280.491946 -18.921476)
			(xy 280.492454 -18.906998) (xy 280.44394 -18.858738) (xy 280.417231 -18.831162) (xy 280.37052 -18.770238)
			(xy 280.332168 -18.703733) (xy 280.31694 -18.668492) (xy 280.302911 -18.633085) (xy 280.283093 -18.55955)
			(xy 280.272975 -18.484066) (xy 280.272236 -18.445988) (xy 280.272236 -18.44421) (xy 280.272749 -18.408796)
			(xy 280.281285 -18.338484) (xy 280.298235 -18.269714) (xy 280.323351 -18.203488) (xy 280.356266 -18.140772)
			(xy 280.396501 -18.082482) (xy 280.443469 -18.029466) (xy 280.496485 -17.982498) (xy 280.554776 -17.942264)
			(xy 280.617491 -17.909349) (xy 280.683717 -17.884234) (xy 280.752488 -17.867285) (xy 280.8228 -17.858749)
			(xy 280.858214 -17.858232) (xy 280.867612 -17.858232) (xy 280.904407 -17.859433) (xy 280.97728 -17.869883)
			(xy 281.048276 -17.889362) (xy 281.082496 -17.902936) (xy 281.117724 -17.91819) (xy 281.184222 -17.956545)
			(xy 281.245147 -18.003249) (xy 281.272742 -18.029936) (xy 281.60345 -18.360898) (xy 281.841194 -18.598642)
			(xy 281.86409 -18.622207) (xy 281.905042 -18.673591) (xy 281.939987 -18.729234) (xy 281.968488 -18.788438)
			(xy 281.990188 -18.850458) (xy 282.004812 -18.914516) (xy 282.012178 -18.979809) (xy 282.012644 -19.012662)
			(xy 282.012644 -21.474684) (xy 282.015573 -21.478429) (xy 282.022607 -21.484824) (xy 282.026614 -21.487384)
			(xy 282.032456 -21.49094) (xy 282.119832 -21.527516) (xy 282.126448 -21.530031) (xy 282.140497 -21.531709)
			(xy 282.147518 -21.530818) (xy 282.736798 -20.941538) (xy 282.737304 -20.937744) (xy 282.737307 -20.930091)
			(xy 282.736798 -20.926298) (xy 282.736798 -20.925536) (xy 282.731464 -20.892516) (xy 282.72359 -20.842986)
			(xy 282.720755 -20.831917) (xy 282.706875 -20.813795) (xy 282.69692 -20.808188) (xy 282.690062 -20.804632)
			(xy 282.664289 -20.790258) (xy 282.617119 -20.754803) (xy 282.575961 -20.712516) (xy 282.541795 -20.664402)
			(xy 282.515435 -20.611608) (xy 282.497506 -20.555387) (xy 282.488436 -20.497079) (xy 282.487878 -20.467574)
			(xy 282.488366 -20.440324) (xy 282.496125 -20.386378) (xy 282.511482 -20.334085) (xy 282.534125 -20.284511)
			(xy 282.563591 -20.238663) (xy 282.599283 -20.197474) (xy 282.640472 -20.161784) (xy 282.686321 -20.132319)
			(xy 282.735897 -20.109678) (xy 282.78819 -20.094322) (xy 282.842136 -20.086565) (xy 282.869386 -20.086066)
			(xy 282.896535 -20.086543) (xy 282.950284 -20.094239) (xy 283.0024 -20.109478) (xy 283.051828 -20.131951)
			(xy 283.097571 -20.161204) (xy 283.138705 -20.196648) (xy 283.174399 -20.237565) (xy 283.203931 -20.283129)
			(xy 283.226705 -20.332419) (xy 283.242261 -20.384441) (xy 283.250284 -20.438142) (xy 283.250894 -20.465288)
			(xy 283.250894 -20.467828) (xy 283.250297 -20.498333) (xy 283.240605 -20.558568) (xy 283.23159 -20.587716)
			(xy 283.230066 -20.592288) (xy 283.228796 -20.601432) (xy 283.228796 -20.601686) (xy 283.227272 -20.611338)
			(xy 283.23032 -20.623276) (xy 283.231376 -20.626895) (xy 283.234432 -20.633787) (xy 283.236416 -20.636992)
			(xy 283.253434 -20.660614) (xy 283.264356 -20.6756) (xy 283.270452 -20.682966) (xy 283.277088 -20.688771)
			(xy 283.29319 -20.695922) (xy 283.301948 -20.696936) (xy 284.848046 -20.696936) (xy 284.880923 -20.697415)
			(xy 284.946261 -20.704809) (xy 285.010362 -20.719464) (xy 285.026541 -20.72513) (xy 289.380434 -20.72513)
			(xy 289.384404 -20.594996) (xy 289.3963 -20.465346) (xy 289.416079 -20.336663) (xy 289.443665 -20.209424)
			(xy 289.478958 -20.084105) (xy 289.521824 -19.961169) (xy 289.572106 -19.841076) (xy 289.629615 -19.724272)
			(xy 289.694139 -19.61119) (xy 289.765436 -19.502253) (xy 289.843241 -19.397865) (xy 289.927266 -19.298414)
			(xy 290.017198 -19.204271) (xy 290.112702 -19.115786) (xy 290.213422 -19.033287) (xy 290.318984 -18.957082)
			(xy 290.428996 -18.887455) (xy 290.543048 -18.824664) (xy 290.660716 -18.768942) (xy 290.781562 -18.720498)
			(xy 290.905137 -18.679511) (xy 291.03098 -18.646134) (xy 291.158625 -18.620491) (xy 291.287595 -18.602677)
			(xy 291.417411 -18.592759) (xy 291.54759 -18.590774) (xy 291.677649 -18.596728) (xy 291.807102 -18.610601)
			(xy 291.935469 -18.632339) (xy 292.062272 -18.661863) (xy 292.187039 -18.699062) (xy 292.309306 -18.743798)
			(xy 292.428619 -18.795906) (xy 292.544532 -18.855189) (xy 292.656617 -18.92143) (xy 292.764454 -18.99438)
			(xy 292.867643 -19.073768) (xy 292.965801 -19.1593) (xy 293.058562 -19.250657) (xy 293.145581 -19.347499)
			(xy 293.226534 -19.449466) (xy 293.30112 -19.556178) (xy 293.369061 -19.667239) (xy 293.430106 -19.782235)
			(xy 293.484027 -19.900739) (xy 293.530622 -20.02231) (xy 293.56972 -20.146495) (xy 293.601174 -20.272833)
			(xy 293.624868 -20.400854) (xy 293.640712 -20.53008) (xy 293.64865 -20.660033) (xy 293.649146 -20.72513)
			(xy 293.64865 -20.790227) (xy 293.640712 -20.92018) (xy 293.624868 -21.049406) (xy 293.601174 -21.177427)
			(xy 293.56972 -21.303765) (xy 293.530622 -21.42795) (xy 293.484027 -21.549521) (xy 293.430106 -21.668025)
			(xy 293.369061 -21.783021) (xy 293.30112 -21.894082) (xy 293.226534 -22.000794) (xy 293.145581 -22.102761)
			(xy 293.058562 -22.199603) (xy 292.965801 -22.29096) (xy 292.867643 -22.376492) (xy 292.764454 -22.45588)
			(xy 292.656617 -22.52883) (xy 292.544532 -22.595071) (xy 292.428619 -22.654354) (xy 292.309306 -22.706462)
			(xy 292.187039 -22.751198) (xy 292.062272 -22.788397) (xy 291.935469 -22.817921) (xy 291.807102 -22.839659)
			(xy 291.677649 -22.853532) (xy 291.54759 -22.859486) (xy 291.417411 -22.857501) (xy 291.287595 -22.847583)
			(xy 291.158625 -22.829769) (xy 291.03098 -22.804126) (xy 290.905137 -22.770749) (xy 290.781562 -22.729762)
			(xy 290.660716 -22.681318) (xy 290.543048 -22.625596) (xy 290.428996 -22.562805) (xy 290.318984 -22.493178)
			(xy 290.213422 -22.416973) (xy 290.112702 -22.334474) (xy 290.017198 -22.245989) (xy 289.927266 -22.151846)
			(xy 289.843241 -22.052395) (xy 289.765436 -21.948007) (xy 289.694139 -21.83907) (xy 289.629615 -21.725988)
			(xy 289.572106 -21.609184) (xy 289.521824 -21.489091) (xy 289.478958 -21.366155) (xy 289.443665 -21.240836)
			(xy 289.416079 -21.113597) (xy 289.3963 -20.984914) (xy 289.384404 -20.855264) (xy 289.380434 -20.72513)
			(xy 285.026541 -20.72513) (xy 285.072421 -20.741198) (xy 285.13166 -20.769738) (xy 285.187334 -20.804724)
			(xy 285.238746 -20.845718) (xy 285.26232 -20.86864) (xy 285.834836 -21.441156) (xy 285.857784 -21.46471)
			(xy 285.898807 -21.516108) (xy 285.933813 -21.571778) (xy 285.962362 -21.631021) (xy 285.984093 -21.693088)
			(xy 285.998733 -21.7572) (xy 286.006098 -21.822549) (xy 286.006427 -21.847048) (xy 286.27273 -21.847048)
			(xy 286.276801 -21.791426) (xy 286.288927 -21.736989) (xy 286.30885 -21.684898) (xy 286.336146 -21.636263)
			(xy 286.370232 -21.59212) (xy 286.410381 -21.553411) (xy 286.455739 -21.52096) (xy 286.505339 -21.495459)
			(xy 286.558123 -21.477452) (xy 286.612966 -21.467322) (xy 286.6687 -21.465285) (xy 286.724137 -21.471385)
			(xy 286.778094 -21.485491) (xy 286.829423 -21.507303) (xy 286.877029 -21.536357) (xy 286.919897 -21.572032)
			(xy 286.957114 -21.613569) (xy 286.987887 -21.660082) (xy 287.011559 -21.710579) (xy 287.027627 -21.763986)
			(xy 287.035747 -21.819162) (xy 287.036256 -21.847048) (xy 287.035747 -21.874934) (xy 287.027627 -21.93011)
			(xy 287.011559 -21.983517) (xy 286.987887 -22.034014) (xy 286.957114 -22.080527) (xy 286.919897 -22.122064)
			(xy 286.877029 -22.157739) (xy 286.829423 -22.186793) (xy 286.778094 -22.208605) (xy 286.724137 -22.222711)
			(xy 286.6687 -22.228811) (xy 286.612966 -22.226774) (xy 286.558123 -22.216644) (xy 286.505339 -22.198637)
			(xy 286.455739 -22.173136) (xy 286.410381 -22.140685) (xy 286.370232 -22.101976) (xy 286.336146 -22.057833)
			(xy 286.30885 -22.009198) (xy 286.288927 -21.957107) (xy 286.276801 -21.90267) (xy 286.27273 -21.847048)
			(xy 286.006427 -21.847048) (xy 286.00654 -21.85543) (xy 286.00654 -21.869908) (xy 286.006286 -21.87575)
			(xy 286.004597 -21.910353) (xy 285.994083 -21.978831) (xy 285.975563 -22.045591) (xy 285.949296 -22.109699)
			(xy 285.915648 -22.17026) (xy 285.875089 -22.226427) (xy 285.828186 -22.277417) (xy 285.775594 -22.322516)
			(xy 285.718049 -22.361095) (xy 285.656353 -22.392615) (xy 285.591369 -22.416635) (xy 285.524006 -22.432819)
			(xy 285.455203 -22.440942) (xy 285.420562 -22.441408) (xy 285.387689 -22.440978) (xy 285.322354 -22.433642)
			(xy 285.258251 -22.419034) (xy 285.196189 -22.397337) (xy 285.136948 -22.368824) (xy 285.081273 -22.333855)
			(xy 285.029867 -22.292869) (xy 285.006288 -22.269958) (xy 284.935422 -22.199092) (xy 284.925516 -22.198584)
			(xy 284.894782 -22.224238) (xy 284.868347 -22.24584) (xy 284.81134 -22.283404) (xy 284.750353 -22.314087)
			(xy 284.686213 -22.337473) (xy 284.619788 -22.353243) (xy 284.551981 -22.361185) (xy 284.517846 -22.361652)
			(xy 284.360112 -22.361652) (xy 284.350968 -22.370542) (xy 284.332426 -22.393656) (xy 284.299406 -22.43455)
			(xy 284.296866 -22.438614) (xy 284.293056 -22.447758) (xy 284.288992 -22.463506) (xy 284.291532 -22.474936)
			(xy 284.295379 -22.494203) (xy 284.299581 -22.533269) (xy 284.299914 -22.552914) (xy 284.299914 -22.553422)
			(xy 284.299914 -22.559264) (xy 284.299151 -22.586805) (xy 284.290677 -22.641245) (xy 284.274463 -22.6939)
			(xy 284.250845 -22.743677) (xy 284.220315 -22.789539) (xy 284.183507 -22.830535) (xy 284.141186 -22.865812)
			(xy 284.094233 -22.894637) (xy 284.043622 -22.91641) (xy 283.990407 -22.930679) (xy 283.96311 -22.934422)
			(xy 283.948886 -22.935946) (xy 283.915612 -22.937216) (xy 283.91358 -22.937216) (xy 283.888547 -22.936492)
			(xy 283.838986 -22.929285) (xy 283.790795 -22.915655) (xy 283.744803 -22.895835) (xy 283.701799 -22.870167)
			(xy 283.681932 -22.85492) (xy 283.665168 -22.84095) (xy 283.663644 -22.83968) (xy 283.661866 -22.838156)
			(xy 283.653738 -22.832822) (xy 283.64332 -22.827174) (xy 283.619736 -22.825173) (xy 283.608526 -22.829012)
			(xy 283.58465 -22.839426) (xy 283.584142 -22.839426) (xy 283.523182 -22.866604) (xy 283.52115 -22.86762)
			(xy 283.507434 -22.874478) (xy 283.502608 -22.882352) (xy 283.502608 -23.965154) (xy 284.277306 -23.965154)
			(xy 284.281377 -23.909532) (xy 284.293503 -23.855095) (xy 284.313426 -23.803004) (xy 284.340722 -23.754369)
			(xy 284.374808 -23.710226) (xy 284.414957 -23.671517) (xy 284.460315 -23.639066) (xy 284.509915 -23.613565)
			(xy 284.562699 -23.595558) (xy 284.617542 -23.585428) (xy 284.673276 -23.583391) (xy 284.728713 -23.589491)
			(xy 284.78267 -23.603597) (xy 284.833999 -23.625409) (xy 284.881605 -23.654463) (xy 284.924473 -23.690138)
			(xy 284.96169 -23.731675) (xy 284.992463 -23.778188) (xy 285.016135 -23.828685) (xy 285.032203 -23.882092)
			(xy 285.040323 -23.937268) (xy 285.040498 -23.946866) (xy 285.280352 -23.946866) (xy 285.284423 -23.891244)
			(xy 285.296549 -23.836807) (xy 285.316472 -23.784716) (xy 285.343768 -23.736081) (xy 285.377854 -23.691938)
			(xy 285.418003 -23.653229) (xy 285.463361 -23.620778) (xy 285.512961 -23.595277) (xy 285.565745 -23.57727)
			(xy 285.620588 -23.56714) (xy 285.676322 -23.565103) (xy 285.731759 -23.571203) (xy 285.785716 -23.585309)
			(xy 285.837045 -23.607121) (xy 285.884651 -23.636175) (xy 285.927519 -23.67185) (xy 285.964736 -23.713387)
			(xy 285.995509 -23.7599) (xy 286.019181 -23.810397) (xy 286.035249 -23.863804) (xy 286.043369 -23.91898)
			(xy 286.043878 -23.946866) (xy 286.043438 -23.970996) (xy 286.27273 -23.970996) (xy 286.276801 -23.915374)
			(xy 286.288927 -23.860937) (xy 286.30885 -23.808846) (xy 286.336146 -23.760211) (xy 286.370232 -23.716068)
			(xy 286.410381 -23.677359) (xy 286.455739 -23.644908) (xy 286.505339 -23.619407) (xy 286.558123 -23.6014)
			(xy 286.612966 -23.59127) (xy 286.6687 -23.589233) (xy 286.724137 -23.595333) (xy 286.778094 -23.609439)
			(xy 286.829423 -23.631251) (xy 286.877029 -23.660305) (xy 286.919897 -23.69598) (xy 286.957114 -23.737517)
			(xy 286.987887 -23.78403) (xy 287.011559 -23.834527) (xy 287.027627 -23.887934) (xy 287.035747 -23.94311)
			(xy 287.036256 -23.970996) (xy 287.035747 -23.998882) (xy 287.027627 -24.054058) (xy 287.011559 -24.107465)
			(xy 286.987887 -24.157962) (xy 286.957114 -24.204475) (xy 286.919897 -24.246012) (xy 286.877029 -24.281687)
			(xy 286.829423 -24.310741) (xy 286.778094 -24.332553) (xy 286.724137 -24.346659) (xy 286.6687 -24.352759)
			(xy 286.612966 -24.350722) (xy 286.558123 -24.340592) (xy 286.505339 -24.322585) (xy 286.455739 -24.297084)
			(xy 286.410381 -24.264633) (xy 286.370232 -24.225924) (xy 286.336146 -24.181781) (xy 286.30885 -24.133146)
			(xy 286.288927 -24.081055) (xy 286.276801 -24.026618) (xy 286.27273 -23.970996) (xy 286.043438 -23.970996)
			(xy 286.043369 -23.974752) (xy 286.035249 -24.029928) (xy 286.019181 -24.083335) (xy 285.995509 -24.133832)
			(xy 285.964736 -24.180345) (xy 285.927519 -24.221882) (xy 285.884651 -24.257557) (xy 285.837045 -24.286611)
			(xy 285.785716 -24.308423) (xy 285.731759 -24.322529) (xy 285.676322 -24.328629) (xy 285.620588 -24.326592)
			(xy 285.565745 -24.316462) (xy 285.512961 -24.298455) (xy 285.463361 -24.272954) (xy 285.418003 -24.240503)
			(xy 285.377854 -24.201794) (xy 285.343768 -24.157651) (xy 285.316472 -24.109016) (xy 285.296549 -24.056925)
			(xy 285.284423 -24.002488) (xy 285.280352 -23.946866) (xy 285.040498 -23.946866) (xy 285.040832 -23.965154)
			(xy 285.040323 -23.99304) (xy 285.032203 -24.048216) (xy 285.016135 -24.101623) (xy 284.992463 -24.15212)
			(xy 284.96169 -24.198633) (xy 284.924473 -24.24017) (xy 284.881605 -24.275845) (xy 284.833999 -24.304899)
			(xy 284.78267 -24.326711) (xy 284.728713 -24.340817) (xy 284.673276 -24.346917) (xy 284.617542 -24.34488)
			(xy 284.562699 -24.33475) (xy 284.509915 -24.316743) (xy 284.460315 -24.291242) (xy 284.414957 -24.258791)
			(xy 284.374808 -24.220082) (xy 284.340722 -24.175939) (xy 284.313426 -24.127304) (xy 284.293503 -24.075213)
			(xy 284.281377 -24.020776) (xy 284.277306 -23.965154) (xy 283.502608 -23.965154) (xy 283.502608 -24.807418)
			(xy 290.571172 -24.807418) (xy 290.575243 -24.751796) (xy 290.587369 -24.697359) (xy 290.607292 -24.645268)
			(xy 290.634588 -24.596633) (xy 290.668674 -24.55249) (xy 290.708823 -24.513781) (xy 290.754181 -24.48133)
			(xy 290.803781 -24.455829) (xy 290.856565 -24.437822) (xy 290.911408 -24.427692) (xy 290.967142 -24.425655)
			(xy 291.022579 -24.431755) (xy 291.076536 -24.445861) (xy 291.127865 -24.467673) (xy 291.175471 -24.496727)
			(xy 291.218339 -24.532402) (xy 291.255556 -24.573939) (xy 291.286329 -24.620452) (xy 291.310001 -24.670949)
			(xy 291.326069 -24.724356) (xy 291.334189 -24.779532) (xy 291.334698 -24.807418) (xy 291.334189 -24.835304)
			(xy 291.326069 -24.89048) (xy 291.310001 -24.943887) (xy 291.286329 -24.994384) (xy 291.255556 -25.040897)
			(xy 291.218339 -25.082434) (xy 291.175471 -25.118109) (xy 291.127865 -25.147163) (xy 291.076536 -25.168975)
			(xy 291.022579 -25.183081) (xy 290.967142 -25.189181) (xy 290.911408 -25.187144) (xy 290.856565 -25.177014)
			(xy 290.803781 -25.159007) (xy 290.754181 -25.133506) (xy 290.708823 -25.101055) (xy 290.668674 -25.062346)
			(xy 290.634588 -25.018203) (xy 290.607292 -24.969568) (xy 290.587369 -24.917477) (xy 290.575243 -24.86304)
			(xy 290.571172 -24.807418) (xy 283.502608 -24.807418) (xy 283.502608 -25.912572) (xy 283.502686 -25.916782)
			(xy 283.504086 -25.925083) (xy 283.505402 -25.929082) (xy 283.507942 -25.936448) (xy 283.512514 -25.942544)
			(xy 283.538422 -25.950418) (xy 283.561988 -25.958147) (xy 283.607073 -25.978816) (xy 283.649142 -26.005085)
			(xy 283.684096 -26.03373) (xy 289.467796 -26.03373) (xy 289.471867 -25.978108) (xy 289.483993 -25.923671)
			(xy 289.503916 -25.87158) (xy 289.531212 -25.822945) (xy 289.565298 -25.778802) (xy 289.605447 -25.740093)
			(xy 289.650805 -25.707642) (xy 289.700405 -25.682141) (xy 289.753189 -25.664134) (xy 289.808032 -25.654004)
			(xy 289.863766 -25.651967) (xy 289.919203 -25.658067) (xy 289.97316 -25.672173) (xy 290.024489 -25.693985)
			(xy 290.072095 -25.723039) (xy 290.114963 -25.758714) (xy 290.15218 -25.800251) (xy 290.182953 -25.846764)
			(xy 290.206625 -25.897261) (xy 290.222693 -25.950668) (xy 290.230813 -26.005844) (xy 290.231322 -26.03373)
			(xy 290.230813 -26.061616) (xy 290.222693 -26.116792) (xy 290.206625 -26.170199) (xy 290.182953 -26.220696)
			(xy 290.15218 -26.267209) (xy 290.114963 -26.308746) (xy 290.072095 -26.344421) (xy 290.024489 -26.373475)
			(xy 289.97316 -26.395287) (xy 289.919203 -26.409393) (xy 289.863766 -26.415493) (xy 289.808032 -26.413456)
			(xy 289.753189 -26.403326) (xy 289.700405 -26.385319) (xy 289.650805 -26.359818) (xy 289.605447 -26.327367)
			(xy 289.565298 -26.288658) (xy 289.531212 -26.244515) (xy 289.503916 -26.19588) (xy 289.483993 -26.143789)
			(xy 289.471867 -26.089352) (xy 289.467796 -26.03373) (xy 283.684096 -26.03373) (xy 283.687503 -26.036522)
			(xy 283.704792 -26.054304) (xy 283.726012 -26.077636) (xy 283.76135 -26.129869) (xy 283.787745 -26.187143)
			(xy 283.79674 -26.217372) (xy 283.799026 -26.2255) (xy 284.743398 -27.169872) (xy 284.761509 -27.188653)
			(xy 284.79219 -27.230851) (xy 284.815886 -27.277332) (xy 284.832012 -27.32695) (xy 284.84017 -27.378481)
			(xy 284.84068 -27.404568) (xy 284.84068 -28.139136) (xy 286.59785 -28.139136) (xy 286.601921 -28.083514)
			(xy 286.614047 -28.029077) (xy 286.63397 -27.976986) (xy 286.661266 -27.928351) (xy 286.695352 -27.884208)
			(xy 286.735501 -27.845499) (xy 286.780859 -27.813048) (xy 286.830459 -27.787547) (xy 286.883243 -27.76954)
			(xy 286.938086 -27.75941) (xy 286.99382 -27.757373) (xy 287.049257 -27.763473) (xy 287.103214 -27.777579)
			(xy 287.154543 -27.799391) (xy 287.202149 -27.828445) (xy 287.245017 -27.86412) (xy 287.282234 -27.905657)
			(xy 287.313007 -27.95217) (xy 287.336679 -28.002667) (xy 287.352747 -28.056074) (xy 287.360867 -28.11125)
			(xy 287.361376 -28.139136) (xy 287.86785 -28.139136) (xy 287.871921 -28.083514) (xy 287.884047 -28.029077)
			(xy 287.90397 -27.976986) (xy 287.931266 -27.928351) (xy 287.965352 -27.884208) (xy 288.005501 -27.845499)
			(xy 288.050859 -27.813048) (xy 288.100459 -27.787547) (xy 288.153243 -27.76954) (xy 288.208086 -27.75941)
			(xy 288.26382 -27.757373) (xy 288.319257 -27.763473) (xy 288.373214 -27.777579) (xy 288.424543 -27.799391)
			(xy 288.472149 -27.828445) (xy 288.515017 -27.86412) (xy 288.552234 -27.905657) (xy 288.583007 -27.95217)
			(xy 288.606679 -28.002667) (xy 288.622747 -28.056074) (xy 288.630867 -28.11125) (xy 288.631376 -28.139136)
			(xy 288.630867 -28.167022) (xy 288.622747 -28.222198) (xy 288.606679 -28.275605) (xy 288.583007 -28.326102)
			(xy 288.552234 -28.372615) (xy 288.515017 -28.414152) (xy 288.472149 -28.449827) (xy 288.424543 -28.478881)
			(xy 288.373214 -28.500693) (xy 288.319257 -28.514799) (xy 288.26382 -28.520899) (xy 288.208086 -28.518862)
			(xy 288.153243 -28.508732) (xy 288.100459 -28.490725) (xy 288.050859 -28.465224) (xy 288.005501 -28.432773)
			(xy 287.965352 -28.394064) (xy 287.931266 -28.349921) (xy 287.90397 -28.301286) (xy 287.884047 -28.249195)
			(xy 287.871921 -28.194758) (xy 287.86785 -28.139136) (xy 287.361376 -28.139136) (xy 287.360867 -28.167022)
			(xy 287.352747 -28.222198) (xy 287.336679 -28.275605) (xy 287.313007 -28.326102) (xy 287.282234 -28.372615)
			(xy 287.245017 -28.414152) (xy 287.202149 -28.449827) (xy 287.154543 -28.478881) (xy 287.103214 -28.500693)
			(xy 287.049257 -28.514799) (xy 286.99382 -28.520899) (xy 286.938086 -28.518862) (xy 286.883243 -28.508732)
			(xy 286.830459 -28.490725) (xy 286.780859 -28.465224) (xy 286.735501 -28.432773) (xy 286.695352 -28.394064)
			(xy 286.661266 -28.349921) (xy 286.63397 -28.301286) (xy 286.614047 -28.249195) (xy 286.601921 -28.194758)
			(xy 286.59785 -28.139136) (xy 284.84068 -28.139136) (xy 284.84068 -30.193742) (xy 284.840191 -30.219828)
			(xy 284.832019 -30.271357) (xy 284.815883 -30.320971) (xy 284.79218 -30.367449) (xy 284.785325 -30.376876)
			(xy 285.088838 -30.376876) (xy 285.089397 -30.34796) (xy 285.098115 -30.29079) (xy 285.115364 -30.235592)
			(xy 285.140748 -30.18363) (xy 285.173686 -30.136095) (xy 285.213421 -30.094077) (xy 285.235904 -30.075886)
			(xy 285.244708 -30.068276) (xy 285.254893 -30.047377) (xy 285.255462 -30.035754) (xy 285.255462 -29.955998)
			(xy 285.254923 -29.944366) (xy 285.244735 -29.923455) (xy 285.235904 -29.915866) (xy 285.213405 -29.897693)
			(xy 285.173671 -29.85567) (xy 285.140733 -29.808131) (xy 285.115348 -29.756166) (xy 285.098095 -29.700965)
			(xy 285.08937 -29.643793) (xy 285.088838 -29.614876) (xy 285.089324 -29.587625) (xy 285.09708 -29.533677)
			(xy 285.112435 -29.481382) (xy 285.135077 -29.431805) (xy 285.164543 -29.385955) (xy 285.200234 -29.344764)
			(xy 285.241425 -29.309073) (xy 285.287275 -29.279607) (xy 285.336852 -29.256965) (xy 285.389147 -29.24161)
			(xy 285.443095 -29.233854) (xy 285.497597 -29.233854) (xy 285.551545 -29.24161) (xy 285.60384 -29.256965)
			(xy 285.653417 -29.279607) (xy 285.699267 -29.309073) (xy 285.740458 -29.344764) (xy 285.776149 -29.385955)
			(xy 285.805615 -29.431805) (xy 285.828257 -29.481382) (xy 285.843612 -29.533677) (xy 285.851368 -29.587625)
			(xy 285.851854 -29.614876) (xy 285.851336 -29.643793) (xy 285.842609 -29.700965) (xy 285.825352 -29.756165)
			(xy 285.799961 -29.808127) (xy 285.767016 -29.855661) (xy 285.727274 -29.897677) (xy 285.704788 -29.915866)
			(xy 285.696004 -29.923496) (xy 285.685808 -29.944379) (xy 285.68523 -29.955998) (xy 285.68523 -30.035754)
			(xy 285.685742 -30.04739) (xy 285.695949 -30.068299) (xy 285.704788 -30.075886) (xy 285.727262 -30.094088)
			(xy 285.766999 -30.136105) (xy 285.799939 -30.183638) (xy 285.825329 -30.235597) (xy 285.842587 -30.290793)
			(xy 285.851318 -30.347961) (xy 285.851854 -30.376876) (xy 285.851368 -30.404127) (xy 285.843612 -30.458075)
			(xy 285.828257 -30.51037) (xy 285.805615 -30.559947) (xy 285.776149 -30.605797) (xy 285.740458 -30.646988)
			(xy 285.699267 -30.682679) (xy 285.653417 -30.712145) (xy 285.60384 -30.734787) (xy 285.551545 -30.750142)
			(xy 285.497597 -30.757898) (xy 285.443095 -30.757898) (xy 285.389147 -30.750142) (xy 285.336852 -30.734787)
			(xy 285.287275 -30.712145) (xy 285.241425 -30.682679) (xy 285.200234 -30.646988) (xy 285.164543 -30.605797)
			(xy 285.135077 -30.559947) (xy 285.112435 -30.51037) (xy 285.09708 -30.458075) (xy 285.089324 -30.404127)
			(xy 285.088838 -30.376876) (xy 284.785325 -30.376876) (xy 284.761496 -30.409644) (xy 284.743398 -30.428438)
			(xy 283.770324 -31.401258) (xy 283.765076 -31.406925) (xy 283.757969 -31.420629) (xy 283.756354 -31.428182)
			(xy 283.755592 -31.437072) (xy 283.755592 -31.567882) (xy 285.198564 -31.567882) (xy 285.202635 -31.51226)
			(xy 285.214761 -31.457823) (xy 285.234684 -31.405732) (xy 285.26198 -31.357097) (xy 285.296066 -31.312954)
			(xy 285.336215 -31.274245) (xy 285.381573 -31.241794) (xy 285.431173 -31.216293) (xy 285.483957 -31.198286)
			(xy 285.5388 -31.188156) (xy 285.594534 -31.186119) (xy 285.649971 -31.192219) (xy 285.703928 -31.206325)
			(xy 285.755257 -31.228137) (xy 285.802863 -31.257191) (xy 285.845731 -31.292866) (xy 285.882948 -31.334403)
			(xy 285.913721 -31.380916) (xy 285.937393 -31.431413) (xy 285.953461 -31.48482) (xy 285.961581 -31.539996)
			(xy 285.96209 -31.567882) (xy 285.961581 -31.595768) (xy 285.953461 -31.650944) (xy 285.937393 -31.704351)
			(xy 285.930401 -31.719266) (xy 286.485328 -31.719266) (xy 286.489399 -31.663644) (xy 286.501525 -31.609207)
			(xy 286.521448 -31.557116) (xy 286.548744 -31.508481) (xy 286.58283 -31.464338) (xy 286.622979 -31.425629)
			(xy 286.668337 -31.393178) (xy 286.717937 -31.367677) (xy 286.770721 -31.34967) (xy 286.825564 -31.33954)
			(xy 286.881298 -31.337503) (xy 286.936735 -31.343603) (xy 286.990692 -31.357709) (xy 287.042021 -31.379521)
			(xy 287.089627 -31.408575) (xy 287.132495 -31.44425) (xy 287.169712 -31.485787) (xy 287.200485 -31.5323)
			(xy 287.224157 -31.582797) (xy 287.240225 -31.636204) (xy 287.244375 -31.664402) (xy 287.760916 -31.664402)
			(xy 287.764987 -31.60878) (xy 287.777113 -31.554343) (xy 287.797036 -31.502252) (xy 287.824332 -31.453617)
			(xy 287.858418 -31.409474) (xy 287.898567 -31.370765) (xy 287.943925 -31.338314) (xy 287.993525 -31.312813)
			(xy 288.046309 -31.294806) (xy 288.101152 -31.284676) (xy 288.156886 -31.282639) (xy 288.212323 -31.288739)
			(xy 288.26628 -31.302845) (xy 288.317609 -31.324657) (xy 288.365215 -31.353711) (xy 288.408083 -31.389386)
			(xy 288.4453 -31.430923) (xy 288.476073 -31.477436) (xy 288.499745 -31.527933) (xy 288.515813 -31.58134)
			(xy 288.523933 -31.636516) (xy 288.524442 -31.664402) (xy 288.523933 -31.692288) (xy 288.515813 -31.747464)
			(xy 288.499745 -31.800871) (xy 288.476073 -31.851368) (xy 288.4453 -31.897881) (xy 288.408083 -31.939418)
			(xy 288.365215 -31.975093) (xy 288.317609 -32.004147) (xy 288.26628 -32.025959) (xy 288.212323 -32.040065)
			(xy 288.156886 -32.046165) (xy 288.101152 -32.044128) (xy 288.046309 -32.033998) (xy 287.993525 -32.015991)
			(xy 287.943925 -31.99049) (xy 287.898567 -31.958039) (xy 287.858418 -31.91933) (xy 287.824332 -31.875187)
			(xy 287.797036 -31.826552) (xy 287.777113 -31.774461) (xy 287.764987 -31.720024) (xy 287.760916 -31.664402)
			(xy 287.244375 -31.664402) (xy 287.248345 -31.69138) (xy 287.248854 -31.719266) (xy 287.248345 -31.747152)
			(xy 287.240225 -31.802328) (xy 287.224157 -31.855735) (xy 287.200485 -31.906232) (xy 287.169712 -31.952745)
			(xy 287.132495 -31.994282) (xy 287.089627 -32.029957) (xy 287.042021 -32.059011) (xy 286.990692 -32.080823)
			(xy 286.936735 -32.094929) (xy 286.881298 -32.101029) (xy 286.825564 -32.098992) (xy 286.770721 -32.088862)
			(xy 286.717937 -32.070855) (xy 286.668337 -32.045354) (xy 286.622979 -32.012903) (xy 286.58283 -31.974194)
			(xy 286.548744 -31.930051) (xy 286.521448 -31.881416) (xy 286.501525 -31.829325) (xy 286.489399 -31.774888)
			(xy 286.485328 -31.719266) (xy 285.930401 -31.719266) (xy 285.913721 -31.754848) (xy 285.882948 -31.801361)
			(xy 285.845731 -31.842898) (xy 285.802863 -31.878573) (xy 285.755257 -31.907627) (xy 285.703928 -31.929439)
			(xy 285.649971 -31.943545) (xy 285.594534 -31.949645) (xy 285.5388 -31.947608) (xy 285.483957 -31.937478)
			(xy 285.431173 -31.919471) (xy 285.381573 -31.89397) (xy 285.336215 -31.861519) (xy 285.296066 -31.82281)
			(xy 285.26198 -31.778667) (xy 285.234684 -31.730032) (xy 285.214761 -31.677941) (xy 285.202635 -31.623504)
			(xy 285.198564 -31.567882) (xy 283.755592 -31.567882) (xy 283.755592 -31.971996) (xy 283.7559 -31.98019)
			(xy 283.761081 -31.995737) (xy 283.765752 -32.002476) (xy 287.027984 -35.264852) (xy 288.102292 -35.264852)
			(xy 288.106363 -35.20923) (xy 288.118489 -35.154793) (xy 288.138412 -35.102702) (xy 288.165708 -35.054067)
			(xy 288.199794 -35.009924) (xy 288.239943 -34.971215) (xy 288.285301 -34.938764) (xy 288.334901 -34.913263)
			(xy 288.387685 -34.895256) (xy 288.442528 -34.885126) (xy 288.498262 -34.883089) (xy 288.553699 -34.889189)
			(xy 288.607656 -34.903295) (xy 288.658985 -34.925107) (xy 288.706591 -34.954161) (xy 288.749459 -34.989836)
			(xy 288.786676 -35.031373) (xy 288.817449 -35.077886) (xy 288.841121 -35.128383) (xy 288.857189 -35.18179)
			(xy 288.865309 -35.236966) (xy 288.865818 -35.264852) (xy 288.865309 -35.292738) (xy 288.857189 -35.347914)
			(xy 288.841121 -35.401321) (xy 288.817449 -35.451818) (xy 288.786676 -35.498331) (xy 288.749459 -35.539868)
			(xy 288.706591 -35.575543) (xy 288.658985 -35.604597) (xy 288.607656 -35.626409) (xy 288.553699 -35.640515)
			(xy 288.498262 -35.646615) (xy 288.442528 -35.644578) (xy 288.387685 -35.634448) (xy 288.334901 -35.616441)
			(xy 288.285301 -35.59094) (xy 288.239943 -35.558489) (xy 288.199794 -35.51978) (xy 288.165708 -35.475637)
			(xy 288.138412 -35.427002) (xy 288.118489 -35.374911) (xy 288.106363 -35.320474) (xy 288.102292 -35.264852)
			(xy 287.027984 -35.264852) (xy 288.050035 -36.286948) (xy 289.400232 -36.286948) (xy 289.404303 -36.231326)
			(xy 289.416429 -36.176889) (xy 289.436352 -36.124798) (xy 289.463648 -36.076163) (xy 289.497734 -36.03202)
			(xy 289.537883 -35.993311) (xy 289.583241 -35.96086) (xy 289.632841 -35.935359) (xy 289.685625 -35.917352)
			(xy 289.740468 -35.907222) (xy 289.796202 -35.905185) (xy 289.851639 -35.911285) (xy 289.905596 -35.925391)
			(xy 289.956925 -35.947203) (xy 290.004531 -35.976257) (xy 290.047399 -36.011932) (xy 290.084616 -36.053469)
			(xy 290.115389 -36.099982) (xy 290.139061 -36.150479) (xy 290.155129 -36.203886) (xy 290.163249 -36.259062)
			(xy 290.163758 -36.286948) (xy 290.163249 -36.314834) (xy 290.155129 -36.37001) (xy 290.139061 -36.423417)
			(xy 290.115389 -36.473914) (xy 290.084616 -36.520427) (xy 290.047399 -36.561964) (xy 290.004531 -36.597639)
			(xy 289.956925 -36.626693) (xy 289.905596 -36.648505) (xy 289.851639 -36.662611) (xy 289.796202 -36.668711)
			(xy 289.740468 -36.666674) (xy 289.685625 -36.656544) (xy 289.632841 -36.638537) (xy 289.583241 -36.613036)
			(xy 289.537883 -36.580585) (xy 289.497734 -36.541876) (xy 289.463648 -36.497733) (xy 289.436352 -36.449098)
			(xy 289.416429 -36.397007) (xy 289.404303 -36.34257) (xy 289.400232 -36.286948) (xy 288.050035 -36.286948)
			(xy 289.530028 -37.767006) (xy 289.534674 -37.767516) (xy 289.544007 -37.767004) (xy 289.54857 -37.76599)
			(xy 289.578796 -37.756846) (xy 289.579304 -37.756846) (xy 289.627564 -37.74186) (xy 289.632534 -37.73974)
			(xy 289.641505 -37.733724) (xy 289.645344 -37.729922) (xy 289.65525 -37.719) (xy 289.655758 -37.718492)
			(xy 289.663886 -37.709602) (xy 289.670236 -37.69995) (xy 289.673538 -37.6936) (xy 289.674554 -37.689536)
			(xy 289.675062 -37.686996) (xy 289.68208 -37.659442) (xy 289.703161 -37.606637) (xy 289.731841 -37.557543)
			(xy 289.767484 -37.513245) (xy 289.809303 -37.474723) (xy 289.856373 -37.442829) (xy 289.907653 -37.418269)
			(xy 289.962007 -37.401586) (xy 290.018235 -37.393148) (xy 290.046664 -37.39261) (xy 290.073918 -37.393071)
			(xy 290.127872 -37.400824) (xy 290.180173 -37.416177) (xy 290.229757 -37.438818) (xy 290.275613 -37.468285)
			(xy 290.316808 -37.503979) (xy 290.352504 -37.545173) (xy 290.381974 -37.591028) (xy 290.404617 -37.64061)
			(xy 290.419972 -37.69291) (xy 290.427728 -37.746864) (xy 290.428172 -37.774118) (xy 290.427647 -37.802546)
			(xy 290.41921 -37.858772) (xy 290.402525 -37.913125) (xy 290.377963 -37.964402) (xy 290.346065 -38.011467)
			(xy 290.307538 -38.05328) (xy 290.263235 -38.088914) (xy 290.214136 -38.117583) (xy 290.161327 -38.13865)
			(xy 290.133786 -38.14572) (xy 290.133532 -38.14572) (xy 290.12642 -38.147498) (xy 290.116006 -38.152832)
			(xy 290.109148 -38.158928) (xy 290.108894 -38.159182) (xy 290.10229 -38.165024) (xy 290.101782 -38.165532)
			(xy 290.09086 -38.175438) (xy 290.087072 -38.179288) (xy 290.081057 -38.188256) (xy 290.078922 -38.193218)
			(xy 290.063936 -38.241478) (xy 290.063936 -38.241986) (xy 290.054792 -38.272212) (xy 290.053801 -38.276778)
			(xy 290.053298 -38.286106) (xy 290.053776 -38.290754) (xy 296.12209 -44.359068) (xy 296.127693 -44.363482)
			(xy 296.140716 -44.369283) (xy 296.147744 -44.370498) (xy 296.162167 -44.372025) (xy 296.190856 -44.367864)
			(xy 296.21722 -44.355809) (xy 296.239135 -44.336832) (xy 296.254834 -44.312461) (xy 296.263053 -44.284661)
			(xy 296.263568 -44.270168) (xy 296.263568 -44.198286) (xy 296.26306 -44.191428) (xy 291.371274 -39.299642)
			(xy 291.353163 -39.280861) (xy 291.322483 -39.238662) (xy 291.298787 -39.192181) (xy 291.28266 -39.142563)
			(xy 291.274501 -39.091032) (xy 291.273992 -39.064946) (xy 291.273992 -36.734496) (xy 291.273738 -36.730686)
			(xy 291.27069 -36.716716) (xy 291.267134 -36.708842) (xy 291.262176 -36.700351) (xy 291.253028 -36.682943)
			(xy 291.248846 -36.674044) (xy 291.248846 -36.673536) (xy 291.238686 -36.64966) (xy 291.237416 -36.64585)
			(xy 291.234622 -36.637722) (xy 291.234368 -36.637214) (xy 291.233606 -36.634674) (xy 291.233352 -36.633912)
			(xy 291.23259 -36.631626) (xy 291.232082 -36.630102) (xy 291.23132 -36.62807) (xy 291.230304 -36.625022)
			(xy 291.229034 -36.621974) (xy 291.227071 -36.618144) (xy 291.22209 -36.611126) (xy 291.219128 -36.608004)
			(xy 289.728656 -35.117532) (xy 289.710621 -35.098762) (xy 289.680036 -35.056647) (xy 289.656405 -35.010271)
			(xy 289.640308 -34.960773) (xy 289.63214 -34.909368) (xy 289.631628 -34.883344) (xy 289.631628 -32.411162)
			(xy 289.623246 -32.402272) (xy 289.587432 -32.372808) (xy 289.586924 -32.3723) (xy 289.563556 -32.35325)
			(xy 289.560698 -32.350958) (xy 289.55445 -32.347134) (xy 289.55111 -32.34563) (xy 289.529774 -32.350202)
			(xy 289.499716 -32.356215) (xy 289.438758 -32.362707) (xy 289.408108 -32.363156) (xy 289.361372 -32.363156)
			(xy 289.361372 -32.361378) (xy 289.327923 -32.358237) (xy 289.262003 -32.345259) (xy 289.198001 -32.324822)
			(xy 289.136758 -32.297196) (xy 289.079079 -32.262742) (xy 289.025722 -32.221914) (xy 288.977387 -32.175249)
			(xy 288.93471 -32.123358) (xy 288.898252 -32.066925) (xy 288.868491 -32.00669) (xy 288.845819 -31.943446)
			(xy 288.830534 -31.878022) (xy 288.822835 -31.811279) (xy 288.822384 -31.777686) (xy 288.822384 -30.776164)
			(xy 288.81959 -30.772862) (xy 288.815018 -30.767782) (xy 288.811716 -30.76575) (xy 288.802064 -30.759908)
			(xy 288.801556 -30.759654) (xy 288.7345 -30.718252) (xy 288.728335 -30.714727) (xy 288.714674 -30.710866)
			(xy 288.707576 -30.710632) (xy 288.695384 -30.710886) (xy 288.684462 -30.716474) (xy 288.677858 -30.719776)
			(xy 288.673032 -30.724094) (xy 288.670197 -30.726521) (xy 288.663949 -30.730603) (xy 288.660586 -30.732222)
			(xy 288.656268 -30.734) (xy 288.654236 -30.734762) (xy 288.631302 -30.743574) (xy 288.583764 -30.755991)
			(xy 288.535037 -30.762292) (xy 288.510472 -30.762702) (xy 288.482914 -30.762208) (xy 288.42836 -30.754361)
			(xy 288.375478 -30.738829) (xy 288.325345 -30.71593) (xy 288.278981 -30.686129) (xy 288.23733 -30.650033)
			(xy 288.20124 -30.608377) (xy 288.171445 -30.562009) (xy 288.148553 -30.511873) (xy 288.133028 -30.458989)
			(xy 288.125188 -30.404434) (xy 288.124646 -30.376876) (xy 288.125156 -30.348468) (xy 288.133511 -30.292268)
			(xy 288.150036 -30.237908) (xy 288.174371 -30.186566) (xy 288.205989 -30.13936) (xy 288.244202 -30.097313)
			(xy 288.26587 -30.078934) (xy 288.266378 -30.078426) (xy 288.271966 -30.0736) (xy 288.27603 -30.070298)
			(xy 288.279586 -30.066234) (xy 288.285428 -30.057344) (xy 288.292032 -30.04312) (xy 288.293698 -30.038667)
			(xy 288.295484 -30.029331) (xy 288.295588 -30.024578) (xy 288.295588 -29.967682) (xy 288.295446 -29.962242)
			(xy 288.293141 -29.951609) (xy 288.291016 -29.9466) (xy 288.287714 -29.939742) (xy 288.287714 -29.939234)
			(xy 288.280856 -29.925518) (xy 288.272474 -29.914088) (xy 288.267648 -29.909262) (xy 288.26587 -29.907738)
			(xy 288.244842 -29.8895) (xy 288.207777 -29.847975) (xy 288.177134 -29.801509) (xy 288.153561 -29.751087)
			(xy 288.137559 -29.697776) (xy 288.129467 -29.642706) (xy 288.128964 -29.614876) (xy 288.129451 -29.587625)
			(xy 288.137211 -29.533679) (xy 288.152567 -29.481385) (xy 288.17521 -29.431809) (xy 288.204676 -29.38596)
			(xy 288.240367 -29.34477) (xy 288.281556 -29.309078) (xy 288.327406 -29.279611) (xy 288.376981 -29.256969)
			(xy 288.429275 -29.241611) (xy 288.483221 -29.233852) (xy 288.510472 -29.233368) (xy 288.535901 -29.233787)
			(xy 288.586309 -29.24054) (xy 288.635373 -29.25393) (xy 288.682223 -29.27372) (xy 288.726029 -29.299559)
			(xy 288.766013 -29.330988) (xy 288.78403 -29.348938) (xy 288.790888 -29.35605) (xy 288.826448 -29.371798)
			(xy 288.838894 -29.37129) (xy 288.86023 -29.370274) (xy 288.867201 -29.369739) (xy 288.880471 -29.365356)
			(xy 288.886392 -29.361638) (xy 288.889937 -29.359141) (xy 288.896194 -29.353138) (xy 288.898838 -29.3497)
			(xy 288.901632 -29.345128) (xy 288.918346 -29.317267) (xy 288.957046 -29.265076) (xy 288.978848 -29.240988)
			(xy 288.993834 -29.225494) (xy 291.432234 -26.787094) (xy 291.437221 -26.781595) (xy 291.444066 -26.768428)
			(xy 291.445696 -26.761186) (xy 291.446712 -26.751534) (xy 291.446712 -24.158194) (xy 291.447208 -24.124094)
			(xy 291.455125 -24.056354) (xy 291.470854 -23.989991) (xy 291.49418 -23.925903) (xy 291.524788 -23.864957)
			(xy 291.562265 -23.807976) (xy 291.606104 -23.755731) (xy 291.655711 -23.708928) (xy 291.710417 -23.668202)
			(xy 291.769481 -23.634101) (xy 291.832104 -23.607088) (xy 291.89744 -23.587528) (xy 291.964604 -23.575685)
			(xy 292.03269 -23.57172) (xy 292.100776 -23.575685) (xy 292.16794 -23.587528) (xy 292.233276 -23.607088)
			(xy 292.295899 -23.634101) (xy 292.354963 -23.668202) (xy 292.409669 -23.708928) (xy 292.459276 -23.755731)
			(xy 292.503115 -23.807976) (xy 292.540592 -23.864957) (xy 292.5712 -23.925903) (xy 292.594526 -23.989991)
			(xy 292.610255 -24.056354) (xy 292.618172 -24.124094) (xy 292.618668 -24.158194) (xy 292.618668 -24.807418)
			(xy 292.820088 -24.807418) (xy 292.824159 -24.751796) (xy 292.836285 -24.697359) (xy 292.856208 -24.645268)
			(xy 292.883504 -24.596633) (xy 292.91759 -24.55249) (xy 292.957739 -24.513781) (xy 293.003097 -24.48133)
			(xy 293.052697 -24.455829) (xy 293.105481 -24.437822) (xy 293.160324 -24.427692) (xy 293.216058 -24.425655)
			(xy 293.271495 -24.431755) (xy 293.325452 -24.445861) (xy 293.376781 -24.467673) (xy 293.424387 -24.496727)
			(xy 293.467255 -24.532402) (xy 293.504472 -24.573939) (xy 293.535245 -24.620452) (xy 293.558917 -24.670949)
			(xy 293.574985 -24.724356) (xy 293.583105 -24.779532) (xy 293.583614 -24.807418) (xy 293.583105 -24.835304)
			(xy 293.574985 -24.89048) (xy 293.558917 -24.943887) (xy 293.535245 -24.994384) (xy 293.504472 -25.040897)
			(xy 293.467255 -25.082434) (xy 293.424387 -25.118109) (xy 293.376781 -25.147163) (xy 293.325452 -25.168975)
			(xy 293.271495 -25.183081) (xy 293.216058 -25.189181) (xy 293.160324 -25.187144) (xy 293.105481 -25.177014)
			(xy 293.052697 -25.159007) (xy 293.003097 -25.133506) (xy 292.957739 -25.101055) (xy 292.91759 -25.062346)
			(xy 292.883504 -25.018203) (xy 292.856208 -24.969568) (xy 292.836285 -24.917477) (xy 292.824159 -24.86304)
			(xy 292.820088 -24.807418) (xy 292.618668 -24.807418) (xy 292.618668 -26.724356) (xy 292.620881 -26.727204)
			(xy 292.62598 -26.732304) (xy 292.628828 -26.734516) (xy 292.923722 -26.734516) (xy 292.926262 -26.734516)
			(xy 292.931621 -26.734085) (xy 292.941993 -26.731263) (xy 292.946836 -26.728928) (xy 292.970458 -26.716228)
			(xy 292.9763 -26.713434) (xy 292.976808 -26.71318) (xy 292.985698 -26.70556) (xy 292.989508 -26.700226)
			(xy 292.994892 -26.691797) (xy 292.999376 -26.672326) (xy 292.996127 -26.652611) (xy 292.985633 -26.635609)
			(xy 292.977824 -26.62936) (xy 292.971982 -26.625296) (xy 292.965886 -26.62301) (xy 292.93919 -26.612242)
			(xy 292.88912 -26.583844) (xy 292.843883 -26.548248) (xy 292.804504 -26.506264) (xy 292.771875 -26.458842)
			(xy 292.746738 -26.407059) (xy 292.729662 -26.352087) (xy 292.721034 -26.295175) (xy 292.720522 -26.266394)
			(xy 292.721008 -26.239143) (xy 292.728764 -26.185195) (xy 292.744119 -26.1329) (xy 292.766761 -26.083323)
			(xy 292.796227 -26.037473) (xy 292.831918 -25.996282) (xy 292.873109 -25.960591) (xy 292.918959 -25.931125)
			(xy 292.968536 -25.908483) (xy 293.020831 -25.893128) (xy 293.074779 -25.885372) (xy 293.129281 -25.885372)
			(xy 293.183229 -25.893128) (xy 293.235524 -25.908483) (xy 293.285101 -25.931125) (xy 293.330951 -25.960591)
			(xy 293.372142 -25.996282) (xy 293.407833 -26.037473) (xy 293.437299 -26.083323) (xy 293.459941 -26.1329)
			(xy 293.475296 -26.185195) (xy 293.483052 -26.239143) (xy 293.483538 -26.266394) (xy 293.483004 -26.29531)
			(xy 293.474277 -26.35248) (xy 293.457022 -26.407679) (xy 293.431633 -26.459641) (xy 293.398694 -26.507176)
			(xy 293.358957 -26.549195) (xy 293.336472 -26.567384) (xy 293.3319 -26.57094) (xy 293.322502 -26.58237)
			(xy 293.320209 -26.585227) (xy 293.316385 -26.591475) (xy 293.314882 -26.594816) (xy 293.314882 -26.595324)
			(xy 293.312771 -26.600591) (xy 293.310711 -26.611749) (xy 293.310818 -26.617422) (xy 293.312088 -26.643838)
			(xy 293.312088 -26.644346) (xy 293.314882 -26.690574) (xy 293.31793 -26.702004) (xy 293.325042 -26.714958)
			(xy 293.331392 -26.72334) (xy 293.33571 -26.727912) (xy 293.337742 -26.729182) (xy 293.34206 -26.731722)
			(xy 293.366526 -26.746893) (xy 293.411114 -26.783303) (xy 293.449861 -26.825877) (xy 293.481921 -26.873689)
			(xy 293.506598 -26.925698) (xy 293.523354 -26.980772) (xy 293.531825 -27.037711) (xy 293.532306 -27.066494)
			(xy 293.53181 -27.094345) (xy 293.523884 -27.149479) (xy 293.508192 -27.202924) (xy 293.485054 -27.253593)
			(xy 293.454941 -27.300452) (xy 293.418465 -27.34255) (xy 293.37637 -27.379027) (xy 293.329512 -27.409143)
			(xy 293.278845 -27.432284) (xy 293.225401 -27.447979) (xy 293.170267 -27.455908) (xy 293.142416 -27.456384)
			(xy 293.142162 -27.456384) (xy 293.116841 -27.455981) (xy 293.066623 -27.449438) (xy 293.017671 -27.436465)
			(xy 292.970803 -27.41728) (xy 292.948614 -27.405076) (xy 292.942772 -27.401774) (xy 292.936676 -27.40025)
			(xy 292.923722 -27.398472) (xy 292.799008 -27.398472) (xy 292.789039 -27.398944) (xy 292.770593 -27.40651)
			(xy 292.763194 -27.413204) (xy 291.209984 -28.965906) (xy 291.053564 -29.12237) (xy 292.806628 -29.12237)
			(xy 292.806628 -28.25877) (xy 292.807118 -28.228786) (xy 292.814946 -28.16933) (xy 292.830467 -28.111405)
			(xy 292.853416 -28.056001) (xy 292.8834 -28.004067) (xy 292.919906 -27.956491) (xy 292.962311 -27.914086)
			(xy 293.009887 -27.87758) (xy 293.061821 -27.847596) (xy 293.117225 -27.824647) (xy 293.17515 -27.809126)
			(xy 293.234606 -27.801298) (xy 293.294574 -27.801298) (xy 293.35403 -27.809126) (xy 293.411955 -27.824647)
			(xy 293.467359 -27.847596) (xy 293.519293 -27.87758) (xy 293.566869 -27.914086) (xy 293.609274 -27.956491)
			(xy 293.64578 -28.004067) (xy 293.675764 -28.056001) (xy 293.698713 -28.111405) (xy 293.714234 -28.16933)
			(xy 293.722062 -28.228786) (xy 293.722552 -28.25877) (xy 293.722552 -29.114242) (xy 303.0474 -29.114242)
			(xy 303.0474 -28.250642) (xy 303.04789 -28.220674) (xy 303.055713 -28.161252) (xy 303.071226 -28.103359)
			(xy 303.094162 -28.047986) (xy 303.124129 -27.99608) (xy 303.160616 -27.94853) (xy 303.202996 -27.90615)
			(xy 303.250546 -27.869663) (xy 303.302452 -27.839696) (xy 303.357825 -27.81676) (xy 303.415718 -27.801247)
			(xy 303.47514 -27.793424) (xy 303.535076 -27.793424) (xy 303.594498 -27.801247) (xy 303.652391 -27.81676)
			(xy 303.707764 -27.839696) (xy 303.75967 -27.869663) (xy 303.80722 -27.90615) (xy 303.8496 -27.94853)
			(xy 303.886087 -27.99608) (xy 303.916054 -28.047986) (xy 303.93899 -28.103359) (xy 303.954503 -28.161252)
			(xy 303.962326 -28.220674) (xy 303.962816 -28.250642) (xy 303.962816 -29.114242) (xy 303.962326 -29.14421)
			(xy 303.954503 -29.203632) (xy 303.93899 -29.261525) (xy 303.916054 -29.316898) (xy 303.886087 -29.368804)
			(xy 303.8496 -29.416354) (xy 303.80722 -29.458734) (xy 303.75967 -29.495221) (xy 303.707764 -29.525188)
			(xy 303.652391 -29.548124) (xy 303.594498 -29.563637) (xy 303.535076 -29.57146) (xy 303.47514 -29.57146)
			(xy 303.415718 -29.563637) (xy 303.357825 -29.548124) (xy 303.302452 -29.525188) (xy 303.250546 -29.495221)
			(xy 303.202996 -29.458734) (xy 303.160616 -29.416354) (xy 303.124129 -29.368804) (xy 303.094162 -29.316898)
			(xy 303.071226 -29.261525) (xy 303.055713 -29.203632) (xy 303.04789 -29.14421) (xy 303.0474 -29.114242)
			(xy 293.722552 -29.114242) (xy 293.722552 -29.12237) (xy 293.722062 -29.152354) (xy 293.714234 -29.21181)
			(xy 293.698713 -29.269735) (xy 293.675764 -29.325139) (xy 293.64578 -29.377073) (xy 293.609274 -29.424649)
			(xy 293.566869 -29.467054) (xy 293.519293 -29.50356) (xy 293.467359 -29.533544) (xy 293.411955 -29.556493)
			(xy 293.35403 -29.572014) (xy 293.294574 -29.579842) (xy 293.234606 -29.579842) (xy 293.17515 -29.572014)
			(xy 293.117225 -29.556493) (xy 293.061821 -29.533544) (xy 293.009887 -29.50356) (xy 292.962311 -29.467054)
			(xy 292.919906 -29.424649) (xy 292.8834 -29.377073) (xy 292.853416 -29.325139) (xy 292.830467 -29.269735)
			(xy 292.814946 -29.21181) (xy 292.807118 -29.152354) (xy 292.806628 -29.12237) (xy 291.053564 -29.12237)
			(xy 290.299902 -29.876242) (xy 290.295076 -29.88183) (xy 290.295076 -30.922468) (xy 290.952428 -30.922468)
			(xy 290.952428 -30.058868) (xy 290.952918 -30.028884) (xy 290.960746 -29.969428) (xy 290.976267 -29.911503)
			(xy 290.999216 -29.856099) (xy 291.0292 -29.804165) (xy 291.065706 -29.756589) (xy 291.108111 -29.714184)
			(xy 291.155687 -29.677678) (xy 291.207621 -29.647694) (xy 291.263025 -29.624745) (xy 291.32095 -29.609224)
			(xy 291.380406 -29.601396) (xy 291.440374 -29.601396) (xy 291.49983 -29.609224) (xy 291.557755 -29.624745)
			(xy 291.613159 -29.647694) (xy 291.665093 -29.677678) (xy 291.712669 -29.714184) (xy 291.755074 -29.756589)
			(xy 291.79158 -29.804165) (xy 291.821564 -29.856099) (xy 291.844513 -29.911503) (xy 291.860034 -29.969428)
			(xy 291.867862 -30.028884) (xy 291.868352 -30.058868) (xy 291.868352 -30.92069) (xy 305.689508 -30.92069)
			(xy 305.689508 -30.05709) (xy 305.689998 -30.027122) (xy 305.697821 -29.9677) (xy 305.713334 -29.909807)
			(xy 305.73627 -29.854434) (xy 305.766237 -29.802528) (xy 305.802724 -29.754978) (xy 305.845104 -29.712598)
			(xy 305.892654 -29.676111) (xy 305.94456 -29.646144) (xy 305.999933 -29.623208) (xy 306.057826 -29.607695)
			(xy 306.117248 -29.599872) (xy 306.177184 -29.599872) (xy 306.236606 -29.607695) (xy 306.294499 -29.623208)
			(xy 306.349872 -29.646144) (xy 306.401778 -29.676111) (xy 306.449328 -29.712598) (xy 306.491708 -29.754978)
			(xy 306.528195 -29.802528) (xy 306.558162 -29.854434) (xy 306.581098 -29.909807) (xy 306.596611 -29.9677)
			(xy 306.604434 -30.027122) (xy 306.604924 -30.05709) (xy 306.604924 -30.92069) (xy 306.604434 -30.950658)
			(xy 306.596611 -31.01008) (xy 306.581098 -31.067973) (xy 306.558162 -31.123346) (xy 306.528195 -31.175252)
			(xy 306.491708 -31.222802) (xy 306.449328 -31.265182) (xy 306.401778 -31.301669) (xy 306.349872 -31.331636)
			(xy 306.294499 -31.354572) (xy 306.236606 -31.370085) (xy 306.177184 -31.377908) (xy 306.117248 -31.377908)
			(xy 306.057826 -31.370085) (xy 305.999933 -31.354572) (xy 305.94456 -31.331636) (xy 305.892654 -31.301669)
			(xy 305.845104 -31.265182) (xy 305.802724 -31.222802) (xy 305.766237 -31.175252) (xy 305.73627 -31.123346)
			(xy 305.713334 -31.067973) (xy 305.697821 -31.01008) (xy 305.689998 -30.950658) (xy 305.689508 -30.92069)
			(xy 291.868352 -30.92069) (xy 291.868352 -30.922468) (xy 291.867862 -30.952452) (xy 291.860034 -31.011908)
			(xy 291.844513 -31.069833) (xy 291.821564 -31.125237) (xy 291.79158 -31.177171) (xy 291.755074 -31.224747)
			(xy 291.712669 -31.267152) (xy 291.665093 -31.303658) (xy 291.613159 -31.333642) (xy 291.557755 -31.356591)
			(xy 291.49983 -31.372112) (xy 291.440374 -31.37994) (xy 291.380406 -31.37994) (xy 291.32095 -31.372112)
			(xy 291.263025 -31.356591) (xy 291.207621 -31.333642) (xy 291.155687 -31.303658) (xy 291.108111 -31.267152)
			(xy 291.065706 -31.224747) (xy 291.0292 -31.177171) (xy 290.999216 -31.125237) (xy 290.976267 -31.069833)
			(xy 290.960746 -31.011908) (xy 290.952918 -30.952452) (xy 290.952428 -30.922468) (xy 290.295076 -30.922468)
			(xy 290.295076 -32.722312) (xy 292.806628 -32.722312) (xy 292.806628 -31.858712) (xy 292.807118 -31.828728)
			(xy 292.814946 -31.769272) (xy 292.830467 -31.711347) (xy 292.853416 -31.655943) (xy 292.8834 -31.604009)
			(xy 292.919906 -31.556433) (xy 292.962311 -31.514028) (xy 293.009887 -31.477522) (xy 293.061821 -31.447538)
			(xy 293.117225 -31.424589) (xy 293.17515 -31.409068) (xy 293.234606 -31.40124) (xy 293.294574 -31.40124)
			(xy 293.35403 -31.409068) (xy 293.411955 -31.424589) (xy 293.467359 -31.447538) (xy 293.519293 -31.477522)
			(xy 293.566869 -31.514028) (xy 293.609274 -31.556433) (xy 293.64578 -31.604009) (xy 293.675764 -31.655943)
			(xy 293.698713 -31.711347) (xy 293.714234 -31.769272) (xy 293.722062 -31.828728) (xy 293.722552 -31.858712)
			(xy 293.722552 -32.714184) (xy 303.0474 -32.714184) (xy 303.0474 -31.850584) (xy 303.04789 -31.820616)
			(xy 303.055713 -31.761194) (xy 303.071226 -31.703301) (xy 303.094162 -31.647928) (xy 303.124129 -31.596022)
			(xy 303.160616 -31.548472) (xy 303.202996 -31.506092) (xy 303.250546 -31.469605) (xy 303.302452 -31.439638)
			(xy 303.357825 -31.416702) (xy 303.415718 -31.401189) (xy 303.47514 -31.393366) (xy 303.535076 -31.393366)
			(xy 303.594498 -31.401189) (xy 303.652391 -31.416702) (xy 303.707764 -31.439638) (xy 303.75967 -31.469605)
			(xy 303.80722 -31.506092) (xy 303.8496 -31.548472) (xy 303.886087 -31.596022) (xy 303.916054 -31.647928)
			(xy 303.93899 -31.703301) (xy 303.954503 -31.761194) (xy 303.962326 -31.820616) (xy 303.962816 -31.850584)
			(xy 303.962816 -32.714184) (xy 303.962326 -32.744152) (xy 303.954503 -32.803574) (xy 303.93899 -32.861467)
			(xy 303.916054 -32.91684) (xy 303.886087 -32.968746) (xy 303.8496 -33.016296) (xy 303.80722 -33.058676)
			(xy 303.75967 -33.095163) (xy 303.707764 -33.12513) (xy 303.652391 -33.148066) (xy 303.594498 -33.163579)
			(xy 303.535076 -33.171402) (xy 303.47514 -33.171402) (xy 303.415718 -33.163579) (xy 303.357825 -33.148066)
			(xy 303.302452 -33.12513) (xy 303.250546 -33.095163) (xy 303.202996 -33.058676) (xy 303.160616 -33.016296)
			(xy 303.124129 -32.968746) (xy 303.094162 -32.91684) (xy 303.071226 -32.861467) (xy 303.055713 -32.803574)
			(xy 303.04789 -32.744152) (xy 303.0474 -32.714184) (xy 293.722552 -32.714184) (xy 293.722552 -32.722312)
			(xy 293.722062 -32.752296) (xy 293.714234 -32.811752) (xy 293.698713 -32.869677) (xy 293.675764 -32.925081)
			(xy 293.64578 -32.977015) (xy 293.609274 -33.024591) (xy 293.566869 -33.066996) (xy 293.519293 -33.103502)
			(xy 293.467359 -33.133486) (xy 293.411955 -33.156435) (xy 293.35403 -33.171956) (xy 293.294574 -33.179784)
			(xy 293.234606 -33.179784) (xy 293.17515 -33.171956) (xy 293.117225 -33.156435) (xy 293.061821 -33.133486)
			(xy 293.009887 -33.103502) (xy 292.962311 -33.066996) (xy 292.919906 -33.024591) (xy 292.8834 -32.977015)
			(xy 292.853416 -32.925081) (xy 292.830467 -32.869677) (xy 292.814946 -32.811752) (xy 292.807118 -32.752296)
			(xy 292.806628 -32.722312) (xy 290.295076 -32.722312) (xy 290.295076 -34.52241) (xy 290.952428 -34.52241)
			(xy 290.952428 -33.65881) (xy 290.952918 -33.628826) (xy 290.960746 -33.56937) (xy 290.976267 -33.511445)
			(xy 290.999216 -33.456041) (xy 291.0292 -33.404107) (xy 291.065706 -33.356531) (xy 291.108111 -33.314126)
			(xy 291.155687 -33.27762) (xy 291.207621 -33.247636) (xy 291.263025 -33.224687) (xy 291.32095 -33.209166)
			(xy 291.380406 -33.201338) (xy 291.440374 -33.201338) (xy 291.49983 -33.209166) (xy 291.557755 -33.224687)
			(xy 291.613159 -33.247636) (xy 291.665093 -33.27762) (xy 291.712669 -33.314126) (xy 291.755074 -33.356531)
			(xy 291.79158 -33.404107) (xy 291.821564 -33.456041) (xy 291.844513 -33.511445) (xy 291.860034 -33.56937)
			(xy 291.867862 -33.628826) (xy 291.868352 -33.65881) (xy 291.868352 -34.520886) (xy 305.689508 -34.520886)
			(xy 305.689508 -33.657286) (xy 305.689998 -33.627318) (xy 305.697821 -33.567896) (xy 305.713334 -33.510003)
			(xy 305.73627 -33.45463) (xy 305.766237 -33.402724) (xy 305.802724 -33.355174) (xy 305.845104 -33.312794)
			(xy 305.892654 -33.276307) (xy 305.94456 -33.24634) (xy 305.999933 -33.223404) (xy 306.057826 -33.207891)
			(xy 306.117248 -33.200068) (xy 306.177184 -33.200068) (xy 306.236606 -33.207891) (xy 306.294499 -33.223404)
			(xy 306.349872 -33.24634) (xy 306.401778 -33.276307) (xy 306.449328 -33.312794) (xy 306.491708 -33.355174)
			(xy 306.528195 -33.402724) (xy 306.558162 -33.45463) (xy 306.581098 -33.510003) (xy 306.596611 -33.567896)
			(xy 306.604434 -33.627318) (xy 306.604924 -33.657286) (xy 306.604924 -34.520886) (xy 306.604434 -34.550854)
			(xy 306.596611 -34.610276) (xy 306.581098 -34.668169) (xy 306.558162 -34.723542) (xy 306.528195 -34.775448)
			(xy 306.491708 -34.822998) (xy 306.449328 -34.865378) (xy 306.401778 -34.901865) (xy 306.349872 -34.931832)
			(xy 306.294499 -34.954768) (xy 306.236606 -34.970281) (xy 306.177184 -34.978104) (xy 306.117248 -34.978104)
			(xy 306.057826 -34.970281) (xy 305.999933 -34.954768) (xy 305.94456 -34.931832) (xy 305.892654 -34.901865)
			(xy 305.845104 -34.865378) (xy 305.802724 -34.822998) (xy 305.766237 -34.775448) (xy 305.73627 -34.723542)
			(xy 305.713334 -34.668169) (xy 305.697821 -34.610276) (xy 305.689998 -34.550854) (xy 305.689508 -34.520886)
			(xy 291.868352 -34.520886) (xy 291.868352 -34.52241) (xy 291.867862 -34.552394) (xy 291.860034 -34.61185)
			(xy 291.844513 -34.669775) (xy 291.821564 -34.725179) (xy 291.79158 -34.777113) (xy 291.755074 -34.824689)
			(xy 291.712669 -34.867094) (xy 291.665093 -34.9036) (xy 291.613159 -34.933584) (xy 291.557755 -34.956533)
			(xy 291.49983 -34.972054) (xy 291.440374 -34.979882) (xy 291.380406 -34.979882) (xy 291.32095 -34.972054)
			(xy 291.263025 -34.956533) (xy 291.207621 -34.933584) (xy 291.155687 -34.9036) (xy 291.108111 -34.867094)
			(xy 291.065706 -34.824689) (xy 291.0292 -34.777113) (xy 290.999216 -34.725179) (xy 290.976267 -34.669775)
			(xy 290.960746 -34.61185) (xy 290.952918 -34.552394) (xy 290.952428 -34.52241) (xy 290.295076 -34.52241)
			(xy 290.295076 -34.72434) (xy 290.295584 -34.73196) (xy 290.297037 -34.739795) (xy 290.304151 -34.754044)
			(xy 290.309554 -34.7599) (xy 291.239702 -35.689794) (xy 291.69741 -36.147502) (xy 291.704014 -36.149534)
			(xy 291.729827 -36.157633) (xy 291.779038 -36.180103) (xy 291.824581 -36.209302) (xy 291.86554 -36.244643)
			(xy 291.901096 -36.285417) (xy 291.930533 -36.330806) (xy 291.953261 -36.379898) (xy 291.968825 -36.43171)
			(xy 291.976912 -36.485201) (xy 291.977572 -36.512246) (xy 291.977572 -36.519104) (xy 291.977257 -36.536613)
			(xy 291.973825 -36.571466) (xy 291.970714 -36.5887) (xy 291.969444 -36.594796) (xy 291.968249 -36.60013)
			(xy 296.198551 -36.60013) (xy 296.202555 -36.512245) (xy 296.214535 -36.425088) (xy 296.23439 -36.339381)
			(xy 296.261957 -36.255836) (xy 296.297007 -36.175143) (xy 296.339249 -36.097971) (xy 296.388334 -36.024961)
			(xy 296.443855 -35.956717) (xy 296.505352 -35.893804) (xy 296.572314 -35.836744) (xy 296.644188 -35.78601)
			(xy 296.720378 -35.742022) (xy 296.800252 -35.705144) (xy 296.883149 -35.675683) (xy 296.968381 -35.653881)
			(xy 297.055243 -35.639921) (xy 297.143014 -35.633917) (xy 297.230968 -35.63592) (xy 297.318375 -35.645912)
			(xy 297.404511 -35.663812) (xy 297.488663 -35.68947) (xy 297.570133 -35.722674) (xy 297.648246 -35.763148)
			(xy 297.722354 -35.810559) (xy 297.791845 -35.864512) (xy 297.804936 -35.876738) (xy 302.917096 -35.876738)
			(xy 302.921167 -35.821116) (xy 302.933293 -35.766679) (xy 302.953216 -35.714588) (xy 302.980512 -35.665953)
			(xy 303.014598 -35.62181) (xy 303.054747 -35.583101) (xy 303.100105 -35.55065) (xy 303.149705 -35.525149)
			(xy 303.202489 -35.507142) (xy 303.257332 -35.497012) (xy 303.313066 -35.494975) (xy 303.368503 -35.501075)
			(xy 303.42246 -35.515181) (xy 303.473789 -35.536993) (xy 303.521395 -35.566047) (xy 303.564263 -35.601722)
			(xy 303.60148 -35.643259) (xy 303.632253 -35.689772) (xy 303.655925 -35.740269) (xy 303.671993 -35.793676)
			(xy 303.680113 -35.848852) (xy 303.680622 -35.876738) (xy 303.680113 -35.904624) (xy 303.671993 -35.9598)
			(xy 303.655925 -36.013207) (xy 303.632253 -36.063704) (xy 303.60148 -36.110217) (xy 303.564263 -36.151754)
			(xy 303.521395 -36.187429) (xy 303.473789 -36.216483) (xy 303.42246 -36.238295) (xy 303.368503 -36.252401)
			(xy 303.313066 -36.258501) (xy 303.257332 -36.256464) (xy 303.202489 -36.246334) (xy 303.149705 -36.228327)
			(xy 303.100105 -36.202826) (xy 303.054747 -36.170375) (xy 303.014598 -36.131666) (xy 302.980512 -36.087523)
			(xy 302.953216 -36.038888) (xy 302.933293 -35.986797) (xy 302.921167 -35.93236) (xy 302.917096 -35.876738)
			(xy 297.804936 -35.876738) (xy 297.856141 -35.92456) (xy 297.91471 -35.990207) (xy 297.967067 -36.060907)
			(xy 298.012779 -36.136076) (xy 298.051465 -36.21509) (xy 298.082806 -36.297295) (xy 298.106541 -36.382009)
			(xy 298.122475 -36.46853) (xy 298.126258 -36.50996) (xy 304.813714 -36.50996) (xy 304.817785 -36.454338)
			(xy 304.829911 -36.399901) (xy 304.849834 -36.34781) (xy 304.87713 -36.299175) (xy 304.911216 -36.255032)
			(xy 304.951365 -36.216323) (xy 304.996723 -36.183872) (xy 305.046323 -36.158371) (xy 305.099107 -36.140364)
			(xy 305.15395 -36.130234) (xy 305.209684 -36.128197) (xy 305.265121 -36.134297) (xy 305.319078 -36.148403)
			(xy 305.370407 -36.170215) (xy 305.418013 -36.199269) (xy 305.460881 -36.234944) (xy 305.498098 -36.276481)
			(xy 305.528871 -36.322994) (xy 305.552543 -36.373491) (xy 305.568611 -36.426898) (xy 305.576731 -36.482074)
			(xy 305.57724 -36.50996) (xy 305.576731 -36.537846) (xy 305.568611 -36.593022) (xy 305.552543 -36.646429)
			(xy 305.528871 -36.696926) (xy 305.498098 -36.743439) (xy 305.460881 -36.784976) (xy 305.418013 -36.820651)
			(xy 305.370407 -36.849705) (xy 305.319078 -36.871517) (xy 305.265121 -36.885623) (xy 305.209684 -36.891723)
			(xy 305.15395 -36.889686) (xy 305.099107 -36.879556) (xy 305.046323 -36.861549) (xy 304.996723 -36.836048)
			(xy 304.951365 -36.803597) (xy 304.911216 -36.764888) (xy 304.87713 -36.720745) (xy 304.849834 -36.67211)
			(xy 304.829911 -36.620019) (xy 304.817785 -36.565582) (xy 304.813714 -36.50996) (xy 298.126258 -36.50996)
			(xy 298.130475 -36.556142) (xy 298.130976 -36.60013) (xy 298.130475 -36.644118) (xy 298.122475 -36.73173)
			(xy 298.106541 -36.818251) (xy 298.082806 -36.902965) (xy 298.051465 -36.98517) (xy 298.012779 -37.064184)
			(xy 297.967067 -37.139353) (xy 297.91471 -37.210053) (xy 297.856141 -37.2757) (xy 297.791845 -37.335748)
			(xy 297.722354 -37.389701) (xy 297.648246 -37.437112) (xy 297.574815 -37.47516) (xy 301.959008 -37.47516)
			(xy 301.963079 -37.419538) (xy 301.975205 -37.365101) (xy 301.995128 -37.31301) (xy 302.022424 -37.264375)
			(xy 302.05651 -37.220232) (xy 302.096659 -37.181523) (xy 302.142017 -37.149072) (xy 302.191617 -37.123571)
			(xy 302.244401 -37.105564) (xy 302.299244 -37.095434) (xy 302.354978 -37.093397) (xy 302.410415 -37.099497)
			(xy 302.464372 -37.113603) (xy 302.515701 -37.135415) (xy 302.563307 -37.164469) (xy 302.606175 -37.200144)
			(xy 302.643392 -37.241681) (xy 302.674165 -37.288194) (xy 302.697837 -37.338691) (xy 302.713905 -37.392098)
			(xy 302.722025 -37.447274) (xy 302.722534 -37.47516) (xy 302.722025 -37.503046) (xy 302.713905 -37.558222)
			(xy 302.697837 -37.611629) (xy 302.674165 -37.662126) (xy 302.674012 -37.662358) (xy 304.148234 -37.662358)
			(xy 304.152305 -37.606736) (xy 304.164431 -37.552299) (xy 304.184354 -37.500208) (xy 304.21165 -37.451573)
			(xy 304.245736 -37.40743) (xy 304.285885 -37.368721) (xy 304.331243 -37.33627) (xy 304.380843 -37.310769)
			(xy 304.433627 -37.292762) (xy 304.48847 -37.282632) (xy 304.544204 -37.280595) (xy 304.599641 -37.286695)
			(xy 304.653598 -37.300801) (xy 304.704927 -37.322613) (xy 304.752533 -37.351667) (xy 304.795401 -37.387342)
			(xy 304.832618 -37.428879) (xy 304.863391 -37.475392) (xy 304.887063 -37.525889) (xy 304.903131 -37.579296)
			(xy 304.911251 -37.634472) (xy 304.91176 -37.662358) (xy 304.911251 -37.690244) (xy 304.903131 -37.74542)
			(xy 304.887063 -37.798827) (xy 304.863391 -37.849324) (xy 304.832618 -37.895837) (xy 304.795401 -37.937374)
			(xy 304.752533 -37.973049) (xy 304.704927 -38.002103) (xy 304.653598 -38.023915) (xy 304.599641 -38.038021)
			(xy 304.544204 -38.044121) (xy 304.48847 -38.042084) (xy 304.433627 -38.031954) (xy 304.380843 -38.013947)
			(xy 304.331243 -37.988446) (xy 304.285885 -37.955995) (xy 304.245736 -37.917286) (xy 304.21165 -37.873143)
			(xy 304.184354 -37.824508) (xy 304.164431 -37.772417) (xy 304.152305 -37.71798) (xy 304.148234 -37.662358)
			(xy 302.674012 -37.662358) (xy 302.643392 -37.708639) (xy 302.606175 -37.750176) (xy 302.563307 -37.785851)
			(xy 302.515701 -37.814905) (xy 302.464372 -37.836717) (xy 302.410415 -37.850823) (xy 302.354978 -37.856923)
			(xy 302.299244 -37.854886) (xy 302.244401 -37.844756) (xy 302.191617 -37.826749) (xy 302.142017 -37.801248)
			(xy 302.096659 -37.768797) (xy 302.05651 -37.730088) (xy 302.022424 -37.685945) (xy 301.995128 -37.63731)
			(xy 301.975205 -37.585219) (xy 301.963079 -37.530782) (xy 301.959008 -37.47516) (xy 297.574815 -37.47516)
			(xy 297.570133 -37.477586) (xy 297.488663 -37.51079) (xy 297.404511 -37.536448) (xy 297.318375 -37.554348)
			(xy 297.230968 -37.56434) (xy 297.143014 -37.566343) (xy 297.055243 -37.560339) (xy 296.968381 -37.546379)
			(xy 296.883149 -37.524577) (xy 296.800252 -37.495116) (xy 296.720378 -37.458238) (xy 296.644188 -37.41425)
			(xy 296.572314 -37.363516) (xy 296.505352 -37.306456) (xy 296.443855 -37.243543) (xy 296.388334 -37.175299)
			(xy 296.339249 -37.102289) (xy 296.297007 -37.025117) (xy 296.261957 -36.944424) (xy 296.23439 -36.860879)
			(xy 296.214535 -36.775172) (xy 296.202555 -36.688015) (xy 296.198551 -36.60013) (xy 291.968249 -36.60013)
			(xy 291.964707 -36.615933) (xy 291.951081 -36.657052) (xy 291.942266 -36.676838) (xy 291.937948 -36.686236)
			(xy 291.937948 -38.729951) (xy 307.900797 -38.729951) (xy 307.900797 -38.675449) (xy 307.908554 -38.621501)
			(xy 307.92391 -38.569206) (xy 307.946553 -38.519629) (xy 307.97602 -38.47378) (xy 308.011714 -38.432591)
			(xy 308.052905 -38.396901) (xy 308.098758 -38.367437) (xy 308.148336 -38.344799) (xy 308.200632 -38.329447)
			(xy 308.254581 -38.321695) (xy 308.281832 -38.321234) (xy 308.310135 -38.321761) (xy 308.366122 -38.330104)
			(xy 308.420262 -38.346632) (xy 308.471363 -38.370981) (xy 308.518303 -38.402616) (xy 308.560051 -38.440842)
			(xy 308.59569 -38.48482) (xy 308.610508 -38.50894) (xy 308.618129 -38.520959) (xy 308.638743 -38.54056)
			(xy 308.66397 -38.553702) (xy 308.691846 -38.559364) (xy 308.720201 -38.557103) (xy 308.746828 -38.547096)
			(xy 308.769654 -38.530122) (xy 308.778656 -38.5191) (xy 308.796815 -38.496201) (xy 308.838984 -38.455739)
			(xy 308.886825 -38.422174) (xy 308.939222 -38.396291) (xy 308.994951 -38.378694) (xy 309.052711 -38.369794)
			(xy 309.081932 -38.36924) (xy 309.109185 -38.369632) (xy 309.163136 -38.377393) (xy 309.215434 -38.392753)
			(xy 309.265013 -38.415399) (xy 309.310865 -38.44487) (xy 309.352057 -38.480566) (xy 309.387749 -38.52176)
			(xy 309.417216 -38.567615) (xy 309.439858 -38.617196) (xy 309.455214 -38.669495) (xy 309.46297 -38.723447)
			(xy 309.46297 -38.777953) (xy 309.455214 -38.831905) (xy 309.439858 -38.884204) (xy 309.417216 -38.933785)
			(xy 309.387749 -38.97964) (xy 309.352057 -39.020834) (xy 309.310865 -39.05653) (xy 309.265013 -39.086001)
			(xy 309.215434 -39.108647) (xy 309.163136 -39.124007) (xy 309.109185 -39.131768) (xy 309.081932 -39.132256)
			(xy 309.053628 -39.131762) (xy 308.997639 -39.123413) (xy 308.943499 -39.106881) (xy 308.892397 -39.082526)
			(xy 308.845457 -39.050886) (xy 308.80371 -39.012654) (xy 308.768073 -38.968672) (xy 308.753256 -38.94455)
			(xy 308.745682 -38.932499) (xy 308.725058 -38.912898) (xy 308.699821 -38.899758) (xy 308.671936 -38.894101)
			(xy 308.643573 -38.896367) (xy 308.61694 -38.906382) (xy 308.594111 -38.923364) (xy 308.585108 -38.93439)
			(xy 308.566909 -38.957256) (xy 308.524749 -38.997721) (xy 308.476916 -39.03129) (xy 308.424527 -39.057179)
			(xy 308.368804 -39.074783) (xy 308.31105 -39.083692) (xy 308.281832 -39.08425) (xy 308.254581 -39.083705)
			(xy 308.200632 -39.075953) (xy 308.148336 -39.060601) (xy 308.098758 -39.037963) (xy 308.052905 -39.008499)
			(xy 308.011714 -38.972809) (xy 307.97602 -38.93162) (xy 307.946553 -38.885771) (xy 307.92391 -38.836194)
			(xy 307.908554 -38.783899) (xy 307.900797 -38.729951) (xy 291.937948 -38.729951) (xy 291.937948 -38.90645)
			(xy 291.938964 -38.916102) (xy 291.940599 -38.923342) (xy 291.947453 -38.936499) (xy 291.952426 -38.94201)
			(xy 294.279167 -41.268751) (xy 300.04385 -41.268751) (xy 300.04385 -41.214249) (xy 300.051605 -41.160302)
			(xy 300.066959 -41.108007) (xy 300.089598 -41.05843) (xy 300.119062 -41.012578) (xy 300.154751 -40.971386)
			(xy 300.195938 -40.935692) (xy 300.241786 -40.906222) (xy 300.29136 -40.883577) (xy 300.343653 -40.868216)
			(xy 300.397599 -40.860453) (xy 300.42485 -40.859964) (xy 300.45359 -40.860467) (xy 300.510417 -40.869096)
			(xy 300.565308 -40.886152) (xy 300.617019 -40.911247) (xy 300.664381 -40.943816) (xy 300.685708 -40.963088)
			(xy 300.692566 -40.969692) (xy 300.7106 -40.976804) (xy 300.7995 -40.976804) (xy 300.817534 -40.969692)
			(xy 300.824392 -40.963088) (xy 300.845706 -40.943802) (xy 300.893071 -40.911236) (xy 300.944785 -40.886145)
			(xy 300.999679 -40.869099) (xy 301.05651 -40.860481) (xy 301.08525 -40.859964) (xy 301.112503 -40.86048)
			(xy 301.166456 -40.86823) (xy 301.218756 -40.883581) (xy 301.268338 -40.906219) (xy 301.314194 -40.935684)
			(xy 301.35539 -40.971375) (xy 301.391086 -41.012566) (xy 301.420557 -41.058418) (xy 301.443201 -41.107998)
			(xy 301.458559 -41.160296) (xy 301.466317 -41.214247) (xy 301.466317 -41.268753) (xy 301.458559 -41.322704)
			(xy 301.443201 -41.375002) (xy 301.420557 -41.424582) (xy 301.391086 -41.470434) (xy 301.35539 -41.511625)
			(xy 301.314194 -41.547316) (xy 301.268338 -41.576781) (xy 301.218756 -41.599419) (xy 301.166456 -41.61477)
			(xy 301.112503 -41.62252) (xy 301.08525 -41.62298) (xy 301.056511 -41.622465) (xy 300.999684 -41.613837)
			(xy 300.944794 -41.596784) (xy 300.893083 -41.571691) (xy 300.84572 -41.539126) (xy 300.824392 -41.519856)
			(xy 300.817534 -41.513252) (xy 300.7995 -41.50614) (xy 300.7106 -41.50614) (xy 300.692566 -41.513252)
			(xy 300.685708 -41.519856) (xy 300.664401 -41.539149) (xy 300.617033 -41.571713) (xy 300.565317 -41.596801)
			(xy 300.510422 -41.613846) (xy 300.45359 -41.622463) (xy 300.42485 -41.62298) (xy 300.397599 -41.622547)
			(xy 300.343653 -41.614784) (xy 300.29136 -41.599423) (xy 300.241786 -41.576778) (xy 300.195938 -41.547308)
			(xy 300.154751 -41.511614) (xy 300.119062 -41.470422) (xy 300.089598 -41.42457) (xy 300.066959 -41.374993)
			(xy 300.051605 -41.322698) (xy 300.04385 -41.268751) (xy 294.279167 -41.268751) (xy 296.315638 -43.305222)
			(xy 302.507142 -43.305222) (xy 302.507611 -43.277852) (xy 302.515426 -43.223672) (xy 302.530914 -43.171169)
			(xy 302.553756 -43.121422) (xy 302.58348 -43.075455) (xy 302.601122 -43.054524) (xy 302.601376 -43.05427)
			(xy 302.606948 -43.047174) (xy 302.613202 -43.030264) (xy 302.613568 -43.02125) (xy 302.613568 -42.954194)
			(xy 302.613221 -42.945176) (xy 302.606967 -42.928259) (xy 302.601376 -42.921174) (xy 302.601122 -42.921174)
			(xy 302.601122 -42.92092) (xy 302.583482 -42.899988) (xy 302.55377 -42.854016) (xy 302.530934 -42.804268)
			(xy 302.515443 -42.751767) (xy 302.507615 -42.697591) (xy 302.507142 -42.670222) (xy 302.507695 -42.641484)
			(xy 302.516313 -42.584659) (xy 302.533357 -42.529769) (xy 302.558441 -42.478057) (xy 302.590999 -42.430693)
			(xy 302.610266 -42.409364) (xy 302.61687 -42.402506) (xy 302.623982 -42.384472) (xy 302.623982 -42.295572)
			(xy 302.61687 -42.277538) (xy 302.610266 -42.27068) (xy 302.59102 -42.249333) (xy 302.558458 -42.201972)
			(xy 302.53337 -42.150263) (xy 302.516321 -42.095376) (xy 302.507697 -42.038553) (xy 302.507695 -41.981079)
			(xy 302.516313 -41.924255) (xy 302.533358 -41.869366) (xy 302.558442 -41.817655) (xy 302.590999 -41.770292)
			(xy 302.610266 -41.748964) (xy 302.61687 -41.742106) (xy 302.623982 -41.724072) (xy 302.623982 -41.635172)
			(xy 302.61687 -41.617138) (xy 302.610266 -41.61028) (xy 302.59101 -41.58894) (xy 302.558441 -41.541582)
			(xy 302.533345 -41.489874) (xy 302.516291 -41.434986) (xy 302.507665 -41.37816) (xy 302.507142 -41.349422)
			(xy 302.507628 -41.322171) (xy 302.515384 -41.268223) (xy 302.530739 -41.215928) (xy 302.553381 -41.166351)
			(xy 302.582847 -41.120501) (xy 302.618538 -41.07931) (xy 302.659729 -41.043619) (xy 302.705579 -41.014153)
			(xy 302.755156 -40.991511) (xy 302.807451 -40.976156) (xy 302.861399 -40.9684) (xy 302.915901 -40.9684)
			(xy 302.939022 -40.971724) (xy 310.79389 -40.971724) (xy 310.797961 -40.916102) (xy 310.810087 -40.861665)
			(xy 310.83001 -40.809574) (xy 310.857306 -40.760939) (xy 310.891392 -40.716796) (xy 310.931541 -40.678087)
			(xy 310.976899 -40.645636) (xy 311.026499 -40.620135) (xy 311.079283 -40.602128) (xy 311.134126 -40.591998)
			(xy 311.18986 -40.589961) (xy 311.245297 -40.596061) (xy 311.299254 -40.610167) (xy 311.350583 -40.631979)
			(xy 311.398189 -40.661033) (xy 311.441057 -40.696708) (xy 311.478274 -40.738245) (xy 311.509047 -40.784758)
			(xy 311.532719 -40.835255) (xy 311.548787 -40.888662) (xy 311.556907 -40.943838) (xy 311.557416 -40.971724)
			(xy 311.556907 -40.99961) (xy 311.548787 -41.054786) (xy 311.532719 -41.108193) (xy 311.509047 -41.15869)
			(xy 311.478274 -41.205203) (xy 311.441057 -41.24674) (xy 311.398189 -41.282415) (xy 311.350583 -41.311469)
			(xy 311.299254 -41.333281) (xy 311.245297 -41.347387) (xy 311.18986 -41.353487) (xy 311.134126 -41.35145)
			(xy 311.079283 -41.34132) (xy 311.026499 -41.323313) (xy 310.976899 -41.297812) (xy 310.931541 -41.265361)
			(xy 310.891392 -41.226652) (xy 310.857306 -41.182509) (xy 310.83001 -41.133874) (xy 310.810087 -41.081783)
			(xy 310.797961 -41.027346) (xy 310.79389 -40.971724) (xy 302.939022 -40.971724) (xy 302.969849 -40.976156)
			(xy 303.022144 -40.991511) (xy 303.071721 -41.014153) (xy 303.117571 -41.043619) (xy 303.158762 -41.07931)
			(xy 303.194453 -41.120501) (xy 303.223919 -41.166351) (xy 303.246561 -41.215928) (xy 303.261916 -41.268223)
			(xy 303.269672 -41.322171) (xy 303.270158 -41.349422) (xy 303.269632 -41.378161) (xy 303.261008 -41.434987)
			(xy 303.243957 -41.489877) (xy 303.218867 -41.541589) (xy 303.186303 -41.588952) (xy 303.167034 -41.61028)
			(xy 303.16043 -41.617138) (xy 303.153318 -41.635172) (xy 303.153318 -41.724072) (xy 303.16043 -41.742106)
			(xy 303.167034 -41.748964) (xy 303.186324 -41.770273) (xy 303.218884 -41.81764) (xy 303.24397 -41.869355)
			(xy 303.261016 -41.924248) (xy 303.269635 -41.981077) (xy 303.269633 -42.038555) (xy 303.261009 -42.095383)
			(xy 303.243958 -42.150275) (xy 303.218868 -42.201987) (xy 303.186304 -42.249352) (xy 303.167034 -42.27068)
			(xy 303.16043 -42.277538) (xy 303.153318 -42.295572) (xy 303.153318 -42.384472) (xy 303.16043 -42.402506)
			(xy 303.167034 -42.409364) (xy 303.186311 -42.430686) (xy 303.218877 -42.478049) (xy 303.243969 -42.529762)
			(xy 303.261018 -42.584654) (xy 303.269639 -42.641483) (xy 303.270158 -42.670222) (xy 303.269715 -42.697593)
			(xy 303.261893 -42.751774) (xy 303.246399 -42.804277) (xy 303.225842 -42.849038) (xy 305.091844 -42.849038)
			(xy 305.095915 -42.793416) (xy 305.108041 -42.738979) (xy 305.127964 -42.686888) (xy 305.15526 -42.638253)
			(xy 305.189346 -42.59411) (xy 305.229495 -42.555401) (xy 305.274853 -42.52295) (xy 305.324453 -42.497449)
			(xy 305.377237 -42.479442) (xy 305.43208 -42.469312) (xy 305.487814 -42.467275) (xy 305.543251 -42.473375)
			(xy 305.597208 -42.487481) (xy 305.648537 -42.509293) (xy 305.696143 -42.538347) (xy 305.739011 -42.574022)
			(xy 305.776228 -42.615559) (xy 305.807001 -42.662072) (xy 305.830673 -42.712569) (xy 305.846741 -42.765976)
			(xy 305.854861 -42.821152) (xy 305.855222 -42.84091) (xy 311.13298 -42.84091) (xy 311.137051 -42.785288)
			(xy 311.149177 -42.730851) (xy 311.1691 -42.67876) (xy 311.196396 -42.630125) (xy 311.230482 -42.585982)
			(xy 311.270631 -42.547273) (xy 311.315989 -42.514822) (xy 311.365589 -42.489321) (xy 311.418373 -42.471314)
			(xy 311.473216 -42.461184) (xy 311.52895 -42.459147) (xy 311.584387 -42.465247) (xy 311.638344 -42.479353)
			(xy 311.689673 -42.501165) (xy 311.737279 -42.530219) (xy 311.780147 -42.565894) (xy 311.817364 -42.607431)
			(xy 311.848137 -42.653944) (xy 311.871809 -42.704441) (xy 311.887877 -42.757848) (xy 311.895997 -42.813024)
			(xy 311.896506 -42.84091) (xy 311.895997 -42.868796) (xy 311.887877 -42.923972) (xy 311.871809 -42.977379)
			(xy 311.848137 -43.027876) (xy 311.817364 -43.074389) (xy 311.780147 -43.115926) (xy 311.737279 -43.151601)
			(xy 311.689673 -43.180655) (xy 311.638344 -43.202467) (xy 311.584387 -43.216573) (xy 311.52895 -43.222673)
			(xy 311.473216 -43.220636) (xy 311.418373 -43.210506) (xy 311.365589 -43.192499) (xy 311.315989 -43.166998)
			(xy 311.270631 -43.134547) (xy 311.230482 -43.095838) (xy 311.196396 -43.051695) (xy 311.1691 -43.00306)
			(xy 311.149177 -42.950969) (xy 311.137051 -42.896532) (xy 311.13298 -42.84091) (xy 305.855222 -42.84091)
			(xy 305.85537 -42.849038) (xy 305.854861 -42.876924) (xy 305.846741 -42.9321) (xy 305.830673 -42.985507)
			(xy 305.807001 -43.036004) (xy 305.776228 -43.082517) (xy 305.739011 -43.124054) (xy 305.696143 -43.159729)
			(xy 305.648537 -43.188783) (xy 305.597208 -43.210595) (xy 305.543251 -43.224701) (xy 305.487814 -43.230801)
			(xy 305.43208 -43.228764) (xy 305.377237 -43.218634) (xy 305.324453 -43.200627) (xy 305.274853 -43.175126)
			(xy 305.229495 -43.142675) (xy 305.189346 -43.103966) (xy 305.15526 -43.059823) (xy 305.127964 -43.011188)
			(xy 305.108041 -42.959097) (xy 305.095915 -42.90466) (xy 305.091844 -42.849038) (xy 303.225842 -42.849038)
			(xy 303.223552 -42.854024) (xy 303.193822 -42.899989) (xy 303.176178 -42.92092) (xy 303.175924 -42.921174)
			(xy 303.170333 -42.928257) (xy 303.164091 -42.945177) (xy 303.163732 -42.954194) (xy 303.163732 -43.02125)
			(xy 303.164106 -43.030265) (xy 303.170341 -43.047183) (xy 303.175924 -43.05427) (xy 303.176178 -43.05427)
			(xy 303.176178 -43.054524) (xy 303.193792 -43.075477) (xy 303.223508 -43.121444) (xy 303.246349 -43.171186)
			(xy 303.261846 -43.223682) (xy 303.269681 -43.277854) (xy 303.270158 -43.305222) (xy 303.269672 -43.332473)
			(xy 303.261916 -43.386421) (xy 303.246561 -43.438716) (xy 303.223919 -43.488293) (xy 303.194453 -43.534143)
			(xy 303.158762 -43.575334) (xy 303.117571 -43.611025) (xy 303.071721 -43.640491) (xy 303.022144 -43.663133)
			(xy 302.969849 -43.678488) (xy 302.915901 -43.686244) (xy 302.861399 -43.686244) (xy 302.807451 -43.678488)
			(xy 302.755156 -43.663133) (xy 302.705579 -43.640491) (xy 302.659729 -43.611025) (xy 302.618538 -43.575334)
			(xy 302.582847 -43.534143) (xy 302.553381 -43.488293) (xy 302.530739 -43.438716) (xy 302.515384 -43.386421)
			(xy 302.507628 -43.332473) (xy 302.507142 -43.305222) (xy 296.315638 -43.305222) (xy 296.746676 -43.73626)
			(xy 304.412902 -43.73626) (xy 304.416973 -43.680638) (xy 304.429099 -43.626201) (xy 304.449022 -43.57411)
			(xy 304.476318 -43.525475) (xy 304.510404 -43.481332) (xy 304.550553 -43.442623) (xy 304.595911 -43.410172)
			(xy 304.645511 -43.384671) (xy 304.698295 -43.366664) (xy 304.753138 -43.356534) (xy 304.808872 -43.354497)
			(xy 304.864309 -43.360597) (xy 304.918266 -43.374703) (xy 304.969595 -43.396515) (xy 305.017201 -43.425569)
			(xy 305.060069 -43.461244) (xy 305.097286 -43.502781) (xy 305.128059 -43.549294) (xy 305.136285 -43.566842)
			(xy 307.329332 -43.566842) (xy 307.329875 -43.531428) (xy 307.338408 -43.461117) (xy 307.355354 -43.392347)
			(xy 307.380466 -43.326122) (xy 307.413378 -43.263406) (xy 307.45361 -43.205115) (xy 307.500576 -43.152098)
			(xy 307.55359 -43.10513) (xy 307.611878 -43.064895) (xy 307.674592 -43.031979) (xy 307.740817 -43.006863)
			(xy 307.809586 -42.989914) (xy 307.879896 -42.981377) (xy 307.91531 -42.980864) (xy 307.948192 -42.981279)
			(xy 308.013542 -42.988648) (xy 308.077654 -43.003293) (xy 308.139722 -43.025028) (xy 308.198964 -43.053581)
			(xy 308.254634 -43.088591) (xy 308.306031 -43.129619) (xy 308.329584 -43.152568) (xy 308.831996 -43.65498)
			(xy 308.840327 -43.662367) (xy 308.861257 -43.669885) (xy 308.872382 -43.669458) (xy 308.961536 -43.66133)
			(xy 308.981094 -43.6499) (xy 308.987444 -43.640502) (xy 309.002757 -43.619015) (xy 309.03839 -43.580102)
			(xy 309.079045 -43.546471) (xy 309.123948 -43.518764) (xy 309.17224 -43.497508) (xy 309.223 -43.483111)
			(xy 309.275261 -43.475845) (xy 309.301642 -43.475402) (xy 309.328892 -43.475871) (xy 309.382837 -43.483632)
			(xy 309.435128 -43.498991) (xy 309.484701 -43.521636) (xy 309.530547 -43.551104) (xy 309.571734 -43.586796)
			(xy 309.607421 -43.627986) (xy 309.636885 -43.673836) (xy 309.659523 -43.723412) (xy 309.674877 -43.775704)
			(xy 309.682632 -43.82965) (xy 309.682632 -43.88415) (xy 309.674877 -43.938096) (xy 309.659523 -43.990388)
			(xy 309.636885 -44.039964) (xy 309.607421 -44.085814) (xy 309.571734 -44.127004) (xy 309.530547 -44.162696)
			(xy 309.484701 -44.192164) (xy 309.435128 -44.214809) (xy 309.382837 -44.230168) (xy 309.328892 -44.237929)
			(xy 309.301642 -44.238418) (xy 309.301388 -44.238418) (xy 309.28183 -44.23791) (xy 309.281576 -44.23791)
			(xy 309.271279 -44.237918) (xy 309.252012 -44.245128) (xy 309.244238 -44.25188) (xy 309.190644 -44.30268)
			(xy 309.183518 -44.310179) (xy 309.175387 -44.329178) (xy 309.174896 -44.33951) (xy 309.174896 -44.871132)
			(xy 309.174966 -44.87291) (xy 311.13298 -44.87291) (xy 311.137051 -44.817288) (xy 311.149177 -44.762851)
			(xy 311.1691 -44.71076) (xy 311.196396 -44.662125) (xy 311.230482 -44.617982) (xy 311.270631 -44.579273)
			(xy 311.315989 -44.546822) (xy 311.365589 -44.521321) (xy 311.418373 -44.503314) (xy 311.473216 -44.493184)
			(xy 311.52895 -44.491147) (xy 311.584387 -44.497247) (xy 311.638344 -44.511353) (xy 311.689673 -44.533165)
			(xy 311.737279 -44.562219) (xy 311.780147 -44.597894) (xy 311.817364 -44.639431) (xy 311.848137 -44.685944)
			(xy 311.871809 -44.736441) (xy 311.887877 -44.789848) (xy 311.895997 -44.845024) (xy 311.896506 -44.87291)
			(xy 311.895997 -44.900796) (xy 311.887877 -44.955972) (xy 311.871809 -45.009379) (xy 311.848137 -45.059876)
			(xy 311.817364 -45.106389) (xy 311.780147 -45.147926) (xy 311.737279 -45.183601) (xy 311.689673 -45.212655)
			(xy 311.638344 -45.234467) (xy 311.584387 -45.248573) (xy 311.52895 -45.254673) (xy 311.473216 -45.252636)
			(xy 311.418373 -45.242506) (xy 311.365589 -45.224499) (xy 311.315989 -45.198998) (xy 311.270631 -45.166547)
			(xy 311.230482 -45.127838) (xy 311.196396 -45.083695) (xy 311.1691 -45.03506) (xy 311.149177 -44.982969)
			(xy 311.137051 -44.928532) (xy 311.13298 -44.87291) (xy 309.174966 -44.87291) (xy 309.175294 -44.881296)
			(xy 309.183177 -44.900033) (xy 309.190136 -44.907454) (xy 309.249318 -44.965366) (xy 309.268368 -44.972986)
			(xy 309.278528 -44.972732) (xy 309.28564 -44.972732) (xy 309.312892 -44.973141) (xy 309.366841 -44.980903)
			(xy 309.419137 -44.996263) (xy 309.468714 -45.018909) (xy 309.514564 -45.048379) (xy 309.555754 -45.084074)
			(xy 309.591445 -45.125268) (xy 309.620911 -45.171121) (xy 309.643551 -45.220701) (xy 309.658906 -45.272998)
			(xy 309.666662 -45.326948) (xy 309.666662 -45.381452) (xy 309.658906 -45.435402) (xy 309.643551 -45.487699)
			(xy 309.620911 -45.537279) (xy 309.591445 -45.583132) (xy 309.555754 -45.624326) (xy 309.514564 -45.660021)
			(xy 309.468714 -45.689491) (xy 309.419137 -45.712137) (xy 309.366841 -45.727497) (xy 309.312892 -45.735259)
			(xy 309.28564 -45.735748) (xy 309.278528 -45.735748) (xy 309.268368 -45.735494) (xy 309.249318 -45.743114)
			(xy 309.190136 -45.801026) (xy 309.183208 -45.808465) (xy 309.175347 -45.827193) (xy 309.174896 -45.837348)
			(xy 309.174896 -46.210982) (xy 309.175315 -46.220774) (xy 309.182637 -46.238937) (xy 309.18912 -46.246288)
			(xy 309.237888 -46.297088) (xy 309.24503 -46.303806) (xy 309.262915 -46.311788) (xy 309.272686 -46.312582)
			(xy 309.299216 -46.314099) (xy 309.351507 -46.323546) (xy 309.401982 -46.340157) (xy 309.449664 -46.363609)
			(xy 309.493631 -46.393451) (xy 309.533033 -46.429104) (xy 309.567107 -46.469878) (xy 309.595195 -46.514986)
			(xy 309.616753 -46.563555) (xy 309.631363 -46.614644) (xy 309.638745 -46.667267) (xy 309.639208 -46.693836)
			(xy 309.638734 -46.720264) (xy 309.631425 -46.772611) (xy 309.616952 -46.823446) (xy 309.595593 -46.871793)
			(xy 309.582058 -46.894496) (xy 309.581804 -46.89475) (xy 309.576467 -46.904768) (xy 309.574212 -46.927318)
			(xy 309.577486 -46.938184) (xy 309.603648 -47.01286) (xy 309.608034 -47.023374) (xy 309.624121 -47.039463)
			(xy 309.634636 -47.043848) (xy 309.63489 -47.043848) (xy 309.659408 -47.052893) (xy 309.70586 -47.07684)
			(xy 309.74861 -47.106901) (xy 309.786861 -47.142512) (xy 309.819896 -47.183008) (xy 309.847098 -47.227631)
			(xy 309.867959 -47.275548) (xy 309.882088 -47.325863) (xy 309.889221 -47.377635) (xy 309.889652 -47.403766)
			(xy 309.8892 -47.431358) (xy 309.887703 -47.441612) (xy 311.161682 -47.441612) (xy 311.165753 -47.38599)
			(xy 311.177879 -47.331553) (xy 311.197802 -47.279462) (xy 311.225098 -47.230827) (xy 311.259184 -47.186684)
			(xy 311.299333 -47.147975) (xy 311.344691 -47.115524) (xy 311.394291 -47.090023) (xy 311.447075 -47.072016)
			(xy 311.501918 -47.061886) (xy 311.557652 -47.059849) (xy 311.613089 -47.065949) (xy 311.667046 -47.080055)
			(xy 311.718375 -47.101867) (xy 311.765981 -47.130921) (xy 311.808849 -47.166596) (xy 311.846066 -47.208133)
			(xy 311.876839 -47.254646) (xy 311.900511 -47.305143) (xy 311.916579 -47.35855) (xy 311.924699 -47.413726)
			(xy 311.925208 -47.441612) (xy 311.924699 -47.469498) (xy 311.916579 -47.524674) (xy 311.900511 -47.578081)
			(xy 311.876839 -47.628578) (xy 311.846066 -47.675091) (xy 311.808849 -47.716628) (xy 311.765981 -47.752303)
			(xy 311.718375 -47.781357) (xy 311.667046 -47.803169) (xy 311.613089 -47.817275) (xy 311.557652 -47.823375)
			(xy 311.501918 -47.821338) (xy 311.447075 -47.811208) (xy 311.394291 -47.793201) (xy 311.344691 -47.7677)
			(xy 311.299333 -47.735249) (xy 311.259184 -47.69654) (xy 311.225098 -47.652397) (xy 311.197802 -47.603762)
			(xy 311.177879 -47.551671) (xy 311.165753 -47.497234) (xy 311.161682 -47.441612) (xy 309.887703 -47.441612)
			(xy 309.881227 -47.485963) (xy 309.865473 -47.53885) (xy 309.842264 -47.588916) (xy 309.812086 -47.635118)
			(xy 309.775567 -47.67649) (xy 309.733471 -47.712171) (xy 309.686673 -47.741416) (xy 309.636151 -47.763615)
			(xy 309.582958 -47.778305) (xy 309.555642 -47.782226) (xy 309.555388 -47.782226) (xy 309.547176 -47.783628)
			(xy 309.532252 -47.791005) (xy 309.526178 -47.796704) (xy 309.525924 -47.796958) (xy 309.519269 -47.804392)
			(xy 309.511668 -47.822816) (xy 309.51166 -47.842745) (xy 309.519246 -47.861174) (xy 309.525924 -47.868586)
			(xy 309.550054 -47.892716) (xy 309.572953 -47.91628) (xy 309.613918 -47.967657) (xy 309.648872 -48.023297)
			(xy 309.677378 -48.0825) (xy 309.699076 -48.144523) (xy 309.713693 -48.208586) (xy 309.721046 -48.273882)
			(xy 309.721504 -48.306736) (xy 309.721504 -48.30699) (xy 309.720935 -48.342392) (xy 309.712404 -48.41268)
			(xy 309.695466 -48.481427) (xy 309.670366 -48.547633) (xy 309.637472 -48.610332) (xy 309.597263 -48.66861)
			(xy 309.550323 -48.721618) (xy 309.497338 -48.768584) (xy 309.43908 -48.808822) (xy 309.376398 -48.841747)
			(xy 309.310205 -48.866879) (xy 309.241465 -48.883852) (xy 309.171182 -48.892417) (xy 309.13578 -48.892968)
			(xy 309.102898 -48.89255) (xy 309.037549 -48.885181) (xy 308.973437 -48.870536) (xy 308.911369 -48.8488)
			(xy 308.852127 -48.820248) (xy 308.796457 -48.785239) (xy 308.745059 -48.744213) (xy 308.721506 -48.721264)
			(xy 308.174898 -48.174656) (xy 308.151977 -48.151113) (xy 308.111015 -48.099732) (xy 308.076064 -48.044088)
			(xy 308.047562 -47.98488) (xy 308.025868 -47.922854) (xy 308.011254 -47.858789) (xy 308.003905 -47.793491)
			(xy 308.003448 -47.760636) (xy 308.003448 -44.504356) (xy 308.003059 -44.494282) (xy 307.995314 -44.475684)
			(xy 307.988462 -44.468288) (xy 307.501036 -43.981116) (xy 307.478112 -43.957545) (xy 307.437118 -43.906132)
			(xy 307.402132 -43.850457) (xy 307.373593 -43.791218) (xy 307.351859 -43.729159) (xy 307.337204 -43.665057)
			(xy 307.329811 -43.599719) (xy 307.329332 -43.566842) (xy 305.136285 -43.566842) (xy 305.151731 -43.599791)
			(xy 305.167799 -43.653198) (xy 305.175919 -43.708374) (xy 305.176428 -43.73626) (xy 305.175919 -43.764146)
			(xy 305.167799 -43.819322) (xy 305.151731 -43.872729) (xy 305.128059 -43.923226) (xy 305.097286 -43.969739)
			(xy 305.060069 -44.011276) (xy 305.017201 -44.046951) (xy 304.969595 -44.076005) (xy 304.918266 -44.097817)
			(xy 304.864309 -44.111923) (xy 304.808872 -44.118023) (xy 304.753138 -44.115986) (xy 304.698295 -44.105856)
			(xy 304.645511 -44.087849) (xy 304.595911 -44.062348) (xy 304.550553 -44.029897) (xy 304.510404 -43.991188)
			(xy 304.476318 -43.947045) (xy 304.449022 -43.89841) (xy 304.429099 -43.846319) (xy 304.416973 -43.791882)
			(xy 304.412902 -43.73626) (xy 296.746676 -43.73626) (xy 296.840656 -43.83024) (xy 296.858692 -43.849009)
			(xy 296.889279 -43.891124) (xy 296.912913 -43.9375) (xy 296.929014 -43.986998) (xy 296.937186 -44.038403)
			(xy 296.937684 -44.064428) (xy 296.937684 -45.114464) (xy 304.265328 -45.114464) (xy 304.269399 -45.058842)
			(xy 304.281525 -45.004405) (xy 304.301448 -44.952314) (xy 304.328744 -44.903679) (xy 304.36283 -44.859536)
			(xy 304.402979 -44.820827) (xy 304.448337 -44.788376) (xy 304.497937 -44.762875) (xy 304.550721 -44.744868)
			(xy 304.605564 -44.734738) (xy 304.661298 -44.732701) (xy 304.716735 -44.738801) (xy 304.770692 -44.752907)
			(xy 304.822021 -44.774719) (xy 304.869627 -44.803773) (xy 304.912495 -44.839448) (xy 304.949712 -44.880985)
			(xy 304.980485 -44.927498) (xy 305.004157 -44.977995) (xy 305.020225 -45.031402) (xy 305.028345 -45.086578)
			(xy 305.028854 -45.114464) (xy 305.028345 -45.14235) (xy 305.020225 -45.197526) (xy 305.004157 -45.250933)
			(xy 304.980485 -45.30143) (xy 304.949712 -45.347943) (xy 304.912495 -45.38948) (xy 304.869627 -45.425155)
			(xy 304.822021 -45.454209) (xy 304.770692 -45.476021) (xy 304.716735 -45.490127) (xy 304.661298 -45.496227)
			(xy 304.605564 -45.49419) (xy 304.550721 -45.48406) (xy 304.497937 -45.466053) (xy 304.448337 -45.440552)
			(xy 304.402979 -45.408101) (xy 304.36283 -45.369392) (xy 304.328744 -45.325249) (xy 304.301448 -45.276614)
			(xy 304.281525 -45.224523) (xy 304.269399 -45.170086) (xy 304.265328 -45.114464) (xy 296.937684 -45.114464)
			(xy 296.937684 -46.082204) (xy 302.25238 -46.082204) (xy 302.252881 -46.054953) (xy 302.260637 -46.001007)
			(xy 302.275991 -45.948713) (xy 302.298631 -45.899137) (xy 302.328096 -45.853287) (xy 302.363786 -45.812097)
			(xy 302.404974 -45.776405) (xy 302.450823 -45.746939) (xy 302.500398 -45.724297) (xy 302.552691 -45.708941)
			(xy 302.606637 -45.701183) (xy 302.633888 -45.700696) (xy 302.66079 -45.701167) (xy 302.71406 -45.708738)
			(xy 302.765738 -45.723715) (xy 302.8148 -45.745804) (xy 302.860272 -45.774565) (xy 302.901254 -45.809428)
			(xy 302.936932 -45.849703) (xy 302.95215 -45.871892) (xy 302.959262 -45.882814) (xy 302.982122 -45.894752)
			(xy 303.09439 -45.89272) (xy 303.116742 -45.879766) (xy 303.1236 -45.86859) (xy 303.138535 -45.844997)
			(xy 303.174212 -45.802046) (xy 303.215768 -45.764752) (xy 303.262316 -45.733914) (xy 303.312861 -45.710189)
			(xy 303.366324 -45.694084) (xy 303.421564 -45.685944) (xy 303.449482 -45.685456) (xy 303.476475 -45.685928)
			(xy 303.529923 -45.693531) (xy 303.581766 -45.708589) (xy 303.630971 -45.7308) (xy 303.676555 -45.759723)
			(xy 303.697386 -45.776896) (xy 303.705514 -45.784008) (xy 303.726088 -45.790104) (xy 303.811432 -45.779182)
			(xy 303.821983 -45.777433) (xy 303.840263 -45.766361) (xy 303.846738 -45.757846) (xy 303.862074 -45.736602)
			(xy 303.897664 -45.69815) (xy 303.938184 -45.664932) (xy 303.98287 -45.637575) (xy 304.030881 -45.616594)
			(xy 304.081312 -45.602384) (xy 304.133214 -45.595212) (xy 304.159412 -45.594778) (xy 304.186662 -45.595293)
			(xy 304.240606 -45.603051) (xy 304.292897 -45.618406) (xy 304.342471 -45.641047) (xy 304.388318 -45.670513)
			(xy 304.429506 -45.706203) (xy 304.465194 -45.747391) (xy 304.494659 -45.793239) (xy 304.517298 -45.842814)
			(xy 304.532652 -45.895106) (xy 304.540408 -45.94905) (xy 304.540408 -46.00355) (xy 304.532652 -46.057494)
			(xy 304.517298 -46.109786) (xy 304.494659 -46.159361) (xy 304.465194 -46.205209) (xy 304.429506 -46.246397)
			(xy 304.388318 -46.282087) (xy 304.342471 -46.311553) (xy 304.292897 -46.334194) (xy 304.240606 -46.349549)
			(xy 304.186662 -46.357307) (xy 304.159412 -46.357794) (xy 304.13242 -46.357314) (xy 304.078973 -46.349711)
			(xy 304.02713 -46.334654) (xy 303.977925 -46.312445) (xy 303.93234 -46.283525) (xy 303.911508 -46.266354)
			(xy 303.90338 -46.259242) (xy 303.882806 -46.253146) (xy 303.797462 -46.264068) (xy 303.786927 -46.265881)
			(xy 303.768641 -46.276909) (xy 303.762156 -46.285404) (xy 303.744546 -46.309706) (xy 303.702948 -46.352965)
			(xy 303.679352 -46.37151) (xy 303.671478 -46.377352) (xy 303.661064 -46.394878) (xy 303.647856 -46.485302)
			(xy 303.652682 -46.504606) (xy 303.658524 -46.51248) (xy 303.658524 -46.512734) (xy 303.676021 -46.537483)
			(xy 303.703826 -46.591333) (xy 303.722764 -46.648904) (xy 303.732358 -46.708745) (xy 303.732946 -46.739048)
			(xy 303.732467 -46.766299) (xy 303.724705 -46.820245) (xy 303.709346 -46.872537) (xy 303.686702 -46.922112)
			(xy 303.657234 -46.96796) (xy 303.621542 -47.009149) (xy 303.580352 -47.04484) (xy 303.534503 -47.074306)
			(xy 303.484928 -47.096949) (xy 303.432635 -47.112307) (xy 303.378689 -47.120068) (xy 303.351438 -47.120556)
			(xy 303.325405 -47.12008) (xy 303.273824 -47.112999) (xy 303.223683 -47.098976) (xy 303.175911 -47.078271)
			(xy 303.131395 -47.051269) (xy 303.1109 -47.035212) (xy 303.10315 -47.029459) (xy 303.084734 -47.023725)
			(xy 303.075086 -47.024036) (xy 302.99533 -47.030386) (xy 302.97755 -47.039022) (xy 302.9712 -47.046388)
			(xy 302.953042 -47.066056) (xy 302.912129 -47.100576) (xy 302.866796 -47.129042) (xy 302.81793 -47.150896)
			(xy 302.76649 -47.165709) (xy 302.713485 -47.17319) (xy 302.68672 -47.173642) (xy 302.659471 -47.173103)
			(xy 302.605527 -47.16535) (xy 302.553235 -47.149999) (xy 302.50366 -47.127363) (xy 302.457812 -47.097902)
			(xy 302.416622 -47.062216) (xy 302.38093 -47.021032) (xy 302.351463 -46.975187) (xy 302.328819 -46.925615)
			(xy 302.313461 -46.873326) (xy 302.305701 -46.819383) (xy 302.305212 -46.792134) (xy 302.305733 -46.76336)
			(xy 302.314385 -46.706465) (xy 302.331481 -46.651515) (xy 302.356636 -46.599755) (xy 302.389277 -46.552359)
			(xy 302.40859 -46.531022) (xy 302.415956 -46.523148) (xy 302.423068 -46.503336) (xy 302.415702 -46.40707)
			(xy 302.405796 -46.388274) (xy 302.397414 -46.38167) (xy 302.375228 -46.363447) (xy 302.336019 -46.321511)
			(xy 302.303533 -46.274175) (xy 302.278505 -46.222507) (xy 302.261499 -46.167672) (xy 302.252898 -46.110909)
			(xy 302.25238 -46.082204) (xy 296.937684 -46.082204) (xy 296.937684 -48.753014) (xy 305.368196 -48.753014)
			(xy 305.372267 -48.697392) (xy 305.384393 -48.642955) (xy 305.404316 -48.590864) (xy 305.431612 -48.542229)
			(xy 305.465698 -48.498086) (xy 305.505847 -48.459377) (xy 305.551205 -48.426926) (xy 305.600805 -48.401425)
			(xy 305.653589 -48.383418) (xy 305.708432 -48.373288) (xy 305.764166 -48.371251) (xy 305.819603 -48.377351)
			(xy 305.87356 -48.391457) (xy 305.924889 -48.413269) (xy 305.972495 -48.442323) (xy 306.015363 -48.477998)
			(xy 306.05258 -48.519535) (xy 306.083353 -48.566048) (xy 306.107025 -48.616545) (xy 306.123093 -48.669952)
			(xy 306.131213 -48.725128) (xy 306.131722 -48.753014) (xy 306.131213 -48.7809) (xy 306.123093 -48.836076)
			(xy 306.120649 -48.8442) (xy 306.387244 -48.8442) (xy 306.391315 -48.788578) (xy 306.403441 -48.734141)
			(xy 306.423364 -48.68205) (xy 306.45066 -48.633415) (xy 306.484746 -48.589272) (xy 306.524895 -48.550563)
			(xy 306.570253 -48.518112) (xy 306.619853 -48.492611) (xy 306.672637 -48.474604) (xy 306.72748 -48.464474)
			(xy 306.783214 -48.462437) (xy 306.838651 -48.468537) (xy 306.892608 -48.482643) (xy 306.943937 -48.504455)
			(xy 306.991543 -48.533509) (xy 307.034411 -48.569184) (xy 307.071628 -48.610721) (xy 307.102401 -48.657234)
			(xy 307.126073 -48.707731) (xy 307.142141 -48.761138) (xy 307.150261 -48.816314) (xy 307.15077 -48.8442)
			(xy 307.150261 -48.872086) (xy 307.147263 -48.89246) (xy 307.413912 -48.89246) (xy 307.417983 -48.836838)
			(xy 307.430109 -48.782401) (xy 307.450032 -48.73031) (xy 307.477328 -48.681675) (xy 307.511414 -48.637532)
			(xy 307.551563 -48.598823) (xy 307.596921 -48.566372) (xy 307.646521 -48.540871) (xy 307.699305 -48.522864)
			(xy 307.754148 -48.512734) (xy 307.809882 -48.510697) (xy 307.865319 -48.516797) (xy 307.919276 -48.530903)
			(xy 307.970605 -48.552715) (xy 308.018211 -48.581769) (xy 308.061079 -48.617444) (xy 308.098296 -48.658981)
			(xy 308.129069 -48.705494) (xy 308.152741 -48.755991) (xy 308.168809 -48.809398) (xy 308.176929 -48.864574)
			(xy 308.177438 -48.89246) (xy 308.176929 -48.920346) (xy 308.174491 -48.93691) (xy 311.13298 -48.93691)
			(xy 311.137051 -48.881288) (xy 311.149177 -48.826851) (xy 311.1691 -48.77476) (xy 311.196396 -48.726125)
			(xy 311.230482 -48.681982) (xy 311.270631 -48.643273) (xy 311.315989 -48.610822) (xy 311.365589 -48.585321)
			(xy 311.418373 -48.567314) (xy 311.473216 -48.557184) (xy 311.52895 -48.555147) (xy 311.584387 -48.561247)
			(xy 311.638344 -48.575353) (xy 311.689673 -48.597165) (xy 311.737279 -48.626219) (xy 311.780147 -48.661894)
			(xy 311.817364 -48.703431) (xy 311.848137 -48.749944) (xy 311.871809 -48.800441) (xy 311.887877 -48.853848)
			(xy 311.895997 -48.909024) (xy 311.896506 -48.93691) (xy 311.895997 -48.964796) (xy 311.887877 -49.019972)
			(xy 311.871809 -49.073379) (xy 311.848137 -49.123876) (xy 311.817364 -49.170389) (xy 311.780147 -49.211926)
			(xy 311.737279 -49.247601) (xy 311.689673 -49.276655) (xy 311.638344 -49.298467) (xy 311.584387 -49.312573)
			(xy 311.52895 -49.318673) (xy 311.473216 -49.316636) (xy 311.418373 -49.306506) (xy 311.365589 -49.288499)
			(xy 311.315989 -49.262998) (xy 311.270631 -49.230547) (xy 311.230482 -49.191838) (xy 311.196396 -49.147695)
			(xy 311.1691 -49.09906) (xy 311.149177 -49.046969) (xy 311.137051 -48.992532) (xy 311.13298 -48.93691)
			(xy 308.174491 -48.93691) (xy 308.168809 -48.975522) (xy 308.152741 -49.028929) (xy 308.129069 -49.079426)
			(xy 308.098296 -49.125939) (xy 308.061079 -49.167476) (xy 308.018211 -49.203151) (xy 307.970605 -49.232205)
			(xy 307.919276 -49.254017) (xy 307.865319 -49.268123) (xy 307.809882 -49.274223) (xy 307.754148 -49.272186)
			(xy 307.699305 -49.262056) (xy 307.646521 -49.244049) (xy 307.596921 -49.218548) (xy 307.551563 -49.186097)
			(xy 307.511414 -49.147388) (xy 307.477328 -49.103245) (xy 307.450032 -49.05461) (xy 307.430109 -49.002519)
			(xy 307.417983 -48.948082) (xy 307.413912 -48.89246) (xy 307.147263 -48.89246) (xy 307.142141 -48.927262)
			(xy 307.126073 -48.980669) (xy 307.102401 -49.031166) (xy 307.071628 -49.077679) (xy 307.034411 -49.119216)
			(xy 306.991543 -49.154891) (xy 306.943937 -49.183945) (xy 306.892608 -49.205757) (xy 306.838651 -49.219863)
			(xy 306.783214 -49.225963) (xy 306.72748 -49.223926) (xy 306.672637 -49.213796) (xy 306.619853 -49.195789)
			(xy 306.570253 -49.170288) (xy 306.524895 -49.137837) (xy 306.484746 -49.099128) (xy 306.45066 -49.054985)
			(xy 306.423364 -49.00635) (xy 306.403441 -48.954259) (xy 306.391315 -48.899822) (xy 306.387244 -48.8442)
			(xy 306.120649 -48.8442) (xy 306.107025 -48.889483) (xy 306.083353 -48.93998) (xy 306.05258 -48.986493)
			(xy 306.015363 -49.02803) (xy 305.972495 -49.063705) (xy 305.924889 -49.092759) (xy 305.87356 -49.114571)
			(xy 305.819603 -49.128677) (xy 305.764166 -49.134777) (xy 305.708432 -49.13274) (xy 305.653589 -49.12261)
			(xy 305.600805 -49.104603) (xy 305.551205 -49.079102) (xy 305.505847 -49.046651) (xy 305.465698 -49.007942)
			(xy 305.431612 -48.963799) (xy 305.404316 -48.915164) (xy 305.384393 -48.863073) (xy 305.372267 -48.808636)
			(xy 305.368196 -48.753014) (xy 296.937684 -48.753014) (xy 296.937684 -49.601953) (xy 316.312759 -49.601953)
			(xy 316.312759 -49.547447) (xy 316.320516 -49.493497) (xy 316.335872 -49.441199) (xy 316.358515 -49.391619)
			(xy 316.387983 -49.345766) (xy 316.423677 -49.304574) (xy 316.464869 -49.268881) (xy 316.510723 -49.239413)
			(xy 316.560303 -49.216771) (xy 316.6126 -49.201415) (xy 316.666551 -49.193659) (xy 316.693804 -49.193196)
			(xy 316.721174 -49.193661) (xy 316.775353 -49.201479) (xy 316.827856 -49.216968) (xy 316.877603 -49.23981)
			(xy 316.92357 -49.269535) (xy 316.944502 -49.287176) (xy 316.944756 -49.28743) (xy 316.951849 -49.293008)
			(xy 316.968761 -49.299259) (xy 316.977776 -49.299622) (xy 317.044832 -49.299622) (xy 317.05385 -49.299276)
			(xy 317.070767 -49.29302) (xy 317.077852 -49.28743) (xy 317.077852 -49.287176) (xy 317.078106 -49.287176)
			(xy 317.099039 -49.269535) (xy 317.145007 -49.239811) (xy 317.194753 -49.216965) (xy 317.247255 -49.201469)
			(xy 317.301433 -49.19364) (xy 317.356175 -49.19364) (xy 317.410353 -49.201469) (xy 317.462855 -49.216965)
			(xy 317.512601 -49.239811) (xy 317.558569 -49.269535) (xy 317.579502 -49.287176) (xy 317.579756 -49.28743)
			(xy 317.586849 -49.293008) (xy 317.603761 -49.299259) (xy 317.612776 -49.299622) (xy 317.679832 -49.299622)
			(xy 317.68885 -49.299276) (xy 317.705767 -49.29302) (xy 317.712852 -49.28743) (xy 317.712852 -49.287176)
			(xy 317.713106 -49.287176) (xy 317.734039 -49.269535) (xy 317.780007 -49.239811) (xy 317.829753 -49.216965)
			(xy 317.882255 -49.201469) (xy 317.936433 -49.19364) (xy 317.991175 -49.19364) (xy 318.045353 -49.201469)
			(xy 318.097855 -49.216965) (xy 318.147601 -49.239811) (xy 318.193569 -49.269535) (xy 318.214502 -49.287176)
			(xy 318.214756 -49.28743) (xy 318.221849 -49.293008) (xy 318.238761 -49.299259) (xy 318.247776 -49.299622)
			(xy 318.314832 -49.299622) (xy 318.32385 -49.299276) (xy 318.340767 -49.29302) (xy 318.347852 -49.28743)
			(xy 318.347852 -49.287176) (xy 318.348106 -49.287176) (xy 318.369022 -49.269517) (xy 318.415 -49.239809)
			(xy 318.464751 -49.216977) (xy 318.517255 -49.201491) (xy 318.571434 -49.193667) (xy 318.598804 -49.193196)
			(xy 318.626055 -49.193674) (xy 318.680003 -49.201431) (xy 318.732298 -49.216787) (xy 318.781875 -49.239428)
			(xy 318.827726 -49.268895) (xy 318.868916 -49.304587) (xy 318.904607 -49.345778) (xy 318.934074 -49.391628)
			(xy 318.956715 -49.441206) (xy 318.97207 -49.493501) (xy 318.979826 -49.547449) (xy 318.979826 -49.601951)
			(xy 318.97207 -49.655899) (xy 318.956715 -49.708194) (xy 318.934074 -49.757772) (xy 318.904607 -49.803622)
			(xy 318.868916 -49.844813) (xy 318.827726 -49.880505) (xy 318.781875 -49.909972) (xy 318.732298 -49.932613)
			(xy 318.680003 -49.947969) (xy 318.626055 -49.955726) (xy 318.598804 -49.956212) (xy 318.571434 -49.955741)
			(xy 318.517255 -49.947924) (xy 318.464752 -49.932436) (xy 318.415005 -49.909595) (xy 318.369038 -49.879872)
			(xy 318.348106 -49.862232) (xy 318.347852 -49.861978) (xy 318.340757 -49.856405) (xy 318.323846 -49.850151)
			(xy 318.314832 -49.849786) (xy 318.247776 -49.849786) (xy 318.238758 -49.850135) (xy 318.221842 -49.856389)
			(xy 318.214756 -49.861978) (xy 318.214502 -49.862232) (xy 318.193569 -49.879873) (xy 318.147601 -49.909597)
			(xy 318.097855 -49.932443) (xy 318.045353 -49.947939) (xy 317.991175 -49.955768) (xy 317.936433 -49.955768)
			(xy 317.882255 -49.947939) (xy 317.829753 -49.932443) (xy 317.780007 -49.909597) (xy 317.734039 -49.879873)
			(xy 317.713106 -49.862232) (xy 317.712852 -49.861978) (xy 317.705757 -49.856405) (xy 317.688846 -49.850151)
			(xy 317.679832 -49.849786) (xy 317.612776 -49.849786) (xy 317.603758 -49.850135) (xy 317.586842 -49.856389)
			(xy 317.579756 -49.861978) (xy 317.579756 -49.862232) (xy 317.579502 -49.862232) (xy 317.558569 -49.879873)
			(xy 317.512601 -49.909597) (xy 317.462855 -49.932443) (xy 317.410353 -49.947939) (xy 317.356175 -49.955768)
			(xy 317.301433 -49.955768) (xy 317.247255 -49.947939) (xy 317.194753 -49.932443) (xy 317.145007 -49.909597)
			(xy 317.099039 -49.879873) (xy 317.078106 -49.862232) (xy 317.077852 -49.861978) (xy 317.070757 -49.856405)
			(xy 317.053846 -49.850151) (xy 317.044832 -49.849786) (xy 316.977776 -49.849786) (xy 316.968758 -49.850135)
			(xy 316.951842 -49.856389) (xy 316.944756 -49.861978) (xy 316.944756 -49.862232) (xy 316.944502 -49.862232)
			(xy 316.923584 -49.879889) (xy 316.877607 -49.909597) (xy 316.827856 -49.932429) (xy 316.775352 -49.947916)
			(xy 316.721174 -49.95574) (xy 316.693804 -49.956212) (xy 316.666551 -49.955741) (xy 316.6126 -49.947985)
			(xy 316.560303 -49.932629) (xy 316.510723 -49.909987) (xy 316.464869 -49.880519) (xy 316.423677 -49.844826)
			(xy 316.387983 -49.803634) (xy 316.358515 -49.757781) (xy 316.335872 -49.708201) (xy 316.320516 -49.655903)
			(xy 316.312759 -49.601953) (xy 296.937684 -49.601953) (xy 296.937684 -50.462434) (xy 307.026054 -50.462434)
			(xy 307.030125 -50.406812) (xy 307.042251 -50.352375) (xy 307.062174 -50.300284) (xy 307.08947 -50.251649)
			(xy 307.123556 -50.207506) (xy 307.163705 -50.168797) (xy 307.209063 -50.136346) (xy 307.258663 -50.110845)
			(xy 307.311447 -50.092838) (xy 307.36629 -50.082708) (xy 307.422024 -50.080671) (xy 307.477461 -50.086771)
			(xy 307.531418 -50.100877) (xy 307.582747 -50.122689) (xy 307.630353 -50.151743) (xy 307.673221 -50.187418)
			(xy 307.710438 -50.228955) (xy 307.741211 -50.275468) (xy 307.764883 -50.325965) (xy 307.780951 -50.379372)
			(xy 307.789071 -50.434548) (xy 307.78958 -50.462434) (xy 307.789071 -50.49032) (xy 307.780951 -50.545496)
			(xy 307.764883 -50.598903) (xy 307.741211 -50.6494) (xy 307.710438 -50.695913) (xy 307.673221 -50.73745)
			(xy 307.630353 -50.773125) (xy 307.582747 -50.802179) (xy 307.531418 -50.823991) (xy 307.477461 -50.838097)
			(xy 307.422024 -50.844197) (xy 307.36629 -50.84216) (xy 307.311447 -50.83203) (xy 307.258663 -50.814023)
			(xy 307.209063 -50.788522) (xy 307.163705 -50.756071) (xy 307.123556 -50.717362) (xy 307.08947 -50.673219)
			(xy 307.062174 -50.624584) (xy 307.042251 -50.572493) (xy 307.030125 -50.518056) (xy 307.026054 -50.462434)
			(xy 296.937684 -50.462434) (xy 296.937684 -51.019456) (xy 308.949342 -51.019456) (xy 308.953413 -50.963834)
			(xy 308.965539 -50.909397) (xy 308.985462 -50.857306) (xy 309.012758 -50.808671) (xy 309.046844 -50.764528)
			(xy 309.086993 -50.725819) (xy 309.132351 -50.693368) (xy 309.181951 -50.667867) (xy 309.234735 -50.64986)
			(xy 309.289578 -50.63973) (xy 309.345312 -50.637693) (xy 309.400749 -50.643793) (xy 309.454706 -50.657899)
			(xy 309.506035 -50.679711) (xy 309.553641 -50.708765) (xy 309.596509 -50.74444) (xy 309.633726 -50.785977)
			(xy 309.664499 -50.83249) (xy 309.688171 -50.882987) (xy 309.704239 -50.936394) (xy 309.712359 -50.99157)
			(xy 309.712868 -51.019456) (xy 309.712359 -51.047342) (xy 309.704239 -51.102518) (xy 309.688171 -51.155925)
			(xy 309.664499 -51.206422) (xy 309.639643 -51.243992) (xy 317.332868 -51.243992) (xy 317.333313 -51.216621)
			(xy 317.341133 -51.16244) (xy 317.356626 -51.109936) (xy 317.379473 -51.06019) (xy 317.409204 -51.014224)
			(xy 317.426848 -50.993294) (xy 317.427102 -50.99304) (xy 317.432678 -50.985946) (xy 317.438931 -50.969035)
			(xy 317.439294 -50.96002) (xy 317.439294 -50.892964) (xy 317.438955 -50.883945) (xy 317.432695 -50.867028)
			(xy 317.427102 -50.859944) (xy 317.426848 -50.859944) (xy 317.426848 -50.85969) (xy 317.409198 -50.838766)
			(xy 317.379486 -50.792792) (xy 317.356652 -50.743042) (xy 317.341163 -50.69054) (xy 317.333339 -50.636362)
			(xy 317.332868 -50.608992) (xy 317.33337 -50.581742) (xy 317.341127 -50.527796) (xy 317.356482 -50.475503)
			(xy 317.379123 -50.425927) (xy 317.408587 -50.380078) (xy 317.444277 -50.338888) (xy 317.485465 -50.303197)
			(xy 317.531313 -50.27373) (xy 317.580888 -50.251088) (xy 317.63318 -50.235731) (xy 317.687126 -50.227971)
			(xy 317.714376 -50.227484) (xy 317.743294 -50.227988) (xy 317.800467 -50.236715) (xy 317.855668 -50.253974)
			(xy 317.90763 -50.279368) (xy 317.955163 -50.312316) (xy 317.997178 -50.352062) (xy 318.015366 -50.37455)
			(xy 318.022989 -50.38334) (xy 318.043878 -50.393531) (xy 318.055498 -50.394108) (xy 318.135254 -50.394108)
			(xy 318.146888 -50.393583) (xy 318.167797 -50.383384) (xy 318.175386 -50.37455) (xy 318.193572 -50.352063)
			(xy 318.235595 -50.31233) (xy 318.283131 -50.279393) (xy 318.335093 -50.254006) (xy 318.39029 -50.23675)
			(xy 318.44746 -50.22802) (xy 318.476376 -50.227484) (xy 318.503628 -50.227978) (xy 318.557577 -50.235731)
			(xy 318.609874 -50.251084) (xy 318.659454 -50.273723) (xy 318.705306 -50.303188) (xy 318.746499 -50.338878)
			(xy 318.782193 -50.380068) (xy 318.811662 -50.425918) (xy 318.834305 -50.475496) (xy 318.849662 -50.527791)
			(xy 318.85742 -50.58174) (xy 318.857884 -50.608992) (xy 318.857416 -50.635306) (xy 318.850182 -50.687435)
			(xy 318.835864 -50.738078) (xy 318.814731 -50.786277) (xy 318.787185 -50.83112) (xy 318.753746 -50.87176)
			(xy 318.734694 -50.889916) (xy 318.727283 -50.897429) (xy 318.718764 -50.916716) (xy 318.718184 -50.927254)
			(xy 318.718184 -51.00193) (xy 318.718742 -51.012476) (xy 318.727257 -51.031772) (xy 318.734694 -51.039268)
			(xy 318.753774 -51.057399) (xy 318.78723 -51.098034) (xy 318.814785 -51.142879) (xy 318.83592 -51.191085)
			(xy 318.850231 -51.241737) (xy 318.857449 -51.293874) (xy 318.857884 -51.320192) (xy 318.857437 -51.347446)
			(xy 318.849681 -51.401399) (xy 318.834324 -51.453698) (xy 318.811681 -51.50328) (xy 318.782212 -51.549134)
			(xy 318.746516 -51.590328) (xy 318.705321 -51.626021) (xy 318.659466 -51.655489) (xy 318.609883 -51.67813)
			(xy 318.557583 -51.693484) (xy 318.50363 -51.701238) (xy 318.476376 -51.7017) (xy 318.44871 -51.701207)
			(xy 318.39396 -51.693204) (xy 318.340938 -51.677384) (xy 318.290754 -51.654078) (xy 318.244459 -51.623774)
			(xy 318.203021 -51.587106) (xy 318.167309 -51.544842) (xy 318.152272 -51.521614) (xy 318.145658 -51.511919)
			(xy 318.12578 -51.499485) (xy 318.114172 -51.497738) (xy 318.034162 -51.489864) (xy 318.022523 -51.489212)
			(xy 318.000684 -51.497306) (xy 317.992252 -51.505358) (xy 317.991998 -51.505612) (xy 317.973903 -51.524179)
			(xy 317.933574 -51.556758) (xy 317.889202 -51.583573) (xy 317.841607 -51.604128) (xy 317.791665 -51.618045)
			(xy 317.740298 -51.625066) (xy 317.714376 -51.6255) (xy 317.687124 -51.625044) (xy 317.633175 -51.617285)
			(xy 317.580879 -51.601926) (xy 317.531301 -51.579281) (xy 317.48545 -51.549812) (xy 317.44426 -51.514117)
			(xy 317.408569 -51.472924) (xy 317.379103 -51.427071) (xy 317.356463 -51.377491) (xy 317.341109 -51.325194)
			(xy 317.333353 -51.271244) (xy 317.332868 -51.243992) (xy 309.639643 -51.243992) (xy 309.633726 -51.252935)
			(xy 309.596509 -51.294472) (xy 309.553641 -51.330147) (xy 309.506035 -51.359201) (xy 309.454706 -51.381013)
			(xy 309.400749 -51.395119) (xy 309.345312 -51.401219) (xy 309.289578 -51.399182) (xy 309.234735 -51.389052)
			(xy 309.181951 -51.371045) (xy 309.132351 -51.345544) (xy 309.086993 -51.313093) (xy 309.046844 -51.274384)
			(xy 309.012758 -51.230241) (xy 308.985462 -51.181606) (xy 308.965539 -51.129515) (xy 308.953413 -51.075078)
			(xy 308.949342 -51.019456) (xy 296.937684 -51.019456) (xy 296.937684 -52.035456) (xy 311.141108 -52.035456)
			(xy 311.145179 -51.979834) (xy 311.157305 -51.925397) (xy 311.177228 -51.873306) (xy 311.204524 -51.824671)
			(xy 311.23861 -51.780528) (xy 311.278759 -51.741819) (xy 311.324117 -51.709368) (xy 311.373717 -51.683867)
			(xy 311.426501 -51.66586) (xy 311.481344 -51.65573) (xy 311.537078 -51.653693) (xy 311.592515 -51.659793)
			(xy 311.646472 -51.673899) (xy 311.697801 -51.695711) (xy 311.745407 -51.724765) (xy 311.788275 -51.76044)
			(xy 311.825492 -51.801977) (xy 311.856265 -51.84849) (xy 311.879937 -51.898987) (xy 311.896005 -51.952394)
			(xy 311.904125 -52.00757) (xy 311.904634 -52.035456) (xy 311.904125 -52.063342) (xy 311.896005 -52.118518)
			(xy 311.879937 -52.171925) (xy 311.856265 -52.222422) (xy 311.825492 -52.268935) (xy 311.788275 -52.310472)
			(xy 311.745407 -52.346147) (xy 311.697801 -52.375201) (xy 311.646472 -52.397013) (xy 311.592515 -52.411119)
			(xy 311.537078 -52.417219) (xy 311.481344 -52.415182) (xy 311.426501 -52.405052) (xy 311.373717 -52.387045)
			(xy 311.324117 -52.361544) (xy 311.278759 -52.329093) (xy 311.23861 -52.290384) (xy 311.204524 -52.246241)
			(xy 311.177228 -52.197606) (xy 311.157305 -52.145515) (xy 311.145179 -52.091078) (xy 311.141108 -52.035456)
			(xy 296.937684 -52.035456) (xy 296.937684 -54.731412) (xy 297.720512 -54.731412) (xy 297.720982 -54.704042)
			(xy 297.728799 -54.649863) (xy 297.744287 -54.59736) (xy 297.767127 -54.547613) (xy 297.796851 -54.501646)
			(xy 297.814492 -54.480714) (xy 297.814746 -54.48046) (xy 297.820319 -54.473364) (xy 297.826573 -54.456454)
			(xy 297.826938 -54.44744) (xy 297.826938 -54.380384) (xy 297.826581 -54.371367) (xy 297.820332 -54.354451)
			(xy 297.814746 -54.347364) (xy 297.814492 -54.347364) (xy 297.814492 -54.34711) (xy 297.796865 -54.326167)
			(xy 297.767142 -54.2802) (xy 297.744298 -54.230455) (xy 297.728802 -54.177955) (xy 297.720973 -54.123779)
			(xy 297.720972 -54.069039) (xy 297.728798 -54.014863) (xy 297.744292 -53.962362) (xy 297.767133 -53.912616)
			(xy 297.796854 -53.866647) (xy 297.814492 -53.845714) (xy 297.814746 -53.84546) (xy 297.820319 -53.838364)
			(xy 297.826573 -53.821454) (xy 297.826938 -53.81244) (xy 297.826938 -53.745384) (xy 297.826581 -53.736367)
			(xy 297.820332 -53.719451) (xy 297.814746 -53.712364) (xy 297.814492 -53.712364) (xy 297.814492 -53.71211)
			(xy 297.796865 -53.691167) (xy 297.767142 -53.6452) (xy 297.744298 -53.595455) (xy 297.728802 -53.542955)
			(xy 297.720973 -53.488779) (xy 297.720972 -53.434039) (xy 297.728798 -53.379863) (xy 297.744292 -53.327362)
			(xy 297.767133 -53.277616) (xy 297.796854 -53.231647) (xy 297.814492 -53.210714) (xy 297.814746 -53.21046)
			(xy 297.820319 -53.203364) (xy 297.826573 -53.186454) (xy 297.826938 -53.17744) (xy 297.826938 -53.110384)
			(xy 297.826581 -53.101367) (xy 297.820332 -53.084451) (xy 297.814746 -53.077364) (xy 297.814492 -53.077364)
			(xy 297.814492 -53.07711) (xy 297.796843 -53.056186) (xy 297.767133 -53.010211) (xy 297.744299 -52.960461)
			(xy 297.72881 -52.907959) (xy 297.720985 -52.853782) (xy 297.720512 -52.826412) (xy 297.720998 -52.799161)
			(xy 297.728754 -52.745213) (xy 297.744109 -52.692918) (xy 297.766751 -52.643341) (xy 297.796217 -52.597491)
			(xy 297.831908 -52.5563) (xy 297.873099 -52.520609) (xy 297.918949 -52.491143) (xy 297.968526 -52.468501)
			(xy 298.020821 -52.453146) (xy 298.074769 -52.44539) (xy 298.129271 -52.44539) (xy 298.183219 -52.453146)
			(xy 298.235514 -52.468501) (xy 298.285091 -52.491143) (xy 298.330941 -52.520609) (xy 298.372132 -52.5563)
			(xy 298.407823 -52.597491) (xy 298.437289 -52.643341) (xy 298.459931 -52.692918) (xy 298.475286 -52.745213)
			(xy 298.483042 -52.799161) (xy 298.483528 -52.826412) (xy 298.483087 -52.853783) (xy 298.475265 -52.907964)
			(xy 298.459772 -52.960468) (xy 298.436924 -53.010215) (xy 298.407193 -53.05618) (xy 298.389548 -53.07711)
			(xy 298.389294 -53.077364) (xy 298.383716 -53.084456) (xy 298.377464 -53.101369) (xy 298.377102 -53.110384)
			(xy 298.377102 -53.17744) (xy 298.37744 -53.186459) (xy 298.383701 -53.203376) (xy 298.389294 -53.21046)
			(xy 298.389548 -53.21046) (xy 298.389548 -53.210714) (xy 298.407201 -53.231637) (xy 298.436928 -53.277606)
			(xy 298.459774 -53.327353) (xy 298.47527 -53.379857) (xy 298.483098 -53.434038) (xy 298.483097 -53.48878)
			(xy 298.475266 -53.54296) (xy 298.459768 -53.595464) (xy 298.436919 -53.64521) (xy 298.407191 -53.691178)
			(xy 298.389548 -53.71211) (xy 298.389294 -53.712364) (xy 298.383716 -53.719456) (xy 298.377464 -53.736369)
			(xy 298.377102 -53.745384) (xy 298.377102 -53.81244) (xy 298.37744 -53.821459) (xy 298.383701 -53.838376)
			(xy 298.389294 -53.84546) (xy 298.389548 -53.84546) (xy 298.389548 -53.845714) (xy 298.407201 -53.866637)
			(xy 298.436928 -53.912606) (xy 298.459774 -53.962353) (xy 298.47527 -54.014857) (xy 298.483098 -54.069038)
			(xy 298.483097 -54.12378) (xy 298.475266 -54.17796) (xy 298.459768 -54.230464) (xy 298.436919 -54.28021)
			(xy 298.407191 -54.326178) (xy 298.389548 -54.34711) (xy 298.389294 -54.347364) (xy 298.383716 -54.354456)
			(xy 298.377464 -54.371369) (xy 298.377102 -54.380384) (xy 298.377102 -54.44744) (xy 298.37744 -54.456459)
			(xy 298.383701 -54.473376) (xy 298.389294 -54.48046) (xy 298.389548 -54.48046) (xy 298.389548 -54.480714)
			(xy 298.407152 -54.501674) (xy 298.436871 -54.547639) (xy 298.459715 -54.597379) (xy 298.475214 -54.649874)
			(xy 298.48305 -54.704045) (xy 298.483528 -54.731412) (xy 298.483042 -54.758663) (xy 298.478378 -54.791102)
			(xy 300.376336 -54.791102) (xy 300.376794 -54.763731) (xy 300.384613 -54.709552) (xy 300.400103 -54.657048)
			(xy 300.422947 -54.607301) (xy 300.452674 -54.561335) (xy 300.470316 -54.540404) (xy 300.47057 -54.54015)
			(xy 300.47615 -54.533059) (xy 300.482399 -54.516145) (xy 300.482762 -54.50713) (xy 300.482762 -54.440074)
			(xy 300.482426 -54.431055) (xy 300.476165 -54.414138) (xy 300.47057 -54.407054) (xy 300.470316 -54.407054)
			(xy 300.470316 -54.4068) (xy 300.452678 -54.385865) (xy 300.422954 -54.339898) (xy 300.400109 -54.290152)
			(xy 300.384613 -54.23765) (xy 300.376784 -54.183472) (xy 300.376784 -54.128731) (xy 300.384612 -54.074553)
			(xy 300.400108 -54.022051) (xy 300.422952 -53.972305) (xy 300.452676 -53.926337) (xy 300.470316 -53.905404)
			(xy 300.47057 -53.90515) (xy 300.47615 -53.898059) (xy 300.482399 -53.881145) (xy 300.482762 -53.87213)
			(xy 300.482762 -53.805074) (xy 300.482426 -53.796055) (xy 300.476165 -53.779138) (xy 300.47057 -53.772054)
			(xy 300.470316 -53.772054) (xy 300.470316 -53.7718) (xy 300.452678 -53.750865) (xy 300.422954 -53.704898)
			(xy 300.400109 -53.655152) (xy 300.384613 -53.60265) (xy 300.376784 -53.548472) (xy 300.376784 -53.493731)
			(xy 300.384612 -53.439553) (xy 300.400108 -53.387051) (xy 300.422952 -53.337305) (xy 300.452676 -53.291337)
			(xy 300.470316 -53.270404) (xy 300.47057 -53.27015) (xy 300.47615 -53.263059) (xy 300.482399 -53.246145)
			(xy 300.482762 -53.23713) (xy 300.482762 -53.170074) (xy 300.482426 -53.161055) (xy 300.476165 -53.144138)
			(xy 300.47057 -53.137054) (xy 300.470316 -53.137054) (xy 300.470316 -53.1368) (xy 300.452666 -53.115877)
			(xy 300.422955 -53.069902) (xy 300.400121 -53.020152) (xy 300.384633 -52.967649) (xy 300.376808 -52.913472)
			(xy 300.376336 -52.886102) (xy 300.376822 -52.858851) (xy 300.384578 -52.804903) (xy 300.399933 -52.752608)
			(xy 300.422575 -52.703031) (xy 300.452041 -52.657181) (xy 300.487732 -52.61599) (xy 300.528923 -52.580299)
			(xy 300.574773 -52.550833) (xy 300.62435 -52.528191) (xy 300.676645 -52.512836) (xy 300.730593 -52.50508)
			(xy 300.785095 -52.50508) (xy 300.839043 -52.512836) (xy 300.891338 -52.528191) (xy 300.930442 -52.54605)
			(xy 305.879496 -52.54605) (xy 305.879496 -52.49155) (xy 305.887252 -52.437605) (xy 305.902607 -52.385313)
			(xy 305.925247 -52.335738) (xy 305.954712 -52.28989) (xy 305.990401 -52.248701) (xy 306.03159 -52.213012)
			(xy 306.077438 -52.183547) (xy 306.127013 -52.160907) (xy 306.179305 -52.145552) (xy 306.23325 -52.137796)
			(xy 306.2605 -52.13731) (xy 306.28787 -52.137774) (xy 306.34205 -52.145592) (xy 306.394553 -52.161081)
			(xy 306.4443 -52.183924) (xy 306.490266 -52.213649) (xy 306.511198 -52.23129) (xy 306.511452 -52.231544)
			(xy 306.518544 -52.237122) (xy 306.535457 -52.243373) (xy 306.544472 -52.243736) (xy 306.611528 -52.243736)
			(xy 306.620545 -52.243385) (xy 306.637462 -52.237132) (xy 306.644548 -52.231544) (xy 306.644548 -52.23129)
			(xy 306.644802 -52.23129) (xy 306.665735 -52.213649) (xy 306.711703 -52.183925) (xy 306.761449 -52.161079)
			(xy 306.813951 -52.145583) (xy 306.868129 -52.137754) (xy 306.922871 -52.137754) (xy 306.977049 -52.145583)
			(xy 307.029551 -52.161079) (xy 307.079297 -52.183925) (xy 307.125265 -52.213649) (xy 307.146198 -52.23129)
			(xy 307.146452 -52.231544) (xy 307.153544 -52.237122) (xy 307.170457 -52.243373) (xy 307.179472 -52.243736)
			(xy 307.246528 -52.243736) (xy 307.255545 -52.243385) (xy 307.272462 -52.237132) (xy 307.279548 -52.231544)
			(xy 307.279548 -52.23129) (xy 307.279802 -52.23129) (xy 307.300721 -52.213635) (xy 307.346698 -52.183926)
			(xy 307.396448 -52.161093) (xy 307.448952 -52.145606) (xy 307.50313 -52.137782) (xy 307.5305 -52.13731)
			(xy 307.557753 -52.13776) (xy 307.611703 -52.145517) (xy 307.664 -52.160873) (xy 307.71358 -52.183515)
			(xy 307.759432 -52.212982) (xy 307.800624 -52.248676) (xy 307.836318 -52.289868) (xy 307.865785 -52.33572)
			(xy 307.888427 -52.3853) (xy 307.903783 -52.437597) (xy 307.91154 -52.491547) (xy 307.91154 -52.546053)
			(xy 307.905595 -52.587398) (xy 308.955184 -52.587398) (xy 308.959255 -52.531776) (xy 308.971381 -52.477339)
			(xy 308.991304 -52.425248) (xy 309.0186 -52.376613) (xy 309.052686 -52.33247) (xy 309.092835 -52.293761)
			(xy 309.138193 -52.26131) (xy 309.187793 -52.235809) (xy 309.240577 -52.217802) (xy 309.29542 -52.207672)
			(xy 309.351154 -52.205635) (xy 309.406591 -52.211735) (xy 309.460548 -52.225841) (xy 309.511877 -52.247653)
			(xy 309.559483 -52.276707) (xy 309.602351 -52.312382) (xy 309.639568 -52.353919) (xy 309.670341 -52.400432)
			(xy 309.694013 -52.450929) (xy 309.710081 -52.504336) (xy 309.717677 -52.555952) (xy 316.783679 -52.555952)
			(xy 316.783679 -52.501448) (xy 316.791436 -52.447499) (xy 316.806792 -52.395203) (xy 316.829435 -52.345624)
			(xy 316.858903 -52.299773) (xy 316.894597 -52.258582) (xy 316.935789 -52.222891) (xy 316.981642 -52.193425)
			(xy 317.031221 -52.170785) (xy 317.083518 -52.155432) (xy 317.137468 -52.147678) (xy 317.16472 -52.147216)
			(xy 317.192091 -52.147666) (xy 317.246271 -52.155487) (xy 317.298774 -52.17098) (xy 317.348521 -52.193825)
			(xy 317.394487 -52.223553) (xy 317.415418 -52.241196) (xy 317.415672 -52.24145) (xy 317.422758 -52.247037)
			(xy 317.439675 -52.253282) (xy 317.448692 -52.253642) (xy 317.515748 -52.253642) (xy 317.524764 -52.253273)
			(xy 317.541682 -52.247035) (xy 317.548768 -52.24145) (xy 317.548768 -52.241196) (xy 317.549022 -52.241196)
			(xy 317.569972 -52.223579) (xy 317.61594 -52.193864) (xy 317.665683 -52.171024) (xy 317.71818 -52.155528)
			(xy 317.772352 -52.147693) (xy 317.79972 -52.147216) (xy 317.826972 -52.147655) (xy 317.880921 -52.155415)
			(xy 317.933217 -52.170772) (xy 317.982794 -52.193416) (xy 318.028645 -52.222885) (xy 318.069836 -52.258579)
			(xy 318.105527 -52.299771) (xy 318.134994 -52.345623) (xy 318.157635 -52.395202) (xy 318.17299 -52.447499)
			(xy 318.180746 -52.501448) (xy 318.180746 -52.555952) (xy 318.17299 -52.609901) (xy 318.157635 -52.662198)
			(xy 318.134994 -52.711777) (xy 318.105527 -52.757629) (xy 318.069836 -52.798821) (xy 318.028645 -52.834515)
			(xy 317.982794 -52.863984) (xy 317.933217 -52.886628) (xy 317.880921 -52.901985) (xy 317.826972 -52.909745)
			(xy 317.79972 -52.910232) (xy 317.772349 -52.909771) (xy 317.718169 -52.901954) (xy 317.665666 -52.886465)
			(xy 317.615919 -52.863622) (xy 317.569953 -52.833895) (xy 317.549022 -52.816252) (xy 317.548768 -52.815998)
			(xy 317.541666 -52.810434) (xy 317.524761 -52.804174) (xy 317.515748 -52.803806) (xy 317.448692 -52.803806)
			(xy 317.439675 -52.804158) (xy 317.422758 -52.810409) (xy 317.415672 -52.815998) (xy 317.415672 -52.816252)
			(xy 317.415418 -52.816252) (xy 317.394484 -52.833889) (xy 317.348512 -52.863603) (xy 317.298765 -52.88644)
			(xy 317.246265 -52.901931) (xy 317.192089 -52.909759) (xy 317.16472 -52.910232) (xy 317.137468 -52.909722)
			(xy 317.083518 -52.901968) (xy 317.031221 -52.886615) (xy 316.981642 -52.863975) (xy 316.935789 -52.834509)
			(xy 316.894597 -52.798818) (xy 316.858903 -52.757627) (xy 316.829435 -52.711776) (xy 316.806792 -52.662197)
			(xy 316.791436 -52.609901) (xy 316.783679 -52.555952) (xy 309.717677 -52.555952) (xy 309.718201 -52.559512)
			(xy 309.71871 -52.587398) (xy 309.718201 -52.615284) (xy 309.710081 -52.67046) (xy 309.694013 -52.723867)
			(xy 309.670341 -52.774364) (xy 309.639568 -52.820877) (xy 309.602351 -52.862414) (xy 309.559483 -52.898089)
			(xy 309.511877 -52.927143) (xy 309.460548 -52.948955) (xy 309.406591 -52.963061) (xy 309.351154 -52.969161)
			(xy 309.29542 -52.967124) (xy 309.240577 -52.956994) (xy 309.187793 -52.938987) (xy 309.138193 -52.913486)
			(xy 309.092835 -52.881035) (xy 309.052686 -52.842326) (xy 309.0186 -52.798183) (xy 308.991304 -52.749548)
			(xy 308.971381 -52.697457) (xy 308.959255 -52.64302) (xy 308.955184 -52.587398) (xy 307.905595 -52.587398)
			(xy 307.903783 -52.600003) (xy 307.888427 -52.6523) (xy 307.865785 -52.70188) (xy 307.836318 -52.747732)
			(xy 307.800624 -52.788924) (xy 307.759432 -52.824618) (xy 307.71358 -52.854085) (xy 307.664 -52.876727)
			(xy 307.611703 -52.892083) (xy 307.557753 -52.89984) (xy 307.5305 -52.900326) (xy 307.503129 -52.899878)
			(xy 307.448948 -52.892059) (xy 307.396444 -52.876566) (xy 307.346698 -52.85372) (xy 307.300732 -52.82399)
			(xy 307.279802 -52.806346) (xy 307.279548 -52.806092) (xy 307.272453 -52.800518) (xy 307.255543 -52.794264)
			(xy 307.246528 -52.7939) (xy 307.179472 -52.7939) (xy 307.170454 -52.794244) (xy 307.153537 -52.800501)
			(xy 307.146452 -52.806092) (xy 307.146198 -52.806346) (xy 307.125265 -52.823987) (xy 307.079297 -52.853711)
			(xy 307.029551 -52.876557) (xy 306.977049 -52.892053) (xy 306.922871 -52.899882) (xy 306.868129 -52.899882)
			(xy 306.813951 -52.892053) (xy 306.761449 -52.876557) (xy 306.711703 -52.853711) (xy 306.665735 -52.823987)
			(xy 306.644802 -52.806346) (xy 306.644548 -52.806092) (xy 306.637453 -52.800518) (xy 306.620543 -52.794264)
			(xy 306.611528 -52.7939) (xy 306.544472 -52.7939) (xy 306.535454 -52.794244) (xy 306.518537 -52.800501)
			(xy 306.511452 -52.806092) (xy 306.511452 -52.806346) (xy 306.511198 -52.806346) (xy 306.490271 -52.823991)
			(xy 306.444297 -52.853704) (xy 306.394549 -52.87654) (xy 306.342047 -52.892029) (xy 306.28787 -52.899854)
			(xy 306.2605 -52.900326) (xy 306.23325 -52.899804) (xy 306.179305 -52.892048) (xy 306.127013 -52.876693)
			(xy 306.077438 -52.854053) (xy 306.03159 -52.824588) (xy 305.990401 -52.788899) (xy 305.954712 -52.74771)
			(xy 305.925247 -52.701862) (xy 305.902607 -52.652287) (xy 305.887252 -52.599995) (xy 305.879496 -52.54605)
			(xy 300.930442 -52.54605) (xy 300.940915 -52.550833) (xy 300.986765 -52.580299) (xy 301.027956 -52.61599)
			(xy 301.063647 -52.657181) (xy 301.093113 -52.703031) (xy 301.115755 -52.752608) (xy 301.13111 -52.804903)
			(xy 301.138866 -52.858851) (xy 301.139352 -52.886102) (xy 301.138899 -52.913473) (xy 301.13108 -52.967653)
			(xy 301.115588 -53.020157) (xy 301.092743 -53.069903) (xy 301.063015 -53.115869) (xy 301.045372 -53.1368)
			(xy 301.045118 -53.137054) (xy 301.039547 -53.144151) (xy 301.033291 -53.16106) (xy 301.032926 -53.170074)
			(xy 301.032926 -53.23713) (xy 301.033263 -53.246149) (xy 301.039524 -53.263066) (xy 301.045118 -53.27015)
			(xy 301.045372 -53.27015) (xy 301.045372 -53.270404) (xy 301.063015 -53.291335) (xy 301.092739 -53.337303)
			(xy 301.115585 -53.38705) (xy 301.131081 -53.439552) (xy 301.138909 -53.493731) (xy 301.138909 -53.548472)
			(xy 301.13108 -53.602651) (xy 301.115584 -53.655153) (xy 301.092738 -53.704899) (xy 301.063013 -53.750867)
			(xy 301.046442 -53.77053) (xy 301.410624 -53.77053) (xy 301.411155 -53.741613) (xy 301.41988 -53.684442)
			(xy 301.437135 -53.629243) (xy 301.462524 -53.577282) (xy 301.495466 -53.529747) (xy 301.535205 -53.48773)
			(xy 301.55769 -53.46954) (xy 301.566468 -53.461904) (xy 301.576668 -53.441025) (xy 301.577248 -53.429408)
			(xy 301.577248 -53.349652) (xy 301.57674 -53.338016) (xy 301.566531 -53.317105) (xy 301.55769 -53.30952)
			(xy 301.535214 -53.29132) (xy 301.495479 -53.249302) (xy 301.462539 -53.201769) (xy 301.43715 -53.149809)
			(xy 301.419892 -53.094613) (xy 301.41116 -53.037445) (xy 301.410624 -53.00853) (xy 301.411083 -52.981276)
			(xy 301.418837 -52.927324) (xy 301.434191 -52.875024) (xy 301.456832 -52.825442) (xy 301.4863 -52.779587)
			(xy 301.521994 -52.738393) (xy 301.563188 -52.702699) (xy 301.609043 -52.673231) (xy 301.658626 -52.65059)
			(xy 301.710926 -52.635237) (xy 301.764878 -52.627483) (xy 301.792132 -52.627022) (xy 301.818447 -52.627461)
			(xy 301.870577 -52.634701) (xy 301.921221 -52.649025) (xy 301.96942 -52.670163) (xy 302.014262 -52.697714)
			(xy 302.0549 -52.731158) (xy 302.073056 -52.750212) (xy 302.08059 -52.757598) (xy 302.099861 -52.766131)
			(xy 302.110394 -52.766722) (xy 302.18507 -52.766722) (xy 302.195618 -52.766183) (xy 302.214913 -52.757654)
			(xy 302.222408 -52.750212) (xy 302.240569 -52.731162) (xy 302.281197 -52.697704) (xy 302.326036 -52.670144)
			(xy 302.374236 -52.649004) (xy 302.424883 -52.634686) (xy 302.477016 -52.627461) (xy 302.503332 -52.627022)
			(xy 302.530585 -52.627448) (xy 302.584537 -52.63521) (xy 302.636835 -52.65057) (xy 302.686414 -52.673218)
			(xy 302.732266 -52.70269) (xy 302.773456 -52.738388) (xy 302.809147 -52.779584) (xy 302.838612 -52.825441)
			(xy 302.861251 -52.875024) (xy 302.876603 -52.927324) (xy 302.884356 -52.981277) (xy 302.88484 -53.00853)
			(xy 302.884379 -53.036197) (xy 302.876374 -53.09095) (xy 302.86055 -53.143974) (xy 302.83724 -53.194159)
			(xy 302.80693 -53.240454) (xy 302.770256 -53.28189) (xy 302.727985 -53.317599) (xy 302.704754 -53.332634)
			(xy 302.695064 -53.339255) (xy 302.682626 -53.359128) (xy 302.680878 -53.370734) (xy 302.673004 -53.450744)
			(xy 302.672366 -53.462382) (xy 302.680452 -53.484219) (xy 302.688498 -53.492654) (xy 302.688752 -53.492908)
			(xy 302.70731 -53.511012) (xy 302.739893 -53.551338) (xy 302.76671 -53.595707) (xy 302.787267 -53.643301)
			(xy 302.801185 -53.693242) (xy 302.808206 -53.744608) (xy 302.80864 -53.77053) (xy 302.80815 -53.797781)
			(xy 302.80039 -53.851726) (xy 302.785033 -53.904019) (xy 302.762391 -53.953594) (xy 302.732924 -53.999443)
			(xy 302.697234 -54.040632) (xy 302.656045 -54.076323) (xy 302.610196 -54.10579) (xy 302.560621 -54.128432)
			(xy 302.508328 -54.14379) (xy 302.454383 -54.15155) (xy 302.427132 -54.152038) (xy 302.399762 -54.151568)
			(xy 302.345582 -54.143754) (xy 302.293079 -54.128266) (xy 302.243332 -54.105425) (xy 302.197365 -54.0757)
			(xy 302.176434 -54.058058) (xy 302.17618 -54.057804) (xy 302.169103 -54.052203) (xy 302.152179 -54.045965)
			(xy 302.14316 -54.045612) (xy 302.076104 -54.045612) (xy 302.067087 -54.045968) (xy 302.05017 -54.052216)
			(xy 302.043084 -54.057804) (xy 302.043084 -54.058058) (xy 302.04283 -54.058058) (xy 302.021892 -54.07569)
			(xy 301.975922 -54.105404) (xy 301.926176 -54.128242) (xy 301.873676 -54.143735) (xy 301.819501 -54.151564)
			(xy 301.792132 -54.152038) (xy 301.764881 -54.151515) (xy 301.710934 -54.143763) (xy 301.658639 -54.128413)
			(xy 301.609061 -54.105776) (xy 301.563209 -54.076314) (xy 301.522017 -54.040627) (xy 301.486323 -53.99944)
			(xy 301.456854 -53.953593) (xy 301.434209 -53.904019) (xy 301.41885 -53.851727) (xy 301.411089 -53.797781)
			(xy 301.410624 -53.77053) (xy 301.046442 -53.77053) (xy 301.045372 -53.7718) (xy 301.045118 -53.772054)
			(xy 301.039547 -53.779151) (xy 301.033291 -53.79606) (xy 301.032926 -53.805074) (xy 301.032926 -53.87213)
			(xy 301.033263 -53.881149) (xy 301.039524 -53.898066) (xy 301.045118 -53.90515) (xy 301.045372 -53.90515)
			(xy 301.045372 -53.905404) (xy 301.063015 -53.926335) (xy 301.092739 -53.972303) (xy 301.115585 -54.02205)
			(xy 301.131081 -54.074552) (xy 301.138909 -54.128731) (xy 301.138909 -54.183472) (xy 301.13108 -54.237651)
			(xy 301.115584 -54.290153) (xy 301.101791 -54.320186) (xy 303.330356 -54.320186) (xy 303.3308 -54.292815)
			(xy 303.338621 -54.238634) (xy 303.354115 -54.18613) (xy 303.376962 -54.136384) (xy 303.406692 -54.090418)
			(xy 303.424336 -54.069488) (xy 303.42459 -54.069234) (xy 303.430167 -54.062141) (xy 303.43642 -54.045229)
			(xy 303.436782 -54.036214) (xy 303.436782 -53.969158) (xy 303.436401 -53.960143) (xy 303.43017 -53.943226)
			(xy 303.42459 -53.936138) (xy 303.424336 -53.936138) (xy 303.424336 -53.935884) (xy 303.406728 -53.914926)
			(xy 303.377011 -53.868961) (xy 303.354168 -53.81922) (xy 303.33867 -53.766725) (xy 303.330834 -53.712554)
			(xy 303.330356 -53.685186) (xy 303.330842 -53.657935) (xy 303.338598 -53.603987) (xy 303.353953 -53.551692)
			(xy 303.376595 -53.502115) (xy 303.406061 -53.456265) (xy 303.441752 -53.415074) (xy 303.482943 -53.379383)
			(xy 303.528793 -53.349917) (xy 303.57837 -53.327275) (xy 303.630665 -53.31192) (xy 303.684613 -53.304164)
			(xy 303.739115 -53.304164) (xy 303.793063 -53.31192) (xy 303.845358 -53.327275) (xy 303.894935 -53.349917)
			(xy 303.940785 -53.379383) (xy 303.981976 -53.415074) (xy 304.017667 -53.456265) (xy 304.047133 -53.502115)
			(xy 304.069775 -53.551692) (xy 304.08513 -53.603987) (xy 304.092886 -53.657935) (xy 304.093372 -53.685186)
			(xy 304.092905 -53.712556) (xy 304.085088 -53.766736) (xy 304.0696 -53.819239) (xy 304.046758 -53.868986)
			(xy 304.017033 -53.914952) (xy 303.999392 -53.935884) (xy 303.999138 -53.936138) (xy 303.993564 -53.943233)
			(xy 303.987311 -53.960144) (xy 303.986946 -53.969158) (xy 303.986946 -54.036214) (xy 303.987286 -54.045233)
			(xy 303.993544 -54.06215) (xy 303.999138 -54.069234) (xy 303.999392 -54.069234) (xy 303.999392 -54.069488)
			(xy 304.017038 -54.090415) (xy 304.046749 -54.136389) (xy 304.069584 -54.186138) (xy 304.085073 -54.23864)
			(xy 304.092899 -54.292816) (xy 304.093372 -54.320186) (xy 304.092886 -54.347437) (xy 304.08513 -54.401385)
			(xy 304.069775 -54.45368) (xy 304.047133 -54.503257) (xy 304.017667 -54.549107) (xy 303.981976 -54.590298)
			(xy 303.940785 -54.625989) (xy 303.894935 -54.655455) (xy 303.845358 -54.678097) (xy 303.793063 -54.693452)
			(xy 303.739115 -54.701208) (xy 303.684613 -54.701208) (xy 303.630665 -54.693452) (xy 303.57837 -54.678097)
			(xy 303.528793 -54.655455) (xy 303.482943 -54.625989) (xy 303.441752 -54.590298) (xy 303.406061 -54.549107)
			(xy 303.376595 -54.503257) (xy 303.353953 -54.45368) (xy 303.338598 -54.401385) (xy 303.330842 -54.347437)
			(xy 303.330356 -54.320186) (xy 301.101791 -54.320186) (xy 301.092738 -54.339899) (xy 301.063013 -54.385867)
			(xy 301.045372 -54.4068) (xy 301.045118 -54.407054) (xy 301.039547 -54.414151) (xy 301.033291 -54.43106)
			(xy 301.032926 -54.440074) (xy 301.032926 -54.50713) (xy 301.033263 -54.516149) (xy 301.039524 -54.533066)
			(xy 301.045118 -54.54015) (xy 301.045372 -54.54015) (xy 301.045372 -54.540404) (xy 301.063022 -54.561327)
			(xy 301.092733 -54.607302) (xy 301.115567 -54.657052) (xy 301.131056 -54.709555) (xy 301.13888 -54.763732)
			(xy 301.138997 -54.770528) (xy 304.270918 -54.770528) (xy 304.271396 -54.743158) (xy 304.27921 -54.688979)
			(xy 304.294696 -54.636476) (xy 304.317536 -54.586729) (xy 304.347258 -54.540762) (xy 304.364898 -54.51983)
			(xy 304.365152 -54.519576) (xy 304.370761 -54.512505) (xy 304.376993 -54.495576) (xy 304.377344 -54.486556)
			(xy 304.377344 -54.4195) (xy 304.376999 -54.410482) (xy 304.370744 -54.393564) (xy 304.365152 -54.38648)
			(xy 304.364898 -54.38648) (xy 304.364898 -54.386226) (xy 304.347257 -54.365295) (xy 304.317546 -54.319322)
			(xy 304.29471 -54.269574) (xy 304.279219 -54.217073) (xy 304.271392 -54.162897) (xy 304.270918 -54.135528)
			(xy 304.271404 -54.108277) (xy 304.27916 -54.054329) (xy 304.294515 -54.002034) (xy 304.317157 -53.952457)
			(xy 304.346623 -53.906607) (xy 304.382314 -53.865416) (xy 304.423505 -53.829725) (xy 304.469355 -53.800259)
			(xy 304.518932 -53.777617) (xy 304.571227 -53.762262) (xy 304.625175 -53.754506) (xy 304.679677 -53.754506)
			(xy 304.733625 -53.762262) (xy 304.78592 -53.777617) (xy 304.835497 -53.800259) (xy 304.881347 -53.829725)
			(xy 304.922538 -53.865416) (xy 304.958229 -53.906607) (xy 304.987695 -53.952457) (xy 304.99277 -53.96357)
			(xy 308.971948 -53.96357) (xy 308.976019 -53.907948) (xy 308.988145 -53.853511) (xy 309.008068 -53.80142)
			(xy 309.035364 -53.752785) (xy 309.06945 -53.708642) (xy 309.109599 -53.669933) (xy 309.154957 -53.637482)
			(xy 309.204557 -53.611981) (xy 309.257341 -53.593974) (xy 309.312184 -53.583844) (xy 309.367918 -53.581807)
			(xy 309.423355 -53.587907) (xy 309.477312 -53.602013) (xy 309.528641 -53.623825) (xy 309.576247 -53.652879)
			(xy 309.619115 -53.688554) (xy 309.656332 -53.730091) (xy 309.687105 -53.776604) (xy 309.710777 -53.827101)
			(xy 309.726845 -53.880508) (xy 309.734965 -53.935684) (xy 309.735474 -53.96357) (xy 309.734965 -53.991456)
			(xy 309.726845 -54.046632) (xy 309.710777 -54.100039) (xy 309.687105 -54.150536) (xy 309.656332 -54.197049)
			(xy 309.619115 -54.238586) (xy 309.576247 -54.274261) (xy 309.528641 -54.303315) (xy 309.477312 -54.325127)
			(xy 309.423355 -54.339233) (xy 309.367918 -54.345333) (xy 309.312184 -54.343296) (xy 309.257341 -54.333166)
			(xy 309.204557 -54.315159) (xy 309.154957 -54.289658) (xy 309.109599 -54.257207) (xy 309.06945 -54.218498)
			(xy 309.035364 -54.174355) (xy 309.008068 -54.12572) (xy 308.988145 -54.073629) (xy 308.976019 -54.019192)
			(xy 308.971948 -53.96357) (xy 304.99277 -53.96357) (xy 305.010337 -54.002034) (xy 305.025692 -54.054329)
			(xy 305.033448 -54.108277) (xy 305.033934 -54.135528) (xy 305.0335 -54.1629) (xy 305.025677 -54.217081)
			(xy 305.010181 -54.269585) (xy 304.987332 -54.319331) (xy 304.957599 -54.365296) (xy 304.939954 -54.386226)
			(xy 304.9397 -54.38648) (xy 304.934116 -54.393568) (xy 304.927868 -54.410484) (xy 304.927508 -54.4195)
			(xy 304.927508 -54.486556) (xy 304.927885 -54.495571) (xy 304.934119 -54.512488) (xy 304.9397 -54.519576)
			(xy 304.939954 -54.519576) (xy 304.939954 -54.51983) (xy 304.957567 -54.540784) (xy 304.987284 -54.58675)
			(xy 305.010126 -54.636492) (xy 305.025623 -54.688988) (xy 305.033457 -54.74316) (xy 305.033934 -54.770528)
			(xy 305.033448 -54.797779) (xy 305.025692 -54.851727) (xy 305.010337 -54.904022) (xy 304.987695 -54.953599)
			(xy 304.958229 -54.999449) (xy 304.922538 -55.04064) (xy 304.881347 -55.076331) (xy 304.835497 -55.105797)
			(xy 304.78592 -55.128439) (xy 304.733625 -55.143794) (xy 304.679677 -55.15155) (xy 304.625175 -55.15155)
			(xy 304.571227 -55.143794) (xy 304.518932 -55.128439) (xy 304.469355 -55.105797) (xy 304.423505 -55.076331)
			(xy 304.382314 -55.04064) (xy 304.346623 -54.999449) (xy 304.317157 -54.953599) (xy 304.294515 -54.904022)
			(xy 304.27916 -54.851727) (xy 304.271404 -54.797779) (xy 304.270918 -54.770528) (xy 301.138997 -54.770528)
			(xy 301.139352 -54.791102) (xy 301.138866 -54.818353) (xy 301.13111 -54.872301) (xy 301.115755 -54.924596)
			(xy 301.093113 -54.974173) (xy 301.063647 -55.020023) (xy 301.027956 -55.061214) (xy 300.986765 -55.096905)
			(xy 300.940915 -55.126371) (xy 300.891338 -55.149013) (xy 300.839043 -55.164368) (xy 300.785095 -55.172124)
			(xy 300.730593 -55.172124) (xy 300.676645 -55.164368) (xy 300.62435 -55.149013) (xy 300.574773 -55.126371)
			(xy 300.528923 -55.096905) (xy 300.487732 -55.061214) (xy 300.452041 -55.020023) (xy 300.422575 -54.974173)
			(xy 300.399933 -54.924596) (xy 300.384578 -54.872301) (xy 300.376822 -54.818353) (xy 300.376336 -54.791102)
			(xy 298.478378 -54.791102) (xy 298.475286 -54.812611) (xy 298.459931 -54.864906) (xy 298.437289 -54.914483)
			(xy 298.407823 -54.960333) (xy 298.372132 -55.001524) (xy 298.330941 -55.037215) (xy 298.285091 -55.066681)
			(xy 298.235514 -55.089323) (xy 298.183219 -55.104678) (xy 298.129271 -55.112434) (xy 298.074769 -55.112434)
			(xy 298.020821 -55.104678) (xy 297.968526 -55.089323) (xy 297.918949 -55.066681) (xy 297.873099 -55.037215)
			(xy 297.831908 -55.001524) (xy 297.796217 -54.960333) (xy 297.766751 -54.914483) (xy 297.744109 -54.864906)
			(xy 297.728754 -54.812611) (xy 297.720998 -54.758663) (xy 297.720512 -54.731412) (xy 296.937684 -54.731412)
			(xy 296.937684 -57.002934) (xy 305.763422 -57.002934) (xy 305.763924 -56.974842) (xy 305.772148 -56.919265)
			(xy 305.788436 -56.865495) (xy 305.812437 -56.814697) (xy 305.843631 -56.76797) (xy 305.881343 -56.726325)
			(xy 305.924757 -56.690664) (xy 305.948588 -56.675782) (xy 305.957478 -56.670448) (xy 305.96967 -56.65343)
			(xy 305.98999 -56.560212) (xy 305.985672 -56.539638) (xy 305.97983 -56.531002) (xy 305.963832 -56.506937)
			(xy 305.938488 -56.455006) (xy 305.921262 -56.399849) (xy 305.912546 -56.342724) (xy 305.912012 -56.313832)
			(xy 305.912485 -56.286579) (xy 305.920238 -56.232627) (xy 305.935591 -56.180329) (xy 305.958231 -56.130747)
			(xy 305.987698 -56.084893) (xy 306.023391 -56.043699) (xy 306.064583 -56.008005) (xy 306.110437 -55.978537)
			(xy 306.160017 -55.955895) (xy 306.212316 -55.940541) (xy 306.266267 -55.932786) (xy 306.29352 -55.932324)
			(xy 306.320891 -55.932772) (xy 306.375071 -55.940594) (xy 306.427575 -55.956087) (xy 306.477321 -55.978932)
			(xy 306.523287 -56.008661) (xy 306.544218 -56.026304) (xy 306.544472 -56.026558) (xy 306.551557 -56.032146)
			(xy 306.568475 -56.03839) (xy 306.577492 -56.03875) (xy 306.644548 -56.03875) (xy 306.653564 -56.038379)
			(xy 306.670481 -56.032142) (xy 306.677568 -56.026558) (xy 306.677568 -56.026304) (xy 306.677822 -56.026304)
			(xy 306.698755 -56.008663) (xy 306.744723 -55.978939) (xy 306.794469 -55.956093) (xy 306.846971 -55.940597)
			(xy 306.901149 -55.932768) (xy 306.955891 -55.932768) (xy 307.010069 -55.940597) (xy 307.062571 -55.956093)
			(xy 307.112317 -55.978939) (xy 307.158285 -56.008663) (xy 307.179218 -56.026304) (xy 307.179472 -56.026558)
			(xy 307.186557 -56.032146) (xy 307.203475 -56.03839) (xy 307.212492 -56.03875) (xy 307.279548 -56.03875)
			(xy 307.288564 -56.038379) (xy 307.305481 -56.032142) (xy 307.312568 -56.026558) (xy 307.312568 -56.026304)
			(xy 307.312822 -56.026304) (xy 307.333773 -56.008689) (xy 307.379741 -55.978973) (xy 307.429483 -55.956133)
			(xy 307.48198 -55.940636) (xy 307.536152 -55.932801) (xy 307.56352 -55.932324) (xy 307.590773 -55.932747)
			(xy 307.644723 -55.940507) (xy 307.697019 -55.955865) (xy 307.746598 -55.978509) (xy 307.79245 -56.007978)
			(xy 307.833641 -56.043673) (xy 307.869334 -56.084866) (xy 307.898801 -56.130719) (xy 307.921442 -56.180299)
			(xy 307.936798 -56.232597) (xy 307.944554 -56.286547) (xy 307.944554 -56.341053) (xy 307.936798 -56.395003)
			(xy 307.921442 -56.447301) (xy 307.898801 -56.496881) (xy 307.869334 -56.542734) (xy 307.833641 -56.583927)
			(xy 307.79245 -56.619622) (xy 307.746598 -56.649091) (xy 307.697019 -56.671735) (xy 307.644723 -56.687093)
			(xy 307.590773 -56.694853) (xy 307.56352 -56.69534) (xy 307.536149 -56.694877) (xy 307.48197 -56.687061)
			(xy 307.429466 -56.671572) (xy 307.379719 -56.648729) (xy 307.333753 -56.619002) (xy 307.312822 -56.60136)
			(xy 307.312568 -56.601106) (xy 307.305466 -56.595542) (xy 307.288561 -56.589282) (xy 307.279548 -56.588914)
			(xy 307.212492 -56.588914) (xy 307.203474 -56.589264) (xy 307.186557 -56.595516) (xy 307.179472 -56.601106)
			(xy 307.179472 -56.60136) (xy 307.179218 -56.60136) (xy 307.158285 -56.619001) (xy 307.112317 -56.648725)
			(xy 307.062571 -56.671571) (xy 307.010069 -56.687067) (xy 306.955891 -56.694896) (xy 306.901149 -56.694896)
			(xy 306.846971 -56.687067) (xy 306.794469 -56.671571) (xy 306.744723 -56.648725) (xy 306.698755 -56.619001)
			(xy 306.677822 -56.60136) (xy 306.677568 -56.601106) (xy 306.670466 -56.595542) (xy 306.653561 -56.589282)
			(xy 306.644548 -56.588914) (xy 306.577492 -56.588914) (xy 306.568474 -56.589264) (xy 306.551557 -56.595516)
			(xy 306.544472 -56.601106) (xy 306.543964 -56.60136) (xy 306.531229 -56.612304) (xy 306.504138 -56.632145)
			(xy 306.489862 -56.640984) (xy 306.480972 -56.646318) (xy 306.46878 -56.663336) (xy 306.44846 -56.756554)
			(xy 306.452778 -56.777128) (xy 306.45862 -56.785764) (xy 306.474609 -56.809835) (xy 306.499954 -56.861764)
			(xy 306.517182 -56.91692) (xy 306.525901 -56.974042) (xy 306.526438 -57.002934) (xy 306.525952 -57.030185)
			(xy 306.518196 -57.084133) (xy 306.502841 -57.136428) (xy 306.480199 -57.186005) (xy 306.450733 -57.231855)
			(xy 306.415042 -57.273046) (xy 306.373851 -57.308737) (xy 306.328001 -57.338203) (xy 306.278424 -57.360845)
			(xy 306.226129 -57.3762) (xy 306.172181 -57.383956) (xy 306.117679 -57.383956) (xy 306.063731 -57.3762)
			(xy 306.011436 -57.360845) (xy 305.961859 -57.338203) (xy 305.916009 -57.308737) (xy 305.874818 -57.273046)
			(xy 305.839127 -57.231855) (xy 305.809661 -57.186005) (xy 305.787019 -57.136428) (xy 305.771664 -57.084133)
			(xy 305.763908 -57.030185) (xy 305.763422 -57.002934) (xy 296.937684 -57.002934) (xy 296.937684 -58.679334)
			(xy 306.195222 -58.679334) (xy 306.195638 -58.653018) (xy 306.202883 -58.600887) (xy 306.217211 -58.550243)
			(xy 306.238353 -58.502044) (xy 306.265909 -58.457202) (xy 306.299356 -58.416565) (xy 306.318412 -58.39841)
			(xy 306.325813 -58.390888) (xy 306.334337 -58.371608) (xy 306.334922 -58.361072) (xy 306.334922 -58.286396)
			(xy 306.334402 -58.275845) (xy 306.32586 -58.256551) (xy 306.318412 -58.249058) (xy 306.299345 -58.230913)
			(xy 306.265889 -58.190282) (xy 306.238331 -58.145439) (xy 306.217194 -58.097236) (xy 306.20288 -58.046587)
			(xy 306.195658 -57.994451) (xy 306.195222 -57.968134) (xy 306.195708 -57.940883) (xy 306.203464 -57.886935)
			(xy 306.218819 -57.83464) (xy 306.241461 -57.785063) (xy 306.270927 -57.739213) (xy 306.306618 -57.698022)
			(xy 306.347809 -57.662331) (xy 306.393659 -57.632865) (xy 306.443236 -57.610223) (xy 306.495531 -57.594868)
			(xy 306.549479 -57.587112) (xy 306.603981 -57.587112) (xy 306.657929 -57.594868) (xy 306.710224 -57.610223)
			(xy 306.759801 -57.632865) (xy 306.805651 -57.662331) (xy 306.846842 -57.698022) (xy 306.882533 -57.739213)
			(xy 306.911999 -57.785063) (xy 306.934641 -57.83464) (xy 306.949996 -57.886935) (xy 306.957752 -57.940883)
			(xy 306.958238 -57.968134) (xy 306.957813 -57.99445) (xy 306.950572 -58.046581) (xy 306.936246 -58.097225)
			(xy 306.915106 -58.145424) (xy 306.887551 -58.190267) (xy 306.854104 -58.230904) (xy 306.835048 -58.249058)
			(xy 306.82767 -58.2566) (xy 306.819131 -58.275864) (xy 306.818538 -58.286396) (xy 306.818538 -58.361072)
			(xy 306.819058 -58.371623) (xy 306.827598 -58.390919) (xy 306.835048 -58.39841) (xy 306.854111 -58.416558)
			(xy 306.887565 -58.457191) (xy 306.915122 -58.502033) (xy 306.936259 -58.550235) (xy 306.950575 -58.600883)
			(xy 306.9578 -58.653018) (xy 306.958238 -58.679334) (xy 306.957752 -58.706585) (xy 306.949996 -58.760533)
			(xy 306.934641 -58.812828) (xy 306.911999 -58.862405) (xy 306.882533 -58.908255) (xy 306.846842 -58.949446)
			(xy 306.805651 -58.985137) (xy 306.759801 -59.014603) (xy 306.710224 -59.037245) (xy 306.657929 -59.0526)
			(xy 306.603981 -59.060356) (xy 306.549479 -59.060356) (xy 306.495531 -59.0526) (xy 306.443236 -59.037245)
			(xy 306.393659 -59.014603) (xy 306.347809 -58.985137) (xy 306.306618 -58.949446) (xy 306.270927 -58.908255)
			(xy 306.241461 -58.862405) (xy 306.218819 -58.812828) (xy 306.203464 -58.760533) (xy 306.195708 -58.706585)
			(xy 306.195222 -58.679334) (xy 296.937684 -58.679334) (xy 296.937684 -60.01925) (xy 306.335684 -60.01925)
			(xy 306.335684 -59.96475) (xy 306.34344 -59.910804) (xy 306.358794 -59.858512) (xy 306.381433 -59.808936)
			(xy 306.410898 -59.763087) (xy 306.446587 -59.721898) (xy 306.487775 -59.686207) (xy 306.533622 -59.656741)
			(xy 306.583197 -59.634099) (xy 306.635489 -59.618743) (xy 306.689434 -59.610985) (xy 306.716684 -59.610498)
			(xy 306.744054 -59.610974) (xy 306.798233 -59.618789) (xy 306.850736 -59.634276) (xy 306.900483 -59.657116)
			(xy 306.94645 -59.686838) (xy 306.967382 -59.704478) (xy 306.967636 -59.704732) (xy 306.974734 -59.710301)
			(xy 306.991642 -59.716557) (xy 307.000656 -59.716924) (xy 307.067712 -59.716924) (xy 307.076729 -59.716567)
			(xy 307.093645 -59.710319) (xy 307.100732 -59.704732) (xy 307.100732 -59.704478) (xy 307.100986 -59.704478)
			(xy 307.121919 -59.686837) (xy 307.167887 -59.657113) (xy 307.217633 -59.634267) (xy 307.270135 -59.618771)
			(xy 307.324313 -59.610942) (xy 307.379055 -59.610942) (xy 307.433233 -59.618771) (xy 307.485735 -59.634267)
			(xy 307.535481 -59.657113) (xy 307.581449 -59.686837) (xy 307.602382 -59.704478) (xy 307.602636 -59.704732)
			(xy 307.609734 -59.710301) (xy 307.626642 -59.716557) (xy 307.635656 -59.716924) (xy 307.702712 -59.716924)
			(xy 307.711729 -59.716567) (xy 307.728645 -59.710319) (xy 307.735732 -59.704732) (xy 307.735732 -59.704478)
			(xy 307.735986 -59.704478) (xy 307.75691 -59.686829) (xy 307.802885 -59.657119) (xy 307.852635 -59.634285)
			(xy 307.905137 -59.618797) (xy 307.959314 -59.610971) (xy 307.986684 -59.610498) (xy 308.013938 -59.610948)
			(xy 308.067892 -59.618704) (xy 308.120192 -59.634058) (xy 308.169775 -59.6567) (xy 308.215631 -59.686168)
			(xy 308.256826 -59.721863) (xy 308.292522 -59.763056) (xy 308.321992 -59.808911) (xy 308.344636 -59.858493)
			(xy 308.359993 -59.910793) (xy 308.367751 -59.964746) (xy 308.367751 -60.019254) (xy 308.359993 -60.073207)
			(xy 308.344636 -60.125507) (xy 308.321992 -60.175089) (xy 308.292522 -60.220944) (xy 308.256826 -60.262137)
			(xy 308.215631 -60.297832) (xy 308.169775 -60.3273) (xy 308.120192 -60.349942) (xy 308.067892 -60.365296)
			(xy 308.013938 -60.373052) (xy 307.986684 -60.373514) (xy 307.959314 -60.373054) (xy 307.905134 -60.365234)
			(xy 307.852631 -60.349743) (xy 307.802885 -60.326901) (xy 307.756918 -60.297175) (xy 307.735986 -60.279534)
			(xy 307.735732 -60.27928) (xy 307.728642 -60.273698) (xy 307.711728 -60.267449) (xy 307.702712 -60.267088)
			(xy 307.635656 -60.267088) (xy 307.626642 -60.267474) (xy 307.609725 -60.273702) (xy 307.602636 -60.27928)
			(xy 307.602382 -60.279534) (xy 307.581449 -60.297175) (xy 307.535481 -60.326899) (xy 307.485735 -60.349745)
			(xy 307.433233 -60.365241) (xy 307.379055 -60.37307) (xy 307.324313 -60.37307) (xy 307.270135 -60.365241)
			(xy 307.217633 -60.349745) (xy 307.167887 -60.326899) (xy 307.121919 -60.297175) (xy 307.100986 -60.279534)
			(xy 307.100732 -60.27928) (xy 307.093642 -60.273698) (xy 307.076728 -60.267449) (xy 307.067712 -60.267088)
			(xy 307.000656 -60.267088) (xy 306.991642 -60.267474) (xy 306.974725 -60.273702) (xy 306.967636 -60.27928)
			(xy 306.967636 -60.279534) (xy 306.967382 -60.279534) (xy 306.946434 -60.297153) (xy 306.900465 -60.326867)
			(xy 306.850722 -60.349706) (xy 306.798225 -60.365202) (xy 306.744052 -60.373036) (xy 306.716684 -60.373514)
			(xy 306.689434 -60.373015) (xy 306.635489 -60.365257) (xy 306.583197 -60.349901) (xy 306.533622 -60.327259)
			(xy 306.487775 -60.297793) (xy 306.446587 -60.262102) (xy 306.410898 -60.220913) (xy 306.381433 -60.175064)
			(xy 306.358794 -60.125488) (xy 306.34344 -60.073196) (xy 306.335684 -60.01925) (xy 296.937684 -60.01925)
			(xy 296.937684 -67.128949) (xy 298.566598 -67.128949) (xy 298.566598 -67.074451) (xy 298.574354 -67.020507)
			(xy 298.589708 -66.968216) (xy 298.612346 -66.918643) (xy 298.64181 -66.872796) (xy 298.677498 -66.831608)
			(xy 298.718684 -66.795918) (xy 298.76453 -66.766453) (xy 298.814103 -66.743812) (xy 298.866394 -66.728457)
			(xy 298.920337 -66.720699) (xy 298.947586 -66.720212) (xy 298.974956 -66.720683) (xy 299.029135 -66.728499)
			(xy 299.081638 -66.743987) (xy 299.131385 -66.766828) (xy 299.177352 -66.796551) (xy 299.198284 -66.814192)
			(xy 299.198538 -66.814446) (xy 299.205634 -66.820018) (xy 299.222544 -66.826272) (xy 299.231558 -66.826638)
			(xy 299.298614 -66.826638) (xy 299.307631 -66.82628) (xy 299.324547 -66.820032) (xy 299.331634 -66.814446)
			(xy 299.331634 -66.814192) (xy 299.331888 -66.814192) (xy 299.352813 -66.796544) (xy 299.398788 -66.766834)
			(xy 299.448537 -66.744) (xy 299.501039 -66.728511) (xy 299.555216 -66.720685) (xy 299.582586 -66.720212)
			(xy 299.609841 -66.720634) (xy 299.663796 -66.72839) (xy 299.716099 -66.743745) (xy 299.765683 -66.766388)
			(xy 299.811541 -66.795857) (xy 299.852737 -66.831553) (xy 299.888434 -66.872748) (xy 299.917905 -66.918605)
			(xy 299.94055 -66.968188) (xy 299.955907 -67.02049) (xy 299.963665 -67.074445) (xy 299.963665 -67.128955)
			(xy 299.955907 -67.18291) (xy 299.94055 -67.235212) (xy 299.917905 -67.284795) (xy 299.888434 -67.330652)
			(xy 299.852737 -67.371847) (xy 299.811541 -67.407543) (xy 299.765683 -67.437012) (xy 299.716099 -67.459655)
			(xy 299.663796 -67.47501) (xy 299.609841 -67.482766) (xy 299.582586 -67.483228) (xy 299.555215 -67.482788)
			(xy 299.501034 -67.474966) (xy 299.44853 -67.459472) (xy 299.398783 -67.436624) (xy 299.352818 -67.406893)
			(xy 299.331888 -67.389248) (xy 299.331634 -67.388994) (xy 299.324542 -67.383415) (xy 299.307629 -67.377164)
			(xy 299.298614 -67.376802) (xy 299.231558 -67.376802) (xy 299.222544 -67.377187) (xy 299.205627 -67.383415)
			(xy 299.198538 -67.388994) (xy 299.198538 -67.389248) (xy 299.198284 -67.389248) (xy 299.177324 -67.406853)
			(xy 299.13136 -67.436572) (xy 299.08162 -67.459415) (xy 299.029125 -67.474914) (xy 298.974953 -67.48275)
			(xy 298.947586 -67.483228) (xy 298.920337 -67.482701) (xy 298.866394 -67.474943) (xy 298.814103 -67.459588)
			(xy 298.76453 -67.436947) (xy 298.718684 -67.407482) (xy 298.677498 -67.371792) (xy 298.64181 -67.330604)
			(xy 298.612346 -67.284757) (xy 298.589708 -67.235184) (xy 298.574354 -67.182893) (xy 298.566598 -67.128949)
			(xy 296.937684 -67.128949) (xy 296.937684 -67.488054) (xy 302.979072 -67.488054) (xy 302.983143 -67.432432)
			(xy 302.995269 -67.377995) (xy 303.015192 -67.325904) (xy 303.042488 -67.277269) (xy 303.076574 -67.233126)
			(xy 303.116723 -67.194417) (xy 303.162081 -67.161966) (xy 303.211681 -67.136465) (xy 303.264465 -67.118458)
			(xy 303.319308 -67.108328) (xy 303.375042 -67.106291) (xy 303.430479 -67.112391) (xy 303.484436 -67.126497)
			(xy 303.535765 -67.148309) (xy 303.583371 -67.177363) (xy 303.626239 -67.213038) (xy 303.663456 -67.254575)
			(xy 303.694229 -67.301088) (xy 303.717901 -67.351585) (xy 303.733969 -67.404992) (xy 303.742089 -67.460168)
			(xy 303.742598 -67.488054) (xy 303.742089 -67.51594) (xy 303.738904 -67.537584) (xy 304.27117 -67.537584)
			(xy 304.275241 -67.481962) (xy 304.287367 -67.427525) (xy 304.30729 -67.375434) (xy 304.334586 -67.326799)
			(xy 304.368672 -67.282656) (xy 304.408821 -67.243947) (xy 304.454179 -67.211496) (xy 304.503779 -67.185995)
			(xy 304.556563 -67.167988) (xy 304.611406 -67.157858) (xy 304.66714 -67.155821) (xy 304.722577 -67.161921)
			(xy 304.776534 -67.176027) (xy 304.827863 -67.197839) (xy 304.875469 -67.226893) (xy 304.918337 -67.262568)
			(xy 304.955554 -67.304105) (xy 304.986327 -67.350618) (xy 305.009999 -67.401115) (xy 305.026067 -67.454522)
			(xy 305.034187 -67.509698) (xy 305.034696 -67.537584) (xy 305.034187 -67.56547) (xy 305.030142 -67.592956)
			(xy 305.545234 -67.592956) (xy 305.549305 -67.537334) (xy 305.561431 -67.482897) (xy 305.581354 -67.430806)
			(xy 305.60865 -67.382171) (xy 305.642736 -67.338028) (xy 305.682885 -67.299319) (xy 305.728243 -67.266868)
			(xy 305.777843 -67.241367) (xy 305.830627 -67.22336) (xy 305.88547 -67.21323) (xy 305.941204 -67.211193)
			(xy 305.996641 -67.217293) (xy 306.050598 -67.231399) (xy 306.101927 -67.253211) (xy 306.149533 -67.282265)
			(xy 306.192401 -67.31794) (xy 306.229618 -67.359477) (xy 306.260391 -67.40599) (xy 306.284063 -67.456487)
			(xy 306.300131 -67.509894) (xy 306.308248 -67.565047) (xy 308.646616 -67.565047) (xy 308.646616 -67.510553)
			(xy 308.654371 -67.456612) (xy 308.669724 -67.404325) (xy 308.692361 -67.354754) (xy 308.721822 -67.30891)
			(xy 308.757507 -67.267724) (xy 308.79869 -67.232036) (xy 308.844533 -67.202572) (xy 308.894102 -67.179932)
			(xy 308.946389 -67.164576) (xy 309.000329 -67.156818) (xy 309.027576 -67.15633) (xy 309.054946 -67.156803)
			(xy 309.109125 -67.164618) (xy 309.161628 -67.180105) (xy 309.211375 -67.202945) (xy 309.257342 -67.232669)
			(xy 309.278274 -67.25031) (xy 309.278528 -67.250564) (xy 309.285626 -67.256134) (xy 309.302534 -67.262389)
			(xy 309.311548 -67.262756) (xy 309.378604 -67.262756) (xy 309.387622 -67.26241) (xy 309.404539 -67.256156)
			(xy 309.411624 -67.250564) (xy 309.411624 -67.25031) (xy 309.411878 -67.25031) (xy 309.432809 -67.232669)
			(xy 309.478782 -67.202957) (xy 309.52853 -67.180122) (xy 309.581031 -67.164631) (xy 309.635207 -67.156804)
			(xy 309.662576 -67.15633) (xy 309.689833 -67.156715) (xy 309.743792 -67.16447) (xy 309.796098 -67.179826)
			(xy 309.845686 -67.202469) (xy 309.891547 -67.23194) (xy 309.932746 -67.267637) (xy 309.968446 -67.308834)
			(xy 309.997919 -67.354693) (xy 310.020566 -67.40428) (xy 310.035925 -67.456585) (xy 310.043683 -67.510543)
			(xy 310.043683 -67.565057) (xy 310.035925 -67.619015) (xy 310.020566 -67.67132) (xy 309.997919 -67.720907)
			(xy 309.968446 -67.766766) (xy 309.932746 -67.807963) (xy 309.891547 -67.84366) (xy 309.845686 -67.873131)
			(xy 309.796098 -67.895774) (xy 309.743792 -67.91113) (xy 309.689833 -67.918885) (xy 309.662576 -67.919346)
			(xy 309.635205 -67.918907) (xy 309.581024 -67.911085) (xy 309.52852 -67.89559) (xy 309.478773 -67.872742)
			(xy 309.432808 -67.843011) (xy 309.411878 -67.825366) (xy 309.411624 -67.825112) (xy 309.404534 -67.819531)
			(xy 309.38762 -67.81328) (xy 309.378604 -67.81292) (xy 309.311548 -67.81292) (xy 309.302533 -67.813296)
			(xy 309.285616 -67.81953) (xy 309.278528 -67.825112) (xy 309.278528 -67.825366) (xy 309.278274 -67.825366)
			(xy 309.25732 -67.842979) (xy 309.211354 -67.872696) (xy 309.161612 -67.895537) (xy 309.109116 -67.911034)
			(xy 309.054944 -67.918869) (xy 309.027576 -67.919346) (xy 309.000329 -67.918782) (xy 308.946389 -67.911024)
			(xy 308.894102 -67.895668) (xy 308.844533 -67.873028) (xy 308.79869 -67.843564) (xy 308.757507 -67.807876)
			(xy 308.721822 -67.76669) (xy 308.692361 -67.720846) (xy 308.669724 -67.671275) (xy 308.654371 -67.618988)
			(xy 308.646616 -67.565047) (xy 306.308248 -67.565047) (xy 306.308251 -67.56507) (xy 306.30876 -67.592956)
			(xy 306.308251 -67.620842) (xy 306.300131 -67.676018) (xy 306.284063 -67.729425) (xy 306.260391 -67.779922)
			(xy 306.229618 -67.826435) (xy 306.192401 -67.867972) (xy 306.149533 -67.903647) (xy 306.101927 -67.932701)
			(xy 306.050598 -67.954513) (xy 305.996641 -67.968619) (xy 305.941204 -67.974719) (xy 305.88547 -67.972682)
			(xy 305.830627 -67.962552) (xy 305.777843 -67.944545) (xy 305.728243 -67.919044) (xy 305.682885 -67.886593)
			(xy 305.642736 -67.847884) (xy 305.60865 -67.803741) (xy 305.581354 -67.755106) (xy 305.561431 -67.703015)
			(xy 305.549305 -67.648578) (xy 305.545234 -67.592956) (xy 305.030142 -67.592956) (xy 305.026067 -67.620646)
			(xy 305.009999 -67.674053) (xy 304.986327 -67.72455) (xy 304.955554 -67.771063) (xy 304.918337 -67.8126)
			(xy 304.875469 -67.848275) (xy 304.827863 -67.877329) (xy 304.776534 -67.899141) (xy 304.722577 -67.913247)
			(xy 304.66714 -67.919347) (xy 304.611406 -67.91731) (xy 304.556563 -67.90718) (xy 304.503779 -67.889173)
			(xy 304.454179 -67.863672) (xy 304.408821 -67.831221) (xy 304.368672 -67.792512) (xy 304.334586 -67.748369)
			(xy 304.30729 -67.699734) (xy 304.287367 -67.647643) (xy 304.275241 -67.593206) (xy 304.27117 -67.537584)
			(xy 303.738904 -67.537584) (xy 303.733969 -67.571116) (xy 303.717901 -67.624523) (xy 303.694229 -67.67502)
			(xy 303.663456 -67.721533) (xy 303.626239 -67.76307) (xy 303.583371 -67.798745) (xy 303.535765 -67.827799)
			(xy 303.484436 -67.849611) (xy 303.430479 -67.863717) (xy 303.375042 -67.869817) (xy 303.319308 -67.86778)
			(xy 303.264465 -67.85765) (xy 303.211681 -67.839643) (xy 303.162081 -67.814142) (xy 303.116723 -67.781691)
			(xy 303.076574 -67.742982) (xy 303.042488 -67.698839) (xy 303.015192 -67.650204) (xy 302.995269 -67.598113)
			(xy 302.983143 -67.543676) (xy 302.979072 -67.488054) (xy 296.937684 -67.488054) (xy 296.937684 -68.586604)
			(xy 300.825154 -68.586604) (xy 300.825609 -68.559233) (xy 300.833428 -68.505053) (xy 300.848919 -68.452549)
			(xy 300.871763 -68.402803) (xy 300.901491 -68.356837) (xy 300.919134 -68.335906) (xy 300.919388 -68.335652)
			(xy 300.924958 -68.328554) (xy 300.931215 -68.311646) (xy 300.93158 -68.302632) (xy 300.93158 -68.235576)
			(xy 300.931239 -68.226557) (xy 300.924981 -68.20964) (xy 300.919388 -68.202556) (xy 300.919134 -68.202556)
			(xy 300.919134 -68.202302) (xy 300.901488 -68.181376) (xy 300.871776 -68.135402) (xy 300.848941 -68.085653)
			(xy 300.833451 -68.033151) (xy 300.825626 -67.978974) (xy 300.825154 -67.951604) (xy 300.825681 -67.924355)
			(xy 300.833436 -67.87041) (xy 300.848789 -67.818119) (xy 300.871427 -67.768544) (xy 300.900889 -67.722695)
			(xy 300.936576 -67.681506) (xy 300.977762 -67.645815) (xy 301.023607 -67.616347) (xy 301.073179 -67.593704)
			(xy 301.125469 -67.578345) (xy 301.179413 -67.570584) (xy 301.206662 -67.570096) (xy 301.232977 -67.570523)
			(xy 301.285108 -67.577767) (xy 301.335751 -67.592094) (xy 301.38395 -67.613234) (xy 301.428792 -67.640787)
			(xy 301.46943 -67.674232) (xy 301.487586 -67.693286) (xy 301.495113 -67.700681) (xy 301.514389 -67.70921)
			(xy 301.524924 -67.709796) (xy 301.5996 -67.709796) (xy 301.610151 -67.709281) (xy 301.629447 -67.700736)
			(xy 301.636938 -67.693286) (xy 301.655079 -67.674216) (xy 301.695712 -67.640761) (xy 301.740556 -67.613204)
			(xy 301.788759 -67.592068) (xy 301.839409 -67.577754) (xy 301.891545 -67.570533) (xy 301.917862 -67.570096)
			(xy 301.945231 -67.570585) (xy 301.999409 -67.578398) (xy 302.051912 -67.593881) (xy 302.101659 -67.616718)
			(xy 302.147627 -67.646437) (xy 302.16856 -67.664076) (xy 302.168814 -67.66433) (xy 302.17589 -67.669932)
			(xy 302.192815 -67.676168) (xy 302.201834 -67.676522) (xy 302.26889 -67.676522) (xy 302.277906 -67.676155)
			(xy 302.294823 -67.669914) (xy 302.30191 -67.66433) (xy 302.30191 -67.664076) (xy 302.302164 -67.664076)
			(xy 302.323096 -67.646437) (xy 302.369069 -67.616726) (xy 302.418817 -67.59389) (xy 302.471317 -67.578399)
			(xy 302.525493 -67.57057) (xy 302.552862 -67.570096) (xy 302.580114 -67.570591) (xy 302.634064 -67.578343)
			(xy 302.686362 -67.593694) (xy 302.735942 -67.616332) (xy 302.781795 -67.645797) (xy 302.822989 -67.681487)
			(xy 302.858683 -67.722677) (xy 302.888151 -67.768528) (xy 302.910794 -67.818106) (xy 302.92615 -67.870403)
			(xy 302.933907 -67.924352) (xy 302.93437 -67.951604) (xy 302.933914 -67.978975) (xy 302.926095 -68.033154)
			(xy 302.910604 -68.085658) (xy 302.88776 -68.135405) (xy 302.858033 -68.181371) (xy 302.84039 -68.202302)
			(xy 302.840136 -68.202556) (xy 302.834554 -68.209645) (xy 302.828306 -68.22656) (xy 302.827944 -68.235576)
			(xy 302.827944 -68.302632) (xy 302.828276 -68.311652) (xy 302.83454 -68.328569) (xy 302.840136 -68.335652)
			(xy 302.84039 -68.335652) (xy 302.84039 -68.335906) (xy 302.858044 -68.356826) (xy 302.887754 -68.402802)
			(xy 302.910587 -68.452553) (xy 302.926075 -68.505056) (xy 302.933898 -68.559234) (xy 302.93437 -68.586604)
			(xy 302.933948 -68.613859) (xy 302.92619 -68.667813) (xy 302.910831 -68.720114) (xy 302.894199 -68.75653)
			(xy 306.370228 -68.75653) (xy 306.370705 -68.72916) (xy 306.378519 -68.674981) (xy 306.394005 -68.622478)
			(xy 306.416845 -68.572731) (xy 306.446567 -68.526764) (xy 306.464208 -68.505832) (xy 306.464462 -68.505578)
			(xy 306.470071 -68.498507) (xy 306.476303 -68.481578) (xy 306.476654 -68.472558) (xy 306.476654 -68.405502)
			(xy 306.476306 -68.396484) (xy 306.470053 -68.379567) (xy 306.464462 -68.372482) (xy 306.464208 -68.372482)
			(xy 306.464208 -68.372228) (xy 306.44657 -68.351295) (xy 306.416858 -68.305323) (xy 306.394021 -68.255575)
			(xy 306.37853 -68.203075) (xy 306.370702 -68.148899) (xy 306.370228 -68.12153) (xy 306.370683 -68.094276)
			(xy 306.378437 -68.040323) (xy 306.393791 -67.988023) (xy 306.416433 -67.938441) (xy 306.445901 -67.892586)
			(xy 306.481596 -67.851392) (xy 306.52279 -67.815697) (xy 306.568646 -67.78623) (xy 306.618229 -67.763589)
			(xy 306.670529 -67.748236) (xy 306.724482 -67.740483) (xy 306.751736 -67.740022) (xy 306.779107 -67.740462)
			(xy 306.833288 -67.748285) (xy 306.885791 -67.76378) (xy 306.935538 -67.786628) (xy 306.981503 -67.816358)
			(xy 307.002434 -67.834002) (xy 307.002688 -67.834256) (xy 307.009769 -67.83985) (xy 307.02669 -67.846091)
			(xy 307.035708 -67.846448) (xy 307.102764 -67.846448) (xy 307.11178 -67.846085) (xy 307.128698 -67.839843)
			(xy 307.135784 -67.834256) (xy 307.135784 -67.834002) (xy 307.136038 -67.834002) (xy 307.156983 -67.816379)
			(xy 307.202952 -67.786665) (xy 307.252696 -67.763825) (xy 307.305194 -67.748331) (xy 307.359368 -67.740498)
			(xy 307.386736 -67.740022) (xy 307.413051 -67.740458) (xy 307.465181 -67.747699) (xy 307.515825 -67.762023)
			(xy 307.564024 -67.783162) (xy 307.608867 -67.810713) (xy 307.649505 -67.844158) (xy 307.66766 -67.863212)
			(xy 307.675193 -67.8706) (xy 307.694464 -67.879132) (xy 307.704998 -67.879722) (xy 307.779674 -67.879722)
			(xy 307.790223 -67.879186) (xy 307.809518 -67.870655) (xy 307.817012 -67.863212) (xy 307.835171 -67.84416)
			(xy 307.8758 -67.810702) (xy 307.920639 -67.783142) (xy 307.968839 -67.762003) (xy 308.019486 -67.747685)
			(xy 308.07162 -67.74046) (xy 308.097936 -67.740022) (xy 308.12519 -67.740444) (xy 308.179141 -67.748207)
			(xy 308.231439 -67.763568) (xy 308.281018 -67.786215) (xy 308.32687 -67.815688) (xy 308.36806 -67.851386)
			(xy 308.403751 -67.892583) (xy 308.433216 -67.93844) (xy 308.455855 -67.988023) (xy 308.471207 -68.040324)
			(xy 308.47896 -68.094276) (xy 308.479444 -68.12153) (xy 308.479009 -68.148902) (xy 308.471186 -68.203082)
			(xy 308.45569 -68.255586) (xy 308.432841 -68.305333) (xy 308.403109 -68.351298) (xy 308.385464 -68.372228)
			(xy 308.38521 -68.372482) (xy 308.379626 -68.37957) (xy 308.373377 -68.396486) (xy 308.373018 -68.405502)
			(xy 308.373018 -68.472558) (xy 308.373391 -68.481573) (xy 308.379627 -68.498491) (xy 308.38521 -68.505578)
			(xy 308.385464 -68.505578) (xy 308.385464 -68.505832) (xy 308.403079 -68.526784) (xy 308.432796 -68.57275)
			(xy 308.455637 -68.622493) (xy 308.471133 -68.674989) (xy 308.478967 -68.729162) (xy 308.479444 -68.75653)
			(xy 308.47895 -68.78378) (xy 308.471191 -68.837726) (xy 308.455833 -68.890018) (xy 308.433191 -68.939593)
			(xy 308.403725 -68.985442) (xy 308.368035 -69.026631) (xy 308.326847 -69.062322) (xy 308.280999 -69.091789)
			(xy 308.231424 -69.114431) (xy 308.179132 -69.129789) (xy 308.125186 -69.13755) (xy 308.097936 -69.138038)
			(xy 308.07162 -69.137633) (xy 308.019488 -69.130388) (xy 307.968843 -69.116058) (xy 307.920644 -69.094914)
			(xy 307.875802 -69.067356) (xy 307.835166 -69.033905) (xy 307.817012 -69.014848) (xy 307.809481 -69.007457)
			(xy 307.790208 -68.998925) (xy 307.779674 -68.998338) (xy 307.704998 -68.998338) (xy 307.694445 -68.998841)
			(xy 307.675149 -69.007393) (xy 307.66766 -69.014848) (xy 307.649526 -69.033925) (xy 307.608891 -69.067378)
			(xy 307.564046 -69.094933) (xy 307.515841 -69.116068) (xy 307.46519 -69.130381) (xy 307.413053 -69.137602)
			(xy 307.386736 -69.138038) (xy 307.359366 -69.137566) (xy 307.305186 -69.129752) (xy 307.252683 -69.114265)
			(xy 307.202936 -69.091424) (xy 307.156969 -69.0617) (xy 307.136038 -69.044058) (xy 307.135784 -69.043804)
			(xy 307.128706 -69.038205) (xy 307.111783 -69.031966) (xy 307.102764 -69.031612) (xy 307.035708 -69.031612)
			(xy 307.026691 -69.03197) (xy 307.009774 -69.038217) (xy 307.002688 -69.043804) (xy 307.002688 -69.044058)
			(xy 307.002434 -69.044058) (xy 306.981495 -69.061688) (xy 306.935524 -69.091403) (xy 306.885779 -69.114241)
			(xy 306.83328 -69.129734) (xy 306.779105 -69.137564) (xy 306.751736 -69.138038) (xy 306.724485 -69.137511)
			(xy 306.670538 -69.12976) (xy 306.618243 -69.11441) (xy 306.568665 -69.091774) (xy 306.522814 -69.062312)
			(xy 306.481621 -69.026625) (xy 306.445927 -68.985439) (xy 306.416458 -68.939593) (xy 306.393813 -68.890018)
			(xy 306.378454 -68.837726) (xy 306.370693 -68.783781) (xy 306.370228 -68.75653) (xy 302.894199 -68.75653)
			(xy 302.888186 -68.769697) (xy 302.858714 -68.815552) (xy 302.823015 -68.856745) (xy 302.781818 -68.892439)
			(xy 302.73596 -68.921906) (xy 302.686375 -68.944546) (xy 302.634072 -68.959899) (xy 302.580117 -68.967651)
			(xy 302.552862 -68.968112) (xy 302.525493 -68.967607) (xy 302.471316 -68.959798) (xy 302.418813 -68.944318)
			(xy 302.369066 -68.921485) (xy 302.323097 -68.891769) (xy 302.302164 -68.874132) (xy 302.30191 -68.873878)
			(xy 302.294827 -68.868287) (xy 302.277907 -68.862044) (xy 302.26889 -68.861686) (xy 302.201834 -68.861686)
			(xy 302.192819 -68.862062) (xy 302.175902 -68.868297) (xy 302.168814 -68.873878) (xy 302.168814 -68.874132)
			(xy 302.16856 -68.874132) (xy 302.14762 -68.891761) (xy 302.101649 -68.921474) (xy 302.051903 -68.944311)
			(xy 301.999405 -68.959804) (xy 301.945231 -68.967636) (xy 301.917862 -68.968112) (xy 301.891547 -68.967666)
			(xy 301.839418 -68.960426) (xy 301.788775 -68.946103) (xy 301.740576 -68.924966) (xy 301.695733 -68.897417)
			(xy 301.655094 -68.863975) (xy 301.636938 -68.844922) (xy 301.629401 -68.837538) (xy 301.610133 -68.829003)
			(xy 301.5996 -68.828412) (xy 301.524924 -68.828412) (xy 301.514374 -68.828937) (xy 301.495078 -68.837475)
			(xy 301.487586 -68.844922) (xy 301.469435 -68.863982) (xy 301.428803 -68.897437) (xy 301.383962 -68.924995)
			(xy 301.335761 -68.946133) (xy 301.285113 -68.96045) (xy 301.232978 -68.967674) (xy 301.206662 -68.968112)
			(xy 301.17941 -68.967658) (xy 301.125461 -68.959896) (xy 301.073166 -68.944536) (xy 301.023589 -68.921891)
			(xy 300.977739 -68.892421) (xy 300.936549 -68.856726) (xy 300.900859 -68.815534) (xy 300.871393 -68.769681)
			(xy 300.848752 -68.720102) (xy 300.833397 -68.667805) (xy 300.82564 -68.613856) (xy 300.825154 -68.586604)
			(xy 296.937684 -68.586604) (xy 296.937684 -71.555864) (xy 303.394362 -71.555864) (xy 303.398433 -71.500242)
			(xy 303.410559 -71.445805) (xy 303.430482 -71.393714) (xy 303.457778 -71.345079) (xy 303.491864 -71.300936)
			(xy 303.532013 -71.262227) (xy 303.577371 -71.229776) (xy 303.626971 -71.204275) (xy 303.679755 -71.186268)
			(xy 303.734598 -71.176138) (xy 303.790332 -71.174101) (xy 303.845769 -71.180201) (xy 303.899726 -71.194307)
			(xy 303.951055 -71.216119) (xy 303.998661 -71.245173) (xy 304.041529 -71.280848) (xy 304.078746 -71.322385)
			(xy 304.109519 -71.368898) (xy 304.133191 -71.419395) (xy 304.149259 -71.472802) (xy 304.157379 -71.527978)
			(xy 304.157888 -71.555864) (xy 304.157379 -71.58375) (xy 304.15154 -71.623428) (xy 304.903376 -71.623428)
			(xy 304.907447 -71.567806) (xy 304.919573 -71.513369) (xy 304.939496 -71.461278) (xy 304.966792 -71.412643)
			(xy 305.000878 -71.3685) (xy 305.041027 -71.329791) (xy 305.086385 -71.29734) (xy 305.135985 -71.271839)
			(xy 305.188769 -71.253832) (xy 305.243612 -71.243702) (xy 305.299346 -71.241665) (xy 305.354783 -71.247765)
			(xy 305.40874 -71.261871) (xy 305.460069 -71.283683) (xy 305.507675 -71.312737) (xy 305.550543 -71.348412)
			(xy 305.58776 -71.389949) (xy 305.618533 -71.436462) (xy 305.642205 -71.486959) (xy 305.658273 -71.540366)
			(xy 305.666393 -71.595542) (xy 305.666902 -71.623428) (xy 305.666393 -71.651314) (xy 305.658273 -71.70649)
			(xy 305.642205 -71.759897) (xy 305.618533 -71.810394) (xy 305.58776 -71.856907) (xy 305.550543 -71.898444)
			(xy 305.507675 -71.934119) (xy 305.460069 -71.963173) (xy 305.40874 -71.984985) (xy 305.354783 -71.999091)
			(xy 305.299346 -72.005191) (xy 305.243612 -72.003154) (xy 305.188769 -71.993024) (xy 305.135985 -71.975017)
			(xy 305.086385 -71.949516) (xy 305.041027 -71.917065) (xy 305.000878 -71.878356) (xy 304.966792 -71.834213)
			(xy 304.939496 -71.785578) (xy 304.919573 -71.733487) (xy 304.907447 -71.67905) (xy 304.903376 -71.623428)
			(xy 304.15154 -71.623428) (xy 304.149259 -71.638926) (xy 304.133191 -71.692333) (xy 304.109519 -71.74283)
			(xy 304.078746 -71.789343) (xy 304.041529 -71.83088) (xy 303.998661 -71.866555) (xy 303.951055 -71.895609)
			(xy 303.899726 -71.917421) (xy 303.845769 -71.931527) (xy 303.790332 -71.937627) (xy 303.734598 -71.93559)
			(xy 303.679755 -71.92546) (xy 303.626971 -71.907453) (xy 303.577371 -71.881952) (xy 303.532013 -71.849501)
			(xy 303.491864 -71.810792) (xy 303.457778 -71.766649) (xy 303.430482 -71.718014) (xy 303.410559 -71.665923)
			(xy 303.398433 -71.611486) (xy 303.394362 -71.555864) (xy 296.937684 -71.555864) (xy 296.937684 -72.979788)
			(xy 296.937754 -72.984263) (xy 296.939288 -72.993078) (xy 296.940732 -72.997314) (xy 296.94274 -73.00241)
			(xy 296.948633 -73.011641) (xy 296.952416 -73.015602) (xy 301.143303 -77.206348) (xy 314.884052 -77.206348)
			(xy 314.888123 -77.150726) (xy 314.900249 -77.096289) (xy 314.920172 -77.044198) (xy 314.947468 -76.995563)
			(xy 314.981554 -76.95142) (xy 315.021703 -76.912711) (xy 315.067061 -76.88026) (xy 315.116661 -76.854759)
			(xy 315.169445 -76.836752) (xy 315.224288 -76.826622) (xy 315.280022 -76.824585) (xy 315.335459 -76.830685)
			(xy 315.389416 -76.844791) (xy 315.440745 -76.866603) (xy 315.488351 -76.895657) (xy 315.531219 -76.931332)
			(xy 315.568436 -76.972869) (xy 315.599209 -77.019382) (xy 315.622881 -77.069879) (xy 315.638949 -77.123286)
			(xy 315.647069 -77.178462) (xy 315.647578 -77.206348) (xy 315.647069 -77.234234) (xy 315.638949 -77.28941)
			(xy 315.622881 -77.342817) (xy 315.599209 -77.393314) (xy 315.568436 -77.439827) (xy 315.531219 -77.481364)
			(xy 315.488351 -77.517039) (xy 315.440745 -77.546093) (xy 315.389416 -77.567905) (xy 315.335459 -77.582011)
			(xy 315.280022 -77.588111) (xy 315.224288 -77.586074) (xy 315.169445 -77.575944) (xy 315.116661 -77.557937)
			(xy 315.067061 -77.532436) (xy 315.021703 -77.499985) (xy 314.981554 -77.461276) (xy 314.947468 -77.417133)
			(xy 314.920172 -77.368498) (xy 314.900249 -77.316407) (xy 314.888123 -77.26197) (xy 314.884052 -77.206348)
			(xy 301.143303 -77.206348) (xy 303.956956 -80.019906) (xy 304.700684 -80.019906) (xy 304.704755 -79.964284)
			(xy 304.716881 -79.909847) (xy 304.736804 -79.857756) (xy 304.7641 -79.809121) (xy 304.798186 -79.764978)
			(xy 304.838335 -79.726269) (xy 304.883693 -79.693818) (xy 304.933293 -79.668317) (xy 304.986077 -79.65031)
			(xy 305.04092 -79.64018) (xy 305.096654 -79.638143) (xy 305.152091 -79.644243) (xy 305.206048 -79.658349)
			(xy 305.257377 -79.680161) (xy 305.304983 -79.709215) (xy 305.347851 -79.74489) (xy 305.385068 -79.786427)
			(xy 305.415841 -79.83294) (xy 305.439513 -79.883437) (xy 305.455581 -79.936844) (xy 305.463701 -79.99202)
			(xy 305.46421 -80.019906) (xy 305.463701 -80.047792) (xy 305.455581 -80.102968) (xy 305.439513 -80.156375)
			(xy 305.415841 -80.206872) (xy 305.385068 -80.253385) (xy 305.347851 -80.294922) (xy 305.304983 -80.330597)
			(xy 305.257377 -80.359651) (xy 305.206048 -80.381463) (xy 305.152091 -80.395569) (xy 305.096654 -80.401669)
			(xy 305.04092 -80.399632) (xy 304.986077 -80.389502) (xy 304.933293 -80.371495) (xy 304.883693 -80.345994)
			(xy 304.838335 -80.313543) (xy 304.798186 -80.274834) (xy 304.7641 -80.230691) (xy 304.736804 -80.182056)
			(xy 304.716881 -80.129965) (xy 304.704755 -80.075528) (xy 304.700684 -80.019906) (xy 303.956956 -80.019906)
			(xy 304.49393 -80.556862) (xy 304.502755 -80.565891) (xy 304.519159 -80.585087) (xy 304.526696 -80.595216)
			(xy 304.54219 -80.61833) (xy 304.547778 -80.624934) (xy 304.842672 -80.919828) (xy 304.858956 -80.936739)
			(xy 304.886956 -80.974421) (xy 304.909197 -81.015764) (xy 304.917602 -81.037684) (xy 304.917602 -81.038954)
			(xy 304.923952 -81.055718) (xy 304.92573 -81.062322) (xy 304.92573 -81.062576) (xy 304.926238 -81.065116)
			(xy 304.927 -81.06791) (xy 304.931584 -81.087463) (xy 304.936429 -81.12733) (xy 304.936652 -81.147412)
			(xy 304.936652 -82.414364) (xy 309.681624 -82.414364) (xy 309.685695 -82.358742) (xy 309.697821 -82.304305)
			(xy 309.717744 -82.252214) (xy 309.74504 -82.203579) (xy 309.779126 -82.159436) (xy 309.819275 -82.120727)
			(xy 309.864633 -82.088276) (xy 309.914233 -82.062775) (xy 309.967017 -82.044768) (xy 310.02186 -82.034638)
			(xy 310.077594 -82.032601) (xy 310.133031 -82.038701) (xy 310.186988 -82.052807) (xy 310.238317 -82.074619)
			(xy 310.285923 -82.103673) (xy 310.328791 -82.139348) (xy 310.366008 -82.180885) (xy 310.396781 -82.227398)
			(xy 310.420453 -82.277895) (xy 310.436521 -82.331302) (xy 310.444641 -82.386478) (xy 310.44515 -82.414364)
			(xy 310.444909 -82.427572) (xy 311.132726 -82.427572) (xy 311.136797 -82.37195) (xy 311.148923 -82.317513)
			(xy 311.168846 -82.265422) (xy 311.196142 -82.216787) (xy 311.230228 -82.172644) (xy 311.270377 -82.133935)
			(xy 311.315735 -82.101484) (xy 311.365335 -82.075983) (xy 311.418119 -82.057976) (xy 311.472962 -82.047846)
			(xy 311.528696 -82.045809) (xy 311.584133 -82.051909) (xy 311.63809 -82.066015) (xy 311.689419 -82.087827)
			(xy 311.737025 -82.116881) (xy 311.779893 -82.152556) (xy 311.81711 -82.194093) (xy 311.847883 -82.240606)
			(xy 311.871555 -82.291103) (xy 311.887623 -82.34451) (xy 311.895743 -82.399686) (xy 311.896252 -82.427572)
			(xy 311.895743 -82.455458) (xy 311.887623 -82.510634) (xy 311.871555 -82.564041) (xy 311.847883 -82.614538)
			(xy 311.81711 -82.661051) (xy 311.779893 -82.702588) (xy 311.737025 -82.738263) (xy 311.689419 -82.767317)
			(xy 311.63809 -82.789129) (xy 311.584133 -82.803235) (xy 311.528696 -82.809335) (xy 311.472962 -82.807298)
			(xy 311.418119 -82.797168) (xy 311.365335 -82.779161) (xy 311.315735 -82.75366) (xy 311.270377 -82.721209)
			(xy 311.230228 -82.6825) (xy 311.196142 -82.638357) (xy 311.168846 -82.589722) (xy 311.148923 -82.537631)
			(xy 311.136797 -82.483194) (xy 311.132726 -82.427572) (xy 310.444909 -82.427572) (xy 310.444641 -82.44225)
			(xy 310.436521 -82.497426) (xy 310.420453 -82.550833) (xy 310.396781 -82.60133) (xy 310.366008 -82.647843)
			(xy 310.328791 -82.68938) (xy 310.285923 -82.725055) (xy 310.238317 -82.754109) (xy 310.186988 -82.775921)
			(xy 310.133031 -82.790027) (xy 310.077594 -82.796127) (xy 310.02186 -82.79409) (xy 309.967017 -82.78396)
			(xy 309.914233 -82.765953) (xy 309.864633 -82.740452) (xy 309.819275 -82.708001) (xy 309.779126 -82.669292)
			(xy 309.74504 -82.625149) (xy 309.717744 -82.576514) (xy 309.697821 -82.524423) (xy 309.685695 -82.469986)
			(xy 309.681624 -82.414364) (xy 304.936652 -82.414364) (xy 304.936652 -84.092288) (xy 308.425086 -84.092288)
			(xy 308.429157 -84.036666) (xy 308.441283 -83.982229) (xy 308.461206 -83.930138) (xy 308.488502 -83.881503)
			(xy 308.522588 -83.83736) (xy 308.562737 -83.798651) (xy 308.608095 -83.7662) (xy 308.657695 -83.740699)
			(xy 308.710479 -83.722692) (xy 308.765322 -83.712562) (xy 308.821056 -83.710525) (xy 308.876493 -83.716625)
			(xy 308.93045 -83.730731) (xy 308.981779 -83.752543) (xy 309.029385 -83.781597) (xy 309.072253 -83.817272)
			(xy 309.10947 -83.858809) (xy 309.140243 -83.905322) (xy 309.163915 -83.955819) (xy 309.179983 -84.009226)
			(xy 309.188103 -84.064402) (xy 309.188612 -84.092288) (xy 309.188103 -84.120174) (xy 309.179983 -84.17535)
			(xy 309.163915 -84.228757) (xy 309.140243 -84.279254) (xy 309.10947 -84.325767) (xy 309.072253 -84.367304)
			(xy 309.029385 -84.402979) (xy 308.981779 -84.432033) (xy 308.93045 -84.453845) (xy 308.876493 -84.467951)
			(xy 308.821056 -84.474051) (xy 308.765322 -84.472014) (xy 308.710479 -84.461884) (xy 308.657695 -84.443877)
			(xy 308.608095 -84.418376) (xy 308.562737 -84.385925) (xy 308.522588 -84.347216) (xy 308.488502 -84.303073)
			(xy 308.461206 -84.254438) (xy 308.441283 -84.202347) (xy 308.429157 -84.14791) (xy 308.425086 -84.092288)
			(xy 304.936652 -84.092288) (xy 304.936652 -84.476336) (xy 311.895234 -84.476336) (xy 311.899305 -84.420714)
			(xy 311.911431 -84.366277) (xy 311.931354 -84.314186) (xy 311.95865 -84.265551) (xy 311.992736 -84.221408)
			(xy 312.032885 -84.182699) (xy 312.078243 -84.150248) (xy 312.127843 -84.124747) (xy 312.180627 -84.10674)
			(xy 312.23547 -84.09661) (xy 312.291204 -84.094573) (xy 312.346641 -84.100673) (xy 312.400598 -84.114779)
			(xy 312.451927 -84.136591) (xy 312.499533 -84.165645) (xy 312.542401 -84.20132) (xy 312.579618 -84.242857)
			(xy 312.610391 -84.28937) (xy 312.634063 -84.339867) (xy 312.650131 -84.393274) (xy 312.658251 -84.44845)
			(xy 312.65876 -84.476336) (xy 312.658251 -84.504222) (xy 312.650131 -84.559398) (xy 312.634063 -84.612805)
			(xy 312.610391 -84.663302) (xy 312.579618 -84.709815) (xy 312.542401 -84.751352) (xy 312.499533 -84.787027)
			(xy 312.451927 -84.816081) (xy 312.400598 -84.837893) (xy 312.346641 -84.851999) (xy 312.291204 -84.858099)
			(xy 312.23547 -84.856062) (xy 312.180627 -84.845932) (xy 312.127843 -84.827925) (xy 312.078243 -84.802424)
			(xy 312.032885 -84.769973) (xy 311.992736 -84.731264) (xy 311.95865 -84.687121) (xy 311.931354 -84.638486)
			(xy 311.911431 -84.586395) (xy 311.899305 -84.531958) (xy 311.895234 -84.476336) (xy 304.936652 -84.476336)
			(xy 304.936652 -86.247986) (xy 307.43855 -86.247986) (xy 307.442621 -86.192364) (xy 307.454747 -86.137927)
			(xy 307.47467 -86.085836) (xy 307.501966 -86.037201) (xy 307.536052 -85.993058) (xy 307.576201 -85.954349)
			(xy 307.621559 -85.921898) (xy 307.671159 -85.896397) (xy 307.723943 -85.87839) (xy 307.778786 -85.86826)
			(xy 307.83452 -85.866223) (xy 307.889957 -85.872323) (xy 307.943914 -85.886429) (xy 307.995243 -85.908241)
			(xy 308.042849 -85.937295) (xy 308.085717 -85.97297) (xy 308.122934 -86.014507) (xy 308.153707 -86.06102)
			(xy 308.177379 -86.111517) (xy 308.193447 -86.164924) (xy 308.201567 -86.2201) (xy 308.202076 -86.247986)
			(xy 308.201567 -86.275872) (xy 308.193447 -86.331048) (xy 308.177379 -86.384455) (xy 308.153707 -86.434952)
			(xy 308.122934 -86.481465) (xy 308.085717 -86.523002) (xy 308.042849 -86.558677) (xy 307.995243 -86.587731)
			(xy 307.943914 -86.609543) (xy 307.889957 -86.623649) (xy 307.83452 -86.629749) (xy 307.778786 -86.627712)
			(xy 307.723943 -86.617582) (xy 307.671159 -86.599575) (xy 307.621559 -86.574074) (xy 307.576201 -86.541623)
			(xy 307.536052 -86.502914) (xy 307.501966 -86.458771) (xy 307.47467 -86.410136) (xy 307.454747 -86.358045)
			(xy 307.442621 -86.303608) (xy 307.43855 -86.247986) (xy 304.936652 -86.247986) (xy 304.936652 -88.068912)
			(xy 304.937668 -88.07831) (xy 304.937668 -88.078818) (xy 304.939376 -88.085976) (xy 304.946212 -88.098999)
			(xy 304.95113 -88.104472) (xy 305.22267 -88.375998) (xy 312.02325 -88.375998) (xy 312.027321 -88.320376)
			(xy 312.039447 -88.265939) (xy 312.05937 -88.213848) (xy 312.086666 -88.165213) (xy 312.120752 -88.12107)
			(xy 312.160901 -88.082361) (xy 312.206259 -88.04991) (xy 312.255859 -88.024409) (xy 312.308643 -88.006402)
			(xy 312.363486 -87.996272) (xy 312.41922 -87.994235) (xy 312.474657 -88.000335) (xy 312.528614 -88.014441)
			(xy 312.579943 -88.036253) (xy 312.627549 -88.065307) (xy 312.670417 -88.100982) (xy 312.707634 -88.142519)
			(xy 312.738407 -88.189032) (xy 312.762079 -88.239529) (xy 312.778147 -88.292936) (xy 312.786267 -88.348112)
			(xy 312.786776 -88.375998) (xy 312.786414 -88.39581) (xy 313.457588 -88.39581) (xy 313.461659 -88.340188)
			(xy 313.473785 -88.285751) (xy 313.493708 -88.23366) (xy 313.521004 -88.185025) (xy 313.55509 -88.140882)
			(xy 313.595239 -88.102173) (xy 313.640597 -88.069722) (xy 313.690197 -88.044221) (xy 313.742981 -88.026214)
			(xy 313.797824 -88.016084) (xy 313.853558 -88.014047) (xy 313.908995 -88.020147) (xy 313.962952 -88.034253)
			(xy 314.014281 -88.056065) (xy 314.061887 -88.085119) (xy 314.104755 -88.120794) (xy 314.141972 -88.162331)
			(xy 314.172745 -88.208844) (xy 314.196417 -88.259341) (xy 314.212485 -88.312748) (xy 314.220605 -88.367924)
			(xy 314.221114 -88.39581) (xy 314.220605 -88.423696) (xy 314.212485 -88.478872) (xy 314.196417 -88.532279)
			(xy 314.172745 -88.582776) (xy 314.141972 -88.629289) (xy 314.104755 -88.670826) (xy 314.061887 -88.706501)
			(xy 314.014281 -88.735555) (xy 313.962952 -88.757367) (xy 313.908995 -88.771473) (xy 313.853558 -88.777573)
			(xy 313.797824 -88.775536) (xy 313.742981 -88.765406) (xy 313.690197 -88.747399) (xy 313.640597 -88.721898)
			(xy 313.595239 -88.689447) (xy 313.55509 -88.650738) (xy 313.521004 -88.606595) (xy 313.493708 -88.55796)
			(xy 313.473785 -88.505869) (xy 313.461659 -88.451432) (xy 313.457588 -88.39581) (xy 312.786414 -88.39581)
			(xy 312.786267 -88.403884) (xy 312.778147 -88.45906) (xy 312.762079 -88.512467) (xy 312.738407 -88.562964)
			(xy 312.707634 -88.609477) (xy 312.670417 -88.651014) (xy 312.627549 -88.686689) (xy 312.579943 -88.715743)
			(xy 312.528614 -88.737555) (xy 312.474657 -88.751661) (xy 312.41922 -88.757761) (xy 312.363486 -88.755724)
			(xy 312.308643 -88.745594) (xy 312.255859 -88.727587) (xy 312.206259 -88.702086) (xy 312.160901 -88.669635)
			(xy 312.120752 -88.630926) (xy 312.086666 -88.586783) (xy 312.05937 -88.538148) (xy 312.039447 -88.486057)
			(xy 312.027321 -88.43162) (xy 312.02325 -88.375998) (xy 305.22267 -88.375998) (xy 306.628122 -89.78138)
			(xy 312.420506 -89.78138) (xy 312.424577 -89.725758) (xy 312.436703 -89.671321) (xy 312.456626 -89.61923)
			(xy 312.483922 -89.570595) (xy 312.518008 -89.526452) (xy 312.558157 -89.487743) (xy 312.603515 -89.455292)
			(xy 312.653115 -89.429791) (xy 312.705899 -89.411784) (xy 312.760742 -89.401654) (xy 312.816476 -89.399617)
			(xy 312.871913 -89.405717) (xy 312.92587 -89.419823) (xy 312.977199 -89.441635) (xy 313.024805 -89.470689)
			(xy 313.067673 -89.506364) (xy 313.10489 -89.547901) (xy 313.135663 -89.594414) (xy 313.159335 -89.644911)
			(xy 313.175403 -89.698318) (xy 313.183523 -89.753494) (xy 313.184032 -89.78138) (xy 313.183523 -89.809266)
			(xy 313.175403 -89.864442) (xy 313.159335 -89.917849) (xy 313.135663 -89.968346) (xy 313.10489 -90.014859)
			(xy 313.067673 -90.056396) (xy 313.024805 -90.092071) (xy 312.977199 -90.121125) (xy 312.92587 -90.142937)
			(xy 312.871913 -90.157043) (xy 312.816476 -90.163143) (xy 312.760742 -90.161106) (xy 312.705899 -90.150976)
			(xy 312.653115 -90.132969) (xy 312.603515 -90.107468) (xy 312.558157 -90.075017) (xy 312.518008 -90.036308)
			(xy 312.483922 -89.992165) (xy 312.456626 -89.94353) (xy 312.436703 -89.891439) (xy 312.424577 -89.837002)
			(xy 312.420506 -89.78138) (xy 306.628122 -89.78138) (xy 310.042814 -93.195902) (xy 310.060369 -93.214117)
			(xy 310.090108 -93.25504) (xy 310.113074 -93.300114) (xy 310.128702 -93.348227) (xy 310.136607 -93.398192)
			(xy 310.137048 -93.423486) (xy 310.137048 -93.502226) (xy 310.137416 -93.51127) (xy 310.143703 -93.52823)
			(xy 310.155487 -93.541953) (xy 310.16321 -93.546676) (xy 310.171084 -93.55074) (xy 310.195976 -93.559122)
			(xy 310.206988 -93.561476) (xy 310.22913 -93.557521) (xy 310.238648 -93.551502) (xy 310.249062 -93.543374)
			(xy 310.25211 -93.539818) (xy 310.270338 -93.519526) (xy 310.31156 -93.483808) (xy 310.357445 -93.454318)
			(xy 310.407059 -93.431657) (xy 310.459393 -93.416287) (xy 310.513382 -93.408519) (xy 310.540654 -93.407992)
			(xy 310.540908 -93.407992) (xy 310.571896 -93.409262) (xy 310.585612 -93.410786) (xy 310.611782 -93.414358)
			(xy 310.662867 -93.427778) (xy 310.711619 -93.448103) (xy 310.757108 -93.474946) (xy 310.798469 -93.507794)
			(xy 310.817006 -93.52661) (xy 310.829976 -93.540549) (xy 310.853387 -93.570577) (xy 310.863742 -93.586554)
			(xy 310.870854 -93.595444) (xy 310.876188 -93.600778) (xy 310.883153 -93.607095) (xy 310.900352 -93.614657)
			(xy 310.909716 -93.61551) (xy 310.927496 -93.616272) (xy 310.99125 -93.619066) (xy 311.001819 -93.619024)
			(xy 311.021515 -93.611425) (xy 311.02935 -93.604334) (xy 311.03443 -93.599254) (xy 311.036208 -93.596968)
			(xy 311.037732 -93.594936) (xy 311.039764 -93.59265) (xy 311.039764 -93.592396) (xy 311.057043 -93.570783)
			(xy 311.096795 -93.532291) (xy 311.141686 -93.49994) (xy 311.166002 -93.486732) (xy 311.184787 -93.477308)
			(xy 311.223993 -93.462163) (xy 311.244234 -93.456506) (xy 311.261302 -93.452173) (xy 311.29603 -93.446319)
			(xy 311.313576 -93.444822) (xy 311.31383 -93.444822) (xy 311.341516 -93.443806) (xy 311.34177 -93.443806)
			(xy 311.371789 -93.444349) (xy 311.43109 -93.453719) (xy 311.488191 -93.472265) (xy 311.541681 -93.499527)
			(xy 311.566306 -93.516704) (xy 311.572402 -93.521276) (xy 311.597294 -93.529912) (xy 311.610248 -93.530928)
			(xy 311.616598 -93.529912) (xy 311.683908 -93.518736) (xy 311.693814 -93.51518) (xy 311.704736 -93.498416)
			(xy 311.722711 -93.471354) (xy 311.763748 -93.420986) (xy 311.810108 -93.37547) (xy 311.861221 -93.335364)
			(xy 311.916459 -93.301162) (xy 311.975143 -93.273285) (xy 312.036553 -93.252074) (xy 312.099932 -93.23779)
			(xy 312.164503 -93.230608) (xy 312.196988 -93.230192) (xy 312.237789 -93.230919) (xy 312.318599 -93.242267)
			(xy 312.358024 -93.252798) (xy 312.393611 -93.263553) (xy 312.461945 -93.292835) (xy 312.526027 -93.330524)
			(xy 312.584828 -93.376015) (xy 312.611516 -93.401896) (xy 312.617358 -93.407992) (xy 312.621422 -93.412056)
			(xy 312.64432 -93.43562) (xy 312.685275 -93.487003) (xy 312.720224 -93.542645) (xy 312.748727 -93.601849)
			(xy 312.770428 -93.663869) (xy 312.785052 -93.727929) (xy 312.792418 -93.793222) (xy 312.792872 -93.826076)
			(xy 312.792872 -114.673888) (xy 312.793126 -114.67846) (xy 312.794174 -114.686946) (xy 312.801185 -114.702528)
			(xy 312.806842 -114.70894) (xy 313.000898 -114.902742) (xy 313.026298 -114.928142) (xy 313.030092 -114.928647)
			(xy 313.037744 -114.928647) (xy 313.041538 -114.928142) (xy 313.717178 -114.757454) (xy 314.348114 -114.598196)
			(xy 314.358884 -114.594864) (xy 314.376266 -114.58055) (xy 314.38586 -114.560179) (xy 314.386468 -114.54892)
			(xy 314.386468 -84.9122) (xy 314.384944 -84.900262) (xy 314.383117 -84.893587) (xy 314.376414 -84.881487)
			(xy 314.371736 -84.876386) (xy 312.303414 -82.808318) (xy 312.292746 -82.801968) (xy 312.286904 -82.80019)
			(xy 312.261335 -82.791744) (xy 312.212681 -82.768669) (xy 312.167753 -82.738986) (xy 312.127443 -82.703284)
			(xy 312.092549 -82.662271) (xy 312.063765 -82.616762) (xy 312.041661 -82.567659) (xy 312.026677 -82.515938)
			(xy 312.01911 -82.462624) (xy 312.01868 -82.4357) (xy 312.019144 -82.409162) (xy 312.026513 -82.356598)
			(xy 312.041095 -82.305564) (xy 312.062609 -82.257042) (xy 312.090639 -82.21197) (xy 312.124645 -82.171217)
			(xy 312.16397 -82.13557) (xy 312.207856 -82.105717) (xy 312.255455 -82.082233) (xy 312.305849 -82.065572)
			(xy 312.331862 -82.060288) (xy 312.340752 -82.058764) (xy 312.364628 -82.045048) (xy 312.374534 -82.037174)
			(xy 312.37936 -82.032094) (xy 312.383932 -82.02676) (xy 312.383932 -81.502504) (xy 312.38409 -81.483206)
			(xy 312.386635 -81.444694) (xy 312.389012 -81.425542) (xy 312.391298 -81.409794) (xy 312.391806 -81.407254)
			(xy 312.39206 -81.405222) (xy 312.39206 -80.508856) (xy 312.393076 -80.475582) (xy 312.393076 -80.475074)
			(xy 312.394346 -80.459072) (xy 312.394346 -80.458818) (xy 312.396124 -80.43672) (xy 312.389266 -80.42783)
			(xy 312.377328 -80.416654) (xy 312.37682 -80.416146) (xy 312.326528 -80.369918) (xy 312.319271 -80.364639)
			(xy 312.302229 -80.359053) (xy 312.293254 -80.358996) (xy 312.291476 -80.358996) (xy 312.28792 -80.35925)
			(xy 312.286142 -80.359504) (xy 312.284618 -80.359758) (xy 312.271984 -80.361451) (xy 312.246563 -80.363357)
			(xy 312.233818 -80.363568) (xy 312.228738 -80.363568) (xy 312.201067 -80.362977) (xy 312.146331 -80.354787)
			(xy 312.093351 -80.338778) (xy 312.043239 -80.315285) (xy 311.997046 -80.2848) (xy 311.955741 -80.247962)
			(xy 311.920189 -80.205546) (xy 311.891136 -80.158438) (xy 311.869192 -80.107629) (xy 311.854817 -80.054183)
			(xy 311.85104 -80.026764) (xy 311.850278 -80.019652) (xy 311.8485 -79.98206) (xy 311.849019 -79.953386)
			(xy 311.857606 -79.896683) (xy 311.874582 -79.841905) (xy 311.899564 -79.790283) (xy 311.93199 -79.742981)
			(xy 311.971129 -79.701064) (xy 311.99328 -79.682848) (xy 311.99582 -79.680816) (xy 311.99963 -79.677006)
			(xy 312.003379 -79.673018) (xy 312.009265 -79.663793) (xy 312.011314 -79.658718) (xy 312.015124 -79.648812)
			(xy 312.014362 -79.637636) (xy 312.008774 -79.55407) (xy 312.007762 -79.544882) (xy 312.000065 -79.528092)
			(xy 311.993788 -79.521304) (xy 311.9882 -79.51597) (xy 311.98312 -79.512922) (xy 311.982866 -79.512668)
			(xy 311.958334 -79.497966) (xy 311.913575 -79.462367) (xy 311.874631 -79.420486) (xy 311.842376 -79.37326)
			(xy 311.817531 -79.321748) (xy 311.800654 -79.267105) (xy 311.792123 -79.210555) (xy 311.791604 -79.18196)
			(xy 311.79209 -79.154709) (xy 311.799846 -79.100761) (xy 311.815201 -79.048466) (xy 311.837843 -78.998889)
			(xy 311.867309 -78.953039) (xy 311.903 -78.911848) (xy 311.944191 -78.876157) (xy 311.990041 -78.846691)
			(xy 312.039618 -78.824049) (xy 312.091913 -78.808694) (xy 312.145861 -78.800938) (xy 312.200363 -78.800938)
			(xy 312.254311 -78.808694) (xy 312.306606 -78.824049) (xy 312.356183 -78.846691) (xy 312.402033 -78.876157)
			(xy 312.443224 -78.911848) (xy 312.478915 -78.953039) (xy 312.508381 -78.998889) (xy 312.531023 -79.048466)
			(xy 312.546378 -79.100761) (xy 312.554134 -79.154709) (xy 312.55462 -79.18196) (xy 312.5541 -79.210634)
			(xy 312.54551 -79.267335) (xy 312.528532 -79.322112) (xy 312.50355 -79.373732) (xy 312.471124 -79.421033)
			(xy 312.431986 -79.46295) (xy 312.40984 -79.481172) (xy 312.4073 -79.483204) (xy 312.40349 -79.487014)
			(xy 312.399735 -79.490998) (xy 312.393833 -79.500217) (xy 312.391806 -79.505302) (xy 312.387996 -79.515208)
			(xy 312.388758 -79.526384) (xy 312.391806 -79.57185) (xy 312.391806 -79.572358) (xy 312.393838 -79.60106)
			(xy 312.39461 -79.605373) (xy 312.397426 -79.613671) (xy 312.399426 -79.61757) (xy 312.414158 -79.641192)
			(xy 312.419492 -79.647796) (xy 312.424572 -79.652876) (xy 312.426604 -79.654146) (xy 312.429906 -79.656178)
			(xy 312.451947 -79.670326) (xy 312.492295 -79.70372) (xy 312.527691 -79.742323) (xy 312.542936 -79.76362)
			(xy 312.543698 -79.76489) (xy 312.551064 -79.775304) (xy 312.555636 -79.783178) (xy 312.567439 -79.803116)
			(xy 312.586671 -79.845269) (xy 312.59399 -79.867252) (xy 312.602372 -79.898748) (xy 312.604912 -79.908908)
			(xy 312.626502 -79.938118) (xy 312.630566 -79.941674) (xy 312.636154 -79.946754) (xy 312.70194 -79.981298)
			(xy 312.713624 -79.985362) (xy 312.734452 -79.975964) (xy 312.755595 -79.966535) (xy 312.799081 -79.950645)
			(xy 312.82132 -79.944214) (xy 312.859738 -79.93431) (xy 312.938368 -79.923735) (xy 312.978038 -79.923132)
			(xy 313.014114 -79.923671) (xy 313.085724 -79.932505) (xy 313.155705 -79.950073) (xy 313.222996 -79.976107)
			(xy 313.286579 -80.010214) (xy 313.316366 -80.030574) (xy 313.319668 -80.03032) (xy 313.343857 -80.013089)
			(xy 313.39511 -79.983076) (xy 313.449141 -79.958414) (xy 313.477148 -79.948532) (xy 313.507578 -79.938674)
			(xy 313.570039 -79.924868) (xy 313.633632 -79.917947) (xy 313.665616 -79.917544) (xy 313.69849 -79.917972)
			(xy 313.763827 -79.925305) (xy 313.827931 -79.939911) (xy 313.889996 -79.961605) (xy 313.949241 -79.990114)
			(xy 314.004919 -80.025081) (xy 314.05633 -80.066064) (xy 314.07989 -80.088994) (xy 314.274454 -80.283558)
			(xy 314.287662 -80.283812) (xy 314.293758 -80.28305) (xy 314.311792 -80.277716) (xy 314.320174 -80.272128)
			(xy 314.329572 -80.266286) (xy 314.351901 -80.253362) (xy 314.399296 -80.232978) (xy 314.449003 -80.219156)
			(xy 314.500118 -80.212149) (xy 314.525914 -80.211676) (xy 314.530994 -80.211676) (xy 314.557964 -80.212466)
			(xy 314.611285 -80.220705) (xy 314.662915 -80.23637) (xy 314.711825 -80.259148) (xy 314.757041 -80.288586)
			(xy 314.797661 -80.324097) (xy 314.832877 -80.364974) (xy 314.861987 -80.410402) (xy 314.88441 -80.459476)
			(xy 314.892436 -80.485234) (xy 314.894468 -80.491838) (xy 315.268102 -80.865472) (xy 316.027308 -81.624932)
			(xy 316.03477 -81.63151) (xy 316.053215 -81.638906) (xy 316.073087 -81.638767) (xy 316.082426 -81.635346)
			(xy 316.109858 -81.623916) (xy 316.113668 -81.618328) (xy 316.113668 -72.22998) (xy 316.113604 -72.226374)
			(xy 316.112583 -72.219236) (xy 316.111636 -72.215756) (xy 316.110112 -72.211184) (xy 316.106302 -72.20204)
			(xy 310.10352 -66.199004) (xy 310.100669 -66.196298) (xy 310.09429 -66.191706) (xy 310.09082 -66.18986)
			(xy 310.085393 -66.187279) (xy 310.073713 -66.18446) (xy 310.067706 -66.184272) (xy 305.476148 -66.184272)
			(xy 305.448695 -66.183845) (xy 305.394548 -66.174773) (xy 305.368452 -66.166238) (xy 305.368198 -66.165984)
			(xy 305.367436 -66.16573) (xy 305.365658 -66.164968) (xy 305.364896 -66.164714) (xy 305.36261 -66.163698)
			(xy 305.344576 -66.156332) (xy 305.249072 -66.089784) (xy 305.242214 -66.083942) (xy 305.098704 -65.940432)
			(xy 305.093624 -65.937384) (xy 305.077693 -65.92714) (xy 305.04803 -65.903588) (xy 305.034442 -65.890394)
			(xy 304.617628 -65.47358) (xy 304.60696 -65.46723) (xy 304.601118 -65.465452) (xy 304.573681 -65.456334)
			(xy 304.521716 -65.430992) (xy 304.474163 -65.398109) (xy 304.432108 -65.358435) (xy 304.396513 -65.312877)
			(xy 304.368189 -65.262475) (xy 304.347785 -65.20838) (xy 304.341276 -65.18021) (xy 304.335612 -65.150847)
			(xy 304.332415 -65.091136) (xy 304.334926 -65.061338) (xy 304.335942 -65.05067) (xy 304.332894 -65.040764)
			(xy 304.331458 -65.036606) (xy 304.327369 -65.028817) (xy 304.324766 -65.02527) (xy 304.278538 -64.9732)
			(xy 304.270918 -64.964564) (xy 304.266642 -64.960344) (xy 304.256498 -64.953915) (xy 304.250852 -64.951864)
			(xy 304.240184 -64.948816) (xy 303.714912 -64.948816) (xy 303.711306 -64.948878) (xy 303.704166 -64.949895)
			(xy 303.700688 -64.950848) (xy 303.696116 -64.952372) (xy 303.686972 -64.956182) (xy 302.904398 -65.73901)
			(xy 302.887682 -65.75514) (xy 302.850445 -65.782908) (xy 302.809599 -65.805029) (xy 302.765996 -65.821041)
			(xy 302.720542 -65.830613) (xy 302.697388 -65.832482) (xy 302.69307 -65.83299) (xy 302.679109 -65.836416)
			(xy 302.650747 -65.84112) (xy 302.636428 -65.842388) (xy 302.610774 -65.843404) (xy 299.16882 -65.843404)
			(xy 299.162667 -65.843575) (xy 299.150721 -65.846529) (xy 299.145198 -65.849246) (xy 299.117638 -65.862983)
			(xy 299.05922 -65.882449) (xy 298.99844 -65.892313) (xy 298.967652 -65.892934) (xy 298.96689 -65.892934)
			(xy 298.939637 -65.892447) (xy 298.885687 -65.884689) (xy 298.83339 -65.869332) (xy 298.783811 -65.846689)
			(xy 298.737958 -65.81722) (xy 298.696766 -65.781526) (xy 298.661074 -65.740334) (xy 298.631606 -65.694481)
			(xy 298.608964 -65.644901) (xy 298.593609 -65.592603) (xy 298.585852 -65.538653) (xy 298.585852 -65.484147)
			(xy 298.593609 -65.430197) (xy 298.608964 -65.377899) (xy 298.631606 -65.328319) (xy 298.661074 -65.282466)
			(xy 298.696766 -65.241274) (xy 298.737958 -65.20558) (xy 298.783811 -65.176111) (xy 298.83339 -65.153468)
			(xy 298.885687 -65.138111) (xy 298.939637 -65.130353) (xy 298.96689 -65.129918) (xy 298.967906 -65.129918)
			(xy 298.998657 -65.130498) (xy 299.059362 -65.140356) (xy 299.117698 -65.159833) (xy 299.145198 -65.173606)
			(xy 299.15073 -65.1763) (xy 299.16267 -65.17925) (xy 299.16882 -65.179448) (xy 302.452278 -65.179448)
			(xy 302.46193 -65.178432) (xy 302.469175 -65.176806) (xy 302.482344 -65.169965) (xy 302.487838 -65.16497)
			(xy 303.289462 -64.363346) (xy 303.305895 -64.347458) (xy 303.342348 -64.31988) (xy 303.382236 -64.297558)
			(xy 303.424808 -64.280914) (xy 303.446942 -64.275208) (xy 303.447196 -64.275208) (xy 303.454308 -64.27343)
			(xy 303.459896 -64.270382) (xy 303.463008 -64.268582) (xy 303.468742 -64.264245) (xy 303.471326 -64.261746)
			(xy 303.996598 -63.736474) (xy 303.99736 -63.735458) (xy 304.017519 -63.715278) (xy 304.063592 -63.68166)
			(xy 304.114864 -63.656679) (xy 304.14214 -63.648336) (xy 304.144934 -63.647828) (xy 304.147728 -63.647066)
			(xy 304.167807 -63.642056) (xy 304.208826 -63.636583) (xy 304.229516 -63.636144) (xy 306.368196 -63.636144)
			(xy 306.375346 -63.635757) (xy 306.389009 -63.631495) (xy 306.39512 -63.627762) (xy 306.401978 -63.622936)
			(xy 306.40655 -63.618872) (xy 306.41107 -63.614056) (xy 306.417635 -63.602601) (xy 306.419504 -63.596266)
			(xy 306.42306 -63.583312) (xy 306.427378 -63.572898) (xy 306.43195 -63.56096) (xy 306.433714 -63.556818)
			(xy 306.438443 -63.549159) (xy 306.441348 -63.54572) (xy 306.442364 -63.54445) (xy 306.446674 -63.539)
			(xy 306.452464 -63.526378) (xy 306.453794 -63.519558) (xy 306.45481 -63.5127) (xy 306.454048 -63.505842)
			(xy 306.453498 -63.502169) (xy 306.451451 -63.49503) (xy 306.449984 -63.491618) (xy 306.441348 -63.472314)
			(xy 306.441348 -63.471806) (xy 306.436776 -63.461392) (xy 306.430172 -63.454534) (xy 306.429918 -63.45428)
			(xy 306.42941 -63.453772) (xy 306.409179 -63.432375) (xy 306.374884 -63.384508) (xy 306.348348 -63.331941)
			(xy 306.330202 -63.275923) (xy 306.320876 -63.217781) (xy 306.32019 -63.188342) (xy 306.32019 -63.180214)
			(xy 306.32119 -63.151262) (xy 306.330861 -63.094148) (xy 306.349057 -63.039152) (xy 306.375358 -62.98754)
			(xy 306.409161 -62.940498) (xy 306.449688 -62.899107) (xy 306.496007 -62.86432) (xy 306.547054 -62.836937)
			(xy 306.601654 -62.817586) (xy 306.658552 -62.806713) (xy 306.687474 -62.805056) (xy 306.687728 -62.805056)
			(xy 306.701698 -62.804802) (xy 306.702206 -62.804802) (xy 306.727832 -62.805233) (xy 306.778617 -62.812133)
			(xy 306.828018 -62.825781) (xy 306.875143 -62.84593) (xy 306.919141 -62.872216) (xy 306.939442 -62.88786)
			(xy 306.946046 -62.89294) (xy 306.957222 -62.89675) (xy 306.970684 -62.898782) (xy 306.992528 -62.898782)
			(xy 306.996133 -62.898847) (xy 307.003272 -62.89987) (xy 307.006752 -62.900814) (xy 307.010308 -62.901576)
			(xy 307.064156 -62.901576) (xy 307.07276 -62.901242) (xy 307.088991 -62.89553) (xy 307.095906 -62.8904)
			(xy 307.09616 -62.890146) (xy 307.096922 -62.889638) (xy 307.101494 -62.886082) (xy 307.104034 -62.88405)
			(xy 307.104796 -62.883288) (xy 307.11648 -62.874906) (xy 307.116988 -62.874398) (xy 307.12664 -62.867794)
			(xy 307.127148 -62.867286) (xy 307.146473 -62.855008) (xy 307.18748 -62.834638) (xy 307.208936 -62.826646)
			(xy 307.209698 -62.826392) (xy 307.213508 -62.825122) (xy 307.23481 -62.818181) (xy 307.278612 -62.808759)
			(xy 307.300884 -62.806326) (xy 307.301392 -62.806326) (xy 307.31587 -62.80531) (xy 307.316632 -62.80531)
			(xy 307.320442 -62.805056) (xy 307.337206 -62.804294) (xy 307.349652 -62.805056) (xy 307.380017 -62.806681)
			(xy 307.439688 -62.818365) (xy 307.496749 -62.839373) (xy 307.549751 -62.86917) (xy 307.573934 -62.887606)
			(xy 307.574188 -62.88786) (xy 307.577236 -62.8904) (xy 307.583345 -62.894137) (xy 307.597009 -62.898401)
			(xy 307.60416 -62.898782) (xy 307.627528 -62.898782) (xy 307.632968 -62.898924) (xy 307.6436 -62.90123)
			(xy 307.64861 -62.903354) (xy 307.662326 -62.909704) (xy 307.667029 -62.911774) (xy 307.677009 -62.914215)
			(xy 307.682138 -62.91453) (xy 307.690774 -62.914022) (xy 307.698061 -62.91274) (xy 307.711487 -62.906543)
			(xy 307.71719 -62.90183) (xy 307.717444 -62.901576) (xy 307.738513 -62.883466) (xy 307.784906 -62.8529)
			(xy 307.835238 -62.82938) (xy 307.888448 -62.813403) (xy 307.943412 -62.805307) (xy 307.97119 -62.804802)
			(xy 307.971698 -62.804802) (xy 307.998951 -62.805265) (xy 308.052901 -62.813022) (xy 308.105199 -62.828378)
			(xy 308.154779 -62.85102) (xy 308.200631 -62.880489) (xy 308.241823 -62.916182) (xy 308.277516 -62.957375)
			(xy 308.306983 -63.003228) (xy 308.329625 -63.052809) (xy 308.34498 -63.105107) (xy 308.352735 -63.159057)
			(xy 308.353206 -63.18631) (xy 308.352636 -63.216037) (xy 308.343409 -63.27477) (xy 308.325181 -63.331361)
			(xy 308.298392 -63.384437) (xy 308.263692 -63.432714) (xy 308.243224 -63.45428) (xy 308.24297 -63.454534)
			(xy 308.236874 -63.460884) (xy 308.228238 -63.479426) (xy 308.227476 -63.48222) (xy 308.223666 -63.499238)
			(xy 308.22298 -63.505124) (xy 308.22401 -63.516926) (xy 308.225698 -63.522606) (xy 308.244748 -63.569342)
			(xy 308.244748 -63.56985) (xy 308.260242 -63.606934) (xy 308.2671 -63.617856) (xy 308.274707 -63.626103)
			(xy 308.295009 -63.63559) (xy 308.306216 -63.636144) (xy 309.501032 -63.636144) (xy 309.509105 -63.634851)
			(xy 309.523871 -63.627853) (xy 309.529988 -63.622428) (xy 309.607204 -63.545212) (xy 309.611776 -63.539878)
			(xy 309.611776 -58.181494) (xy 309.611614 -58.175483) (xy 309.608798 -58.163797) (xy 309.606188 -58.15838)
			(xy 309.604348 -58.154906) (xy 309.599754 -58.148528) (xy 309.597044 -58.14568) (xy 309.274972 -57.823608)
			(xy 309.259519 -57.807639) (xy 309.232702 -57.772207) (xy 309.211012 -57.733424) (xy 309.202582 -57.712864)
			(xy 309.19674 -57.701942) (xy 309.195724 -57.700418) (xy 309.180088 -57.678707) (xy 309.15523 -57.631332)
			(xy 309.138291 -57.580585) (xy 309.129708 -57.527778) (xy 309.129176 -57.501028) (xy 309.129176 -56.577992)
			(xy 309.125102 -56.572855) (xy 309.114807 -56.564742) (xy 309.108856 -56.56199) (xy 309.0164 -56.528208)
			(xy 309.009026 -56.525742) (xy 308.993505 -56.52497) (xy 308.98592 -56.526684) (xy 308.978554 -56.528716)
			(xy 308.965346 -56.537098) (xy 308.960266 -56.543194) (xy 308.942011 -56.564014) (xy 308.900527 -56.600686)
			(xy 308.854186 -56.63099) (xy 308.803959 -56.654291) (xy 308.750895 -56.670103) (xy 308.696105 -56.678093)
			(xy 308.66842 -56.678576) (xy 308.641168 -56.678114) (xy 308.58722 -56.67036) (xy 308.534924 -56.655007)
			(xy 308.485346 -56.632368) (xy 308.439494 -56.602903) (xy 308.398302 -56.567212) (xy 308.362609 -56.526022)
			(xy 308.333142 -56.480172) (xy 308.3105 -56.430595) (xy 308.295144 -56.3783) (xy 308.287387 -56.324351)
			(xy 308.287387 -56.269849) (xy 308.295144 -56.2159) (xy 308.3105 -56.163605) (xy 308.333142 -56.114028)
			(xy 308.362609 -56.068178) (xy 308.398302 -56.026988) (xy 308.439494 -55.991297) (xy 308.485346 -55.961832)
			(xy 308.534924 -55.939193) (xy 308.58722 -55.92384) (xy 308.641168 -55.916086) (xy 308.66842 -55.91556)
			(xy 308.695396 -55.916026) (xy 308.748812 -55.923619) (xy 308.800628 -55.938652) (xy 308.849814 -55.960826)
			(xy 308.895391 -55.989699) (xy 308.936452 -56.024698) (xy 308.954678 -56.044592) (xy 308.96052 -56.051196)
			(xy 308.976268 -56.06161) (xy 308.98551 -56.0663) (xy 309.006082 -56.068656) (xy 309.016146 -56.066182)
			(xy 309.072788 -56.045608) (xy 309.106062 -56.033416) (xy 309.112862 -56.030663) (xy 309.124602 -56.021879)
			(xy 309.129176 -56.016144) (xy 309.129176 -55.113428) (xy 309.12966 -55.08734) (xy 309.137824 -55.035807)
			(xy 309.153954 -54.986187) (xy 309.177653 -54.939704) (xy 309.208337 -54.897505) (xy 309.226458 -54.878732)
			(xy 311.150508 -52.954682) (xy 311.156858 -52.944014) (xy 311.158636 -52.938172) (xy 311.167071 -52.912592)
			(xy 311.190129 -52.863915) (xy 311.219801 -52.818964) (xy 311.255498 -52.77863) (xy 311.296511 -52.743716)
			(xy 311.342025 -52.714913) (xy 311.391136 -52.692796) (xy 311.442868 -52.677802) (xy 311.496195 -52.67023)
			(xy 311.550057 -52.67023) (xy 311.603384 -52.677802) (xy 311.655116 -52.692796) (xy 311.704227 -52.714913)
			(xy 311.749741 -52.743716) (xy 311.790754 -52.77863) (xy 311.826451 -52.818964) (xy 311.856123 -52.863915)
			(xy 311.879181 -52.912592) (xy 311.887616 -52.938172) (xy 311.889394 -52.944014) (xy 311.895744 -52.954682)
			(xy 312.32475 -53.383688) (xy 312.337961 -53.397261) (xy 312.361519 -53.426924) (xy 312.37174 -53.44287)
			(xy 312.374788 -53.44795) (xy 312.423389 -53.496551) (xy 316.333364 -53.496551) (xy 316.333364 -53.442049)
			(xy 316.34112 -53.388101) (xy 316.356475 -53.335806) (xy 316.379115 -53.286228) (xy 316.40858 -53.240377)
			(xy 316.444271 -53.199186) (xy 316.48546 -53.163493) (xy 316.531309 -53.134025) (xy 316.580885 -53.111382)
			(xy 316.633179 -53.096025) (xy 316.687127 -53.088265) (xy 316.714378 -53.087778) (xy 316.741749 -53.088238)
			(xy 316.795929 -53.096054) (xy 316.848433 -53.111544) (xy 316.89818 -53.134387) (xy 316.944145 -53.164115)
			(xy 316.965076 -53.181758) (xy 316.96533 -53.182012) (xy 316.972431 -53.187577) (xy 316.989337 -53.193836)
			(xy 316.99835 -53.194204) (xy 317.065406 -53.194204) (xy 317.074423 -53.193849) (xy 317.09134 -53.1876)
			(xy 317.098426 -53.182012) (xy 317.098426 -53.181758) (xy 317.09868 -53.181758) (xy 317.119603 -53.164108)
			(xy 317.165579 -53.134399) (xy 317.215329 -53.111566) (xy 317.267831 -53.096077) (xy 317.322008 -53.088251)
			(xy 317.349378 -53.087778) (xy 317.376631 -53.088268) (xy 317.430582 -53.096022) (xy 317.482881 -53.111376)
			(xy 317.532462 -53.134016) (xy 317.578316 -53.163482) (xy 317.61951 -53.199175) (xy 317.655205 -53.240366)
			(xy 317.684674 -53.286219) (xy 317.707317 -53.335799) (xy 317.722673 -53.388096) (xy 317.730431 -53.442047)
			(xy 317.730431 -53.496553) (xy 317.722673 -53.550504) (xy 317.707317 -53.602801) (xy 317.684674 -53.652381)
			(xy 317.655205 -53.698234) (xy 317.61951 -53.739425) (xy 317.578316 -53.775118) (xy 317.532462 -53.804584)
			(xy 317.482881 -53.827224) (xy 317.430582 -53.842578) (xy 317.376631 -53.850332) (xy 317.349378 -53.850794)
			(xy 317.322007 -53.850342) (xy 317.267827 -53.842521) (xy 317.215324 -53.827029) (xy 317.165578 -53.804184)
			(xy 317.119611 -53.774457) (xy 317.09868 -53.756814) (xy 317.098426 -53.75656) (xy 317.09134 -53.750973)
			(xy 317.074423 -53.744728) (xy 317.065406 -53.744368) (xy 316.99835 -53.744368) (xy 316.989336 -53.744756)
			(xy 316.97242 -53.750983) (xy 316.96533 -53.75656) (xy 316.96533 -53.756814) (xy 316.965076 -53.756814)
			(xy 316.944128 -53.774433) (xy 316.898159 -53.804147) (xy 316.848416 -53.826987) (xy 316.795919 -53.842483)
			(xy 316.741746 -53.850317) (xy 316.714378 -53.850794) (xy 316.687127 -53.850335) (xy 316.633179 -53.842575)
			(xy 316.580885 -53.827218) (xy 316.531309 -53.804575) (xy 316.48546 -53.775107) (xy 316.444271 -53.739414)
			(xy 316.40858 -53.698223) (xy 316.379115 -53.652372) (xy 316.356475 -53.602794) (xy 316.34112 -53.550499)
			(xy 316.333364 -53.496551) (xy 312.423389 -53.496551) (xy 312.559446 -53.632608) (xy 312.577004 -53.650822)
			(xy 312.606748 -53.691743) (xy 312.629718 -53.736816) (xy 312.645349 -53.78493) (xy 312.653255 -53.834897)
			(xy 312.65368 -53.860192) (xy 312.65368 -54.91353) (xy 312.65416 -54.924278) (xy 312.662978 -54.943882)
			(xy 312.670698 -54.951376) (xy 312.686446 -54.965346) (xy 312.713154 -54.989051) (xy 314.100968 -54.989051)
			(xy 314.100968 -54.934549) (xy 314.108724 -54.880603) (xy 314.124078 -54.828309) (xy 314.146718 -54.778732)
			(xy 314.176182 -54.732882) (xy 314.211871 -54.691691) (xy 314.253059 -54.655999) (xy 314.298907 -54.626531)
			(xy 314.348482 -54.603888) (xy 314.400775 -54.58853) (xy 314.454721 -54.58077) (xy 314.481972 -54.580282)
			(xy 314.510063 -54.580799) (xy 314.565639 -54.589022) (xy 314.619407 -54.605309) (xy 314.670205 -54.629308)
			(xy 314.716932 -54.6605) (xy 314.758578 -54.698209) (xy 314.794241 -54.741619) (xy 314.809124 -54.765448)
			(xy 314.814458 -54.774338) (xy 314.831476 -54.78653) (xy 314.924694 -54.80685) (xy 314.945268 -54.802532)
			(xy 314.953904 -54.79669) (xy 314.977965 -54.780685) (xy 315.029897 -54.755344) (xy 315.085056 -54.738119)
			(xy 315.142181 -54.729406) (xy 315.171074 -54.728872) (xy 315.198325 -54.729379) (xy 315.252274 -54.737132)
			(xy 315.304569 -54.752484) (xy 315.354148 -54.775122) (xy 315.4 -54.804586) (xy 315.441193 -54.840275)
			(xy 315.476887 -54.881463) (xy 315.506356 -54.927311) (xy 315.529 -54.976887) (xy 315.544358 -55.029181)
			(xy 315.552117 -55.083129) (xy 315.552582 -55.11038) (xy 315.552109 -55.13775) (xy 315.544293 -55.191929)
			(xy 315.528806 -55.244432) (xy 315.505966 -55.294179) (xy 315.476243 -55.340146) (xy 315.458602 -55.361078)
			(xy 315.458348 -55.361332) (xy 315.452778 -55.368429) (xy 315.446522 -55.385338) (xy 315.446156 -55.394352)
			(xy 315.446156 -55.461408) (xy 315.446497 -55.470427) (xy 315.452755 -55.487344) (xy 315.458348 -55.494428)
			(xy 315.458602 -55.494428) (xy 315.458602 -55.494682) (xy 315.476222 -55.515631) (xy 315.505945 -55.561597)
			(xy 315.52879 -55.611341) (xy 315.544287 -55.66384) (xy 315.552116 -55.718016) (xy 315.552119 -55.772754)
			(xy 315.544293 -55.826931) (xy 315.528801 -55.879431) (xy 315.50596 -55.929177) (xy 315.47624 -55.975145)
			(xy 315.458602 -55.996078) (xy 315.458348 -55.996332) (xy 315.452778 -56.003429) (xy 315.446522 -56.020338)
			(xy 315.446156 -56.029352) (xy 315.446156 -56.096408) (xy 315.446497 -56.105427) (xy 315.452755 -56.122344)
			(xy 315.458348 -56.129428) (xy 315.458602 -56.129428) (xy 315.458602 -56.129682) (xy 315.476246 -56.15061)
			(xy 315.505957 -56.196584) (xy 315.528792 -56.246332) (xy 315.544282 -56.298834) (xy 315.552109 -56.353011)
			(xy 315.552582 -56.38038) (xy 315.552096 -56.407631) (xy 315.54434 -56.461579) (xy 315.528985 -56.513874)
			(xy 315.506343 -56.563451) (xy 315.476877 -56.609301) (xy 315.441186 -56.650492) (xy 315.399995 -56.686183)
			(xy 315.354145 -56.715649) (xy 315.304568 -56.738291) (xy 315.252273 -56.753646) (xy 315.198325 -56.761402)
			(xy 315.143823 -56.761402) (xy 315.089875 -56.753646) (xy 315.03758 -56.738291) (xy 314.988003 -56.715649)
			(xy 314.942153 -56.686183) (xy 314.900962 -56.650492) (xy 314.865271 -56.609301) (xy 314.835805 -56.563451)
			(xy 314.813163 -56.513874) (xy 314.797808 -56.461579) (xy 314.790052 -56.407631) (xy 314.789566 -56.38038)
			(xy 314.790004 -56.353009) (xy 314.797826 -56.298828) (xy 314.813321 -56.246324) (xy 314.836169 -56.196577)
			(xy 314.865901 -56.150612) (xy 314.883546 -56.129682) (xy 314.8838 -56.129428) (xy 314.889381 -56.122338)
			(xy 314.895631 -56.105424) (xy 314.895992 -56.096408) (xy 314.895992 -56.029352) (xy 314.895612 -56.020337)
			(xy 314.88938 -56.00342) (xy 314.8838 -55.996332) (xy 314.883546 -55.996332) (xy 314.883546 -55.996078)
			(xy 314.865885 -55.975162) (xy 314.836159 -55.929191) (xy 314.813314 -55.879443) (xy 314.797819 -55.826938)
			(xy 314.789991 -55.772757) (xy 314.789994 -55.718013) (xy 314.797825 -55.663833) (xy 314.813325 -55.611329)
			(xy 314.836174 -55.561582) (xy 314.865903 -55.515614) (xy 314.883546 -55.494682) (xy 314.8838 -55.494428)
			(xy 314.889381 -55.487338) (xy 314.895631 -55.470424) (xy 314.895992 -55.461408) (xy 314.895992 -55.394352)
			(xy 314.895612 -55.385337) (xy 314.88938 -55.36842) (xy 314.8838 -55.361332) (xy 314.883546 -55.360824)
			(xy 314.872599 -55.348092) (xy 314.85276 -55.320999) (xy 314.843922 -55.306722) (xy 314.838588 -55.297832)
			(xy 314.82157 -55.28564) (xy 314.728352 -55.26532) (xy 314.707778 -55.269638) (xy 314.699142 -55.27548)
			(xy 314.675067 -55.291462) (xy 314.62314 -55.316809) (xy 314.567985 -55.33404) (xy 314.510864 -55.342761)
			(xy 314.481972 -55.343298) (xy 314.454721 -55.34283) (xy 314.400775 -55.33507) (xy 314.348482 -55.319712)
			(xy 314.298907 -55.297069) (xy 314.253059 -55.267601) (xy 314.211871 -55.231909) (xy 314.176182 -55.190718)
			(xy 314.146718 -55.144868) (xy 314.124078 -55.095291) (xy 314.108724 -55.042997) (xy 314.100968 -54.989051)
			(xy 312.713154 -54.989051) (xy 312.729372 -55.003446) (xy 312.732842 -55.006108) (xy 312.740508 -55.010317)
			(xy 312.744612 -55.011828) (xy 312.755026 -55.015384) (xy 312.7629 -55.014368) (xy 312.773534 -55.013276)
			(xy 312.794882 -55.012133) (xy 312.805572 -55.012082) (xy 312.807858 -55.012082) (xy 312.838219 -55.012849)
			(xy 312.898125 -55.022822) (xy 312.955696 -55.042156) (xy 313.009478 -55.070365) (xy 313.058113 -55.106735)
			(xy 313.079638 -55.12816) (xy 313.08675 -55.135526) (xy 313.11596 -55.148226) (xy 313.120114 -55.149779)
			(xy 313.128802 -55.15156) (xy 313.133232 -55.151782) (xy 313.187842 -55.151782) (xy 313.197748 -55.150004)
			(xy 313.2074 -55.147972) (xy 313.235594 -55.135526) (xy 313.242452 -55.128414) (xy 313.26048 -55.110344)
			(xy 313.300528 -55.078695) (xy 313.34444 -55.052671) (xy 313.391431 -55.032738) (xy 313.440661 -55.019251)
			(xy 313.49125 -55.012451) (xy 313.516772 -55.012082) (xy 313.544027 -55.012543) (xy 313.597982 -55.020297)
			(xy 313.650285 -55.035651) (xy 313.69987 -55.058292) (xy 313.745728 -55.087761) (xy 313.786925 -55.123455)
			(xy 313.822623 -55.16465) (xy 313.852094 -55.210505) (xy 313.874739 -55.260089) (xy 313.890097 -55.31239)
			(xy 313.897855 -55.366345) (xy 313.897855 -55.420855) (xy 313.890097 -55.47481) (xy 313.874739 -55.527111)
			(xy 313.852094 -55.576695) (xy 313.822623 -55.62255) (xy 313.786925 -55.663745) (xy 313.745728 -55.699439)
			(xy 313.69987 -55.728908) (xy 313.650285 -55.751549) (xy 313.597982 -55.766903) (xy 313.544027 -55.774657)
			(xy 313.516772 -55.775098) (xy 313.491284 -55.774672) (xy 313.440762 -55.767881) (xy 313.391595 -55.754425)
			(xy 313.344656 -55.734542) (xy 313.300783 -55.708587) (xy 313.260755 -55.677021) (xy 313.242706 -55.65902)
			(xy 313.235594 -55.651654) (xy 313.206384 -55.638954) (xy 313.20223 -55.637398) (xy 313.193543 -55.635609)
			(xy 313.189112 -55.635398) (xy 313.14009 -55.635398) (xy 313.12993 -55.636414) (xy 313.119008 -55.6387)
			(xy 313.11342 -55.639716) (xy 313.08675 -55.651654) (xy 313.079892 -55.65902) (xy 313.062231 -55.676676)
			(xy 313.023084 -55.707686) (xy 312.980221 -55.733316) (xy 312.957464 -55.743602) (xy 312.94959 -55.747158)
			(xy 312.943748 -55.752238) (xy 312.935112 -55.762398) (xy 312.922158 -55.785004) (xy 312.922158 -55.785258)
			(xy 312.919364 -55.790084) (xy 312.915717 -55.796929) (xy 312.912348 -55.812058) (xy 312.91276 -55.819802)
			(xy 312.913014 -55.824374) (xy 312.913776 -55.84825) (xy 312.913776 -57.48528) (xy 314.80582 -57.48528)
			(xy 314.809891 -57.429658) (xy 314.822017 -57.375221) (xy 314.84194 -57.32313) (xy 314.869236 -57.274495)
			(xy 314.903322 -57.230352) (xy 314.943471 -57.191643) (xy 314.988829 -57.159192) (xy 315.038429 -57.133691)
			(xy 315.091213 -57.115684) (xy 315.146056 -57.105554) (xy 315.20179 -57.103517) (xy 315.257227 -57.109617)
			(xy 315.311184 -57.123723) (xy 315.362513 -57.145535) (xy 315.410119 -57.174589) (xy 315.452987 -57.210264)
			(xy 315.490204 -57.251801) (xy 315.520977 -57.298314) (xy 315.544649 -57.348811) (xy 315.560717 -57.402218)
			(xy 315.568837 -57.457394) (xy 315.569346 -57.48528) (xy 315.568837 -57.513166) (xy 315.560717 -57.568342)
			(xy 315.544649 -57.621749) (xy 315.520977 -57.672246) (xy 315.490204 -57.718759) (xy 315.452987 -57.760296)
			(xy 315.410119 -57.795971) (xy 315.362513 -57.825025) (xy 315.311184 -57.846837) (xy 315.257227 -57.860943)
			(xy 315.20179 -57.867043) (xy 315.146056 -57.865006) (xy 315.091213 -57.854876) (xy 315.038429 -57.836869)
			(xy 314.988829 -57.811368) (xy 314.943471 -57.778917) (xy 314.903322 -57.740208) (xy 314.869236 -57.696065)
			(xy 314.84194 -57.64743) (xy 314.822017 -57.595339) (xy 314.809891 -57.540902) (xy 314.80582 -57.48528)
			(xy 312.913776 -57.48528) (xy 312.913776 -58.561224) (xy 316.762128 -58.561224) (xy 316.766199 -58.505602)
			(xy 316.778325 -58.451165) (xy 316.798248 -58.399074) (xy 316.825544 -58.350439) (xy 316.85963 -58.306296)
			(xy 316.899779 -58.267587) (xy 316.945137 -58.235136) (xy 316.994737 -58.209635) (xy 317.047521 -58.191628)
			(xy 317.102364 -58.181498) (xy 317.158098 -58.179461) (xy 317.213535 -58.185561) (xy 317.267492 -58.199667)
			(xy 317.318821 -58.221479) (xy 317.366427 -58.250533) (xy 317.409295 -58.286208) (xy 317.446512 -58.327745)
			(xy 317.477285 -58.374258) (xy 317.500957 -58.424755) (xy 317.517025 -58.478162) (xy 317.525145 -58.533338)
			(xy 317.525654 -58.561224) (xy 317.525145 -58.58911) (xy 317.517025 -58.644286) (xy 317.500957 -58.697693)
			(xy 317.477285 -58.74819) (xy 317.446512 -58.794703) (xy 317.409295 -58.83624) (xy 317.366427 -58.871915)
			(xy 317.318821 -58.900969) (xy 317.267492 -58.922781) (xy 317.213535 -58.936887) (xy 317.158098 -58.942987)
			(xy 317.102364 -58.94095) (xy 317.047521 -58.93082) (xy 316.994737 -58.912813) (xy 316.945137 -58.887312)
			(xy 316.899779 -58.854861) (xy 316.85963 -58.816152) (xy 316.825544 -58.772009) (xy 316.798248 -58.723374)
			(xy 316.778325 -58.671283) (xy 316.766199 -58.616846) (xy 316.762128 -58.561224) (xy 312.913776 -58.561224)
			(xy 312.913776 -59.174634) (xy 315.292992 -59.174634) (xy 315.297063 -59.119012) (xy 315.309189 -59.064575)
			(xy 315.329112 -59.012484) (xy 315.356408 -58.963849) (xy 315.390494 -58.919706) (xy 315.430643 -58.880997)
			(xy 315.476001 -58.848546) (xy 315.525601 -58.823045) (xy 315.578385 -58.805038) (xy 315.633228 -58.794908)
			(xy 315.688962 -58.792871) (xy 315.744399 -58.798971) (xy 315.798356 -58.813077) (xy 315.849685 -58.834889)
			(xy 315.897291 -58.863943) (xy 315.940159 -58.899618) (xy 315.977376 -58.941155) (xy 316.008149 -58.987668)
			(xy 316.031821 -59.038165) (xy 316.047889 -59.091572) (xy 316.056009 -59.146748) (xy 316.056518 -59.174634)
			(xy 316.056009 -59.20252) (xy 316.047889 -59.257696) (xy 316.031821 -59.311103) (xy 316.008149 -59.3616)
			(xy 315.977376 -59.408113) (xy 315.940159 -59.44965) (xy 315.897291 -59.485325) (xy 315.849685 -59.514379)
			(xy 315.798356 -59.536191) (xy 315.744399 -59.550297) (xy 315.688962 -59.556397) (xy 315.633228 -59.55436)
			(xy 315.578385 -59.54423) (xy 315.525601 -59.526223) (xy 315.476001 -59.500722) (xy 315.430643 -59.468271)
			(xy 315.390494 -59.429562) (xy 315.356408 -59.385419) (xy 315.329112 -59.336784) (xy 315.309189 -59.284693)
			(xy 315.297063 -59.230256) (xy 315.292992 -59.174634) (xy 312.913776 -59.174634) (xy 312.913776 -60.633356)
			(xy 317.996822 -60.633356) (xy 318.000893 -60.577734) (xy 318.013019 -60.523297) (xy 318.032942 -60.471206)
			(xy 318.060238 -60.422571) (xy 318.094324 -60.378428) (xy 318.134473 -60.339719) (xy 318.179831 -60.307268)
			(xy 318.229431 -60.281767) (xy 318.282215 -60.26376) (xy 318.337058 -60.25363) (xy 318.392792 -60.251593)
			(xy 318.448229 -60.257693) (xy 318.502186 -60.271799) (xy 318.553515 -60.293611) (xy 318.601121 -60.322665)
			(xy 318.643989 -60.35834) (xy 318.681206 -60.399877) (xy 318.711979 -60.44639) (xy 318.735651 -60.496887)
			(xy 318.751719 -60.550294) (xy 318.759839 -60.60547) (xy 318.760348 -60.633356) (xy 318.759839 -60.661242)
			(xy 318.751719 -60.716418) (xy 318.735651 -60.769825) (xy 318.711979 -60.820322) (xy 318.681206 -60.866835)
			(xy 318.643989 -60.908372) (xy 318.601121 -60.944047) (xy 318.553515 -60.973101) (xy 318.502186 -60.994913)
			(xy 318.448229 -61.009019) (xy 318.392792 -61.015119) (xy 318.337058 -61.013082) (xy 318.282215 -61.002952)
			(xy 318.229431 -60.984945) (xy 318.179831 -60.959444) (xy 318.134473 -60.926993) (xy 318.094324 -60.888284)
			(xy 318.060238 -60.844141) (xy 318.032942 -60.795506) (xy 318.013019 -60.743415) (xy 318.000893 -60.688978)
			(xy 317.996822 -60.633356) (xy 312.913776 -60.633356) (xy 312.913776 -61.487812) (xy 316.504318 -61.487812)
			(xy 316.508389 -61.43219) (xy 316.520515 -61.377753) (xy 316.540438 -61.325662) (xy 316.567734 -61.277027)
			(xy 316.60182 -61.232884) (xy 316.641969 -61.194175) (xy 316.687327 -61.161724) (xy 316.736927 -61.136223)
			(xy 316.789711 -61.118216) (xy 316.844554 -61.108086) (xy 316.900288 -61.106049) (xy 316.955725 -61.112149)
			(xy 317.009682 -61.126255) (xy 317.061011 -61.148067) (xy 317.108617 -61.177121) (xy 317.151485 -61.212796)
			(xy 317.188702 -61.254333) (xy 317.219475 -61.300846) (xy 317.243147 -61.351343) (xy 317.259215 -61.40475)
			(xy 317.267335 -61.459926) (xy 317.267844 -61.487812) (xy 317.267335 -61.515698) (xy 317.259215 -61.570874)
			(xy 317.243147 -61.624281) (xy 317.219475 -61.674778) (xy 317.188702 -61.721291) (xy 317.151485 -61.762828)
			(xy 317.108617 -61.798503) (xy 317.061011 -61.827557) (xy 317.009682 -61.849369) (xy 316.955725 -61.863475)
			(xy 316.900288 -61.869575) (xy 316.844554 -61.867538) (xy 316.789711 -61.857408) (xy 316.736927 -61.839401)
			(xy 316.687327 -61.8139) (xy 316.641969 -61.781449) (xy 316.60182 -61.74274) (xy 316.567734 -61.698597)
			(xy 316.540438 -61.649962) (xy 316.520515 -61.597871) (xy 316.508389 -61.543434) (xy 316.504318 -61.487812)
			(xy 312.913776 -61.487812) (xy 312.913776 -62.121034) (xy 314.442092 -62.121034) (xy 314.446163 -62.065412)
			(xy 314.458289 -62.010975) (xy 314.478212 -61.958884) (xy 314.505508 -61.910249) (xy 314.539594 -61.866106)
			(xy 314.579743 -61.827397) (xy 314.625101 -61.794946) (xy 314.674701 -61.769445) (xy 314.727485 -61.751438)
			(xy 314.782328 -61.741308) (xy 314.838062 -61.739271) (xy 314.893499 -61.745371) (xy 314.947456 -61.759477)
			(xy 314.998785 -61.781289) (xy 315.046391 -61.810343) (xy 315.089259 -61.846018) (xy 315.126476 -61.887555)
			(xy 315.157249 -61.934068) (xy 315.180921 -61.984565) (xy 315.196989 -62.037972) (xy 315.205109 -62.093148)
			(xy 315.205618 -62.121034) (xy 315.205109 -62.14892) (xy 315.196989 -62.204096) (xy 315.180921 -62.257503)
			(xy 315.157249 -62.308) (xy 315.126476 -62.354513) (xy 315.089259 -62.39605) (xy 315.046391 -62.431725)
			(xy 314.998785 -62.460779) (xy 314.947456 -62.482591) (xy 314.893499 -62.496697) (xy 314.838062 -62.502797)
			(xy 314.782328 -62.50076) (xy 314.727485 -62.49063) (xy 314.674701 -62.472623) (xy 314.625101 -62.447122)
			(xy 314.579743 -62.414671) (xy 314.539594 -62.375962) (xy 314.505508 -62.331819) (xy 314.478212 -62.283184)
			(xy 314.458289 -62.231093) (xy 314.446163 -62.176656) (xy 314.442092 -62.121034) (xy 312.913776 -62.121034)
			(xy 312.913776 -63.273432) (xy 313.776612 -63.273432) (xy 313.780683 -63.21781) (xy 313.792809 -63.163373)
			(xy 313.812732 -63.111282) (xy 313.840028 -63.062647) (xy 313.874114 -63.018504) (xy 313.914263 -62.979795)
			(xy 313.959621 -62.947344) (xy 314.009221 -62.921843) (xy 314.062005 -62.903836) (xy 314.116848 -62.893706)
			(xy 314.172582 -62.891669) (xy 314.228019 -62.897769) (xy 314.281976 -62.911875) (xy 314.333305 -62.933687)
			(xy 314.380911 -62.962741) (xy 314.423779 -62.998416) (xy 314.460996 -63.039953) (xy 314.491769 -63.086466)
			(xy 314.515441 -63.136963) (xy 314.531509 -63.19037) (xy 314.539629 -63.245546) (xy 314.540138 -63.273432)
			(xy 314.539629 -63.301318) (xy 314.531509 -63.356494) (xy 314.515441 -63.409901) (xy 314.491769 -63.460398)
			(xy 314.460996 -63.506911) (xy 314.423779 -63.548448) (xy 314.380911 -63.584123) (xy 314.333305 -63.613177)
			(xy 314.281976 -63.634989) (xy 314.228019 -63.649095) (xy 314.172582 -63.655195) (xy 314.116848 -63.653158)
			(xy 314.062005 -63.643028) (xy 314.009221 -63.625021) (xy 313.959621 -63.59952) (xy 313.914263 -63.567069)
			(xy 313.874114 -63.52836) (xy 313.840028 -63.484217) (xy 313.812732 -63.435582) (xy 313.792809 -63.383491)
			(xy 313.780683 -63.329054) (xy 313.776612 -63.273432) (xy 312.913776 -63.273432) (xy 312.913776 -65.124076)
			(xy 316.307214 -65.124076) (xy 316.311285 -65.068454) (xy 316.323411 -65.014017) (xy 316.343334 -64.961926)
			(xy 316.37063 -64.913291) (xy 316.404716 -64.869148) (xy 316.444865 -64.830439) (xy 316.490223 -64.797988)
			(xy 316.539823 -64.772487) (xy 316.592607 -64.75448) (xy 316.64745 -64.74435) (xy 316.703184 -64.742313)
			(xy 316.758621 -64.748413) (xy 316.812578 -64.762519) (xy 316.863907 -64.784331) (xy 316.911513 -64.813385)
			(xy 316.954381 -64.84906) (xy 316.991598 -64.890597) (xy 317.022371 -64.93711) (xy 317.046043 -64.987607)
			(xy 317.062111 -65.041014) (xy 317.070231 -65.09619) (xy 317.07074 -65.124076) (xy 317.070231 -65.151962)
			(xy 317.062111 -65.207138) (xy 317.046043 -65.260545) (xy 317.022371 -65.311042) (xy 316.991598 -65.357555)
			(xy 316.954381 -65.399092) (xy 316.911513 -65.434767) (xy 316.863907 -65.463821) (xy 316.812578 -65.485633)
			(xy 316.758621 -65.499739) (xy 316.703184 -65.505839) (xy 316.64745 -65.503802) (xy 316.592607 -65.493672)
			(xy 316.539823 -65.475665) (xy 316.490223 -65.450164) (xy 316.444865 -65.417713) (xy 316.404716 -65.379004)
			(xy 316.37063 -65.334861) (xy 316.343334 -65.286226) (xy 316.323411 -65.234135) (xy 316.311285 -65.179698)
			(xy 316.307214 -65.124076) (xy 312.913776 -65.124076) (xy 312.913776 -66.86804) (xy 312.914792 -66.877438)
			(xy 312.914792 -66.877946) (xy 312.916504 -66.885101) (xy 312.923347 -66.898117) (xy 312.928254 -66.9036)
			(xy 314.685934 -68.66128) (xy 314.691362 -68.666264) (xy 314.704401 -68.673116) (xy 314.711588 -68.674742)
			(xy 314.712096 -68.674742) (xy 314.721494 -68.675758) (xy 317.86703 -68.675758) (xy 317.86703 -68.666614)
			(xy 318.474598 -68.059046) (xy 318.479578 -68.053616) (xy 318.486423 -68.040576) (xy 318.48806 -68.033392)
			(xy 318.48806 -68.032884) (xy 318.489076 -68.023486) (xy 318.489076 -63.172086) (xy 318.488568 -63.164974)
			(xy 318.487044 -63.153798) (xy 318.484971 -63.147481) (xy 318.478027 -63.136148) (xy 318.473328 -63.131446)
			(xy 318.460628 -63.122048) (xy 318.400176 -63.07709) (xy 318.391212 -63.071841) (xy 318.370761 -63.06831)
			(xy 318.360552 -63.070232) (xy 318.358012 -63.070994) (xy 318.330914 -63.078709) (xy 318.275185 -63.086994)
			(xy 318.247014 -63.087504) (xy 318.219761 -63.087042) (xy 318.165808 -63.079286) (xy 318.113509 -63.063931)
			(xy 318.063927 -63.04129) (xy 318.018073 -63.011822) (xy 317.976879 -62.976128) (xy 317.941184 -62.934935)
			(xy 317.911715 -62.889081) (xy 317.889072 -62.8395) (xy 317.873716 -62.787201) (xy 317.865959 -62.733249)
			(xy 317.865506 -62.705996) (xy 317.865987 -62.678826) (xy 317.873698 -62.625036) (xy 317.888964 -62.572885)
			(xy 317.911476 -62.523427) (xy 317.940777 -62.477664) (xy 317.976276 -62.436522) (xy 318.017254 -62.400834)
			(xy 318.062881 -62.371321) (xy 318.112234 -62.348582) (xy 318.164315 -62.333076) (xy 318.218069 -62.325116)
			(xy 318.245236 -62.324488) (xy 318.247522 -62.324488) (xy 318.271906 -62.32525) (xy 318.272668 -62.32525)
			(xy 318.274446 -62.325504) (xy 318.27597 -62.325504) (xy 318.308626 -62.328676) (xy 318.372224 -62.344774)
			(xy 318.402462 -62.357508) (xy 318.413892 -62.362842) (xy 318.4144 -62.363096) (xy 318.42075 -62.366144)
			(xy 318.43218 -62.368684) (xy 318.438276 -62.368684) (xy 318.448299 -62.368269) (xy 318.466822 -62.360602)
			(xy 318.480998 -62.346429) (xy 318.488667 -62.327907) (xy 318.489076 -62.317884) (xy 318.489076 -62.27191)
			(xy 318.487298 -62.258702) (xy 318.486028 -62.253622) (xy 318.481964 -62.247018) (xy 318.46972 -62.225368)
			(xy 318.450321 -62.17957) (xy 318.437024 -62.131644) (xy 318.430054 -62.082397) (xy 318.429386 -62.057534)
			(xy 318.429386 -62.048136) (xy 318.430081 -62.021187) (xy 318.438126 -61.967882) (xy 318.453594 -61.91624)
			(xy 318.476177 -61.86729) (xy 318.505426 -61.822006) (xy 318.540759 -61.78129) (xy 318.58147 -61.745953)
			(xy 318.626751 -61.716699) (xy 318.675698 -61.69411) (xy 318.727338 -61.678636) (xy 318.780642 -61.670585)
			(xy 318.807592 -61.66993) (xy 318.816736 -61.66993) (xy 318.846844 -61.670795) (xy 318.906227 -61.680851)
			(xy 318.96329 -61.700124) (xy 318.990218 -61.713618) (xy 318.99575 -61.716309) (xy 319.007691 -61.719254)
			(xy 319.01384 -61.71946) (xy 319.161414 -61.71946) (xy 319.171066 -61.718444) (xy 319.178308 -61.716814)
			(xy 319.191473 -61.709967) (xy 319.196974 -61.704982) (xy 319.728596 -61.17336) (xy 319.729104 -61.165994)
			(xy 319.729104 -58.87085) (xy 319.72885 -58.865516) (xy 319.727057 -58.854473) (xy 319.715474 -58.835361)
			(xy 319.706498 -58.828686) (xy 319.673478 -58.809382) (xy 319.629028 -58.783474) (xy 319.620873 -58.779489)
			(xy 319.602905 -58.777017) (xy 319.593976 -58.778648) (xy 319.577974 -58.782458) (xy 319.572386 -58.785506)
			(xy 319.544384 -58.799879) (xy 319.484837 -58.82026) (xy 319.422753 -58.830589) (xy 319.391284 -58.831226)
			(xy 319.390776 -58.831226) (xy 319.363525 -58.830739) (xy 319.309577 -58.822979) (xy 319.257283 -58.807621)
			(xy 319.207706 -58.784977) (xy 319.161856 -58.755509) (xy 319.120667 -58.719816) (xy 319.084977 -58.678624)
			(xy 319.055511 -58.632773) (xy 319.032871 -58.583195) (xy 319.017516 -58.5309) (xy 319.00976 -58.476951)
			(xy 319.00976 -58.422449) (xy 319.017516 -58.3685) (xy 319.032871 -58.316205) (xy 319.055511 -58.266627)
			(xy 319.084977 -58.220776) (xy 319.120667 -58.179584) (xy 319.161856 -58.143891) (xy 319.207706 -58.114423)
			(xy 319.257283 -58.091779) (xy 319.309577 -58.076421) (xy 319.363525 -58.068661) (xy 319.390776 -58.06821)
			(xy 319.391538 -58.06821) (xy 319.423444 -58.068852) (xy 319.486365 -58.079473) (xy 319.546638 -58.100428)
			(xy 319.574926 -58.1152) (xy 319.576704 -58.116216) (xy 319.586102 -58.121804) (xy 319.59677 -58.123074)
			(xy 319.597278 -58.123074) (xy 319.602197 -58.123521) (xy 319.612044 -58.122748) (xy 319.616836 -58.12155)
			(xy 319.624964 -58.11901) (xy 319.631568 -58.114692) (xy 319.703958 -58.072274) (xy 319.711382 -58.067509)
			(xy 319.722674 -58.053973) (xy 319.728676 -58.0374) (xy 319.729104 -58.028586) (xy 319.729104 -54.863238)
			(xy 319.728854 -54.857976) (xy 319.726426 -54.847728) (xy 319.724278 -54.842918) (xy 319.71869 -54.840632)
			(xy 319.697862 -54.831996) (xy 319.688477 -54.828467) (xy 319.668442 -54.828322) (xy 319.649898 -54.835907)
			(xy 319.64249 -54.842664) (xy 316.618089 -57.867296) (xy 317.842898 -57.867296) (xy 317.846969 -57.811674)
			(xy 317.859095 -57.757237) (xy 317.879018 -57.705146) (xy 317.906314 -57.656511) (xy 317.9404 -57.612368)
			(xy 317.980549 -57.573659) (xy 318.025907 -57.541208) (xy 318.075507 -57.515707) (xy 318.128291 -57.4977)
			(xy 318.183134 -57.48757) (xy 318.238868 -57.485533) (xy 318.294305 -57.491633) (xy 318.348262 -57.505739)
			(xy 318.399591 -57.527551) (xy 318.447197 -57.556605) (xy 318.490065 -57.59228) (xy 318.527282 -57.633817)
			(xy 318.558055 -57.68033) (xy 318.581727 -57.730827) (xy 318.597795 -57.784234) (xy 318.605915 -57.83941)
			(xy 318.606424 -57.867296) (xy 318.605915 -57.895182) (xy 318.597795 -57.950358) (xy 318.581727 -58.003765)
			(xy 318.558055 -58.054262) (xy 318.527282 -58.100775) (xy 318.490065 -58.142312) (xy 318.447197 -58.177987)
			(xy 318.399591 -58.207041) (xy 318.348262 -58.228853) (xy 318.294305 -58.242959) (xy 318.238868 -58.249059)
			(xy 318.183134 -58.247022) (xy 318.128291 -58.236892) (xy 318.075507 -58.218885) (xy 318.025907 -58.193384)
			(xy 317.980549 -58.160933) (xy 317.9404 -58.122224) (xy 317.906314 -58.078081) (xy 317.879018 -58.029446)
			(xy 317.859095 -57.977355) (xy 317.846969 -57.922918) (xy 317.842898 -57.867296) (xy 316.618089 -57.867296)
			(xy 316.31255 -58.172858) (xy 316.3062 -58.183526) (xy 316.304422 -58.189368) (xy 316.295973 -58.214935)
			(xy 316.272893 -58.263583) (xy 316.243206 -58.308505) (xy 316.207503 -58.348811) (xy 316.166491 -58.383701)
			(xy 316.120983 -58.412483) (xy 316.071883 -58.434585) (xy 316.020165 -58.44957) (xy 315.966855 -58.45714)
			(xy 315.939932 -58.457592) (xy 315.912678 -58.457131) (xy 315.858725 -58.449377) (xy 315.806424 -58.434024)
			(xy 315.756841 -58.411383) (xy 315.710985 -58.381916) (xy 315.669789 -58.346222) (xy 315.634094 -58.305028)
			(xy 315.604625 -58.259173) (xy 315.581982 -58.209591) (xy 315.566626 -58.157291) (xy 315.55887 -58.103338)
			(xy 315.558424 -58.076084) (xy 315.55817 -58.076084) (xy 315.558627 -58.049149) (xy 315.566193 -57.995812)
			(xy 315.581187 -57.94407) (xy 315.603309 -57.894952) (xy 315.632121 -57.849434) (xy 315.667049 -57.808421)
			(xy 315.707399 -57.772729) (xy 315.752368 -57.743067) (xy 315.801062 -57.720027) (xy 315.826648 -57.711594)
			(xy 315.826902 -57.711594) (xy 315.832736 -57.709581) (xy 315.843269 -57.703158) (xy 315.84773 -57.698894)
			(xy 319.366392 -54.180486) (xy 319.370732 -54.175863) (xy 319.377152 -54.164933) (xy 319.379092 -54.158896)
			(xy 319.380039 -54.155417) (xy 319.381054 -54.148277) (xy 319.381124 -54.144672) (xy 319.381124 -46.412658)
			(xy 319.380958 -46.406648) (xy 319.378137 -46.394964) (xy 319.375536 -46.389544) (xy 319.373695 -46.386071)
			(xy 319.369101 -46.379693) (xy 319.366392 -46.376844) (xy 313.307984 -40.318436) (xy 313.305133 -40.315731)
			(xy 313.298753 -40.31114) (xy 313.295284 -40.309292) (xy 313.289858 -40.306706) (xy 313.278178 -40.303877)
			(xy 313.27217 -40.303704) (xy 310.666892 -40.303704) (xy 310.662574 -40.30599) (xy 310.634149 -40.320908)
			(xy 310.573548 -40.342075) (xy 310.510265 -40.352832) (xy 310.47817 -40.353488) (xy 310.477662 -40.353488)
			(xy 310.450414 -40.352999) (xy 310.396473 -40.345239) (xy 310.344186 -40.329881) (xy 310.294616 -40.307239)
			(xy 310.248773 -40.277773) (xy 310.207589 -40.242084) (xy 310.171904 -40.200897) (xy 310.142443 -40.155051)
			(xy 310.119806 -40.105478) (xy 310.104453 -40.05319) (xy 310.096698 -39.999248) (xy 310.096698 -39.944752)
			(xy 310.104453 -39.89081) (xy 310.119806 -39.838522) (xy 310.142443 -39.788949) (xy 310.171904 -39.743103)
			(xy 310.207589 -39.701916) (xy 310.248773 -39.666227) (xy 310.294616 -39.636761) (xy 310.344186 -39.614119)
			(xy 310.396473 -39.598761) (xy 310.450414 -39.591001) (xy 310.477662 -39.590472) (xy 310.477916 -39.590472)
			(xy 310.502164 -39.590867) (xy 310.550265 -39.597036) (xy 310.597202 -39.609235) (xy 310.642219 -39.627269)
			(xy 310.66359 -39.638732) (xy 310.666384 -39.640256) (xy 313.248294 -39.640256) (xy 313.258338 -39.639832)
			(xy 313.276889 -39.632123) (xy 313.29106 -39.617884) (xy 313.295284 -39.60876) (xy 313.306714 -39.581074)
			(xy 313.305444 -39.574724) (xy 313.142376 -39.41191) (xy 309.940706 -36.210494) (xy 309.93842 -36.208716)
			(xy 308.938422 -36.208716) (xy 308.929532 -36.216844) (xy 308.89702 -36.261802) (xy 308.88051 -36.284916)
			(xy 308.876769 -36.291024) (xy 308.8725 -36.304688) (xy 308.872128 -36.31184) (xy 308.872128 -36.331906)
			(xy 308.874414 -36.339526) (xy 308.882578 -36.367329) (xy 308.891374 -36.424601) (xy 308.89194 -36.453572)
			(xy 308.891456 -36.480825) (xy 308.883703 -36.534778) (xy 308.868351 -36.587078) (xy 308.845712 -36.636661)
			(xy 308.816247 -36.682517) (xy 308.780555 -36.723713) (xy 308.739365 -36.759411) (xy 308.693513 -36.788883)
			(xy 308.643934 -36.81153) (xy 308.591637 -36.82689) (xy 308.537685 -36.834652) (xy 308.510432 -36.83508)
			(xy 308.483307 -36.834605) (xy 308.429603 -36.826924) (xy 308.377529 -36.811712) (xy 308.328136 -36.789276)
			(xy 308.282419 -36.760069) (xy 308.241301 -36.72468) (xy 308.205611 -36.683823) (xy 308.17607 -36.638321)
			(xy 308.153272 -36.589094) (xy 308.137679 -36.537133) (xy 308.129604 -36.483487) (xy 308.128924 -36.456366)
			(xy 308.128924 -36.45281) (xy 308.129485 -36.423839) (xy 308.138291 -36.366569) (xy 308.14645 -36.338764)
			(xy 308.147212 -36.336224) (xy 308.148736 -36.331398) (xy 308.15026 -36.318444) (xy 308.150531 -36.31029)
			(xy 308.146529 -36.294483) (xy 308.142386 -36.287456) (xy 308.123336 -36.260786) (xy 308.092348 -36.21786)
			(xy 308.08295 -36.208716) (xy 307.572664 -36.208716) (xy 307.56651 -36.208881) (xy 307.554559 -36.211827)
			(xy 307.549042 -36.214558) (xy 307.521483 -36.228299) (xy 307.463065 -36.24777) (xy 307.402284 -36.257641)
			(xy 307.371496 -36.258246) (xy 307.370734 -36.258246) (xy 307.343477 -36.257785) (xy 307.289517 -36.250032)
			(xy 307.23721 -36.234677) (xy 307.18762 -36.212034) (xy 307.141758 -36.182564) (xy 307.100557 -36.146867)
			(xy 307.064856 -36.105669) (xy 307.035382 -36.05981) (xy 307.012735 -36.010222) (xy 306.997376 -35.957916)
			(xy 306.989617 -35.903957) (xy 306.989617 -35.849443) (xy 306.997376 -35.795484) (xy 307.012735 -35.743178)
			(xy 307.035382 -35.69359) (xy 307.064856 -35.647731) (xy 307.100557 -35.606533) (xy 307.141758 -35.570836)
			(xy 307.18762 -35.541366) (xy 307.23721 -35.518723) (xy 307.289517 -35.503368) (xy 307.343477 -35.495615)
			(xy 307.370734 -35.49523) (xy 307.37175 -35.49523) (xy 307.402502 -35.495805) (xy 307.463211 -35.505656)
			(xy 307.521551 -35.525126) (xy 307.549042 -35.538918) (xy 307.554573 -35.541617) (xy 307.566513 -35.54458)
			(xy 307.572664 -35.54476) (xy 309.723536 -35.54476) (xy 309.732631 -35.544343) (xy 309.749646 -35.537901)
			(xy 309.763335 -35.525917) (xy 309.767986 -35.51809) (xy 309.770018 -35.51301) (xy 309.772747 -35.505979)
			(xy 309.774313 -35.490984) (xy 309.773066 -35.483546) (xy 309.771796 -35.476942) (xy 309.764684 -35.463734)
			(xy 307.35016 -33.04921) (xy 307.332126 -33.03044) (xy 307.301544 -32.988324) (xy 307.277916 -32.941948)
			(xy 307.261822 -32.89245) (xy 307.253657 -32.841046) (xy 307.253132 -32.815022) (xy 307.253132 -29.71292)
			(xy 307.253662 -29.686897) (xy 307.261832 -29.635496) (xy 307.277929 -29.586001) (xy 307.301557 -29.539627)
			(xy 307.332137 -29.497511) (xy 307.35016 -29.478732) (xy 307.941472 -28.88742) (xy 307.94759 -28.880736)
			(xy 307.95507 -28.864246) (xy 307.956335 -28.846183) (xy 307.954172 -28.837382) (xy 307.951886 -28.832048)
			(xy 307.948804 -28.825227) (xy 307.939392 -28.813597) (xy 307.933344 -28.809188) (xy 307.927756 -28.805378)
			(xy 307.913278 -28.80106) (xy 305.583082 -28.80106) (xy 305.556995 -28.800573) (xy 305.505465 -28.792403)
			(xy 305.455849 -28.776269) (xy 305.40937 -28.752568) (xy 305.367173 -28.721884) (xy 305.348386 -28.703778)
			(xy 304.324512 -27.67965) (xy 304.318533 -27.674209) (xy 304.304024 -27.667098) (xy 304.296064 -27.66568)
			(xy 304.288952 -27.665172) (xy 302.933354 -27.665172) (xy 302.90733 -27.664645) (xy 302.855926 -27.656479)
			(xy 302.806428 -27.640386) (xy 302.76005 -27.616761) (xy 302.71793 -27.586184) (xy 302.699166 -27.568144)
			(xy 301.74692 -26.615644) (xy 301.740312 -26.609708) (xy 301.724153 -26.602368) (xy 301.706459 -26.600992)
			(xy 301.689359 -26.605745) (xy 301.681896 -26.610564) (xy 301.669082 -26.620382) (xy 301.649919 -26.646342)
			(xy 301.639805 -26.676982) (xy 301.639224 -26.693114) (xy 301.639224 -27.342846) (xy 301.638734 -27.37283)
			(xy 301.630906 -27.432286) (xy 301.615385 -27.490211) (xy 301.592436 -27.545615) (xy 301.562452 -27.597549)
			(xy 301.525946 -27.645125) (xy 301.483541 -27.68753) (xy 301.435965 -27.724036) (xy 301.384031 -27.75402)
			(xy 301.328627 -27.776969) (xy 301.270702 -27.79249) (xy 301.211246 -27.800318) (xy 301.151278 -27.800318)
			(xy 301.091822 -27.79249) (xy 301.033897 -27.776969) (xy 300.978493 -27.75402) (xy 300.926559 -27.724036)
			(xy 300.878983 -27.68753) (xy 300.836578 -27.645125) (xy 300.800072 -27.597549) (xy 300.770088 -27.545615)
			(xy 300.747139 -27.490211) (xy 300.731618 -27.432286) (xy 300.72379 -27.37283) (xy 300.7233 -27.342846)
			(xy 300.7233 -26.479246) (xy 300.723831 -26.448026) (xy 300.732314 -26.386163) (xy 300.749116 -26.326025)
			(xy 300.773926 -26.268725) (xy 300.806284 -26.215322) (xy 300.845591 -26.166806) (xy 300.89112 -26.124074)
			(xy 300.942028 -26.087919) (xy 300.997373 -26.059008) (xy 301.026576 -26.047954) (xy 301.03699 -26.044144)
			(xy 301.05223 -26.029412) (xy 301.055532 -26.025602) (xy 301.05861 -26.021651) (xy 301.063349 -26.012828)
			(xy 301.06493 -26.008076) (xy 301.067724 -25.99563) (xy 301.067724 -25.995122) (xy 301.08398 -25.923494)
			(xy 301.085066 -25.915003) (xy 301.082217 -25.898132) (xy 301.078392 -25.890474) (xy 301.073312 -25.8826)
			(xy 300.678088 -25.487376) (xy 300.673008 -25.483058) (xy 300.63059 -25.453086) (xy 300.520862 -25.37587)
			(xy 300.514333 -25.371573) (xy 300.499462 -25.366794) (xy 300.491652 -25.366472) (xy 298.904914 -25.366472)
			(xy 298.901612 -25.366472) (xy 298.892594 -25.367424) (xy 298.876065 -25.37485) (xy 298.869354 -25.38095)
			(xy 298.79544 -25.455118) (xy 298.76369 -25.486868) (xy 298.75734 -25.497536) (xy 298.755562 -25.503378)
			(xy 298.747112 -25.528942) (xy 298.724029 -25.577585) (xy 298.694341 -25.622501) (xy 298.658636 -25.662801)
			(xy 298.617623 -25.697683) (xy 298.572116 -25.726457) (xy 298.523017 -25.748552) (xy 298.4713 -25.763528)
			(xy 298.417993 -25.77109) (xy 298.391072 -25.771602) (xy 298.363822 -25.771114) (xy 298.309878 -25.763355)
			(xy 298.257587 -25.747997) (xy 298.208013 -25.725354) (xy 298.162167 -25.695887) (xy 298.120981 -25.660195)
			(xy 298.085293 -25.619006) (xy 298.05583 -25.573157) (xy 298.033191 -25.523581) (xy 298.017838 -25.471289)
			(xy 298.010083 -25.417344) (xy 298.009564 -25.390094) (xy 298.00931 -25.390094) (xy 298.009767 -25.363157)
			(xy 298.017331 -25.309818) (xy 298.032322 -25.258072) (xy 298.054442 -25.208949) (xy 298.083252 -25.163426)
			(xy 298.118177 -25.122408) (xy 298.158525 -25.086709) (xy 298.203493 -25.057041) (xy 298.252187 -25.033992)
			(xy 298.277788 -25.025604) (xy 298.278042 -25.025604) (xy 298.28388 -25.023598) (xy 298.294423 -25.017184)
			(xy 298.29887 -25.012904) (xy 298.341288 -24.970486) (xy 298.34173 -24.96688) (xy 298.341737 -24.959614)
			(xy 298.341288 -24.956008) (xy 297.989498 -24.604218) (xy 297.964352 -24.578276) (xy 297.919937 -24.52129)
			(xy 297.882856 -24.45928) (xy 297.853672 -24.393186) (xy 297.832826 -24.324008) (xy 297.826176 -24.288496)
			(xy 297.822112 -24.263858) (xy 297.818061 -24.260144) (xy 297.808713 -24.254367) (xy 297.80357 -24.252428)
			(xy 297.736514 -24.231092) (xy 297.736006 -24.231092) (xy 297.723814 -24.227282) (xy 297.715178 -24.225504)
			(xy 297.708574 -24.224996) (xy 297.702986 -24.224996) (xy 297.693842 -24.228806) (xy 297.689278 -24.230813)
			(xy 297.680961 -24.236309) (xy 297.677332 -24.239728) (xy 297.49242 -24.42464) (xy 297.47365 -24.442674)
			(xy 297.431534 -24.473258) (xy 297.385158 -24.496888) (xy 297.335661 -24.512983) (xy 297.284256 -24.521149)
			(xy 297.258232 -24.521668) (xy 296.07002 -24.521668) (xy 296.065702 -24.523954) (xy 296.037276 -24.538868)
			(xy 295.976675 -24.560025) (xy 295.913392 -24.570772) (xy 295.881298 -24.571452) (xy 295.88079 -24.571452)
			(xy 295.853536 -24.570965) (xy 295.799583 -24.563207) (xy 295.747284 -24.547849) (xy 295.697702 -24.525205)
			(xy 295.651848 -24.495735) (xy 295.610654 -24.460039) (xy 295.574959 -24.418844) (xy 295.54549 -24.372989)
			(xy 295.522847 -24.323407) (xy 295.507491 -24.271107) (xy 295.499734 -24.217154) (xy 295.499734 -24.162646)
			(xy 295.507491 -24.108693) (xy 295.522847 -24.056393) (xy 295.54549 -24.006811) (xy 295.574959 -23.960956)
			(xy 295.610654 -23.919761) (xy 295.651848 -23.884065) (xy 295.697702 -23.854595) (xy 295.747284 -23.831951)
			(xy 295.799583 -23.816593) (xy 295.853536 -23.808835) (xy 295.88079 -23.808436) (xy 295.881044 -23.808436)
			(xy 295.905291 -23.808832) (xy 295.953392 -23.815004) (xy 296.000327 -23.827206) (xy 296.045344 -23.845241)
			(xy 296.066718 -23.856696) (xy 296.069512 -23.85822) (xy 297.099228 -23.85822) (xy 297.10253 -23.85822)
			(xy 297.111552 -23.857277) (xy 297.128094 -23.849863) (xy 297.134788 -23.843742) (xy 297.214798 -23.763478)
			(xy 297.253914 -23.724362) (xy 297.254168 -23.710646) (xy 297.252136 -23.701756) (xy 297.242738 -23.673562)
			(xy 297.242738 -23.673054) (xy 297.221402 -23.603712) (xy 297.214036 -23.597108) (xy 297.189398 -23.59279)
			(xy 297.15655 -23.586395) (xy 297.092475 -23.567079) (xy 297.031019 -23.540584) (xy 296.972985 -23.507256)
			(xy 296.919128 -23.46753) (xy 296.870151 -23.421923) (xy 296.826692 -23.37103) (xy 296.789319 -23.315515)
			(xy 296.758518 -23.256101) (xy 296.746168 -23.224998) (xy 296.737786 -23.203154) (xy 296.733753 -23.200571)
			(xy 296.724929 -23.196853) (xy 296.72026 -23.195788) (xy 296.670984 -23.185374) (xy 296.670476 -23.185374)
			(xy 296.634662 -23.177754) (xy 296.620438 -23.178008) (xy 296.358818 -23.439628) (xy 296.335242 -23.462575)
			(xy 296.283802 -23.503597) (xy 296.228092 -23.5386) (xy 296.168814 -23.567146) (xy 296.106712 -23.588876)
			(xy 296.042567 -23.603515) (xy 295.977187 -23.610881) (xy 295.94429 -23.611332) (xy 295.908862 -23.610797)
			(xy 295.838523 -23.602255) (xy 295.769727 -23.585297) (xy 295.703476 -23.560171) (xy 295.640737 -23.527242)
			(xy 295.582425 -23.486991) (xy 295.529389 -23.440004) (xy 295.482403 -23.386968) (xy 295.442153 -23.328654)
			(xy 295.409225 -23.265915) (xy 295.3841 -23.199663) (xy 295.367143 -23.130867) (xy 295.358603 -23.060528)
			(xy 295.358058 -23.0251) (xy 295.358519 -22.992204) (xy 295.365885 -22.926825) (xy 295.380525 -22.862682)
			(xy 295.402255 -22.800581) (xy 295.430801 -22.741304) (xy 295.465804 -22.685596) (xy 295.506824 -22.634157)
			(xy 295.529762 -22.610572) (xy 296.022522 -22.117812) (xy 296.046096 -22.094861) (xy 296.097534 -22.053832)
			(xy 296.153242 -22.01882) (xy 296.212521 -21.990266) (xy 296.274623 -21.968528) (xy 296.338769 -21.953881)
			(xy 296.404152 -21.946509) (xy 296.43705 -21.946108) (xy 296.458386 -21.946616) (xy 300.268894 -21.946616)
			(xy 300.270418 -21.94433) (xy 300.271434 -21.942806) (xy 300.301914 -21.892514) (xy 300.301914 -21.892006)
			(xy 300.317408 -21.866098) (xy 300.322234 -21.85416) (xy 300.323758 -21.842476) (xy 300.324012 -21.830792)
			(xy 300.318424 -21.818854) (xy 300.317916 -21.817838) (xy 300.304016 -21.790283) (xy 300.284331 -21.731793)
			(xy 300.27433 -21.670894) (xy 300.27372 -21.640038) (xy 300.27372 -21.63572) (xy 300.274488 -21.607317)
			(xy 300.283399 -21.551204) (xy 300.300537 -21.497034) (xy 300.32552 -21.446006) (xy 300.357798 -21.399248)
			(xy 300.376844 -21.378164) (xy 300.383702 -21.371052) (xy 300.387258 -21.362162) (xy 300.389798 -21.353018)
			(xy 300.39056 -21.344128) (xy 300.39056 -21.27377) (xy 300.390496 -21.269636) (xy 300.389226 -21.261468)
			(xy 300.38802 -21.257514) (xy 300.387258 -21.255736) (xy 300.383956 -21.2471) (xy 300.376844 -21.23948)
			(xy 300.357571 -21.218154) (xy 300.325 -21.170791) (xy 300.299904 -21.119078) (xy 300.28285 -21.064186)
			(xy 300.274225 -21.007356) (xy 300.274222 -20.949876) (xy 300.282843 -20.893045) (xy 300.299893 -20.838151)
			(xy 300.324984 -20.786437) (xy 300.35755 -20.739071) (xy 300.376844 -20.717764) (xy 300.383956 -20.710144)
			(xy 300.387258 -20.701508) (xy 300.38802 -20.69973) (xy 300.389252 -20.695781) (xy 300.390529 -20.68761)
			(xy 300.39056 -20.683474) (xy 300.39056 -20.61337) (xy 300.390496 -20.609236) (xy 300.389226 -20.601068)
			(xy 300.38802 -20.597114) (xy 300.387258 -20.595336) (xy 300.383956 -20.5867) (xy 300.376844 -20.57908)
			(xy 300.357571 -20.557754) (xy 300.325 -20.510391) (xy 300.299904 -20.458678) (xy 300.28285 -20.403786)
			(xy 300.274225 -20.346956) (xy 300.274222 -20.289476) (xy 300.282843 -20.232645) (xy 300.299893 -20.177751)
			(xy 300.324984 -20.126037) (xy 300.35755 -20.078671) (xy 300.376844 -20.057364) (xy 300.383956 -20.049744)
			(xy 300.387258 -20.041108) (xy 300.38802 -20.03933) (xy 300.389252 -20.035381) (xy 300.390529 -20.02721)
			(xy 300.39056 -20.023074) (xy 300.39056 -19.95297) (xy 300.390496 -19.948836) (xy 300.389226 -19.940668)
			(xy 300.38802 -19.936714) (xy 300.387258 -19.934936) (xy 300.383956 -19.9263) (xy 300.376844 -19.91868)
			(xy 300.357571 -19.897354) (xy 300.325 -19.849991) (xy 300.299904 -19.798278) (xy 300.28285 -19.743386)
			(xy 300.274225 -19.686556) (xy 300.274222 -19.629076) (xy 300.282843 -19.572245) (xy 300.299893 -19.517351)
			(xy 300.324984 -19.465637) (xy 300.35755 -19.418271) (xy 300.376844 -19.396964) (xy 300.383956 -19.389344)
			(xy 300.387258 -19.380708) (xy 300.38802 -19.37893) (xy 300.389252 -19.374981) (xy 300.390529 -19.36681)
			(xy 300.39056 -19.362674) (xy 300.39056 -19.29257) (xy 300.390496 -19.288436) (xy 300.389226 -19.280268)
			(xy 300.38802 -19.276314) (xy 300.387258 -19.274536) (xy 300.383956 -19.2659) (xy 300.376844 -19.25828)
			(xy 300.357576 -19.236952) (xy 300.325014 -19.189588) (xy 300.299925 -19.137876) (xy 300.282876 -19.082986)
			(xy 300.274252 -19.02616) (xy 300.27372 -18.997422) (xy 300.274206 -18.970171) (xy 300.281962 -18.916223)
			(xy 300.297317 -18.863928) (xy 300.319959 -18.814351) (xy 300.349425 -18.768501) (xy 300.385116 -18.72731)
			(xy 300.426307 -18.691619) (xy 300.472157 -18.662153) (xy 300.521734 -18.639511) (xy 300.574029 -18.624156)
			(xy 300.627977 -18.6164) (xy 300.682479 -18.6164) (xy 300.736427 -18.624156) (xy 300.788722 -18.639511)
			(xy 300.838299 -18.662153) (xy 300.884149 -18.691619) (xy 300.92534 -18.72731) (xy 300.961031 -18.768501)
			(xy 300.990497 -18.814351) (xy 301.013139 -18.863928) (xy 301.028494 -18.916223) (xy 301.03625 -18.970171)
			(xy 301.036736 -18.997422) (xy 301.036213 -19.02616) (xy 301.027587 -19.082985) (xy 301.010532 -19.137873)
			(xy 300.985435 -19.18958) (xy 300.952864 -19.236937) (xy 300.933612 -19.25828) (xy 300.9265 -19.2659)
			(xy 300.923198 -19.274536) (xy 300.922436 -19.276314) (xy 300.921206 -19.280263) (xy 300.919935 -19.288434)
			(xy 300.919896 -19.29257) (xy 300.919896 -19.362674) (xy 300.919963 -19.366807) (xy 300.921239 -19.374974)
			(xy 300.922436 -19.37893) (xy 300.923198 -19.380708) (xy 300.9265 -19.389344) (xy 300.933612 -19.396964)
			(xy 300.95288 -19.418292) (xy 300.985439 -19.465654) (xy 301.010525 -19.517365) (xy 301.02757 -19.572254)
			(xy 301.036189 -19.629079) (xy 301.036186 -19.686553) (xy 301.027563 -19.743377) (xy 301.010513 -19.798265)
			(xy 300.985422 -19.849973) (xy 300.952859 -19.897334) (xy 300.933612 -19.91868) (xy 300.9265 -19.9263)
			(xy 300.923198 -19.934936) (xy 300.922436 -19.936714) (xy 300.921206 -19.940663) (xy 300.919935 -19.948834)
			(xy 300.919896 -19.95297) (xy 300.919896 -20.023074) (xy 300.919963 -20.027207) (xy 300.921239 -20.035374)
			(xy 300.922436 -20.03933) (xy 300.923198 -20.041108) (xy 300.9265 -20.049744) (xy 300.933612 -20.057364)
			(xy 300.95288 -20.078692) (xy 300.985439 -20.126054) (xy 301.010525 -20.177765) (xy 301.02757 -20.232654)
			(xy 301.036189 -20.289479) (xy 301.036186 -20.346953) (xy 301.027563 -20.403777) (xy 301.010513 -20.458665)
			(xy 300.985422 -20.510373) (xy 300.952859 -20.557734) (xy 300.933612 -20.57908) (xy 300.9265 -20.5867)
			(xy 300.923198 -20.595336) (xy 300.922436 -20.597114) (xy 300.921206 -20.601063) (xy 300.919935 -20.609234)
			(xy 300.919896 -20.61337) (xy 300.919896 -20.683474) (xy 300.919963 -20.687607) (xy 300.921239 -20.695774)
			(xy 300.922436 -20.69973) (xy 300.923198 -20.701508) (xy 300.9265 -20.710144) (xy 300.933612 -20.717764)
			(xy 300.95288 -20.739092) (xy 300.985439 -20.786454) (xy 301.010525 -20.838165) (xy 301.02757 -20.893054)
			(xy 301.036189 -20.949879) (xy 301.036186 -21.007353) (xy 301.027563 -21.064177) (xy 301.010513 -21.119065)
			(xy 300.985422 -21.170773) (xy 300.952859 -21.218134) (xy 300.933612 -21.23948) (xy 300.9265 -21.2471)
			(xy 300.923198 -21.255736) (xy 300.922436 -21.257514) (xy 300.921206 -21.261463) (xy 300.919935 -21.269634)
			(xy 300.919896 -21.27377) (xy 300.919896 -21.344128) (xy 300.920658 -21.353018) (xy 300.923198 -21.362162)
			(xy 300.926754 -21.371052) (xy 300.93412 -21.378672) (xy 300.95306 -21.39972) (xy 300.985153 -21.446369)
			(xy 301.009999 -21.497248) (xy 301.027052 -21.551241) (xy 301.035939 -21.607161) (xy 301.036736 -21.635466)
			(xy 301.036736 -21.63953) (xy 301.036135 -21.67047) (xy 301.026157 -21.73154) (xy 301.006467 -21.790204)
			(xy 300.99254 -21.817838) (xy 300.991016 -21.820632) (xy 300.988895 -21.825769) (xy 300.98671 -21.836664)
			(xy 300.986698 -21.842222) (xy 300.986952 -21.855684) (xy 301.008542 -21.892006) (xy 301.008542 -21.892514)
			(xy 301.039022 -21.942552) (xy 301.041816 -21.946616) (xy 305.452526 -21.946616) (xy 305.460236 -21.946388)
			(xy 305.474973 -21.941864) (xy 305.481482 -21.937726) (xy 305.485546 -21.934424) (xy 305.8287 -21.59127)
			(xy 305.829208 -21.583904) (xy 305.829208 -21.567902) (xy 305.82616 -21.556218) (xy 305.821842 -21.547836)
			(xy 305.80831 -21.520574) (xy 305.789117 -21.462819) (xy 305.779331 -21.402751) (xy 305.778662 -21.372322)
			(xy 305.778662 -21.36394) (xy 305.779657 -21.337046) (xy 305.788277 -21.283923) (xy 305.804279 -21.232539)
			(xy 305.827345 -21.183914) (xy 305.857017 -21.139015) (xy 305.892706 -21.098733) (xy 305.933704 -21.063868)
			(xy 305.979195 -21.035112) (xy 306.028276 -21.013036) (xy 306.079974 -20.998079) (xy 306.133261 -20.990537)
			(xy 306.16017 -20.990052) (xy 306.160424 -20.990052) (xy 306.176426 -20.990306) (xy 306.187094 -20.990814)
			(xy 306.196238 -20.987258) (xy 306.200603 -20.985508) (xy 306.208657 -20.980653) (xy 306.21224 -20.977606)
			(xy 306.225956 -20.964652) (xy 306.226464 -20.964144) (xy 306.268374 -20.923758) (xy 306.272184 -20.919186)
			(xy 306.272184 -19.452844) (xy 306.272749 -19.417134) (xy 306.281497 -19.346249) (xy 306.298794 -19.276954)
			(xy 306.324386 -19.210274) (xy 306.357891 -19.147199) (xy 306.398814 -19.088663) (xy 306.446548 -19.035535)
			(xy 306.473098 -19.011646) (xy 306.483766 -19.002248) (xy 306.485798 -18.99793) (xy 306.487806 -18.993217)
			(xy 306.490108 -18.983235) (xy 306.49037 -18.978118) (xy 306.491894 -18.922238) (xy 306.491894 -18.921476)
			(xy 306.492402 -18.906998) (xy 306.443888 -18.858738) (xy 306.417181 -18.831161) (xy 306.370473 -18.770235)
			(xy 306.332125 -18.703728) (xy 306.316888 -18.668492) (xy 306.302858 -18.633086) (xy 306.283038 -18.55955)
			(xy 306.27292 -18.484066) (xy 306.272184 -18.445988) (xy 306.272184 -18.44421) (xy 306.272718 -18.408796)
			(xy 306.281254 -18.338484) (xy 306.298202 -18.269714) (xy 306.323317 -18.203488) (xy 306.35623 -18.140772)
			(xy 306.396463 -18.08248) (xy 306.443428 -18.029462) (xy 306.496442 -17.982492) (xy 306.55473 -17.942255)
			(xy 306.617444 -17.909336) (xy 306.683668 -17.884217) (xy 306.752437 -17.867263) (xy 306.822748 -17.858721)
			(xy 306.858162 -17.858232) (xy 306.86756 -17.858232) (xy 306.904355 -17.85943) (xy 306.977231 -17.869873)
			(xy 307.04823 -17.889347) (xy 307.082444 -17.902936) (xy 307.117673 -17.918188) (xy 307.184176 -17.956538)
			(xy 307.245105 -18.003238) (xy 307.27269 -18.029936) (xy 307.603398 -18.360898) (xy 307.841142 -18.598642)
			(xy 307.86404 -18.622206) (xy 307.904995 -18.673589) (xy 307.939944 -18.729232) (xy 307.968447 -18.788435)
			(xy 307.990149 -18.850456) (xy 308.004774 -18.914515) (xy 308.012141 -18.979808) (xy 308.012592 -19.012662)
			(xy 308.012592 -21.474684) (xy 308.015523 -21.478427) (xy 308.022561 -21.484816) (xy 308.026562 -21.487384)
			(xy 308.032404 -21.49094) (xy 308.11978 -21.527516) (xy 308.126396 -21.530025) (xy 308.140443 -21.53169)
			(xy 308.147466 -21.530818) (xy 308.736746 -20.941538) (xy 308.737253 -20.937744) (xy 308.737256 -20.930091)
			(xy 308.736746 -20.926298) (xy 308.736746 -20.925536) (xy 308.731412 -20.892516) (xy 308.723538 -20.842986)
			(xy 308.7207 -20.831921) (xy 308.706813 -20.813811) (xy 308.696868 -20.808188) (xy 308.69001 -20.804632)
			(xy 308.664235 -20.79026) (xy 308.617059 -20.754808) (xy 308.575896 -20.712522) (xy 308.541726 -20.664409)
			(xy 308.515361 -20.611613) (xy 308.49743 -20.555391) (xy 308.488359 -20.49708) (xy 308.487826 -20.467574)
			(xy 308.488291 -20.440323) (xy 308.496051 -20.386377) (xy 308.51141 -20.334084) (xy 308.534054 -20.284509)
			(xy 308.563524 -20.238662) (xy 308.599218 -20.197475) (xy 308.64041 -20.161788) (xy 308.686262 -20.132326)
			(xy 308.73584 -20.109689) (xy 308.788136 -20.094339) (xy 308.842083 -20.086587) (xy 308.869334 -20.086066)
			(xy 308.896481 -20.086547) (xy 308.950225 -20.094248) (xy 309.002334 -20.109491) (xy 309.051757 -20.131966)
			(xy 309.097494 -20.161221) (xy 309.138622 -20.196665) (xy 309.174311 -20.237581) (xy 309.203838 -20.283142)
			(xy 309.226609 -20.33243) (xy 309.242162 -20.384448) (xy 309.250184 -20.438145) (xy 309.250842 -20.465288)
			(xy 309.250842 -20.467828) (xy 309.250245 -20.498333) (xy 309.240552 -20.558568) (xy 309.231538 -20.587716)
			(xy 309.230014 -20.592288) (xy 309.228744 -20.601432) (xy 309.228744 -20.601686) (xy 309.22722 -20.611338)
			(xy 309.229506 -20.62099) (xy 309.23079 -20.625741) (xy 309.234884 -20.634689) (xy 309.237634 -20.63877)
			(xy 309.258716 -20.668488) (xy 309.267352 -20.677886) (xy 309.273896 -20.682986) (xy 309.289315 -20.689088)
			(xy 309.297578 -20.689824) (xy 310.840628 -20.689824) (xy 310.873484 -20.690264) (xy 310.938783 -20.697613)
			(xy 311.002849 -20.712228) (xy 311.039733 -20.72513) (xy 315.380636 -20.72513) (xy 315.384606 -20.594996)
			(xy 315.396502 -20.465346) (xy 315.416281 -20.336663) (xy 315.443867 -20.209424) (xy 315.47916 -20.084105)
			(xy 315.522026 -19.961169) (xy 315.572308 -19.841076) (xy 315.629817 -19.724272) (xy 315.694341 -19.61119)
			(xy 315.765638 -19.502253) (xy 315.843443 -19.397865) (xy 315.927468 -19.298414) (xy 316.0174 -19.204271)
			(xy 316.112904 -19.115786) (xy 316.213624 -19.033287) (xy 316.319186 -18.957082) (xy 316.429198 -18.887455)
			(xy 316.54325 -18.824664) (xy 316.660918 -18.768942) (xy 316.781764 -18.720498) (xy 316.905339 -18.679511)
			(xy 317.031182 -18.646134) (xy 317.158827 -18.620491) (xy 317.287797 -18.602677) (xy 317.417613 -18.592759)
			(xy 317.547792 -18.590774) (xy 317.677851 -18.596728) (xy 317.807304 -18.610601) (xy 317.935671 -18.632339)
			(xy 318.062474 -18.661863) (xy 318.187241 -18.699062) (xy 318.309508 -18.743798) (xy 318.428821 -18.795906)
			(xy 318.544734 -18.855189) (xy 318.656819 -18.92143) (xy 318.764656 -18.99438) (xy 318.867845 -19.073768)
			(xy 318.966003 -19.1593) (xy 319.058764 -19.250657) (xy 319.145783 -19.347499) (xy 319.226736 -19.449466)
			(xy 319.301322 -19.556178) (xy 319.369263 -19.667239) (xy 319.430308 -19.782235) (xy 319.484229 -19.900739)
			(xy 319.530824 -20.02231) (xy 319.569922 -20.146495) (xy 319.601376 -20.272833) (xy 319.62507 -20.400854)
			(xy 319.640914 -20.53008) (xy 319.648852 -20.660033) (xy 319.649348 -20.72513) (xy 319.648852 -20.790227)
			(xy 319.640914 -20.92018) (xy 319.62507 -21.049406) (xy 319.601376 -21.177427) (xy 319.569922 -21.303765)
			(xy 319.530824 -21.42795) (xy 319.484229 -21.549521) (xy 319.430308 -21.668025) (xy 319.369263 -21.783021)
			(xy 319.301322 -21.894082) (xy 319.226736 -22.000794) (xy 319.145783 -22.102761) (xy 319.058764 -22.199603)
			(xy 318.966003 -22.29096) (xy 318.867845 -22.376492) (xy 318.764656 -22.45588) (xy 318.656819 -22.52883)
			(xy 318.544734 -22.595071) (xy 318.428821 -22.654354) (xy 318.309508 -22.706462) (xy 318.187241 -22.751198)
			(xy 318.062474 -22.788397) (xy 317.935671 -22.817921) (xy 317.807304 -22.839659) (xy 317.677851 -22.853532)
			(xy 317.547792 -22.859486) (xy 317.417613 -22.857501) (xy 317.287797 -22.847583) (xy 317.158827 -22.829769)
			(xy 317.031182 -22.804126) (xy 316.905339 -22.770749) (xy 316.781764 -22.729762) (xy 316.660918 -22.681318)
			(xy 316.54325 -22.625596) (xy 316.429198 -22.562805) (xy 316.319186 -22.493178) (xy 316.213624 -22.416973)
			(xy 316.112904 -22.334474) (xy 316.0174 -22.245989) (xy 315.927468 -22.151846) (xy 315.843443 -22.052395)
			(xy 315.765638 -21.948007) (xy 315.694341 -21.83907) (xy 315.629817 -21.725988) (xy 315.572308 -21.609184)
			(xy 315.522026 -21.489091) (xy 315.47916 -21.366155) (xy 315.443867 -21.240836) (xy 315.416281 -21.113597)
			(xy 315.396502 -20.984914) (xy 315.384606 -20.855264) (xy 315.380636 -20.72513) (xy 311.039733 -20.72513)
			(xy 311.064876 -20.733925) (xy 311.124083 -20.76243) (xy 311.179727 -20.797385) (xy 311.231106 -20.83835)
			(xy 311.254648 -20.861274) (xy 311.496964 -21.10359) (xy 311.834784 -21.441156) (xy 311.85773 -21.464711)
			(xy 311.89875 -21.51611) (xy 311.933754 -21.571781) (xy 311.9623 -21.631023) (xy 311.984029 -21.693091)
			(xy 311.998668 -21.757202) (xy 312.006032 -21.822549) (xy 312.006372 -21.847048) (xy 312.272678 -21.847048)
			(xy 312.276749 -21.791426) (xy 312.288875 -21.736989) (xy 312.308798 -21.684898) (xy 312.336094 -21.636263)
			(xy 312.37018 -21.59212) (xy 312.410329 -21.553411) (xy 312.455687 -21.52096) (xy 312.505287 -21.495459)
			(xy 312.558071 -21.477452) (xy 312.612914 -21.467322) (xy 312.668648 -21.465285) (xy 312.724085 -21.471385)
			(xy 312.778042 -21.485491) (xy 312.829371 -21.507303) (xy 312.876977 -21.536357) (xy 312.919845 -21.572032)
			(xy 312.957062 -21.613569) (xy 312.987835 -21.660082) (xy 313.011507 -21.710579) (xy 313.027575 -21.763986)
			(xy 313.035695 -21.819162) (xy 313.036204 -21.847048) (xy 313.035695 -21.874934) (xy 313.027575 -21.93011)
			(xy 313.011507 -21.983517) (xy 312.987835 -22.034014) (xy 312.957062 -22.080527) (xy 312.919845 -22.122064)
			(xy 312.876977 -22.157739) (xy 312.829371 -22.186793) (xy 312.778042 -22.208605) (xy 312.724085 -22.222711)
			(xy 312.668648 -22.228811) (xy 312.612914 -22.226774) (xy 312.558071 -22.216644) (xy 312.505287 -22.198637)
			(xy 312.455687 -22.173136) (xy 312.410329 -22.140685) (xy 312.37018 -22.101976) (xy 312.336094 -22.057833)
			(xy 312.308798 -22.009198) (xy 312.288875 -21.957107) (xy 312.276749 -21.90267) (xy 312.272678 -21.847048)
			(xy 312.006372 -21.847048) (xy 312.006488 -21.85543) (xy 312.006488 -21.869908) (xy 312.006234 -21.87575)
			(xy 312.004545 -21.910354) (xy 311.994032 -21.978835) (xy 311.975512 -22.045596) (xy 311.949245 -22.109707)
			(xy 311.915598 -22.170271) (xy 311.875039 -22.226441) (xy 311.828137 -22.277434) (xy 311.775546 -22.322537)
			(xy 311.718001 -22.36112) (xy 311.656305 -22.392644) (xy 311.591321 -22.416669) (xy 311.523956 -22.432859)
			(xy 311.455152 -22.440987) (xy 311.42051 -22.441408) (xy 311.387636 -22.440981) (xy 311.322298 -22.43365)
			(xy 311.258193 -22.419046) (xy 311.196127 -22.397353) (xy 311.136882 -22.368843) (xy 311.081204 -22.333876)
			(xy 311.029793 -22.292892) (xy 311.006236 -22.269958) (xy 310.93537 -22.199092) (xy 310.925464 -22.198584)
			(xy 310.89473 -22.224238) (xy 310.868294 -22.245837) (xy 310.811286 -22.283397) (xy 310.750299 -22.314074)
			(xy 310.686158 -22.337454) (xy 310.619734 -22.353219) (xy 310.551928 -22.361154) (xy 310.517794 -22.361652)
			(xy 310.36006 -22.361652) (xy 310.350916 -22.370542) (xy 310.332374 -22.393656) (xy 310.299354 -22.43455)
			(xy 310.296814 -22.438614) (xy 310.293004 -22.447758) (xy 310.28894 -22.463506) (xy 310.29148 -22.474936)
			(xy 310.295327 -22.494203) (xy 310.299528 -22.533269) (xy 310.299862 -22.552914) (xy 310.299862 -22.553422)
			(xy 310.299862 -22.559264) (xy 310.299099 -22.586806) (xy 310.290626 -22.641248) (xy 310.274412 -22.693906)
			(xy 310.250795 -22.743685) (xy 310.220266 -22.789552) (xy 310.183459 -22.830552) (xy 310.14114 -22.865833)
			(xy 310.094187 -22.894663) (xy 310.043577 -22.916442) (xy 309.990361 -22.930718) (xy 309.963058 -22.934422)
			(xy 309.948834 -22.935946) (xy 309.91556 -22.937216) (xy 309.913528 -22.937216) (xy 309.888496 -22.936488)
			(xy 309.838939 -22.929275) (xy 309.790751 -22.91564) (xy 309.744763 -22.895815) (xy 309.701764 -22.870144)
			(xy 309.68188 -22.85492) (xy 309.665116 -22.84095) (xy 309.663592 -22.83968) (xy 309.661814 -22.838156)
			(xy 309.653686 -22.832822) (xy 309.643267 -22.827186) (xy 309.619693 -22.825208) (xy 309.608474 -22.829012)
			(xy 309.584598 -22.839426) (xy 309.58409 -22.839426) (xy 309.52313 -22.866604) (xy 309.521098 -22.86762)
			(xy 309.507382 -22.874478) (xy 309.502556 -22.882352) (xy 309.502556 -23.965154) (xy 310.277254 -23.965154)
			(xy 310.281325 -23.909532) (xy 310.293451 -23.855095) (xy 310.313374 -23.803004) (xy 310.34067 -23.754369)
			(xy 310.374756 -23.710226) (xy 310.414905 -23.671517) (xy 310.460263 -23.639066) (xy 310.509863 -23.613565)
			(xy 310.562647 -23.595558) (xy 310.61749 -23.585428) (xy 310.673224 -23.583391) (xy 310.728661 -23.589491)
			(xy 310.782618 -23.603597) (xy 310.833947 -23.625409) (xy 310.881553 -23.654463) (xy 310.924421 -23.690138)
			(xy 310.961638 -23.731675) (xy 310.992411 -23.778188) (xy 311.016083 -23.828685) (xy 311.032151 -23.882092)
			(xy 311.040271 -23.937268) (xy 311.040446 -23.946866) (xy 311.2803 -23.946866) (xy 311.284371 -23.891244)
			(xy 311.296497 -23.836807) (xy 311.31642 -23.784716) (xy 311.343716 -23.736081) (xy 311.377802 -23.691938)
			(xy 311.417951 -23.653229) (xy 311.463309 -23.620778) (xy 311.512909 -23.595277) (xy 311.565693 -23.57727)
			(xy 311.620536 -23.56714) (xy 311.67627 -23.565103) (xy 311.731707 -23.571203) (xy 311.785664 -23.585309)
			(xy 311.836993 -23.607121) (xy 311.884599 -23.636175) (xy 311.927467 -23.67185) (xy 311.964684 -23.713387)
			(xy 311.995457 -23.7599) (xy 312.019129 -23.810397) (xy 312.035197 -23.863804) (xy 312.043317 -23.91898)
			(xy 312.043826 -23.946866) (xy 312.043386 -23.970996) (xy 312.272678 -23.970996) (xy 312.276749 -23.915374)
			(xy 312.288875 -23.860937) (xy 312.308798 -23.808846) (xy 312.336094 -23.760211) (xy 312.37018 -23.716068)
			(xy 312.410329 -23.677359) (xy 312.455687 -23.644908) (xy 312.505287 -23.619407) (xy 312.558071 -23.6014)
			(xy 312.612914 -23.59127) (xy 312.668648 -23.589233) (xy 312.724085 -23.595333) (xy 312.778042 -23.609439)
			(xy 312.829371 -23.631251) (xy 312.876977 -23.660305) (xy 312.919845 -23.69598) (xy 312.957062 -23.737517)
			(xy 312.987835 -23.78403) (xy 313.011507 -23.834527) (xy 313.027575 -23.887934) (xy 313.035695 -23.94311)
			(xy 313.036204 -23.970996) (xy 313.035695 -23.998882) (xy 313.027575 -24.054058) (xy 313.011507 -24.107465)
			(xy 312.987835 -24.157962) (xy 312.957062 -24.204475) (xy 312.919845 -24.246012) (xy 312.876977 -24.281687)
			(xy 312.829371 -24.310741) (xy 312.778042 -24.332553) (xy 312.724085 -24.346659) (xy 312.668648 -24.352759)
			(xy 312.612914 -24.350722) (xy 312.558071 -24.340592) (xy 312.505287 -24.322585) (xy 312.455687 -24.297084)
			(xy 312.410329 -24.264633) (xy 312.37018 -24.225924) (xy 312.336094 -24.181781) (xy 312.308798 -24.133146)
			(xy 312.288875 -24.081055) (xy 312.276749 -24.026618) (xy 312.272678 -23.970996) (xy 312.043386 -23.970996)
			(xy 312.043317 -23.974752) (xy 312.035197 -24.029928) (xy 312.019129 -24.083335) (xy 311.995457 -24.133832)
			(xy 311.964684 -24.180345) (xy 311.927467 -24.221882) (xy 311.884599 -24.257557) (xy 311.836993 -24.286611)
			(xy 311.785664 -24.308423) (xy 311.731707 -24.322529) (xy 311.67627 -24.328629) (xy 311.620536 -24.326592)
			(xy 311.565693 -24.316462) (xy 311.512909 -24.298455) (xy 311.463309 -24.272954) (xy 311.417951 -24.240503)
			(xy 311.377802 -24.201794) (xy 311.343716 -24.157651) (xy 311.31642 -24.109016) (xy 311.296497 -24.056925)
			(xy 311.284371 -24.002488) (xy 311.2803 -23.946866) (xy 311.040446 -23.946866) (xy 311.04078 -23.965154)
			(xy 311.040271 -23.99304) (xy 311.032151 -24.048216) (xy 311.016083 -24.101623) (xy 310.992411 -24.15212)
			(xy 310.961638 -24.198633) (xy 310.924421 -24.24017) (xy 310.881553 -24.275845) (xy 310.833947 -24.304899)
			(xy 310.782618 -24.326711) (xy 310.728661 -24.340817) (xy 310.673224 -24.346917) (xy 310.61749 -24.34488)
			(xy 310.562647 -24.33475) (xy 310.509863 -24.316743) (xy 310.460263 -24.291242) (xy 310.414905 -24.258791)
			(xy 310.374756 -24.220082) (xy 310.34067 -24.175939) (xy 310.313374 -24.127304) (xy 310.293451 -24.075213)
			(xy 310.281325 -24.020776) (xy 310.277254 -23.965154) (xy 309.502556 -23.965154) (xy 309.502556 -24.807418)
			(xy 316.57112 -24.807418) (xy 316.575191 -24.751796) (xy 316.587317 -24.697359) (xy 316.60724 -24.645268)
			(xy 316.634536 -24.596633) (xy 316.668622 -24.55249) (xy 316.708771 -24.513781) (xy 316.754129 -24.48133)
			(xy 316.803729 -24.455829) (xy 316.856513 -24.437822) (xy 316.911356 -24.427692) (xy 316.96709 -24.425655)
			(xy 317.022527 -24.431755) (xy 317.076484 -24.445861) (xy 317.127813 -24.467673) (xy 317.175419 -24.496727)
			(xy 317.218287 -24.532402) (xy 317.255504 -24.573939) (xy 317.286277 -24.620452) (xy 317.309949 -24.670949)
			(xy 317.326017 -24.724356) (xy 317.334137 -24.779532) (xy 317.334646 -24.807418) (xy 317.334137 -24.835304)
			(xy 317.326017 -24.89048) (xy 317.309949 -24.943887) (xy 317.286277 -24.994384) (xy 317.255504 -25.040897)
			(xy 317.218287 -25.082434) (xy 317.175419 -25.118109) (xy 317.127813 -25.147163) (xy 317.076484 -25.168975)
			(xy 317.022527 -25.183081) (xy 316.96709 -25.189181) (xy 316.911356 -25.187144) (xy 316.856513 -25.177014)
			(xy 316.803729 -25.159007) (xy 316.754129 -25.133506) (xy 316.708771 -25.101055) (xy 316.668622 -25.062346)
			(xy 316.634536 -25.018203) (xy 316.60724 -24.969568) (xy 316.587317 -24.917477) (xy 316.575191 -24.86304)
			(xy 316.57112 -24.807418) (xy 309.502556 -24.807418) (xy 309.502556 -25.912572) (xy 309.502634 -25.916781)
			(xy 309.504036 -25.925082) (xy 309.50535 -25.929082) (xy 309.50789 -25.936448) (xy 309.512462 -25.942544)
			(xy 309.53837 -25.950418) (xy 309.561935 -25.958149) (xy 309.607016 -25.978822) (xy 309.649081 -26.005095)
			(xy 309.684016 -26.03373) (xy 315.467744 -26.03373) (xy 315.471815 -25.978108) (xy 315.483941 -25.923671)
			(xy 315.503864 -25.87158) (xy 315.53116 -25.822945) (xy 315.565246 -25.778802) (xy 315.605395 -25.740093)
			(xy 315.650753 -25.707642) (xy 315.700353 -25.682141) (xy 315.753137 -25.664134) (xy 315.80798 -25.654004)
			(xy 315.863714 -25.651967) (xy 315.919151 -25.658067) (xy 315.973108 -25.672173) (xy 316.024437 -25.693985)
			(xy 316.072043 -25.723039) (xy 316.114911 -25.758714) (xy 316.152128 -25.800251) (xy 316.182901 -25.846764)
			(xy 316.206573 -25.897261) (xy 316.222641 -25.950668) (xy 316.230761 -26.005844) (xy 316.23127 -26.03373)
			(xy 316.230761 -26.061616) (xy 316.222641 -26.116792) (xy 316.206573 -26.170199) (xy 316.182901 -26.220696)
			(xy 316.152128 -26.267209) (xy 316.114911 -26.308746) (xy 316.072043 -26.344421) (xy 316.024437 -26.373475)
			(xy 315.973108 -26.395287) (xy 315.919151 -26.409393) (xy 315.863714 -26.415493) (xy 315.80798 -26.413456)
			(xy 315.753137 -26.403326) (xy 315.700353 -26.385319) (xy 315.650753 -26.359818) (xy 315.605395 -26.327367)
			(xy 315.565246 -26.288658) (xy 315.53116 -26.244515) (xy 315.503864 -26.19588) (xy 315.483941 -26.143789)
			(xy 315.471815 -26.089352) (xy 315.467744 -26.03373) (xy 309.684016 -26.03373) (xy 309.687438 -26.036535)
			(xy 309.70474 -26.054304) (xy 309.725962 -26.077634) (xy 309.761305 -26.129866) (xy 309.787704 -26.18714)
			(xy 309.796688 -26.217372) (xy 309.798974 -26.2255) (xy 310.763666 -27.190192) (xy 310.781783 -27.20897)
			(xy 310.812478 -27.251165) (xy 310.836187 -27.297646) (xy 310.852327 -27.347265) (xy 310.860498 -27.398799)
			(xy 310.860948 -27.424888) (xy 310.860948 -28.139136) (xy 312.597798 -28.139136) (xy 312.601869 -28.083514)
			(xy 312.613995 -28.029077) (xy 312.633918 -27.976986) (xy 312.661214 -27.928351) (xy 312.6953 -27.884208)
			(xy 312.735449 -27.845499) (xy 312.780807 -27.813048) (xy 312.830407 -27.787547) (xy 312.883191 -27.76954)
			(xy 312.938034 -27.75941) (xy 312.993768 -27.757373) (xy 313.049205 -27.763473) (xy 313.103162 -27.777579)
			(xy 313.154491 -27.799391) (xy 313.202097 -27.828445) (xy 313.244965 -27.86412) (xy 313.282182 -27.905657)
			(xy 313.312955 -27.95217) (xy 313.336627 -28.002667) (xy 313.352695 -28.056074) (xy 313.360815 -28.11125)
			(xy 313.361324 -28.139136) (xy 313.867798 -28.139136) (xy 313.871869 -28.083514) (xy 313.883995 -28.029077)
			(xy 313.903918 -27.976986) (xy 313.931214 -27.928351) (xy 313.9653 -27.884208) (xy 314.005449 -27.845499)
			(xy 314.050807 -27.813048) (xy 314.100407 -27.787547) (xy 314.153191 -27.76954) (xy 314.208034 -27.75941)
			(xy 314.263768 -27.757373) (xy 314.319205 -27.763473) (xy 314.373162 -27.777579) (xy 314.424491 -27.799391)
			(xy 314.472097 -27.828445) (xy 314.514965 -27.86412) (xy 314.552182 -27.905657) (xy 314.582955 -27.95217)
			(xy 314.606627 -28.002667) (xy 314.622695 -28.056074) (xy 314.630815 -28.11125) (xy 314.631324 -28.139136)
			(xy 314.630815 -28.167022) (xy 314.622695 -28.222198) (xy 314.606627 -28.275605) (xy 314.582955 -28.326102)
			(xy 314.552182 -28.372615) (xy 314.514965 -28.414152) (xy 314.472097 -28.449827) (xy 314.424491 -28.478881)
			(xy 314.373162 -28.500693) (xy 314.319205 -28.514799) (xy 314.263768 -28.520899) (xy 314.208034 -28.518862)
			(xy 314.153191 -28.508732) (xy 314.100407 -28.490725) (xy 314.050807 -28.465224) (xy 314.005449 -28.432773)
			(xy 313.9653 -28.394064) (xy 313.931214 -28.349921) (xy 313.903918 -28.301286) (xy 313.883995 -28.249195)
			(xy 313.871869 -28.194758) (xy 313.867798 -28.139136) (xy 313.361324 -28.139136) (xy 313.360815 -28.167022)
			(xy 313.352695 -28.222198) (xy 313.336627 -28.275605) (xy 313.312955 -28.326102) (xy 313.282182 -28.372615)
			(xy 313.244965 -28.414152) (xy 313.202097 -28.449827) (xy 313.154491 -28.478881) (xy 313.103162 -28.500693)
			(xy 313.049205 -28.514799) (xy 312.993768 -28.520899) (xy 312.938034 -28.518862) (xy 312.883191 -28.508732)
			(xy 312.830407 -28.490725) (xy 312.780807 -28.465224) (xy 312.735449 -28.432773) (xy 312.6953 -28.394064)
			(xy 312.661214 -28.349921) (xy 312.633918 -28.301286) (xy 312.613995 -28.249195) (xy 312.601869 -28.194758)
			(xy 312.597798 -28.139136) (xy 310.860948 -28.139136) (xy 310.860948 -30.180534) (xy 310.860459 -30.20662)
			(xy 310.852288 -30.258149) (xy 310.836151 -30.307763) (xy 310.812448 -30.35424) (xy 310.795986 -30.376876)
			(xy 311.088786 -30.376876) (xy 311.089326 -30.34796) (xy 311.098046 -30.290788) (xy 311.115298 -30.235588)
			(xy 311.140685 -30.183626) (xy 311.173626 -30.136091) (xy 311.213367 -30.094075) (xy 311.235852 -30.075886)
			(xy 311.244664 -30.068284) (xy 311.254843 -30.047379) (xy 311.25541 -30.035754) (xy 311.25541 -29.955998)
			(xy 311.254854 -29.944368) (xy 311.244677 -29.923459) (xy 311.235852 -29.915866) (xy 311.213342 -29.897706)
			(xy 311.173611 -29.855679) (xy 311.140676 -29.808137) (xy 311.115293 -29.75617) (xy 311.098042 -29.700967)
			(xy 311.089318 -29.643794) (xy 311.088786 -29.614876) (xy 311.089272 -29.587625) (xy 311.097028 -29.533677)
			(xy 311.112383 -29.481382) (xy 311.135025 -29.431805) (xy 311.164491 -29.385955) (xy 311.200182 -29.344764)
			(xy 311.241373 -29.309073) (xy 311.287223 -29.279607) (xy 311.3368 -29.256965) (xy 311.389095 -29.24161)
			(xy 311.443043 -29.233854) (xy 311.497545 -29.233854) (xy 311.551493 -29.24161) (xy 311.603788 -29.256965)
			(xy 311.653365 -29.279607) (xy 311.699215 -29.309073) (xy 311.740406 -29.344764) (xy 311.776097 -29.385955)
			(xy 311.805563 -29.431805) (xy 311.828205 -29.481382) (xy 311.84356 -29.533677) (xy 311.851316 -29.587625)
			(xy 311.851802 -29.614876) (xy 311.851266 -29.643792) (xy 311.84254 -29.700963) (xy 311.825286 -29.756161)
			(xy 311.799898 -29.808123) (xy 311.766957 -29.855657) (xy 311.72722 -29.897675) (xy 311.704736 -29.915866)
			(xy 311.695943 -29.923487) (xy 311.685754 -29.944378) (xy 311.685178 -29.955998) (xy 311.685178 -30.035754)
			(xy 311.685708 -30.047387) (xy 311.695904 -30.068295) (xy 311.704736 -30.075886) (xy 311.72722 -30.094076)
			(xy 311.766954 -30.136097) (xy 311.799892 -30.183632) (xy 311.82528 -30.235594) (xy 311.842536 -30.290791)
			(xy 311.851266 -30.34796) (xy 311.851802 -30.376876) (xy 311.851316 -30.404127) (xy 311.84356 -30.458075)
			(xy 311.828205 -30.51037) (xy 311.805563 -30.559947) (xy 311.776097 -30.605797) (xy 311.740406 -30.646988)
			(xy 311.699215 -30.682679) (xy 311.653365 -30.712145) (xy 311.603788 -30.734787) (xy 311.551493 -30.750142)
			(xy 311.497545 -30.757898) (xy 311.443043 -30.757898) (xy 311.389095 -30.750142) (xy 311.3368 -30.734787)
			(xy 311.287223 -30.712145) (xy 311.241373 -30.682679) (xy 311.200182 -30.646988) (xy 311.164491 -30.605797)
			(xy 311.135025 -30.559947) (xy 311.112383 -30.51037) (xy 311.097028 -30.458075) (xy 311.089272 -30.404127)
			(xy 311.088786 -30.376876) (xy 310.795986 -30.376876) (xy 310.781762 -30.396434) (xy 310.763666 -30.41523)
			(xy 309.770272 -31.40837) (xy 309.76503 -31.41404) (xy 309.757933 -31.427746) (xy 309.756302 -31.435294)
			(xy 309.75554 -31.444184) (xy 309.75554 -31.567882) (xy 311.198512 -31.567882) (xy 311.202583 -31.51226)
			(xy 311.214709 -31.457823) (xy 311.234632 -31.405732) (xy 311.261928 -31.357097) (xy 311.296014 -31.312954)
			(xy 311.336163 -31.274245) (xy 311.381521 -31.241794) (xy 311.431121 -31.216293) (xy 311.483905 -31.198286)
			(xy 311.538748 -31.188156) (xy 311.594482 -31.186119) (xy 311.649919 -31.192219) (xy 311.703876 -31.206325)
			(xy 311.755205 -31.228137) (xy 311.802811 -31.257191) (xy 311.845679 -31.292866) (xy 311.882896 -31.334403)
			(xy 311.913669 -31.380916) (xy 311.937341 -31.431413) (xy 311.953409 -31.48482) (xy 311.961529 -31.539996)
			(xy 311.962038 -31.567882) (xy 311.961529 -31.595768) (xy 311.953409 -31.650944) (xy 311.937341 -31.704351)
			(xy 311.930349 -31.719266) (xy 312.485276 -31.719266) (xy 312.489347 -31.663644) (xy 312.501473 -31.609207)
			(xy 312.521396 -31.557116) (xy 312.548692 -31.508481) (xy 312.582778 -31.464338) (xy 312.622927 -31.425629)
			(xy 312.668285 -31.393178) (xy 312.717885 -31.367677) (xy 312.770669 -31.34967) (xy 312.825512 -31.33954)
			(xy 312.881246 -31.337503) (xy 312.936683 -31.343603) (xy 312.99064 -31.357709) (xy 313.041969 -31.379521)
			(xy 313.089575 -31.408575) (xy 313.132443 -31.44425) (xy 313.16966 -31.485787) (xy 313.200433 -31.5323)
			(xy 313.224105 -31.582797) (xy 313.240173 -31.636204) (xy 313.244323 -31.664402) (xy 313.760864 -31.664402)
			(xy 313.764935 -31.60878) (xy 313.777061 -31.554343) (xy 313.796984 -31.502252) (xy 313.82428 -31.453617)
			(xy 313.858366 -31.409474) (xy 313.898515 -31.370765) (xy 313.943873 -31.338314) (xy 313.993473 -31.312813)
			(xy 314.046257 -31.294806) (xy 314.1011 -31.284676) (xy 314.156834 -31.282639) (xy 314.212271 -31.288739)
			(xy 314.266228 -31.302845) (xy 314.317557 -31.324657) (xy 314.365163 -31.353711) (xy 314.408031 -31.389386)
			(xy 314.445248 -31.430923) (xy 314.476021 -31.477436) (xy 314.499693 -31.527933) (xy 314.515761 -31.58134)
			(xy 314.523881 -31.636516) (xy 314.52439 -31.664402) (xy 314.523881 -31.692288) (xy 314.515761 -31.747464)
			(xy 314.499693 -31.800871) (xy 314.476021 -31.851368) (xy 314.445248 -31.897881) (xy 314.408031 -31.939418)
			(xy 314.365163 -31.975093) (xy 314.317557 -32.004147) (xy 314.266228 -32.025959) (xy 314.212271 -32.040065)
			(xy 314.156834 -32.046165) (xy 314.1011 -32.044128) (xy 314.046257 -32.033998) (xy 313.993473 -32.015991)
			(xy 313.943873 -31.99049) (xy 313.898515 -31.958039) (xy 313.858366 -31.91933) (xy 313.82428 -31.875187)
			(xy 313.796984 -31.826552) (xy 313.777061 -31.774461) (xy 313.764935 -31.720024) (xy 313.760864 -31.664402)
			(xy 313.244323 -31.664402) (xy 313.248293 -31.69138) (xy 313.248802 -31.719266) (xy 313.248293 -31.747152)
			(xy 313.240173 -31.802328) (xy 313.224105 -31.855735) (xy 313.200433 -31.906232) (xy 313.16966 -31.952745)
			(xy 313.132443 -31.994282) (xy 313.089575 -32.029957) (xy 313.041969 -32.059011) (xy 312.99064 -32.080823)
			(xy 312.936683 -32.094929) (xy 312.881246 -32.101029) (xy 312.825512 -32.098992) (xy 312.770669 -32.088862)
			(xy 312.717885 -32.070855) (xy 312.668285 -32.045354) (xy 312.622927 -32.012903) (xy 312.582778 -31.974194)
			(xy 312.548692 -31.930051) (xy 312.521396 -31.881416) (xy 312.501473 -31.829325) (xy 312.489347 -31.774888)
			(xy 312.485276 -31.719266) (xy 311.930349 -31.719266) (xy 311.913669 -31.754848) (xy 311.882896 -31.801361)
			(xy 311.845679 -31.842898) (xy 311.802811 -31.878573) (xy 311.755205 -31.907627) (xy 311.703876 -31.929439)
			(xy 311.649919 -31.943545) (xy 311.594482 -31.949645) (xy 311.538748 -31.947608) (xy 311.483905 -31.937478)
			(xy 311.431121 -31.919471) (xy 311.381521 -31.89397) (xy 311.336163 -31.861519) (xy 311.296014 -31.82281)
			(xy 311.261928 -31.778667) (xy 311.234632 -31.730032) (xy 311.214709 -31.677941) (xy 311.202583 -31.623504)
			(xy 311.198512 -31.567882) (xy 309.75554 -31.567882) (xy 309.75554 -31.894018) (xy 309.755622 -31.898227)
			(xy 309.75703 -31.906525) (xy 309.758334 -31.910528) (xy 309.760351 -31.915891) (xy 309.766371 -31.925637)
			(xy 309.770272 -31.929832) (xy 313.105437 -35.264852) (xy 314.10224 -35.264852) (xy 314.106311 -35.20923)
			(xy 314.118437 -35.154793) (xy 314.13836 -35.102702) (xy 314.165656 -35.054067) (xy 314.199742 -35.009924)
			(xy 314.239891 -34.971215) (xy 314.285249 -34.938764) (xy 314.334849 -34.913263) (xy 314.387633 -34.895256)
			(xy 314.442476 -34.885126) (xy 314.49821 -34.883089) (xy 314.553647 -34.889189) (xy 314.607604 -34.903295)
			(xy 314.658933 -34.925107) (xy 314.706539 -34.954161) (xy 314.749407 -34.989836) (xy 314.786624 -35.031373)
			(xy 314.817397 -35.077886) (xy 314.841069 -35.128383) (xy 314.857137 -35.18179) (xy 314.865257 -35.236966)
			(xy 314.865766 -35.264852) (xy 314.865257 -35.292738) (xy 314.857137 -35.347914) (xy 314.841069 -35.401321)
			(xy 314.817397 -35.451818) (xy 314.786624 -35.498331) (xy 314.749407 -35.539868) (xy 314.706539 -35.575543)
			(xy 314.658933 -35.604597) (xy 314.607604 -35.626409) (xy 314.553647 -35.640515) (xy 314.49821 -35.646615)
			(xy 314.442476 -35.644578) (xy 314.387633 -35.634448) (xy 314.334849 -35.616441) (xy 314.285249 -35.59094)
			(xy 314.239891 -35.558489) (xy 314.199742 -35.51978) (xy 314.165656 -35.475637) (xy 314.13836 -35.427002)
			(xy 314.118437 -35.374911) (xy 314.106311 -35.320474) (xy 314.10224 -35.264852) (xy 313.105437 -35.264852)
			(xy 314.127578 -36.286948) (xy 315.40018 -36.286948) (xy 315.404251 -36.231326) (xy 315.416377 -36.176889)
			(xy 315.4363 -36.124798) (xy 315.463596 -36.076163) (xy 315.497682 -36.03202) (xy 315.537831 -35.993311)
			(xy 315.583189 -35.96086) (xy 315.632789 -35.935359) (xy 315.685573 -35.917352) (xy 315.740416 -35.907222)
			(xy 315.79615 -35.905185) (xy 315.851587 -35.911285) (xy 315.905544 -35.925391) (xy 315.956873 -35.947203)
			(xy 316.004479 -35.976257) (xy 316.047347 -36.011932) (xy 316.084564 -36.053469) (xy 316.115337 -36.099982)
			(xy 316.139009 -36.150479) (xy 316.155077 -36.203886) (xy 316.163197 -36.259062) (xy 316.163706 -36.286948)
			(xy 316.163197 -36.314834) (xy 316.155077 -36.37001) (xy 316.139009 -36.423417) (xy 316.115337 -36.473914)
			(xy 316.084564 -36.520427) (xy 316.047347 -36.561964) (xy 316.004479 -36.597639) (xy 315.956873 -36.626693)
			(xy 315.905544 -36.648505) (xy 315.851587 -36.662611) (xy 315.79615 -36.668711) (xy 315.740416 -36.666674)
			(xy 315.685573 -36.656544) (xy 315.632789 -36.638537) (xy 315.583189 -36.613036) (xy 315.537831 -36.580585)
			(xy 315.497682 -36.541876) (xy 315.463596 -36.497733) (xy 315.4363 -36.449098) (xy 315.416377 -36.397007)
			(xy 315.404251 -36.34257) (xy 315.40018 -36.286948) (xy 314.127578 -36.286948) (xy 315.593222 -37.752528)
			(xy 315.60135 -37.749988) (xy 315.61786 -37.744908) (xy 315.626242 -37.742368) (xy 315.631635 -37.740236)
			(xy 315.641383 -37.733959) (xy 315.645546 -37.729922) (xy 315.655198 -37.719) (xy 315.655706 -37.718492)
			(xy 315.663834 -37.709602) (xy 315.670184 -37.69995) (xy 315.673486 -37.6936) (xy 315.674502 -37.689536)
			(xy 315.67501 -37.686996) (xy 315.682027 -37.65944) (xy 315.703107 -37.606632) (xy 315.731786 -37.557533)
			(xy 315.767428 -37.51323) (xy 315.809247 -37.474703) (xy 315.856316 -37.442804) (xy 315.907596 -37.418237)
			(xy 315.961952 -37.401546) (xy 316.018182 -37.393101) (xy 316.046612 -37.39261) (xy 316.073864 -37.393074)
			(xy 316.127812 -37.400833) (xy 316.180108 -37.41619) (xy 316.229685 -37.438833) (xy 316.275536 -37.468302)
			(xy 316.316725 -37.503996) (xy 316.352416 -37.545188) (xy 316.381881 -37.591041) (xy 316.404521 -37.64062)
			(xy 316.419874 -37.692917) (xy 316.427628 -37.746866) (xy 316.42812 -37.774118) (xy 316.427595 -37.802547)
			(xy 316.419159 -37.858776) (xy 316.402475 -37.913131) (xy 316.377913 -37.96441) (xy 316.346017 -38.011478)
			(xy 316.307492 -38.053295) (xy 316.26319 -38.088935) (xy 316.214092 -38.117609) (xy 316.161284 -38.138683)
			(xy 316.133734 -38.14572) (xy 316.13348 -38.14572) (xy 316.126368 -38.147498) (xy 316.115954 -38.152832)
			(xy 316.109096 -38.158928) (xy 316.108842 -38.159182) (xy 316.102238 -38.165024) (xy 316.10173 -38.165532)
			(xy 316.090808 -38.175184) (xy 316.08673 -38.179315) (xy 316.080439 -38.189068) (xy 316.078362 -38.194488)
			(xy 316.075822 -38.20287) (xy 316.070742 -38.21938) (xy 316.068202 -38.227508) (xy 322.203318 -44.362624)
			(xy 322.209668 -44.359576) (xy 322.213063 -44.357703) (xy 322.219311 -44.353112) (xy 322.222114 -44.350432)
			(xy 322.242688 -44.329858) (xy 322.243958 -44.328588) (xy 322.251832 -44.317666) (xy 322.257281 -44.306556)
			(xy 322.263204 -44.282537) (xy 322.263516 -44.270168) (xy 322.263516 -44.198286) (xy 322.263008 -44.191428)
			(xy 317.371222 -39.299642) (xy 317.353109 -39.280862) (xy 317.322424 -39.238665) (xy 317.298725 -39.192184)
			(xy 317.282596 -39.142565) (xy 317.274435 -39.091033) (xy 317.27394 -39.064946) (xy 317.27394 -36.734496)
			(xy 317.273686 -36.730686) (xy 317.270638 -36.716716) (xy 317.267082 -36.708842) (xy 317.262123 -36.700351)
			(xy 317.252974 -36.682944) (xy 317.248794 -36.674044) (xy 317.248794 -36.673536) (xy 317.238634 -36.64966)
			(xy 317.237364 -36.64585) (xy 317.23457 -36.637722) (xy 317.234316 -36.637214) (xy 317.233554 -36.634674)
			(xy 317.2333 -36.633912) (xy 317.232538 -36.631626) (xy 317.23203 -36.630102) (xy 317.231268 -36.62807)
			(xy 317.230252 -36.625022) (xy 317.228982 -36.621974) (xy 317.227021 -36.618143) (xy 317.222043 -36.611122)
			(xy 317.219076 -36.608004) (xy 315.728604 -35.117532) (xy 315.710572 -35.098761) (xy 315.679992 -35.056644)
			(xy 315.656364 -35.010268) (xy 315.64027 -34.960771) (xy 315.632103 -34.909368) (xy 315.631576 -34.883344)
			(xy 315.631576 -32.411162) (xy 315.623194 -32.402272) (xy 315.58738 -32.372808) (xy 315.586872 -32.3723)
			(xy 315.563504 -32.35325) (xy 315.560645 -32.350961) (xy 315.554394 -32.347142) (xy 315.551058 -32.34563)
			(xy 315.529722 -32.350202) (xy 315.499664 -32.356212) (xy 315.438706 -32.362699) (xy 315.408056 -32.363156)
			(xy 315.36132 -32.363156) (xy 315.36132 -32.361378) (xy 315.327873 -32.358235) (xy 315.261957 -32.345252)
			(xy 315.19796 -32.324811) (xy 315.136722 -32.297182) (xy 315.079048 -32.262727) (xy 315.025696 -32.221898)
			(xy 314.977366 -32.175232) (xy 314.934694 -32.123343) (xy 314.898239 -32.066912) (xy 314.868482 -32.006679)
			(xy 314.845812 -31.943437) (xy 314.830528 -31.878017) (xy 314.822831 -31.811277) (xy 314.822332 -31.777686)
			(xy 314.822332 -30.776164) (xy 314.819538 -30.772862) (xy 314.814966 -30.767782) (xy 314.811664 -30.76575)
			(xy 314.802012 -30.759908) (xy 314.801504 -30.759654) (xy 314.734448 -30.718252) (xy 314.728284 -30.714721)
			(xy 314.714624 -30.710848) (xy 314.707524 -30.710632) (xy 314.695332 -30.710886) (xy 314.68441 -30.716474)
			(xy 314.677806 -30.719776) (xy 314.67298 -30.724094) (xy 314.670143 -30.726519) (xy 314.663892 -30.730595)
			(xy 314.660534 -30.732222) (xy 314.656216 -30.734) (xy 314.654184 -30.734762) (xy 314.631249 -30.743571)
			(xy 314.583711 -30.755981) (xy 314.534985 -30.762276) (xy 314.51042 -30.762702) (xy 314.482858 -30.762235)
			(xy 314.428296 -30.754392) (xy 314.375405 -30.738864) (xy 314.325263 -30.715966) (xy 314.27889 -30.686165)
			(xy 314.237231 -30.650067) (xy 314.201133 -30.608407) (xy 314.171332 -30.562034) (xy 314.148435 -30.511891)
			(xy 314.132907 -30.459) (xy 314.125065 -30.404438) (xy 314.124594 -30.376876) (xy 314.125104 -30.348467)
			(xy 314.133458 -30.292267) (xy 314.149981 -30.237904) (xy 314.174314 -30.186561) (xy 314.205929 -30.139351)
			(xy 314.244139 -30.0973) (xy 314.265818 -30.078934) (xy 314.266326 -30.078426) (xy 314.271914 -30.0736)
			(xy 314.275978 -30.070298) (xy 314.279534 -30.066234) (xy 314.285376 -30.057344) (xy 314.29198 -30.04312)
			(xy 314.293647 -30.038668) (xy 314.295436 -30.029331) (xy 314.295536 -30.024578) (xy 314.295536 -29.967682)
			(xy 314.295394 -29.962242) (xy 314.293086 -29.951611) (xy 314.290964 -29.9466) (xy 314.287662 -29.939742)
			(xy 314.287662 -29.939234) (xy 314.280804 -29.925518) (xy 314.272422 -29.914088) (xy 314.267596 -29.909262)
			(xy 314.265818 -29.907738) (xy 314.244793 -29.889498) (xy 314.207733 -29.847972) (xy 314.177093 -29.801505)
			(xy 314.153524 -29.751083) (xy 314.137525 -29.697773) (xy 314.129434 -29.642705) (xy 314.128912 -29.614876)
			(xy 314.1294 -29.587626) (xy 314.137159 -29.533682) (xy 314.152517 -29.481392) (xy 314.175159 -29.431819)
			(xy 314.204627 -29.385973) (xy 314.240318 -29.344787) (xy 314.281508 -29.3091) (xy 314.327358 -29.279638)
			(xy 314.376933 -29.257001) (xy 314.429225 -29.24165) (xy 314.48317 -29.233897) (xy 314.51042 -29.233368)
			(xy 314.535848 -29.23379) (xy 314.586253 -29.240548) (xy 314.635313 -29.253944) (xy 314.682158 -29.273738)
			(xy 314.725959 -29.29958) (xy 314.765939 -29.331012) (xy 314.783978 -29.348938) (xy 314.790836 -29.35605)
			(xy 314.826396 -29.371798) (xy 314.840874 -29.37129) (xy 314.849546 -29.370245) (xy 314.865467 -29.363093)
			(xy 314.878047 -29.350994) (xy 314.882276 -29.34335) (xy 314.88253 -29.342842) (xy 314.897048 -29.314309)
			(xy 314.931411 -29.260291) (xy 314.97146 -29.210342) (xy 314.993782 -29.187394) (xy 317.432182 -26.748994)
			(xy 317.437173 -26.743497) (xy 317.444025 -26.730332) (xy 317.445644 -26.723086) (xy 317.44666 -26.713434)
			(xy 317.44666 -24.158194) (xy 317.447156 -24.124094) (xy 317.455073 -24.056354) (xy 317.470802 -23.989991)
			(xy 317.494128 -23.925903) (xy 317.524736 -23.864957) (xy 317.562213 -23.807976) (xy 317.606052 -23.755731)
			(xy 317.655659 -23.708928) (xy 317.710365 -23.668202) (xy 317.769429 -23.634101) (xy 317.832052 -23.607088)
			(xy 317.897388 -23.587528) (xy 317.964552 -23.575685) (xy 318.032638 -23.57172) (xy 318.100724 -23.575685)
			(xy 318.167888 -23.587528) (xy 318.233224 -23.607088) (xy 318.295847 -23.634101) (xy 318.354911 -23.668202)
			(xy 318.409617 -23.708928) (xy 318.459224 -23.755731) (xy 318.503063 -23.807976) (xy 318.54054 -23.864957)
			(xy 318.571148 -23.925903) (xy 318.594474 -23.989991) (xy 318.610203 -24.056354) (xy 318.61812 -24.124094)
			(xy 318.618616 -24.158194) (xy 318.618616 -24.807418) (xy 318.820036 -24.807418) (xy 318.824107 -24.751796)
			(xy 318.836233 -24.697359) (xy 318.856156 -24.645268) (xy 318.883452 -24.596633) (xy 318.917538 -24.55249)
			(xy 318.957687 -24.513781) (xy 319.003045 -24.48133) (xy 319.052645 -24.455829) (xy 319.105429 -24.437822)
			(xy 319.160272 -24.427692) (xy 319.216006 -24.425655) (xy 319.271443 -24.431755) (xy 319.3254 -24.445861)
			(xy 319.376729 -24.467673) (xy 319.424335 -24.496727) (xy 319.467203 -24.532402) (xy 319.50442 -24.573939)
			(xy 319.535193 -24.620452) (xy 319.558865 -24.670949) (xy 319.574933 -24.724356) (xy 319.583053 -24.779532)
			(xy 319.583562 -24.807418) (xy 319.583053 -24.835304) (xy 319.574933 -24.89048) (xy 319.558865 -24.943887)
			(xy 319.535193 -24.994384) (xy 319.50442 -25.040897) (xy 319.467203 -25.082434) (xy 319.424335 -25.118109)
			(xy 319.376729 -25.147163) (xy 319.3254 -25.168975) (xy 319.271443 -25.183081) (xy 319.216006 -25.189181)
			(xy 319.160272 -25.187144) (xy 319.105429 -25.177014) (xy 319.052645 -25.159007) (xy 319.003045 -25.133506)
			(xy 318.957687 -25.101055) (xy 318.917538 -25.062346) (xy 318.883452 -25.018203) (xy 318.856156 -24.969568)
			(xy 318.836233 -24.917477) (xy 318.824107 -24.86304) (xy 318.820036 -24.807418) (xy 318.618616 -24.807418)
			(xy 318.618616 -26.724102) (xy 318.620877 -26.727027) (xy 318.626107 -26.732252) (xy 318.62903 -26.734516)
			(xy 318.92367 -26.734516) (xy 318.92621 -26.734516) (xy 318.93157 -26.73409) (xy 318.941947 -26.731277)
			(xy 318.946784 -26.728928) (xy 318.970406 -26.716228) (xy 318.976248 -26.713434) (xy 318.976756 -26.71318)
			(xy 318.985646 -26.70556) (xy 318.989456 -26.700226) (xy 318.994844 -26.691799) (xy 318.999333 -26.672328)
			(xy 318.996082 -26.652612) (xy 318.985579 -26.635613) (xy 318.977772 -26.62936) (xy 318.97193 -26.625296)
			(xy 318.965834 -26.62301) (xy 318.939135 -26.612244) (xy 318.88906 -26.58385) (xy 318.843817 -26.548257)
			(xy 318.804433 -26.506273) (xy 318.7718 -26.458851) (xy 318.746659 -26.407065) (xy 318.729581 -26.352092)
			(xy 318.720951 -26.295177) (xy 318.72047 -26.266394) (xy 318.720956 -26.239143) (xy 318.728712 -26.185195)
			(xy 318.744067 -26.1329) (xy 318.766709 -26.083323) (xy 318.796175 -26.037473) (xy 318.831866 -25.996282)
			(xy 318.873057 -25.960591) (xy 318.918907 -25.931125) (xy 318.968484 -25.908483) (xy 319.020779 -25.893128)
			(xy 319.074727 -25.885372) (xy 319.129229 -25.885372) (xy 319.183177 -25.893128) (xy 319.235472 -25.908483)
			(xy 319.285049 -25.931125) (xy 319.330899 -25.960591) (xy 319.37209 -25.996282) (xy 319.407781 -26.037473)
			(xy 319.437247 -26.083323) (xy 319.459889 -26.1329) (xy 319.475244 -26.185195) (xy 319.483 -26.239143)
			(xy 319.483486 -26.266394) (xy 319.482952 -26.295311) (xy 319.474226 -26.352482) (xy 319.456972 -26.407682)
			(xy 319.431586 -26.459646) (xy 319.398649 -26.507184) (xy 319.358915 -26.549207) (xy 319.33642 -26.567384)
			(xy 319.331848 -26.57094) (xy 319.32245 -26.58237) (xy 319.320159 -26.585229) (xy 319.316338 -26.591478)
			(xy 319.31483 -26.594816) (xy 319.31483 -26.595324) (xy 319.31272 -26.600592) (xy 319.310663 -26.611749)
			(xy 319.310766 -26.617422) (xy 319.312036 -26.643838) (xy 319.312036 -26.644346) (xy 319.31483 -26.690574)
			(xy 319.317878 -26.702004) (xy 319.32499 -26.714958) (xy 319.33134 -26.72334) (xy 319.335658 -26.727912)
			(xy 319.33769 -26.729182) (xy 319.342008 -26.731722) (xy 319.366476 -26.746891) (xy 319.41107 -26.783298)
			(xy 319.449822 -26.825872) (xy 319.481886 -26.873683) (xy 319.506567 -26.925693) (xy 319.523326 -26.980768)
			(xy 319.531798 -27.03771) (xy 319.532254 -27.066494) (xy 319.531781 -27.094345) (xy 319.523854 -27.14948)
			(xy 319.508161 -27.202926) (xy 319.485021 -27.253594) (xy 319.454905 -27.300452) (xy 319.418427 -27.342548)
			(xy 319.376328 -27.379023) (xy 319.329467 -27.409135) (xy 319.278797 -27.432271) (xy 319.225351 -27.447961)
			(xy 319.170215 -27.455883) (xy 319.142364 -27.456384) (xy 319.14211 -27.456384) (xy 319.11679 -27.455978)
			(xy 319.066575 -27.449428) (xy 319.017626 -27.43645) (xy 318.970762 -27.41726) (xy 318.948562 -27.405076)
			(xy 318.94272 -27.401774) (xy 318.936624 -27.40025) (xy 318.92367 -27.398472) (xy 318.798956 -27.398472)
			(xy 318.788991 -27.398953) (xy 318.770559 -27.406532) (xy 318.763142 -27.413204) (xy 317.209932 -28.965906)
			(xy 317.053512 -29.12237) (xy 318.806576 -29.12237) (xy 318.806576 -28.25877) (xy 318.807066 -28.228786)
			(xy 318.814894 -28.16933) (xy 318.830415 -28.111405) (xy 318.853364 -28.056001) (xy 318.883348 -28.004067)
			(xy 318.919854 -27.956491) (xy 318.962259 -27.914086) (xy 319.009835 -27.87758) (xy 319.061769 -27.847596)
			(xy 319.117173 -27.824647) (xy 319.175098 -27.809126) (xy 319.234554 -27.801298) (xy 319.294522 -27.801298)
			(xy 319.353978 -27.809126) (xy 319.411903 -27.824647) (xy 319.467307 -27.847596) (xy 319.519241 -27.87758)
			(xy 319.566817 -27.914086) (xy 319.609222 -27.956491) (xy 319.645728 -28.004067) (xy 319.675712 -28.056001)
			(xy 319.698661 -28.111405) (xy 319.714182 -28.16933) (xy 319.72201 -28.228786) (xy 319.7225 -28.25877)
			(xy 319.7225 -29.114242) (xy 329.047348 -29.114242) (xy 329.047348 -28.250642) (xy 329.047838 -28.220674)
			(xy 329.055661 -28.161252) (xy 329.071174 -28.103359) (xy 329.09411 -28.047986) (xy 329.124077 -27.99608)
			(xy 329.160564 -27.94853) (xy 329.202944 -27.90615) (xy 329.250494 -27.869663) (xy 329.3024 -27.839696)
			(xy 329.357773 -27.81676) (xy 329.415666 -27.801247) (xy 329.475088 -27.793424) (xy 329.535024 -27.793424)
			(xy 329.594446 -27.801247) (xy 329.652339 -27.81676) (xy 329.707712 -27.839696) (xy 329.759618 -27.869663)
			(xy 329.807168 -27.90615) (xy 329.849548 -27.94853) (xy 329.886035 -27.99608) (xy 329.916002 -28.047986)
			(xy 329.938938 -28.103359) (xy 329.954451 -28.161252) (xy 329.962274 -28.220674) (xy 329.962764 -28.250642)
			(xy 329.962764 -29.114242) (xy 329.962274 -29.14421) (xy 329.954451 -29.203632) (xy 329.938938 -29.261525)
			(xy 329.916002 -29.316898) (xy 329.886035 -29.368804) (xy 329.849548 -29.416354) (xy 329.807168 -29.458734)
			(xy 329.759618 -29.495221) (xy 329.707712 -29.525188) (xy 329.652339 -29.548124) (xy 329.594446 -29.563637)
			(xy 329.535024 -29.57146) (xy 329.475088 -29.57146) (xy 329.415666 -29.563637) (xy 329.357773 -29.548124)
			(xy 329.3024 -29.525188) (xy 329.250494 -29.495221) (xy 329.202944 -29.458734) (xy 329.160564 -29.416354)
			(xy 329.124077 -29.368804) (xy 329.09411 -29.316898) (xy 329.071174 -29.261525) (xy 329.055661 -29.203632)
			(xy 329.047838 -29.14421) (xy 329.047348 -29.114242) (xy 319.7225 -29.114242) (xy 319.7225 -29.12237)
			(xy 319.72201 -29.152354) (xy 319.714182 -29.21181) (xy 319.698661 -29.269735) (xy 319.675712 -29.325139)
			(xy 319.645728 -29.377073) (xy 319.609222 -29.424649) (xy 319.566817 -29.467054) (xy 319.519241 -29.50356)
			(xy 319.467307 -29.533544) (xy 319.411903 -29.556493) (xy 319.353978 -29.572014) (xy 319.294522 -29.579842)
			(xy 319.234554 -29.579842) (xy 319.175098 -29.572014) (xy 319.117173 -29.556493) (xy 319.061769 -29.533544)
			(xy 319.009835 -29.50356) (xy 318.962259 -29.467054) (xy 318.919854 -29.424649) (xy 318.883348 -29.377073)
			(xy 318.853364 -29.325139) (xy 318.830415 -29.269735) (xy 318.814894 -29.21181) (xy 318.807066 -29.152354)
			(xy 318.806576 -29.12237) (xy 317.053512 -29.12237) (xy 316.29985 -29.876242) (xy 316.295024 -29.88183)
			(xy 316.295024 -30.922468) (xy 316.952376 -30.922468) (xy 316.952376 -30.058868) (xy 316.952866 -30.028884)
			(xy 316.960694 -29.969428) (xy 316.976215 -29.911503) (xy 316.999164 -29.856099) (xy 317.029148 -29.804165)
			(xy 317.065654 -29.756589) (xy 317.108059 -29.714184) (xy 317.155635 -29.677678) (xy 317.207569 -29.647694)
			(xy 317.262973 -29.624745) (xy 317.320898 -29.609224) (xy 317.380354 -29.601396) (xy 317.440322 -29.601396)
			(xy 317.499778 -29.609224) (xy 317.557703 -29.624745) (xy 317.613107 -29.647694) (xy 317.665041 -29.677678)
			(xy 317.712617 -29.714184) (xy 317.755022 -29.756589) (xy 317.791528 -29.804165) (xy 317.821512 -29.856099)
			(xy 317.844461 -29.911503) (xy 317.859982 -29.969428) (xy 317.86781 -30.028884) (xy 317.8683 -30.058868)
			(xy 317.8683 -30.92069) (xy 331.689456 -30.92069) (xy 331.689456 -30.05709) (xy 331.689946 -30.027122)
			(xy 331.697769 -29.9677) (xy 331.713282 -29.909807) (xy 331.736218 -29.854434) (xy 331.766185 -29.802528)
			(xy 331.802672 -29.754978) (xy 331.845052 -29.712598) (xy 331.892602 -29.676111) (xy 331.944508 -29.646144)
			(xy 331.999881 -29.623208) (xy 332.057774 -29.607695) (xy 332.117196 -29.599872) (xy 332.177132 -29.599872)
			(xy 332.236554 -29.607695) (xy 332.294447 -29.623208) (xy 332.34982 -29.646144) (xy 332.401726 -29.676111)
			(xy 332.449276 -29.712598) (xy 332.491656 -29.754978) (xy 332.528143 -29.802528) (xy 332.55811 -29.854434)
			(xy 332.581046 -29.909807) (xy 332.596559 -29.9677) (xy 332.604382 -30.027122) (xy 332.604872 -30.05709)
			(xy 332.604872 -30.92069) (xy 332.604382 -30.950658) (xy 332.596559 -31.01008) (xy 332.581046 -31.067973)
			(xy 332.55811 -31.123346) (xy 332.528143 -31.175252) (xy 332.491656 -31.222802) (xy 332.449276 -31.265182)
			(xy 332.401726 -31.301669) (xy 332.34982 -31.331636) (xy 332.294447 -31.354572) (xy 332.236554 -31.370085)
			(xy 332.177132 -31.377908) (xy 332.117196 -31.377908) (xy 332.057774 -31.370085) (xy 331.999881 -31.354572)
			(xy 331.944508 -31.331636) (xy 331.892602 -31.301669) (xy 331.845052 -31.265182) (xy 331.802672 -31.222802)
			(xy 331.766185 -31.175252) (xy 331.736218 -31.123346) (xy 331.713282 -31.067973) (xy 331.697769 -31.01008)
			(xy 331.689946 -30.950658) (xy 331.689456 -30.92069) (xy 317.8683 -30.92069) (xy 317.8683 -30.922468)
			(xy 317.86781 -30.952452) (xy 317.859982 -31.011908) (xy 317.844461 -31.069833) (xy 317.821512 -31.125237)
			(xy 317.791528 -31.177171) (xy 317.755022 -31.224747) (xy 317.712617 -31.267152) (xy 317.665041 -31.303658)
			(xy 317.613107 -31.333642) (xy 317.557703 -31.356591) (xy 317.499778 -31.372112) (xy 317.440322 -31.37994)
			(xy 317.380354 -31.37994) (xy 317.320898 -31.372112) (xy 317.262973 -31.356591) (xy 317.207569 -31.333642)
			(xy 317.155635 -31.303658) (xy 317.108059 -31.267152) (xy 317.065654 -31.224747) (xy 317.029148 -31.177171)
			(xy 316.999164 -31.125237) (xy 316.976215 -31.069833) (xy 316.960694 -31.011908) (xy 316.952866 -30.952452)
			(xy 316.952376 -30.922468) (xy 316.295024 -30.922468) (xy 316.295024 -32.722312) (xy 318.806576 -32.722312)
			(xy 318.806576 -31.858712) (xy 318.807066 -31.828728) (xy 318.814894 -31.769272) (xy 318.830415 -31.711347)
			(xy 318.853364 -31.655943) (xy 318.883348 -31.604009) (xy 318.919854 -31.556433) (xy 318.962259 -31.514028)
			(xy 319.009835 -31.477522) (xy 319.061769 -31.447538) (xy 319.117173 -31.424589) (xy 319.175098 -31.409068)
			(xy 319.234554 -31.40124) (xy 319.294522 -31.40124) (xy 319.353978 -31.409068) (xy 319.411903 -31.424589)
			(xy 319.467307 -31.447538) (xy 319.519241 -31.477522) (xy 319.566817 -31.514028) (xy 319.609222 -31.556433)
			(xy 319.645728 -31.604009) (xy 319.675712 -31.655943) (xy 319.698661 -31.711347) (xy 319.714182 -31.769272)
			(xy 319.72201 -31.828728) (xy 319.7225 -31.858712) (xy 319.7225 -32.714184) (xy 329.047348 -32.714184)
			(xy 329.047348 -31.850584) (xy 329.047838 -31.820616) (xy 329.055661 -31.761194) (xy 329.071174 -31.703301)
			(xy 329.09411 -31.647928) (xy 329.124077 -31.596022) (xy 329.160564 -31.548472) (xy 329.202944 -31.506092)
			(xy 329.250494 -31.469605) (xy 329.3024 -31.439638) (xy 329.357773 -31.416702) (xy 329.415666 -31.401189)
			(xy 329.475088 -31.393366) (xy 329.535024 -31.393366) (xy 329.594446 -31.401189) (xy 329.652339 -31.416702)
			(xy 329.707712 -31.439638) (xy 329.759618 -31.469605) (xy 329.807168 -31.506092) (xy 329.849548 -31.548472)
			(xy 329.886035 -31.596022) (xy 329.916002 -31.647928) (xy 329.938938 -31.703301) (xy 329.954451 -31.761194)
			(xy 329.962274 -31.820616) (xy 329.962764 -31.850584) (xy 329.962764 -32.714184) (xy 329.962274 -32.744152)
			(xy 329.954451 -32.803574) (xy 329.938938 -32.861467) (xy 329.916002 -32.91684) (xy 329.886035 -32.968746)
			(xy 329.849548 -33.016296) (xy 329.807168 -33.058676) (xy 329.759618 -33.095163) (xy 329.707712 -33.12513)
			(xy 329.652339 -33.148066) (xy 329.594446 -33.163579) (xy 329.535024 -33.171402) (xy 329.475088 -33.171402)
			(xy 329.415666 -33.163579) (xy 329.357773 -33.148066) (xy 329.3024 -33.12513) (xy 329.250494 -33.095163)
			(xy 329.202944 -33.058676) (xy 329.160564 -33.016296) (xy 329.124077 -32.968746) (xy 329.09411 -32.91684)
			(xy 329.071174 -32.861467) (xy 329.055661 -32.803574) (xy 329.047838 -32.744152) (xy 329.047348 -32.714184)
			(xy 319.7225 -32.714184) (xy 319.7225 -32.722312) (xy 319.72201 -32.752296) (xy 319.714182 -32.811752)
			(xy 319.698661 -32.869677) (xy 319.675712 -32.925081) (xy 319.645728 -32.977015) (xy 319.609222 -33.024591)
			(xy 319.566817 -33.066996) (xy 319.519241 -33.103502) (xy 319.467307 -33.133486) (xy 319.411903 -33.156435)
			(xy 319.353978 -33.171956) (xy 319.294522 -33.179784) (xy 319.234554 -33.179784) (xy 319.175098 -33.171956)
			(xy 319.117173 -33.156435) (xy 319.061769 -33.133486) (xy 319.009835 -33.103502) (xy 318.962259 -33.066996)
			(xy 318.919854 -33.024591) (xy 318.883348 -32.977015) (xy 318.853364 -32.925081) (xy 318.830415 -32.869677)
			(xy 318.814894 -32.811752) (xy 318.807066 -32.752296) (xy 318.806576 -32.722312) (xy 316.295024 -32.722312)
			(xy 316.295024 -34.52241) (xy 316.952376 -34.52241) (xy 316.952376 -33.65881) (xy 316.952866 -33.628826)
			(xy 316.960694 -33.56937) (xy 316.976215 -33.511445) (xy 316.999164 -33.456041) (xy 317.029148 -33.404107)
			(xy 317.065654 -33.356531) (xy 317.108059 -33.314126) (xy 317.155635 -33.27762) (xy 317.207569 -33.247636)
			(xy 317.262973 -33.224687) (xy 317.320898 -33.209166) (xy 317.380354 -33.201338) (xy 317.440322 -33.201338)
			(xy 317.499778 -33.209166) (xy 317.557703 -33.224687) (xy 317.613107 -33.247636) (xy 317.665041 -33.27762)
			(xy 317.712617 -33.314126) (xy 317.755022 -33.356531) (xy 317.791528 -33.404107) (xy 317.821512 -33.456041)
			(xy 317.844461 -33.511445) (xy 317.859982 -33.56937) (xy 317.86781 -33.628826) (xy 317.8683 -33.65881)
			(xy 317.8683 -34.520886) (xy 331.689456 -34.520886) (xy 331.689456 -33.657286) (xy 331.689946 -33.627318)
			(xy 331.697769 -33.567896) (xy 331.713282 -33.510003) (xy 331.736218 -33.45463) (xy 331.766185 -33.402724)
			(xy 331.802672 -33.355174) (xy 331.845052 -33.312794) (xy 331.892602 -33.276307) (xy 331.944508 -33.24634)
			(xy 331.999881 -33.223404) (xy 332.057774 -33.207891) (xy 332.117196 -33.200068) (xy 332.177132 -33.200068)
			(xy 332.236554 -33.207891) (xy 332.294447 -33.223404) (xy 332.34982 -33.24634) (xy 332.401726 -33.276307)
			(xy 332.449276 -33.312794) (xy 332.491656 -33.355174) (xy 332.528143 -33.402724) (xy 332.55811 -33.45463)
			(xy 332.581046 -33.510003) (xy 332.596559 -33.567896) (xy 332.604382 -33.627318) (xy 332.604872 -33.657286)
			(xy 332.604872 -34.520886) (xy 332.604382 -34.550854) (xy 332.596559 -34.610276) (xy 332.581046 -34.668169)
			(xy 332.55811 -34.723542) (xy 332.528143 -34.775448) (xy 332.491656 -34.822998) (xy 332.449276 -34.865378)
			(xy 332.401726 -34.901865) (xy 332.34982 -34.931832) (xy 332.294447 -34.954768) (xy 332.236554 -34.970281)
			(xy 332.177132 -34.978104) (xy 332.117196 -34.978104) (xy 332.057774 -34.970281) (xy 331.999881 -34.954768)
			(xy 331.944508 -34.931832) (xy 331.892602 -34.901865) (xy 331.845052 -34.865378) (xy 331.802672 -34.822998)
			(xy 331.766185 -34.775448) (xy 331.736218 -34.723542) (xy 331.713282 -34.668169) (xy 331.697769 -34.610276)
			(xy 331.689946 -34.550854) (xy 331.689456 -34.520886) (xy 317.8683 -34.520886) (xy 317.8683 -34.52241)
			(xy 317.86781 -34.552394) (xy 317.859982 -34.61185) (xy 317.844461 -34.669775) (xy 317.821512 -34.725179)
			(xy 317.791528 -34.777113) (xy 317.755022 -34.824689) (xy 317.712617 -34.867094) (xy 317.665041 -34.9036)
			(xy 317.613107 -34.933584) (xy 317.557703 -34.956533) (xy 317.499778 -34.972054) (xy 317.440322 -34.979882)
			(xy 317.380354 -34.979882) (xy 317.320898 -34.972054) (xy 317.262973 -34.956533) (xy 317.207569 -34.933584)
			(xy 317.155635 -34.9036) (xy 317.108059 -34.867094) (xy 317.065654 -34.824689) (xy 317.029148 -34.777113)
			(xy 316.999164 -34.725179) (xy 316.976215 -34.669775) (xy 316.960694 -34.61185) (xy 316.952866 -34.552394)
			(xy 316.952376 -34.52241) (xy 316.295024 -34.52241) (xy 316.295024 -34.72434) (xy 316.295532 -34.73196)
			(xy 316.296983 -34.739796) (xy 316.304092 -34.75405) (xy 316.309502 -34.7599) (xy 317.23965 -35.689794)
			(xy 317.697358 -36.147502) (xy 317.703962 -36.149534) (xy 317.729772 -36.157635) (xy 317.778978 -36.18011)
			(xy 317.824515 -36.209311) (xy 317.86547 -36.244653) (xy 317.90102 -36.285427) (xy 317.930454 -36.330815)
			(xy 317.953179 -36.379906) (xy 317.96874 -36.431715) (xy 317.976826 -36.485203) (xy 317.97752 -36.512246)
			(xy 317.97752 -36.519104) (xy 317.977205 -36.536613) (xy 317.973773 -36.571467) (xy 317.970662 -36.5887)
			(xy 317.969392 -36.594796) (xy 317.968197 -36.60013) (xy 322.197991 -36.60013) (xy 322.201996 -36.512222)
			(xy 322.213979 -36.425042) (xy 322.233839 -36.339313) (xy 322.261414 -36.255745) (xy 322.296473 -36.175031)
			(xy 322.338726 -36.097839) (xy 322.387824 -36.02481) (xy 322.44336 -35.956548) (xy 322.504872 -35.893618)
			(xy 322.571853 -35.836544) (xy 322.643746 -35.785796) (xy 322.719955 -35.741796) (xy 322.79985 -35.704909)
			(xy 322.882769 -35.67544) (xy 322.968024 -35.653633) (xy 323.054908 -35.639669) (xy 323.142702 -35.633663)
			(xy 323.230679 -35.635667) (xy 323.318109 -35.645662) (xy 323.404268 -35.663566) (xy 323.488442 -35.68923)
			(xy 323.569933 -35.722443) (xy 323.648067 -35.762929) (xy 323.722195 -35.810351) (xy 323.791703 -35.864318)
			(xy 323.856017 -35.924383) (xy 323.914601 -35.990047) (xy 323.966972 -36.060766) (xy 324.012695 -36.135954)
			(xy 324.051392 -36.214989) (xy 324.082741 -36.297215) (xy 324.106483 -36.381951) (xy 324.122421 -36.468495)
			(xy 324.130423 -36.55613) (xy 324.130924 -36.60013) (xy 324.130423 -36.64413) (xy 324.122421 -36.731765)
			(xy 324.106483 -36.818309) (xy 324.082741 -36.903045) (xy 324.051392 -36.985271) (xy 324.012695 -37.064306)
			(xy 323.966972 -37.139494) (xy 323.914601 -37.210213) (xy 323.856017 -37.275877) (xy 323.791703 -37.335942)
			(xy 323.722195 -37.389909) (xy 323.648067 -37.437331) (xy 323.569933 -37.477817) (xy 323.488442 -37.51103)
			(xy 323.404268 -37.536694) (xy 323.318109 -37.554598) (xy 323.230679 -37.564593) (xy 323.142702 -37.566597)
			(xy 323.054908 -37.560591) (xy 322.968024 -37.546627) (xy 322.882769 -37.52482) (xy 322.79985 -37.495351)
			(xy 322.719955 -37.458464) (xy 322.643746 -37.414464) (xy 322.571853 -37.363716) (xy 322.504872 -37.306642)
			(xy 322.44336 -37.243712) (xy 322.387824 -37.17545) (xy 322.338726 -37.102421) (xy 322.296473 -37.025229)
			(xy 322.261414 -36.944515) (xy 322.233839 -36.860947) (xy 322.213979 -36.775218) (xy 322.201996 -36.688038)
			(xy 322.197991 -36.60013) (xy 317.968197 -36.60013) (xy 317.964656 -36.615933) (xy 317.951031 -36.657052)
			(xy 317.942214 -36.676838) (xy 317.937896 -36.686236) (xy 317.937896 -38.90645) (xy 317.938912 -38.916102)
			(xy 317.940545 -38.923343) (xy 317.947394 -38.936505) (xy 317.952374 -38.94201) (xy 320.279117 -41.268753)
			(xy 326.04375 -41.268753) (xy 326.04375 -41.214247) (xy 326.051507 -41.160295) (xy 326.066863 -41.107997)
			(xy 326.089506 -41.058416) (xy 326.118974 -41.012563) (xy 326.154668 -40.971369) (xy 326.195861 -40.935675)
			(xy 326.241714 -40.906207) (xy 326.291295 -40.883564) (xy 326.343593 -40.868207) (xy 326.397545 -40.86045)
			(xy 326.424798 -40.859964) (xy 326.453536 -40.860499) (xy 326.510363 -40.86912) (xy 326.565253 -40.886168)
			(xy 326.616965 -40.911257) (xy 326.664328 -40.943819) (xy 326.685656 -40.963088) (xy 326.692514 -40.969692)
			(xy 326.710548 -40.976804) (xy 326.799448 -40.976804) (xy 326.817482 -40.969692) (xy 326.82434 -40.963088)
			(xy 326.845675 -40.943827) (xy 326.893034 -40.911257) (xy 326.944744 -40.886162) (xy 326.999633 -40.869109)
			(xy 327.056459 -40.860485) (xy 327.085198 -40.859964) (xy 327.112449 -40.860483) (xy 327.166396 -40.868239)
			(xy 327.21869 -40.883594) (xy 327.268267 -40.906235) (xy 327.314117 -40.935701) (xy 327.355307 -40.971392)
			(xy 327.390998 -41.012581) (xy 327.420464 -41.058431) (xy 327.443105 -41.108008) (xy 327.45846 -41.160302)
			(xy 327.466217 -41.214249) (xy 327.466217 -41.268751) (xy 327.45846 -41.322698) (xy 327.443105 -41.374992)
			(xy 327.420464 -41.424569) (xy 327.390998 -41.470419) (xy 327.355307 -41.511608) (xy 327.314117 -41.547299)
			(xy 327.268267 -41.576765) (xy 327.21869 -41.599406) (xy 327.166396 -41.614761) (xy 327.112449 -41.622517)
			(xy 327.085198 -41.62298) (xy 327.05646 -41.622436) (xy 326.999635 -41.613815) (xy 326.944745 -41.596769)
			(xy 326.893033 -41.571682) (xy 326.845669 -41.539123) (xy 326.82434 -41.519856) (xy 326.817482 -41.513252)
			(xy 326.799448 -41.50614) (xy 326.710548 -41.50614) (xy 326.692514 -41.513252) (xy 326.685656 -41.519856)
			(xy 326.664329 -41.539127) (xy 326.616967 -41.571693) (xy 326.565255 -41.596786) (xy 326.510365 -41.613836)
			(xy 326.453537 -41.622459) (xy 326.424798 -41.62298) (xy 326.397545 -41.62255) (xy 326.343593 -41.614793)
			(xy 326.291295 -41.599436) (xy 326.241714 -41.576793) (xy 326.195861 -41.547325) (xy 326.154668 -41.511631)
			(xy 326.118974 -41.470437) (xy 326.089506 -41.424584) (xy 326.066863 -41.375003) (xy 326.051507 -41.322705)
			(xy 326.04375 -41.268753) (xy 320.279117 -41.268753) (xy 322.315586 -43.305222) (xy 328.50709 -43.305222)
			(xy 328.507571 -43.277852) (xy 328.515386 -43.223674) (xy 328.530872 -43.171171) (xy 328.55371 -43.121424)
			(xy 328.583431 -43.075456) (xy 328.60107 -43.054524) (xy 328.601324 -43.05427) (xy 328.60689 -43.04717)
			(xy 328.613148 -43.030263) (xy 328.613516 -43.02125) (xy 328.613516 -42.954194) (xy 328.613158 -42.945177)
			(xy 328.606911 -42.928261) (xy 328.601324 -42.921174) (xy 328.60107 -42.921174) (xy 328.60107 -42.92092)
			(xy 328.583422 -42.899995) (xy 328.553713 -42.85402) (xy 328.530879 -42.80427) (xy 328.51539 -42.751768)
			(xy 328.507563 -42.697592) (xy 328.50709 -42.670222) (xy 328.50763 -42.641484) (xy 328.516249 -42.584657)
			(xy 328.533295 -42.529767) (xy 328.558383 -42.478055) (xy 328.590945 -42.430691) (xy 328.610214 -42.409364)
			(xy 328.616818 -42.402506) (xy 328.62393 -42.384472) (xy 328.62393 -42.295572) (xy 328.616818 -42.277538)
			(xy 328.610214 -42.27068) (xy 328.590965 -42.249334) (xy 328.5584 -42.201975) (xy 328.533308 -42.150266)
			(xy 328.516257 -42.095378) (xy 328.507633 -42.038554) (xy 328.50763 -41.981078) (xy 328.51625 -41.924253)
			(xy 328.533296 -41.869364) (xy 328.558384 -41.817653) (xy 328.590945 -41.770291) (xy 328.610214 -41.748964)
			(xy 328.616818 -41.742106) (xy 328.62393 -41.724072) (xy 328.62393 -41.635172) (xy 328.616818 -41.617138)
			(xy 328.610214 -41.61028) (xy 328.59095 -41.588947) (xy 328.558383 -41.541587) (xy 328.53329 -41.489876)
			(xy 328.516238 -41.434987) (xy 328.507613 -41.378161) (xy 328.50709 -41.349422) (xy 328.507576 -41.322171)
			(xy 328.515332 -41.268223) (xy 328.530687 -41.215928) (xy 328.553329 -41.166351) (xy 328.582795 -41.120501)
			(xy 328.618486 -41.07931) (xy 328.659677 -41.043619) (xy 328.705527 -41.014153) (xy 328.755104 -40.991511)
			(xy 328.807399 -40.976156) (xy 328.861347 -40.9684) (xy 328.915849 -40.9684) (xy 328.969797 -40.976156)
			(xy 329.022092 -40.991511) (xy 329.071669 -41.014153) (xy 329.117519 -41.043619) (xy 329.15871 -41.07931)
			(xy 329.194401 -41.120501) (xy 329.223867 -41.166351) (xy 329.246509 -41.215928) (xy 329.261864 -41.268223)
			(xy 329.26962 -41.322171) (xy 329.270106 -41.349422) (xy 329.269594 -41.378161) (xy 329.260968 -41.434989)
			(xy 329.243915 -41.48988) (xy 329.218821 -41.541591) (xy 329.186254 -41.588954) (xy 329.166982 -41.61028)
			(xy 329.160378 -41.617138) (xy 329.153266 -41.635172) (xy 329.153266 -41.724072) (xy 329.160378 -41.742106)
			(xy 329.166982 -41.748964) (xy 329.186274 -41.770272) (xy 329.218838 -41.817638) (xy 329.243928 -41.869353)
			(xy 329.260976 -41.924246) (xy 329.269597 -41.981076) (xy 329.269594 -42.038556) (xy 329.260969 -42.095385)
			(xy 329.243917 -42.150277) (xy 329.218822 -42.20199) (xy 329.186254 -42.249353) (xy 329.166982 -42.27068)
			(xy 329.160378 -42.277538) (xy 329.153266 -42.295572) (xy 329.153266 -42.384472) (xy 329.160378 -42.402506)
			(xy 329.166982 -42.409364) (xy 329.186266 -42.430679) (xy 329.21883 -42.478045) (xy 329.24392 -42.529759)
			(xy 329.260967 -42.584653) (xy 329.269587 -42.641482) (xy 329.270106 -42.670222) (xy 329.269651 -42.697593)
			(xy 329.261831 -42.751772) (xy 329.246339 -42.804275) (xy 329.225784 -42.849038) (xy 331.091792 -42.849038)
			(xy 331.095863 -42.793416) (xy 331.107989 -42.738979) (xy 331.127912 -42.686888) (xy 331.155208 -42.638253)
			(xy 331.189294 -42.59411) (xy 331.229443 -42.555401) (xy 331.274801 -42.52295) (xy 331.324401 -42.497449)
			(xy 331.377185 -42.479442) (xy 331.432028 -42.469312) (xy 331.487762 -42.467275) (xy 331.543199 -42.473375)
			(xy 331.597156 -42.487481) (xy 331.648485 -42.509293) (xy 331.696091 -42.538347) (xy 331.738959 -42.574022)
			(xy 331.776176 -42.615559) (xy 331.806949 -42.662072) (xy 331.830621 -42.712569) (xy 331.846689 -42.765976)
			(xy 331.854809 -42.821152) (xy 331.85517 -42.84091) (xy 337.132928 -42.84091) (xy 337.136999 -42.785288)
			(xy 337.149125 -42.730851) (xy 337.169048 -42.67876) (xy 337.196344 -42.630125) (xy 337.23043 -42.585982)
			(xy 337.270579 -42.547273) (xy 337.315937 -42.514822) (xy 337.365537 -42.489321) (xy 337.418321 -42.471314)
			(xy 337.473164 -42.461184) (xy 337.528898 -42.459147) (xy 337.584335 -42.465247) (xy 337.638292 -42.479353)
			(xy 337.689621 -42.501165) (xy 337.737227 -42.530219) (xy 337.780095 -42.565894) (xy 337.817312 -42.607431)
			(xy 337.848085 -42.653944) (xy 337.871757 -42.704441) (xy 337.887825 -42.757848) (xy 337.895945 -42.813024)
			(xy 337.896454 -42.84091) (xy 337.895945 -42.868796) (xy 337.887825 -42.923972) (xy 337.871757 -42.977379)
			(xy 337.848085 -43.027876) (xy 337.817312 -43.074389) (xy 337.780095 -43.115926) (xy 337.737227 -43.151601)
			(xy 337.689621 -43.180655) (xy 337.638292 -43.202467) (xy 337.584335 -43.216573) (xy 337.528898 -43.222673)
			(xy 337.473164 -43.220636) (xy 337.418321 -43.210506) (xy 337.365537 -43.192499) (xy 337.315937 -43.166998)
			(xy 337.270579 -43.134547) (xy 337.23043 -43.095838) (xy 337.196344 -43.051695) (xy 337.169048 -43.00306)
			(xy 337.149125 -42.950969) (xy 337.136999 -42.896532) (xy 337.132928 -42.84091) (xy 331.85517 -42.84091)
			(xy 331.855318 -42.849038) (xy 331.854809 -42.876924) (xy 331.846689 -42.9321) (xy 331.830621 -42.985507)
			(xy 331.806949 -43.036004) (xy 331.776176 -43.082517) (xy 331.738959 -43.124054) (xy 331.696091 -43.159729)
			(xy 331.648485 -43.188783) (xy 331.597156 -43.210595) (xy 331.543199 -43.224701) (xy 331.487762 -43.230801)
			(xy 331.432028 -43.228764) (xy 331.377185 -43.218634) (xy 331.324401 -43.200627) (xy 331.274801 -43.175126)
			(xy 331.229443 -43.142675) (xy 331.189294 -43.103966) (xy 331.155208 -43.059823) (xy 331.127912 -43.011188)
			(xy 331.107989 -42.959097) (xy 331.095863 -42.90466) (xy 331.091792 -42.849038) (xy 329.225784 -42.849038)
			(xy 329.223495 -42.854022) (xy 329.193768 -42.899988) (xy 329.176126 -42.92092) (xy 329.175872 -42.921174)
			(xy 329.170287 -42.928262) (xy 329.16404 -42.945178) (xy 329.16368 -42.954194) (xy 329.16368 -43.02125)
			(xy 329.164065 -43.030264) (xy 329.170294 -43.047181) (xy 329.175872 -43.05427) (xy 329.176126 -43.05427)
			(xy 329.176126 -43.054524) (xy 329.193747 -43.075471) (xy 329.223461 -43.12144) (xy 329.2463 -43.171184)
			(xy 329.261795 -43.223681) (xy 329.269629 -43.277854) (xy 329.270106 -43.305222) (xy 329.26962 -43.332473)
			(xy 329.261864 -43.386421) (xy 329.246509 -43.438716) (xy 329.223867 -43.488293) (xy 329.194401 -43.534143)
			(xy 329.15871 -43.575334) (xy 329.117519 -43.611025) (xy 329.071669 -43.640491) (xy 329.022092 -43.663133)
			(xy 328.969797 -43.678488) (xy 328.915849 -43.686244) (xy 328.861347 -43.686244) (xy 328.807399 -43.678488)
			(xy 328.755104 -43.663133) (xy 328.705527 -43.640491) (xy 328.659677 -43.611025) (xy 328.618486 -43.575334)
			(xy 328.582795 -43.534143) (xy 328.553329 -43.488293) (xy 328.530687 -43.438716) (xy 328.515332 -43.386421)
			(xy 328.507576 -43.332473) (xy 328.50709 -43.305222) (xy 322.315586 -43.305222) (xy 322.746624 -43.73626)
			(xy 330.41285 -43.73626) (xy 330.416921 -43.680638) (xy 330.429047 -43.626201) (xy 330.44897 -43.57411)
			(xy 330.476266 -43.525475) (xy 330.510352 -43.481332) (xy 330.550501 -43.442623) (xy 330.595859 -43.410172)
			(xy 330.645459 -43.384671) (xy 330.698243 -43.366664) (xy 330.753086 -43.356534) (xy 330.80882 -43.354497)
			(xy 330.864257 -43.360597) (xy 330.918214 -43.374703) (xy 330.969543 -43.396515) (xy 331.017149 -43.425569)
			(xy 331.060017 -43.461244) (xy 331.097234 -43.502781) (xy 331.128007 -43.549294) (xy 331.136233 -43.566842)
			(xy 333.32928 -43.566842) (xy 333.329896 -43.531432) (xy 333.338427 -43.461127) (xy 333.355371 -43.392363)
			(xy 333.380479 -43.326143) (xy 333.413387 -43.263432) (xy 333.453613 -43.205145) (xy 333.500572 -43.152132)
			(xy 333.553579 -43.105165) (xy 333.61186 -43.06493) (xy 333.674566 -43.032014) (xy 333.740783 -43.006896)
			(xy 333.809544 -42.989943) (xy 333.879848 -42.981401) (xy 333.915258 -42.980864) (xy 333.948139 -42.981313)
			(xy 334.013487 -42.988677) (xy 334.077599 -43.003316) (xy 334.139667 -43.025046) (xy 334.198909 -43.053593)
			(xy 334.25458 -43.088599) (xy 334.305978 -43.129621) (xy 334.329532 -43.152568) (xy 334.831944 -43.65498)
			(xy 334.840257 -43.662391) (xy 334.861201 -43.669895) (xy 334.87233 -43.669458) (xy 334.961484 -43.66133)
			(xy 334.981042 -43.6499) (xy 334.987392 -43.640502) (xy 335.002737 -43.61904) (xy 335.038365 -43.580126)
			(xy 335.079015 -43.546493) (xy 335.123911 -43.518783) (xy 335.172198 -43.497523) (xy 335.222954 -43.48312)
			(xy 335.27521 -43.475849) (xy 335.30159 -43.475402) (xy 335.328844 -43.475844) (xy 335.382798 -43.4836)
			(xy 335.435098 -43.498956) (xy 335.484681 -43.521598) (xy 335.530536 -43.551067) (xy 335.571731 -43.586762)
			(xy 335.607427 -43.627956) (xy 335.636897 -43.67381) (xy 335.659541 -43.723393) (xy 335.674898 -43.775693)
			(xy 335.682655 -43.829646) (xy 335.682655 -43.884154) (xy 335.674898 -43.938107) (xy 335.659541 -43.990407)
			(xy 335.636897 -44.03999) (xy 335.607427 -44.085844) (xy 335.571731 -44.127038) (xy 335.530536 -44.162733)
			(xy 335.484681 -44.192202) (xy 335.435098 -44.214844) (xy 335.382798 -44.2302) (xy 335.328844 -44.237956)
			(xy 335.30159 -44.238418) (xy 335.301336 -44.238418) (xy 335.281778 -44.23791) (xy 335.281524 -44.23791)
			(xy 335.271225 -44.23789) (xy 335.251957 -44.245119) (xy 335.244186 -44.25188) (xy 335.190592 -44.30268)
			(xy 335.183473 -44.310185) (xy 335.175336 -44.329179) (xy 335.174844 -44.33951) (xy 335.174844 -44.871132)
			(xy 335.174916 -44.87291) (xy 337.132928 -44.87291) (xy 337.136999 -44.817288) (xy 337.149125 -44.762851)
			(xy 337.169048 -44.71076) (xy 337.196344 -44.662125) (xy 337.23043 -44.617982) (xy 337.270579 -44.579273)
			(xy 337.315937 -44.546822) (xy 337.365537 -44.521321) (xy 337.418321 -44.503314) (xy 337.473164 -44.493184)
			(xy 337.528898 -44.491147) (xy 337.584335 -44.497247) (xy 337.638292 -44.511353) (xy 337.689621 -44.533165)
			(xy 337.737227 -44.562219) (xy 337.780095 -44.597894) (xy 337.817312 -44.639431) (xy 337.848085 -44.685944)
			(xy 337.871757 -44.736441) (xy 337.887825 -44.789848) (xy 337.895945 -44.845024) (xy 337.896454 -44.87291)
			(xy 337.895945 -44.900796) (xy 337.887825 -44.955972) (xy 337.871757 -45.009379) (xy 337.848085 -45.059876)
			(xy 337.817312 -45.106389) (xy 337.780095 -45.147926) (xy 337.737227 -45.183601) (xy 337.689621 -45.212655)
			(xy 337.638292 -45.234467) (xy 337.584335 -45.248573) (xy 337.528898 -45.254673) (xy 337.473164 -45.252636)
			(xy 337.418321 -45.242506) (xy 337.365537 -45.224499) (xy 337.315937 -45.198998) (xy 337.270579 -45.166547)
			(xy 337.23043 -45.127838) (xy 337.196344 -45.083695) (xy 337.169048 -45.03506) (xy 337.149125 -44.982969)
			(xy 337.136999 -44.928532) (xy 337.132928 -44.87291) (xy 335.174916 -44.87291) (xy 335.175256 -44.881294)
			(xy 335.183131 -44.90003) (xy 335.190084 -44.907454) (xy 335.249266 -44.965366) (xy 335.268316 -44.972986)
			(xy 335.278476 -44.972732) (xy 335.285588 -44.972732) (xy 335.312844 -44.973114) (xy 335.366802 -44.980871)
			(xy 335.419107 -44.996227) (xy 335.468694 -45.018871) (xy 335.514553 -45.048342) (xy 335.555752 -45.08404)
			(xy 335.591451 -45.125237) (xy 335.620923 -45.171095) (xy 335.643569 -45.220682) (xy 335.658927 -45.272986)
			(xy 335.666685 -45.326944) (xy 335.666685 -45.381456) (xy 335.658927 -45.435414) (xy 335.643569 -45.487718)
			(xy 335.620923 -45.537305) (xy 335.591451 -45.583163) (xy 335.555752 -45.62436) (xy 335.514553 -45.660058)
			(xy 335.468694 -45.689529) (xy 335.419107 -45.712173) (xy 335.366802 -45.727529) (xy 335.312844 -45.735286)
			(xy 335.285588 -45.735748) (xy 335.278476 -45.735748) (xy 335.268316 -45.735494) (xy 335.249266 -45.743114)
			(xy 335.190084 -45.801026) (xy 335.183163 -45.808471) (xy 335.175296 -45.827194) (xy 335.174844 -45.837348)
			(xy 335.174844 -46.210982) (xy 335.175251 -46.220776) (xy 335.18258 -46.238939) (xy 335.189068 -46.246288)
			(xy 335.237836 -46.297088) (xy 335.244962 -46.303825) (xy 335.262859 -46.311795) (xy 335.272634 -46.312582)
			(xy 335.299161 -46.314145) (xy 335.351451 -46.323585) (xy 335.401925 -46.34019) (xy 335.449607 -46.363637)
			(xy 335.493575 -46.393473) (xy 335.532978 -46.429121) (xy 335.567053 -46.469892) (xy 335.595141 -46.514996)
			(xy 335.6167 -46.563561) (xy 335.631311 -46.614648) (xy 335.638693 -46.667268) (xy 335.639156 -46.693836)
			(xy 335.638689 -46.720264) (xy 335.631379 -46.772612) (xy 335.616904 -46.823447) (xy 335.595542 -46.871793)
			(xy 335.582006 -46.894496) (xy 335.581752 -46.89475) (xy 335.576415 -46.904768) (xy 335.574158 -46.927318)
			(xy 335.577434 -46.938184) (xy 335.603596 -47.01286) (xy 335.60796 -47.023386) (xy 335.624062 -47.03947)
			(xy 335.634584 -47.043848) (xy 335.634838 -47.043848) (xy 335.659345 -47.052922) (xy 335.705798 -47.076864)
			(xy 335.74855 -47.106919) (xy 335.786802 -47.142525) (xy 335.819839 -47.183018) (xy 335.847043 -47.227638)
			(xy 335.867905 -47.275553) (xy 335.882035 -47.325866) (xy 335.889169 -47.377636) (xy 335.8896 -47.403766)
			(xy 335.889106 -47.431356) (xy 335.887609 -47.441612) (xy 337.16163 -47.441612) (xy 337.165701 -47.38599)
			(xy 337.177827 -47.331553) (xy 337.19775 -47.279462) (xy 337.225046 -47.230827) (xy 337.259132 -47.186684)
			(xy 337.299281 -47.147975) (xy 337.344639 -47.115524) (xy 337.394239 -47.090023) (xy 337.447023 -47.072016)
			(xy 337.501866 -47.061886) (xy 337.5576 -47.059849) (xy 337.613037 -47.065949) (xy 337.666994 -47.080055)
			(xy 337.718323 -47.101867) (xy 337.765929 -47.130921) (xy 337.808797 -47.166596) (xy 337.846014 -47.208133)
			(xy 337.876787 -47.254646) (xy 337.900459 -47.305143) (xy 337.916527 -47.35855) (xy 337.924647 -47.413726)
			(xy 337.925156 -47.441612) (xy 337.924647 -47.469498) (xy 337.916527 -47.524674) (xy 337.900459 -47.578081)
			(xy 337.876787 -47.628578) (xy 337.846014 -47.675091) (xy 337.808797 -47.716628) (xy 337.765929 -47.752303)
			(xy 337.718323 -47.781357) (xy 337.666994 -47.803169) (xy 337.613037 -47.817275) (xy 337.5576 -47.823375)
			(xy 337.501866 -47.821338) (xy 337.447023 -47.811208) (xy 337.394239 -47.793201) (xy 337.344639 -47.7677)
			(xy 337.299281 -47.735249) (xy 337.259132 -47.69654) (xy 337.225046 -47.652397) (xy 337.19775 -47.603762)
			(xy 337.177827 -47.551671) (xy 337.165701 -47.497234) (xy 337.16163 -47.441612) (xy 335.887609 -47.441612)
			(xy 335.881135 -47.485957) (xy 335.865382 -47.538841) (xy 335.842177 -47.588905) (xy 335.812004 -47.635104)
			(xy 335.77549 -47.676476) (xy 335.733399 -47.712157) (xy 335.686607 -47.741404) (xy 335.636091 -47.763607)
			(xy 335.582904 -47.778302) (xy 335.55559 -47.782226) (xy 335.555336 -47.782226) (xy 335.547119 -47.783607)
			(xy 335.532197 -47.790998) (xy 335.526126 -47.796704) (xy 335.525872 -47.796958) (xy 335.519211 -47.80439)
			(xy 335.511604 -47.822814) (xy 335.511596 -47.842747) (xy 335.519189 -47.861176) (xy 335.525872 -47.868586)
			(xy 335.550002 -47.892716) (xy 335.57291 -47.916272) (xy 335.613872 -47.967651) (xy 335.648825 -48.023292)
			(xy 335.677329 -48.082498) (xy 335.699025 -48.144522) (xy 335.713641 -48.208585) (xy 335.720994 -48.273881)
			(xy 335.721452 -48.306736) (xy 335.721452 -48.30699) (xy 335.720935 -48.342394) (xy 335.712403 -48.412686)
			(xy 335.695463 -48.481437) (xy 335.670361 -48.547646) (xy 335.637463 -48.610347) (xy 335.597249 -48.668627)
			(xy 335.550305 -48.721636) (xy 335.497315 -48.768602) (xy 335.439051 -48.80884) (xy 335.376363 -48.841763)
			(xy 335.310164 -48.866892) (xy 335.24142 -48.88386) (xy 335.171132 -48.89242) (xy 335.135728 -48.892968)
			(xy 335.102847 -48.892519) (xy 335.037499 -48.885155) (xy 334.973388 -48.870515) (xy 334.91132 -48.848785)
			(xy 334.852078 -48.820237) (xy 334.796407 -48.785232) (xy 334.745008 -48.744211) (xy 334.721454 -48.721264)
			(xy 334.174846 -48.174656) (xy 334.151933 -48.151105) (xy 334.11097 -48.099726) (xy 334.076017 -48.044084)
			(xy 334.047513 -47.984878) (xy 334.025817 -47.922853) (xy 334.011203 -47.858789) (xy 334.003853 -47.793491)
			(xy 334.003396 -47.760636) (xy 334.003396 -44.504356) (xy 334.003021 -44.494281) (xy 333.995268 -44.475682)
			(xy 333.98841 -44.468288) (xy 333.500984 -43.981116) (xy 333.478068 -43.957536) (xy 333.437072 -43.906126)
			(xy 333.402084 -43.850453) (xy 333.373544 -43.791215) (xy 333.351809 -43.729157) (xy 333.337153 -43.665057)
			(xy 333.329759 -43.599719) (xy 333.32928 -43.566842) (xy 331.136233 -43.566842) (xy 331.151679 -43.599791)
			(xy 331.167747 -43.653198) (xy 331.175867 -43.708374) (xy 331.176376 -43.73626) (xy 331.175867 -43.764146)
			(xy 331.167747 -43.819322) (xy 331.151679 -43.872729) (xy 331.128007 -43.923226) (xy 331.097234 -43.969739)
			(xy 331.060017 -44.011276) (xy 331.017149 -44.046951) (xy 330.969543 -44.076005) (xy 330.918214 -44.097817)
			(xy 330.864257 -44.111923) (xy 330.80882 -44.118023) (xy 330.753086 -44.115986) (xy 330.698243 -44.105856)
			(xy 330.645459 -44.087849) (xy 330.595859 -44.062348) (xy 330.550501 -44.029897) (xy 330.510352 -43.991188)
			(xy 330.476266 -43.947045) (xy 330.44897 -43.89841) (xy 330.429047 -43.846319) (xy 330.416921 -43.791882)
			(xy 330.41285 -43.73626) (xy 322.746624 -43.73626) (xy 322.860924 -43.85056) (xy 322.87896 -43.869329)
			(xy 322.909548 -43.911444) (xy 322.933181 -43.957819) (xy 322.949281 -44.007318) (xy 322.95745 -44.058723)
			(xy 322.957952 -44.084748) (xy 322.957952 -45.114464) (xy 330.265276 -45.114464) (xy 330.269347 -45.058842)
			(xy 330.281473 -45.004405) (xy 330.301396 -44.952314) (xy 330.328692 -44.903679) (xy 330.362778 -44.859536)
			(xy 330.402927 -44.820827) (xy 330.448285 -44.788376) (xy 330.497885 -44.762875) (xy 330.550669 -44.744868)
			(xy 330.605512 -44.734738) (xy 330.661246 -44.732701) (xy 330.716683 -44.738801) (xy 330.77064 -44.752907)
			(xy 330.821969 -44.774719) (xy 330.869575 -44.803773) (xy 330.912443 -44.839448) (xy 330.94966 -44.880985)
			(xy 330.980433 -44.927498) (xy 331.004105 -44.977995) (xy 331.020173 -45.031402) (xy 331.028293 -45.086578)
			(xy 331.028802 -45.114464) (xy 331.028293 -45.14235) (xy 331.020173 -45.197526) (xy 331.004105 -45.250933)
			(xy 330.980433 -45.30143) (xy 330.94966 -45.347943) (xy 330.912443 -45.38948) (xy 330.869575 -45.425155)
			(xy 330.821969 -45.454209) (xy 330.77064 -45.476021) (xy 330.716683 -45.490127) (xy 330.661246 -45.496227)
			(xy 330.605512 -45.49419) (xy 330.550669 -45.48406) (xy 330.497885 -45.466053) (xy 330.448285 -45.440552)
			(xy 330.402927 -45.408101) (xy 330.362778 -45.369392) (xy 330.328692 -45.325249) (xy 330.301396 -45.276614)
			(xy 330.281473 -45.224523) (xy 330.269347 -45.170086) (xy 330.265276 -45.114464) (xy 322.957952 -45.114464)
			(xy 322.957952 -46.082204) (xy 328.252328 -46.082204) (xy 328.252759 -46.05495) (xy 328.260517 -46.000996)
			(xy 328.275874 -45.948695) (xy 328.298519 -45.899113) (xy 328.327989 -45.853258) (xy 328.363687 -45.812064)
			(xy 328.404883 -45.77637) (xy 328.450741 -45.746903) (xy 328.500325 -45.724263) (xy 328.552627 -45.70891)
			(xy 328.606582 -45.701157) (xy 328.633836 -45.700696) (xy 328.66074 -45.701131) (xy 328.714011 -45.708708)
			(xy 328.76569 -45.723692) (xy 328.814751 -45.745786) (xy 328.860224 -45.774553) (xy 328.901204 -45.809422)
			(xy 328.936881 -45.849701) (xy 328.952098 -45.871892) (xy 328.95921 -45.882814) (xy 328.98207 -45.894752)
			(xy 329.094338 -45.89272) (xy 329.11669 -45.879766) (xy 329.123548 -45.86859) (xy 329.13845 -45.844976)
			(xy 329.174133 -45.802024) (xy 329.215694 -45.764732) (xy 329.262247 -45.733896) (xy 329.312798 -45.710175)
			(xy 329.366266 -45.694075) (xy 329.42151 -45.68594) (xy 329.44943 -45.685456) (xy 329.476424 -45.6859)
			(xy 329.529873 -45.69351) (xy 329.581716 -45.708574) (xy 329.630921 -45.730792) (xy 329.676504 -45.75972)
			(xy 329.697334 -45.776896) (xy 329.705462 -45.784008) (xy 329.726036 -45.790104) (xy 329.81138 -45.779182)
			(xy 329.821925 -45.777408) (xy 329.840208 -45.766353) (xy 329.846686 -45.757846) (xy 329.862055 -45.736627)
			(xy 329.897639 -45.698174) (xy 329.938153 -45.664954) (xy 329.982834 -45.637594) (xy 330.03084 -45.616609)
			(xy 330.081266 -45.602393) (xy 330.133164 -45.595215) (xy 330.15936 -45.594778) (xy 330.186614 -45.595267)
			(xy 330.240567 -45.603019) (xy 330.292868 -45.618371) (xy 330.342451 -45.64101) (xy 330.388308 -45.670476)
			(xy 330.429503 -45.706168) (xy 330.4652 -45.74736) (xy 330.494671 -45.793214) (xy 330.517315 -45.842795)
			(xy 330.532673 -45.895094) (xy 330.540431 -45.949046) (xy 330.540431 -46.003554) (xy 330.532673 -46.057506)
			(xy 330.517315 -46.109805) (xy 330.494671 -46.159386) (xy 330.4652 -46.20524) (xy 330.429503 -46.246432)
			(xy 330.388308 -46.282124) (xy 330.342451 -46.31159) (xy 330.292868 -46.334229) (xy 330.240567 -46.349581)
			(xy 330.186614 -46.357333) (xy 330.15936 -46.357794) (xy 330.132366 -46.357344) (xy 330.078918 -46.349734)
			(xy 330.027075 -46.33467) (xy 329.977871 -46.312454) (xy 329.932287 -46.283528) (xy 329.911456 -46.266354)
			(xy 329.903328 -46.259242) (xy 329.882754 -46.253146) (xy 329.79741 -46.264068) (xy 329.786869 -46.265855)
			(xy 329.768586 -46.276902) (xy 329.762104 -46.285404) (xy 329.744487 -46.309701) (xy 329.702894 -46.352963)
			(xy 329.6793 -46.37151) (xy 329.671426 -46.377352) (xy 329.661012 -46.394878) (xy 329.647804 -46.485302)
			(xy 329.65263 -46.504606) (xy 329.658472 -46.51248) (xy 329.658472 -46.512734) (xy 329.675975 -46.537478)
			(xy 329.703777 -46.591331) (xy 329.722714 -46.648903) (xy 329.732307 -46.708745) (xy 329.732894 -46.739048)
			(xy 329.732467 -46.766301) (xy 329.724703 -46.820252) (xy 329.709341 -46.872548) (xy 329.686694 -46.922127)
			(xy 329.657221 -46.967977) (xy 329.621524 -47.009167) (xy 329.580328 -47.044858) (xy 329.534472 -47.074323)
			(xy 329.48489 -47.096963) (xy 329.432591 -47.112317) (xy 329.378639 -47.120071) (xy 329.351386 -47.120556)
			(xy 329.325352 -47.12011) (xy 329.27377 -47.113021) (xy 329.223628 -47.098992) (xy 329.175857 -47.078281)
			(xy 329.131342 -47.051272) (xy 329.110848 -47.035212) (xy 329.103084 -47.029482) (xy 329.084679 -47.023734)
			(xy 329.075034 -47.024036) (xy 328.995278 -47.030386) (xy 328.977498 -47.039022) (xy 328.971148 -47.046388)
			(xy 328.952966 -47.066033) (xy 328.912059 -47.100555) (xy 328.86673 -47.129024) (xy 328.817869 -47.150882)
			(xy 328.766433 -47.1657) (xy 328.713432 -47.173187) (xy 328.686668 -47.173642) (xy 328.659418 -47.173152)
			(xy 328.605472 -47.165392) (xy 328.553179 -47.150035) (xy 328.503604 -47.127392) (xy 328.457755 -47.097926)
			(xy 328.416566 -47.062235) (xy 328.380875 -47.021046) (xy 328.351409 -46.975198) (xy 328.328766 -46.925623)
			(xy 328.313408 -46.87333) (xy 328.305648 -46.819384) (xy 328.30516 -46.792134) (xy 328.305695 -46.76336)
			(xy 328.314345 -46.706467) (xy 328.33144 -46.651517) (xy 328.35659 -46.599757) (xy 328.389228 -46.55236)
			(xy 328.408538 -46.531022) (xy 328.415904 -46.523148) (xy 328.423016 -46.503336) (xy 328.41565 -46.40707)
			(xy 328.405744 -46.388274) (xy 328.397362 -46.38167) (xy 328.375186 -46.363435) (xy 328.335974 -46.321503)
			(xy 328.303486 -46.27417) (xy 328.278455 -46.222504) (xy 328.261448 -46.167671) (xy 328.252846 -46.110909)
			(xy 328.252328 -46.082204) (xy 322.957952 -46.082204) (xy 322.957952 -48.753014) (xy 331.368144 -48.753014)
			(xy 331.372215 -48.697392) (xy 331.384341 -48.642955) (xy 331.404264 -48.590864) (xy 331.43156 -48.542229)
			(xy 331.465646 -48.498086) (xy 331.505795 -48.459377) (xy 331.551153 -48.426926) (xy 331.600753 -48.401425)
			(xy 331.653537 -48.383418) (xy 331.70838 -48.373288) (xy 331.764114 -48.371251) (xy 331.819551 -48.377351)
			(xy 331.873508 -48.391457) (xy 331.924837 -48.413269) (xy 331.972443 -48.442323) (xy 332.015311 -48.477998)
			(xy 332.052528 -48.519535) (xy 332.083301 -48.566048) (xy 332.106973 -48.616545) (xy 332.123041 -48.669952)
			(xy 332.131161 -48.725128) (xy 332.13167 -48.753014) (xy 332.131161 -48.7809) (xy 332.123041 -48.836076)
			(xy 332.120597 -48.8442) (xy 332.387192 -48.8442) (xy 332.391263 -48.788578) (xy 332.403389 -48.734141)
			(xy 332.423312 -48.68205) (xy 332.450608 -48.633415) (xy 332.484694 -48.589272) (xy 332.524843 -48.550563)
			(xy 332.570201 -48.518112) (xy 332.619801 -48.492611) (xy 332.672585 -48.474604) (xy 332.727428 -48.464474)
			(xy 332.783162 -48.462437) (xy 332.838599 -48.468537) (xy 332.892556 -48.482643) (xy 332.943885 -48.504455)
			(xy 332.991491 -48.533509) (xy 333.034359 -48.569184) (xy 333.071576 -48.610721) (xy 333.102349 -48.657234)
			(xy 333.126021 -48.707731) (xy 333.142089 -48.761138) (xy 333.150209 -48.816314) (xy 333.150718 -48.8442)
			(xy 333.150209 -48.872086) (xy 333.147211 -48.89246) (xy 333.41386 -48.89246) (xy 333.417931 -48.836838)
			(xy 333.430057 -48.782401) (xy 333.44998 -48.73031) (xy 333.477276 -48.681675) (xy 333.511362 -48.637532)
			(xy 333.551511 -48.598823) (xy 333.596869 -48.566372) (xy 333.646469 -48.540871) (xy 333.699253 -48.522864)
			(xy 333.754096 -48.512734) (xy 333.80983 -48.510697) (xy 333.865267 -48.516797) (xy 333.919224 -48.530903)
			(xy 333.970553 -48.552715) (xy 334.018159 -48.581769) (xy 334.061027 -48.617444) (xy 334.098244 -48.658981)
			(xy 334.129017 -48.705494) (xy 334.152689 -48.755991) (xy 334.168757 -48.809398) (xy 334.176877 -48.864574)
			(xy 334.177386 -48.89246) (xy 334.176877 -48.920346) (xy 334.174439 -48.93691) (xy 337.132928 -48.93691)
			(xy 337.136999 -48.881288) (xy 337.149125 -48.826851) (xy 337.169048 -48.77476) (xy 337.196344 -48.726125)
			(xy 337.23043 -48.681982) (xy 337.270579 -48.643273) (xy 337.315937 -48.610822) (xy 337.365537 -48.585321)
			(xy 337.418321 -48.567314) (xy 337.473164 -48.557184) (xy 337.528898 -48.555147) (xy 337.584335 -48.561247)
			(xy 337.638292 -48.575353) (xy 337.689621 -48.597165) (xy 337.737227 -48.626219) (xy 337.780095 -48.661894)
			(xy 337.817312 -48.703431) (xy 337.848085 -48.749944) (xy 337.871757 -48.800441) (xy 337.887825 -48.853848)
			(xy 337.895945 -48.909024) (xy 337.896454 -48.93691) (xy 337.895945 -48.964796) (xy 337.887825 -49.019972)
			(xy 337.871757 -49.073379) (xy 337.848085 -49.123876) (xy 337.817312 -49.170389) (xy 337.780095 -49.211926)
			(xy 337.737227 -49.247601) (xy 337.689621 -49.276655) (xy 337.638292 -49.298467) (xy 337.584335 -49.312573)
			(xy 337.528898 -49.318673) (xy 337.473164 -49.316636) (xy 337.418321 -49.306506) (xy 337.365537 -49.288499)
			(xy 337.315937 -49.262998) (xy 337.270579 -49.230547) (xy 337.23043 -49.191838) (xy 337.196344 -49.147695)
			(xy 337.169048 -49.09906) (xy 337.149125 -49.046969) (xy 337.136999 -48.992532) (xy 337.132928 -48.93691)
			(xy 334.174439 -48.93691) (xy 334.168757 -48.975522) (xy 334.152689 -49.028929) (xy 334.129017 -49.079426)
			(xy 334.098244 -49.125939) (xy 334.061027 -49.167476) (xy 334.018159 -49.203151) (xy 333.970553 -49.232205)
			(xy 333.919224 -49.254017) (xy 333.865267 -49.268123) (xy 333.80983 -49.274223) (xy 333.754096 -49.272186)
			(xy 333.699253 -49.262056) (xy 333.646469 -49.244049) (xy 333.596869 -49.218548) (xy 333.551511 -49.186097)
			(xy 333.511362 -49.147388) (xy 333.477276 -49.103245) (xy 333.44998 -49.05461) (xy 333.430057 -49.002519)
			(xy 333.417931 -48.948082) (xy 333.41386 -48.89246) (xy 333.147211 -48.89246) (xy 333.142089 -48.927262)
			(xy 333.126021 -48.980669) (xy 333.102349 -49.031166) (xy 333.071576 -49.077679) (xy 333.034359 -49.119216)
			(xy 332.991491 -49.154891) (xy 332.943885 -49.183945) (xy 332.892556 -49.205757) (xy 332.838599 -49.219863)
			(xy 332.783162 -49.225963) (xy 332.727428 -49.223926) (xy 332.672585 -49.213796) (xy 332.619801 -49.195789)
			(xy 332.570201 -49.170288) (xy 332.524843 -49.137837) (xy 332.484694 -49.099128) (xy 332.450608 -49.054985)
			(xy 332.423312 -49.00635) (xy 332.403389 -48.954259) (xy 332.391263 -48.899822) (xy 332.387192 -48.8442)
			(xy 332.120597 -48.8442) (xy 332.106973 -48.889483) (xy 332.083301 -48.93998) (xy 332.052528 -48.986493)
			(xy 332.015311 -49.02803) (xy 331.972443 -49.063705) (xy 331.924837 -49.092759) (xy 331.873508 -49.114571)
			(xy 331.819551 -49.128677) (xy 331.764114 -49.134777) (xy 331.70838 -49.13274) (xy 331.653537 -49.12261)
			(xy 331.600753 -49.104603) (xy 331.551153 -49.079102) (xy 331.505795 -49.046651) (xy 331.465646 -49.007942)
			(xy 331.43156 -48.963799) (xy 331.404264 -48.915164) (xy 331.384341 -48.863073) (xy 331.372215 -48.808636)
			(xy 331.368144 -48.753014) (xy 322.957952 -48.753014) (xy 322.957952 -49.95291) (xy 337.132928 -49.95291)
			(xy 337.136999 -49.897288) (xy 337.149125 -49.842851) (xy 337.169048 -49.79076) (xy 337.196344 -49.742125)
			(xy 337.23043 -49.697982) (xy 337.270579 -49.659273) (xy 337.315937 -49.626822) (xy 337.365537 -49.601321)
			(xy 337.418321 -49.583314) (xy 337.473164 -49.573184) (xy 337.528898 -49.571147) (xy 337.584335 -49.577247)
			(xy 337.638292 -49.591353) (xy 337.689621 -49.613165) (xy 337.737227 -49.642219) (xy 337.780095 -49.677894)
			(xy 337.817312 -49.719431) (xy 337.848085 -49.765944) (xy 337.871757 -49.816441) (xy 337.887825 -49.869848)
			(xy 337.895945 -49.925024) (xy 337.896454 -49.95291) (xy 337.895945 -49.980796) (xy 337.887825 -50.035972)
			(xy 337.871757 -50.089379) (xy 337.848085 -50.139876) (xy 337.817312 -50.186389) (xy 337.780095 -50.227926)
			(xy 337.737227 -50.263601) (xy 337.689621 -50.292655) (xy 337.638292 -50.314467) (xy 337.584335 -50.328573)
			(xy 337.528898 -50.334673) (xy 337.473164 -50.332636) (xy 337.418321 -50.322506) (xy 337.365537 -50.304499)
			(xy 337.315937 -50.278998) (xy 337.270579 -50.246547) (xy 337.23043 -50.207838) (xy 337.196344 -50.163695)
			(xy 337.169048 -50.11506) (xy 337.149125 -50.062969) (xy 337.136999 -50.008532) (xy 337.132928 -49.95291)
			(xy 322.957952 -49.95291) (xy 322.957952 -51.019456) (xy 334.94929 -51.019456) (xy 334.953361 -50.963834)
			(xy 334.965487 -50.909397) (xy 334.98541 -50.857306) (xy 335.012706 -50.808671) (xy 335.046792 -50.764528)
			(xy 335.086941 -50.725819) (xy 335.132299 -50.693368) (xy 335.181899 -50.667867) (xy 335.234683 -50.64986)
			(xy 335.289526 -50.63973) (xy 335.34526 -50.637693) (xy 335.400697 -50.643793) (xy 335.454654 -50.657899)
			(xy 335.505983 -50.679711) (xy 335.553589 -50.708765) (xy 335.596457 -50.74444) (xy 335.633674 -50.785977)
			(xy 335.664447 -50.83249) (xy 335.688119 -50.882987) (xy 335.704187 -50.936394) (xy 335.712307 -50.99157)
			(xy 335.712816 -51.019456) (xy 335.712307 -51.047342) (xy 335.704187 -51.102518) (xy 335.688119 -51.155925)
			(xy 335.664447 -51.206422) (xy 335.633674 -51.252935) (xy 335.596457 -51.294472) (xy 335.553589 -51.330147)
			(xy 335.505983 -51.359201) (xy 335.454654 -51.381013) (xy 335.400697 -51.395119) (xy 335.34526 -51.401219)
			(xy 335.289526 -51.399182) (xy 335.234683 -51.389052) (xy 335.181899 -51.371045) (xy 335.132299 -51.345544)
			(xy 335.086941 -51.313093) (xy 335.046792 -51.274384) (xy 335.012706 -51.230241) (xy 334.98541 -51.181606)
			(xy 334.965487 -51.129515) (xy 334.953361 -51.075078) (xy 334.94929 -51.019456) (xy 322.957952 -51.019456)
			(xy 322.957952 -52.035456) (xy 337.141056 -52.035456) (xy 337.145127 -51.979834) (xy 337.157253 -51.925397)
			(xy 337.177176 -51.873306) (xy 337.204472 -51.824671) (xy 337.238558 -51.780528) (xy 337.278707 -51.741819)
			(xy 337.324065 -51.709368) (xy 337.373665 -51.683867) (xy 337.426449 -51.66586) (xy 337.481292 -51.65573)
			(xy 337.537026 -51.653693) (xy 337.592463 -51.659793) (xy 337.64642 -51.673899) (xy 337.697749 -51.695711)
			(xy 337.745355 -51.724765) (xy 337.788223 -51.76044) (xy 337.82544 -51.801977) (xy 337.856213 -51.84849)
			(xy 337.879885 -51.898987) (xy 337.895953 -51.952394) (xy 337.904073 -52.00757) (xy 337.904582 -52.035456)
			(xy 337.904073 -52.063342) (xy 337.895953 -52.118518) (xy 337.879885 -52.171925) (xy 337.856213 -52.222422)
			(xy 337.82544 -52.268935) (xy 337.788223 -52.310472) (xy 337.745355 -52.346147) (xy 337.697749 -52.375201)
			(xy 337.64642 -52.397013) (xy 337.592463 -52.411119) (xy 337.537026 -52.417219) (xy 337.481292 -52.415182)
			(xy 337.426449 -52.405052) (xy 337.373665 -52.387045) (xy 337.324065 -52.361544) (xy 337.278707 -52.329093)
			(xy 337.238558 -52.290384) (xy 337.204472 -52.246241) (xy 337.177176 -52.197606) (xy 337.157253 -52.145515)
			(xy 337.145127 -52.091078) (xy 337.141056 -52.035456) (xy 322.957952 -52.035456) (xy 322.957952 -54.731412)
			(xy 323.72046 -54.731412) (xy 323.720918 -54.704041) (xy 323.728736 -54.649861) (xy 323.744226 -54.597358)
			(xy 323.76707 -54.547611) (xy 323.796797 -54.501645) (xy 323.81444 -54.480714) (xy 323.814694 -54.48046)
			(xy 323.820261 -54.47336) (xy 323.82652 -54.456454) (xy 323.826886 -54.44744) (xy 323.826886 -54.380384)
			(xy 323.82654 -54.371366) (xy 323.820285 -54.354449) (xy 323.814694 -54.347364) (xy 323.81444 -54.347364)
			(xy 323.81444 -54.34711) (xy 323.796811 -54.326168) (xy 323.767084 -54.280202) (xy 323.744237 -54.230457)
			(xy 323.72874 -54.177957) (xy 323.72091 -54.123779) (xy 323.720908 -54.069039) (xy 323.728736 -54.014861)
			(xy 323.744231 -53.962359) (xy 323.767076 -53.912614) (xy 323.7968 -53.866646) (xy 323.81444 -53.845714)
			(xy 323.814694 -53.84546) (xy 323.820261 -53.83836) (xy 323.82652 -53.821454) (xy 323.826886 -53.81244)
			(xy 323.826886 -53.745384) (xy 323.82654 -53.736366) (xy 323.820285 -53.719449) (xy 323.814694 -53.712364)
			(xy 323.81444 -53.712364) (xy 323.81444 -53.71211) (xy 323.796811 -53.691168) (xy 323.767084 -53.645202)
			(xy 323.744237 -53.595457) (xy 323.72874 -53.542957) (xy 323.72091 -53.488779) (xy 323.720908 -53.434039)
			(xy 323.728736 -53.379861) (xy 323.744231 -53.327359) (xy 323.767076 -53.277614) (xy 323.7968 -53.231646)
			(xy 323.81444 -53.210714) (xy 323.814694 -53.21046) (xy 323.820261 -53.20336) (xy 323.82652 -53.186454)
			(xy 323.826886 -53.17744) (xy 323.826886 -53.110384) (xy 323.82654 -53.101366) (xy 323.820285 -53.084449)
			(xy 323.814694 -53.077364) (xy 323.81444 -53.077364) (xy 323.81444 -53.07711) (xy 323.796798 -53.05618)
			(xy 323.767086 -53.010207) (xy 323.744249 -52.960459) (xy 323.728759 -52.907958) (xy 323.720933 -52.853781)
			(xy 323.72046 -52.826412) (xy 323.720946 -52.799161) (xy 323.728702 -52.745213) (xy 323.744057 -52.692918)
			(xy 323.766699 -52.643341) (xy 323.796165 -52.597491) (xy 323.831856 -52.5563) (xy 323.873047 -52.520609)
			(xy 323.918897 -52.491143) (xy 323.968474 -52.468501) (xy 324.020769 -52.453146) (xy 324.074717 -52.44539)
			(xy 324.129219 -52.44539) (xy 324.183167 -52.453146) (xy 324.235462 -52.468501) (xy 324.285039 -52.491143)
			(xy 324.330889 -52.520609) (xy 324.37208 -52.5563) (xy 324.407771 -52.597491) (xy 324.437237 -52.643341)
			(xy 324.459879 -52.692918) (xy 324.475234 -52.745213) (xy 324.48299 -52.799161) (xy 324.483476 -52.826412)
			(xy 324.483023 -52.853783) (xy 324.475203 -52.907963) (xy 324.459711 -52.960466) (xy 324.436866 -53.010213)
			(xy 324.407139 -53.056179) (xy 324.389496 -53.07711) (xy 324.389242 -53.077364) (xy 324.383657 -53.084452)
			(xy 324.377411 -53.101368) (xy 324.37705 -53.110384) (xy 324.37705 -53.17744) (xy 324.377377 -53.18646)
			(xy 324.383644 -53.203377) (xy 324.389242 -53.21046) (xy 324.389496 -53.21046) (xy 324.389496 -53.210714)
			(xy 324.407147 -53.231638) (xy 324.43687 -53.277608) (xy 324.459713 -53.327355) (xy 324.475208 -53.379859)
			(xy 324.483035 -53.434038) (xy 324.483033 -53.48878) (xy 324.475204 -53.542959) (xy 324.459707 -53.595461)
			(xy 324.436861 -53.645208) (xy 324.407137 -53.691177) (xy 324.389496 -53.71211) (xy 324.389242 -53.712364)
			(xy 324.383657 -53.719452) (xy 324.377411 -53.736368) (xy 324.37705 -53.745384) (xy 324.37705 -53.81244)
			(xy 324.377377 -53.82146) (xy 324.383644 -53.838377) (xy 324.389242 -53.84546) (xy 324.389496 -53.84546)
			(xy 324.389496 -53.845714) (xy 324.407147 -53.866638) (xy 324.43687 -53.912608) (xy 324.459713 -53.962355)
			(xy 324.475208 -54.014859) (xy 324.483035 -54.069038) (xy 324.483033 -54.12378) (xy 324.475204 -54.177959)
			(xy 324.459707 -54.230461) (xy 324.436861 -54.280208) (xy 324.407137 -54.326177) (xy 324.389496 -54.34711)
			(xy 324.389242 -54.347364) (xy 324.383657 -54.354452) (xy 324.377411 -54.371368) (xy 324.37705 -54.380384)
			(xy 324.37705 -54.44744) (xy 324.377377 -54.45646) (xy 324.383644 -54.473377) (xy 324.389242 -54.48046)
			(xy 324.389496 -54.48046) (xy 324.389496 -54.480714) (xy 324.407108 -54.501668) (xy 324.436824 -54.547635)
			(xy 324.459665 -54.597377) (xy 324.475163 -54.649873) (xy 324.482998 -54.704044) (xy 324.483476 -54.731412)
			(xy 324.48299 -54.758663) (xy 324.478326 -54.791102) (xy 326.376284 -54.791102) (xy 326.376731 -54.763731)
			(xy 326.38455 -54.70955) (xy 326.400043 -54.657046) (xy 326.422889 -54.607299) (xy 326.45262 -54.561334)
			(xy 326.470264 -54.540404) (xy 326.470518 -54.54015) (xy 326.476092 -54.533055) (xy 326.482346 -54.516145)
			(xy 326.48271 -54.50713) (xy 326.48271 -54.440074) (xy 326.482363 -54.431056) (xy 326.476108 -54.414139)
			(xy 326.470518 -54.407054) (xy 326.470264 -54.407054) (xy 326.470264 -54.4068) (xy 326.452624 -54.385866)
			(xy 326.422896 -54.3399) (xy 326.400048 -54.290154) (xy 326.38455 -54.237652) (xy 326.376721 -54.183472)
			(xy 326.37672 -54.128731) (xy 326.38455 -54.074551) (xy 326.400047 -54.022049) (xy 326.422895 -53.972303)
			(xy 326.452622 -53.926336) (xy 326.470264 -53.905404) (xy 326.470518 -53.90515) (xy 326.476092 -53.898055)
			(xy 326.482346 -53.881145) (xy 326.48271 -53.87213) (xy 326.48271 -53.805074) (xy 326.482363 -53.796056)
			(xy 326.476108 -53.779139) (xy 326.470518 -53.772054) (xy 326.470264 -53.772054) (xy 326.470264 -53.7718)
			(xy 326.452624 -53.750866) (xy 326.422896 -53.7049) (xy 326.400048 -53.655154) (xy 326.38455 -53.602652)
			(xy 326.376721 -53.548472) (xy 326.37672 -53.493731) (xy 326.38455 -53.439551) (xy 326.400047 -53.387049)
			(xy 326.422895 -53.337303) (xy 326.452622 -53.291336) (xy 326.470264 -53.270404) (xy 326.470518 -53.27015)
			(xy 326.476092 -53.263055) (xy 326.482346 -53.246145) (xy 326.48271 -53.23713) (xy 326.48271 -53.170074)
			(xy 326.482363 -53.161056) (xy 326.476108 -53.144139) (xy 326.470518 -53.137054) (xy 326.470264 -53.137054)
			(xy 326.470264 -53.1368) (xy 326.452606 -53.115883) (xy 326.422898 -53.069906) (xy 326.400066 -53.020154)
			(xy 326.38458 -52.96765) (xy 326.376756 -52.913472) (xy 326.376284 -52.886102) (xy 326.37677 -52.858851)
			(xy 326.384526 -52.804903) (xy 326.399881 -52.752608) (xy 326.422523 -52.703031) (xy 326.451989 -52.657181)
			(xy 326.48768 -52.61599) (xy 326.528871 -52.580299) (xy 326.574721 -52.550833) (xy 326.624298 -52.528191)
			(xy 326.676593 -52.512836) (xy 326.730541 -52.50508) (xy 326.785043 -52.50508) (xy 326.838991 -52.512836)
			(xy 326.891286 -52.528191) (xy 326.930399 -52.546054) (xy 331.879373 -52.546054) (xy 331.879373 -52.491546)
			(xy 331.887131 -52.437594) (xy 331.902489 -52.385294) (xy 331.925134 -52.335713) (xy 331.954605 -52.28986)
			(xy 331.990302 -52.248668) (xy 332.031499 -52.212976) (xy 332.077356 -52.183511) (xy 332.126939 -52.160872)
			(xy 332.179241 -52.145521) (xy 332.233194 -52.13777) (xy 332.260448 -52.13731) (xy 332.287817 -52.137804)
			(xy 332.341995 -52.145615) (xy 332.394498 -52.161097) (xy 332.444245 -52.183933) (xy 332.490213 -52.213651)
			(xy 332.511146 -52.23129) (xy 332.5114 -52.231544) (xy 332.518479 -52.237142) (xy 332.535402 -52.243381)
			(xy 332.54442 -52.243736) (xy 332.611476 -52.243736) (xy 332.620491 -52.24336) (xy 332.637407 -52.237125)
			(xy 332.644496 -52.231544) (xy 332.644496 -52.23129) (xy 332.64475 -52.23129) (xy 332.665683 -52.213649)
			(xy 332.711651 -52.183925) (xy 332.761397 -52.161079) (xy 332.813899 -52.145583) (xy 332.868077 -52.137754)
			(xy 332.922819 -52.137754) (xy 332.976997 -52.145583) (xy 333.029499 -52.161079) (xy 333.079245 -52.183925)
			(xy 333.125213 -52.213649) (xy 333.146146 -52.23129) (xy 333.1464 -52.231544) (xy 333.153479 -52.237142)
			(xy 333.170402 -52.243381) (xy 333.17942 -52.243736) (xy 333.246476 -52.243736) (xy 333.255491 -52.24336)
			(xy 333.272407 -52.237125) (xy 333.279496 -52.231544) (xy 333.279496 -52.23129) (xy 333.27975 -52.23129)
			(xy 333.300689 -52.213659) (xy 333.34666 -52.183947) (xy 333.396406 -52.161109) (xy 333.448905 -52.145616)
			(xy 333.503079 -52.137785) (xy 333.530448 -52.13731) (xy 333.557698 -52.137763) (xy 333.611643 -52.145526)
			(xy 333.663935 -52.160886) (xy 333.713508 -52.18353) (xy 333.759355 -52.212999) (xy 333.800541 -52.248693)
			(xy 333.836229 -52.289884) (xy 333.865693 -52.335734) (xy 333.888331 -52.38531) (xy 333.903685 -52.437604)
			(xy 333.91144 -52.49155) (xy 333.91144 -52.54605) (xy 333.905496 -52.587398) (xy 334.955132 -52.587398)
			(xy 334.959203 -52.531776) (xy 334.971329 -52.477339) (xy 334.991252 -52.425248) (xy 335.018548 -52.376613)
			(xy 335.052634 -52.33247) (xy 335.092783 -52.293761) (xy 335.138141 -52.26131) (xy 335.187741 -52.235809)
			(xy 335.240525 -52.217802) (xy 335.295368 -52.207672) (xy 335.351102 -52.205635) (xy 335.406539 -52.211735)
			(xy 335.460496 -52.225841) (xy 335.511825 -52.247653) (xy 335.559431 -52.276707) (xy 335.602299 -52.312382)
			(xy 335.639516 -52.353919) (xy 335.670289 -52.400432) (xy 335.693961 -52.450929) (xy 335.710029 -52.504336)
			(xy 335.718149 -52.559512) (xy 335.718658 -52.587398) (xy 335.718149 -52.615284) (xy 335.710029 -52.67046)
			(xy 335.693961 -52.723867) (xy 335.670289 -52.774364) (xy 335.639516 -52.820877) (xy 335.602299 -52.862414)
			(xy 335.559431 -52.898089) (xy 335.511825 -52.927143) (xy 335.460496 -52.948955) (xy 335.406539 -52.963061)
			(xy 335.351102 -52.969161) (xy 335.295368 -52.967124) (xy 335.240525 -52.956994) (xy 335.187741 -52.938987)
			(xy 335.138141 -52.913486) (xy 335.092783 -52.881035) (xy 335.052634 -52.842326) (xy 335.018548 -52.798183)
			(xy 334.991252 -52.749548) (xy 334.971329 -52.697457) (xy 334.959203 -52.64302) (xy 334.955132 -52.587398)
			(xy 333.905496 -52.587398) (xy 333.903685 -52.599996) (xy 333.888331 -52.65229) (xy 333.865693 -52.701866)
			(xy 333.836229 -52.747716) (xy 333.800541 -52.788907) (xy 333.759355 -52.824601) (xy 333.713508 -52.85407)
			(xy 333.663935 -52.876714) (xy 333.611643 -52.892074) (xy 333.557698 -52.899837) (xy 333.530448 -52.900326)
			(xy 333.503078 -52.89985) (xy 333.448899 -52.892037) (xy 333.396395 -52.876552) (xy 333.346648 -52.853712)
			(xy 333.300681 -52.823987) (xy 333.27975 -52.806346) (xy 333.279496 -52.806092) (xy 333.272415 -52.800497)
			(xy 333.255494 -52.794256) (xy 333.246476 -52.7939) (xy 333.17942 -52.7939) (xy 333.170404 -52.794266)
			(xy 333.153487 -52.800507) (xy 333.1464 -52.806092) (xy 333.146146 -52.806346) (xy 333.125213 -52.823987)
			(xy 333.079245 -52.853711) (xy 333.029499 -52.876557) (xy 332.976997 -52.892053) (xy 332.922819 -52.899882)
			(xy 332.868077 -52.899882) (xy 332.813899 -52.892053) (xy 332.761397 -52.876557) (xy 332.711651 -52.853711)
			(xy 332.665683 -52.823987) (xy 332.64475 -52.806346) (xy 332.644496 -52.806092) (xy 332.637415 -52.800497)
			(xy 332.620494 -52.794256) (xy 332.611476 -52.7939) (xy 332.54442 -52.7939) (xy 332.535404 -52.794266)
			(xy 332.518487 -52.800507) (xy 332.5114 -52.806092) (xy 332.5114 -52.806346) (xy 332.511146 -52.806346)
			(xy 332.4902 -52.823969) (xy 332.444232 -52.853685) (xy 332.394488 -52.876525) (xy 332.34199 -52.892019)
			(xy 332.287816 -52.899851) (xy 332.260448 -52.900326) (xy 332.233194 -52.89983) (xy 332.179241 -52.892079)
			(xy 332.126939 -52.876728) (xy 332.077356 -52.854089) (xy 332.031499 -52.824624) (xy 331.990302 -52.788932)
			(xy 331.954605 -52.74774) (xy 331.925134 -52.701887) (xy 331.902489 -52.652306) (xy 331.887131 -52.600006)
			(xy 331.879373 -52.546054) (xy 326.930399 -52.546054) (xy 326.940863 -52.550833) (xy 326.986713 -52.580299)
			(xy 327.027904 -52.61599) (xy 327.063595 -52.657181) (xy 327.093061 -52.703031) (xy 327.115703 -52.752608)
			(xy 327.131058 -52.804903) (xy 327.138814 -52.858851) (xy 327.1393 -52.886102) (xy 327.138835 -52.913472)
			(xy 327.131017 -52.967651) (xy 327.115528 -53.020155) (xy 327.092686 -53.069901) (xy 327.062961 -53.115868)
			(xy 327.04532 -53.1368) (xy 327.045066 -53.137054) (xy 327.039489 -53.144147) (xy 327.033238 -53.161059)
			(xy 327.032874 -53.170074) (xy 327.032874 -53.23713) (xy 327.033222 -53.246148) (xy 327.039476 -53.263064)
			(xy 327.045066 -53.27015) (xy 327.04532 -53.27015) (xy 327.04532 -53.270404) (xy 327.062961 -53.291336)
			(xy 327.092682 -53.337305) (xy 327.115524 -53.387052) (xy 327.131018 -53.439554) (xy 327.138846 -53.493731)
			(xy 327.138845 -53.548472) (xy 327.131018 -53.602649) (xy 327.115523 -53.655151) (xy 327.09268 -53.704897)
			(xy 327.062959 -53.750866) (xy 327.04639 -53.77053) (xy 327.410572 -53.77053) (xy 327.411084 -53.741613)
			(xy 327.419811 -53.68444) (xy 327.437068 -53.62924) (xy 327.462461 -53.577277) (xy 327.495407 -53.529744)
			(xy 327.535151 -53.487729) (xy 327.557638 -53.46954) (xy 327.566423 -53.461912) (xy 327.576617 -53.441027)
			(xy 327.577196 -53.429408) (xy 327.577196 -53.349652) (xy 327.576672 -53.338018) (xy 327.566473 -53.317109)
			(xy 327.557638 -53.30952) (xy 327.535172 -53.291308) (xy 327.495434 -53.249294) (xy 327.462492 -53.201764)
			(xy 327.4371 -53.149806) (xy 327.419841 -53.094612) (xy 327.411108 -53.037445) (xy 327.410572 -53.00853)
			(xy 327.411083 -52.981279) (xy 327.418836 -52.927331) (xy 327.434187 -52.875035) (xy 327.456824 -52.825456)
			(xy 327.486287 -52.779604) (xy 327.521976 -52.738411) (xy 327.563164 -52.702717) (xy 327.609012 -52.673248)
			(xy 327.658588 -52.650604) (xy 327.710882 -52.635246) (xy 327.764829 -52.627487) (xy 327.79208 -52.627022)
			(xy 327.818394 -52.627496) (xy 327.870522 -52.634728) (xy 327.921165 -52.649046) (xy 327.969364 -52.670177)
			(xy 328.014208 -52.697722) (xy 328.054848 -52.731161) (xy 328.073004 -52.750212) (xy 328.08052 -52.757619)
			(xy 328.099804 -52.76614) (xy 328.110342 -52.766722) (xy 328.185018 -52.766722) (xy 328.195563 -52.766155)
			(xy 328.214858 -52.757646) (xy 328.222356 -52.750212) (xy 328.240494 -52.731139) (xy 328.281127 -52.697683)
			(xy 328.325971 -52.670126) (xy 328.374175 -52.64899) (xy 328.424826 -52.634677) (xy 328.476963 -52.627458)
			(xy 328.50328 -52.627022) (xy 328.530534 -52.627474) (xy 328.584487 -52.635229) (xy 328.636787 -52.650584)
			(xy 328.686369 -52.673226) (xy 328.732223 -52.702695) (xy 328.773417 -52.73839) (xy 328.809111 -52.779585)
			(xy 328.838578 -52.82544) (xy 328.861219 -52.875023) (xy 328.876573 -52.927323) (xy 328.884327 -52.981276)
			(xy 328.884788 -53.00853) (xy 328.884305 -53.036196) (xy 328.876301 -53.090947) (xy 328.86048 -53.143969)
			(xy 328.837172 -53.194154) (xy 328.806866 -53.240449) (xy 328.770197 -53.281886) (xy 328.727931 -53.317598)
			(xy 328.704702 -53.332634) (xy 328.695021 -53.339266) (xy 328.682577 -53.35913) (xy 328.680826 -53.370734)
			(xy 328.672952 -53.450744) (xy 328.6723 -53.462383) (xy 328.680394 -53.484221) (xy 328.688446 -53.492654)
			(xy 328.6887 -53.492908) (xy 328.707267 -53.511003) (xy 328.739847 -53.551332) (xy 328.766662 -53.595703)
			(xy 328.787217 -53.643299) (xy 328.801133 -53.693241) (xy 328.808154 -53.744608) (xy 328.808588 -53.77053)
			(xy 328.80815 -53.797783) (xy 328.800389 -53.851733) (xy 328.785029 -53.90403) (xy 328.762383 -53.953609)
			(xy 328.732912 -53.99946) (xy 328.697215 -54.040651) (xy 328.65602 -54.076342) (xy 328.610165 -54.105807)
			(xy 328.560583 -54.128446) (xy 328.508284 -54.1438) (xy 328.454333 -54.151554) (xy 328.42708 -54.152038)
			(xy 328.399709 -54.151599) (xy 328.345528 -54.143777) (xy 328.293024 -54.128282) (xy 328.243277 -54.105434)
			(xy 328.197312 -54.075703) (xy 328.176382 -54.058058) (xy 328.176128 -54.057804) (xy 328.169037 -54.052223)
			(xy 328.152124 -54.045973) (xy 328.143108 -54.045612) (xy 328.076052 -54.045612) (xy 328.067037 -54.045991)
			(xy 328.05012 -54.052223) (xy 328.043032 -54.057804) (xy 328.043032 -54.058058) (xy 328.042778 -54.058058)
			(xy 328.021822 -54.075667) (xy 327.975856 -54.105385) (xy 327.926115 -54.128228) (xy 327.873619 -54.143725)
			(xy 327.819448 -54.151561) (xy 327.79208 -54.152038) (xy 327.76483 -54.151541) (xy 327.710884 -54.143782)
			(xy 327.658591 -54.128426) (xy 327.609016 -54.105785) (xy 327.563167 -54.076319) (xy 327.521978 -54.040629)
			(xy 327.486287 -53.999441) (xy 327.45682 -53.953593) (xy 327.434177 -53.904018) (xy 327.41882 -53.851726)
			(xy 327.41106 -53.79778) (xy 327.410572 -53.77053) (xy 327.04639 -53.77053) (xy 327.04532 -53.7718)
			(xy 327.045066 -53.772054) (xy 327.039489 -53.779147) (xy 327.033238 -53.796059) (xy 327.032874 -53.805074)
			(xy 327.032874 -53.87213) (xy 327.033222 -53.881148) (xy 327.039476 -53.898064) (xy 327.045066 -53.90515)
			(xy 327.04532 -53.90515) (xy 327.04532 -53.905404) (xy 327.062961 -53.926336) (xy 327.092682 -53.972305)
			(xy 327.115524 -54.022052) (xy 327.131018 -54.074554) (xy 327.138846 -54.128731) (xy 327.138845 -54.183472)
			(xy 327.131018 -54.237649) (xy 327.115523 -54.290151) (xy 327.101731 -54.320186) (xy 329.330304 -54.320186)
			(xy 329.330761 -54.292815) (xy 329.338581 -54.238636) (xy 329.354072 -54.186133) (xy 329.376916 -54.136386)
			(xy 329.406642 -54.090419) (xy 329.424284 -54.069488) (xy 329.424538 -54.069234) (xy 329.430121 -54.062145)
			(xy 329.436369 -54.04523) (xy 329.43673 -54.036214) (xy 329.43673 -53.969158) (xy 329.436339 -53.960145)
			(xy 329.430114 -53.943228) (xy 329.424538 -53.936138) (xy 329.424284 -53.936138) (xy 329.424284 -53.935884)
			(xy 329.406668 -53.914933) (xy 329.376954 -53.868965) (xy 329.354113 -53.819222) (xy 329.338617 -53.766726)
			(xy 329.330782 -53.712554) (xy 329.330304 -53.685186) (xy 329.33079 -53.657935) (xy 329.338546 -53.603987)
			(xy 329.353901 -53.551692) (xy 329.376543 -53.502115) (xy 329.406009 -53.456265) (xy 329.4417 -53.415074)
			(xy 329.482891 -53.379383) (xy 329.528741 -53.349917) (xy 329.578318 -53.327275) (xy 329.630613 -53.31192)
			(xy 329.684561 -53.304164) (xy 329.739063 -53.304164) (xy 329.793011 -53.31192) (xy 329.845306 -53.327275)
			(xy 329.894883 -53.349917) (xy 329.940733 -53.379383) (xy 329.981924 -53.415074) (xy 330.017615 -53.456265)
			(xy 330.047081 -53.502115) (xy 330.069723 -53.551692) (xy 330.085078 -53.603987) (xy 330.092834 -53.657935)
			(xy 330.09332 -53.685186) (xy 330.092865 -53.712557) (xy 330.085048 -53.766737) (xy 330.069557 -53.819241)
			(xy 330.046712 -53.868988) (xy 330.016984 -53.914954) (xy 329.99934 -53.935884) (xy 329.999086 -53.936138)
			(xy 329.993518 -53.943237) (xy 329.98726 -53.960144) (xy 329.986894 -53.969158) (xy 329.986894 -54.036214)
			(xy 329.987246 -54.045231) (xy 329.993497 -54.062148) (xy 329.999086 -54.069234) (xy 329.99934 -54.069234)
			(xy 329.99934 -54.069488) (xy 330.016994 -54.090408) (xy 330.046702 -54.136385) (xy 330.069535 -54.186136)
			(xy 330.085022 -54.238639) (xy 330.092848 -54.292816) (xy 330.09332 -54.320186) (xy 330.092834 -54.347437)
			(xy 330.085078 -54.401385) (xy 330.069723 -54.45368) (xy 330.047081 -54.503257) (xy 330.017615 -54.549107)
			(xy 329.981924 -54.590298) (xy 329.940733 -54.625989) (xy 329.894883 -54.655455) (xy 329.845306 -54.678097)
			(xy 329.793011 -54.693452) (xy 329.739063 -54.701208) (xy 329.684561 -54.701208) (xy 329.630613 -54.693452)
			(xy 329.578318 -54.678097) (xy 329.528741 -54.655455) (xy 329.482891 -54.625989) (xy 329.4417 -54.590298)
			(xy 329.406009 -54.549107) (xy 329.376543 -54.503257) (xy 329.353901 -54.45368) (xy 329.338546 -54.401385)
			(xy 329.33079 -54.347437) (xy 329.330304 -54.320186) (xy 327.101731 -54.320186) (xy 327.09268 -54.339897)
			(xy 327.062959 -54.385866) (xy 327.04532 -54.4068) (xy 327.045066 -54.407054) (xy 327.039489 -54.414147)
			(xy 327.033238 -54.431059) (xy 327.032874 -54.440074) (xy 327.032874 -54.50713) (xy 327.033222 -54.516148)
			(xy 327.039476 -54.533064) (xy 327.045066 -54.54015) (xy 327.04532 -54.54015) (xy 327.04532 -54.540404)
			(xy 327.062978 -54.561321) (xy 327.092686 -54.607298) (xy 327.115518 -54.65705) (xy 327.131005 -54.709554)
			(xy 327.138828 -54.763732) (xy 327.138945 -54.770528) (xy 330.270866 -54.770528) (xy 330.271332 -54.743158)
			(xy 330.279148 -54.688978) (xy 330.294636 -54.636474) (xy 330.317478 -54.586727) (xy 330.347204 -54.540761)
			(xy 330.364846 -54.51983) (xy 330.3651 -54.519576) (xy 330.370703 -54.5125) (xy 330.37694 -54.495575)
			(xy 330.377292 -54.486556) (xy 330.377292 -54.4195) (xy 330.376937 -54.410483) (xy 330.370688 -54.393566)
			(xy 330.3651 -54.38648) (xy 330.364846 -54.38648) (xy 330.364846 -54.386226) (xy 330.347213 -54.365289)
			(xy 330.317498 -54.319318) (xy 330.294661 -54.269572) (xy 330.279168 -54.217072) (xy 330.27134 -54.162897)
			(xy 330.270866 -54.135528) (xy 330.271352 -54.108277) (xy 330.279108 -54.054329) (xy 330.294463 -54.002034)
			(xy 330.317105 -53.952457) (xy 330.346571 -53.906607) (xy 330.382262 -53.865416) (xy 330.423453 -53.829725)
			(xy 330.469303 -53.800259) (xy 330.51888 -53.777617) (xy 330.571175 -53.762262) (xy 330.625123 -53.754506)
			(xy 330.679625 -53.754506) (xy 330.733573 -53.762262) (xy 330.785868 -53.777617) (xy 330.835445 -53.800259)
			(xy 330.881295 -53.829725) (xy 330.922486 -53.865416) (xy 330.958177 -53.906607) (xy 330.987643 -53.952457)
			(xy 330.992718 -53.96357) (xy 334.971896 -53.96357) (xy 334.975967 -53.907948) (xy 334.988093 -53.853511)
			(xy 335.008016 -53.80142) (xy 335.035312 -53.752785) (xy 335.069398 -53.708642) (xy 335.109547 -53.669933)
			(xy 335.154905 -53.637482) (xy 335.204505 -53.611981) (xy 335.257289 -53.593974) (xy 335.312132 -53.583844)
			(xy 335.367866 -53.581807) (xy 335.423303 -53.587907) (xy 335.47726 -53.602013) (xy 335.528589 -53.623825)
			(xy 335.576195 -53.652879) (xy 335.619063 -53.688554) (xy 335.65628 -53.730091) (xy 335.687053 -53.776604)
			(xy 335.710725 -53.827101) (xy 335.726793 -53.880508) (xy 335.734913 -53.935684) (xy 335.735422 -53.96357)
			(xy 335.734913 -53.991456) (xy 335.726793 -54.046632) (xy 335.710725 -54.100039) (xy 335.687053 -54.150536)
			(xy 335.65628 -54.197049) (xy 335.619063 -54.238586) (xy 335.576195 -54.274261) (xy 335.528589 -54.303315)
			(xy 335.47726 -54.325127) (xy 335.423303 -54.339233) (xy 335.367866 -54.345333) (xy 335.312132 -54.343296)
			(xy 335.257289 -54.333166) (xy 335.204505 -54.315159) (xy 335.154905 -54.289658) (xy 335.109547 -54.257207)
			(xy 335.069398 -54.218498) (xy 335.035312 -54.174355) (xy 335.008016 -54.12572) (xy 334.988093 -54.073629)
			(xy 334.975967 -54.019192) (xy 334.971896 -53.96357) (xy 330.992718 -53.96357) (xy 331.010285 -54.002034)
			(xy 331.02564 -54.054329) (xy 331.033396 -54.108277) (xy 331.033882 -54.135528) (xy 331.033437 -54.162899)
			(xy 331.025615 -54.217079) (xy 331.010121 -54.269583) (xy 330.987274 -54.319329) (xy 330.957545 -54.365295)
			(xy 330.939902 -54.386226) (xy 330.939648 -54.38648) (xy 330.934057 -54.393564) (xy 330.927814 -54.410483)
			(xy 330.927456 -54.4195) (xy 330.927456 -54.486556) (xy 330.927822 -54.495572) (xy 330.934062 -54.51249)
			(xy 330.939648 -54.519576) (xy 330.939902 -54.519576) (xy 330.939902 -54.51983) (xy 330.957522 -54.540777)
			(xy 330.987237 -54.586746) (xy 331.010076 -54.63649) (xy 331.025572 -54.688987) (xy 331.033405 -54.74316)
			(xy 331.033882 -54.770528) (xy 331.033396 -54.797779) (xy 331.02564 -54.851727) (xy 331.010285 -54.904022)
			(xy 330.987643 -54.953599) (xy 330.958177 -54.999449) (xy 330.922486 -55.04064) (xy 330.881295 -55.076331)
			(xy 330.835445 -55.105797) (xy 330.785868 -55.128439) (xy 330.733573 -55.143794) (xy 330.679625 -55.15155)
			(xy 330.625123 -55.15155) (xy 330.571175 -55.143794) (xy 330.51888 -55.128439) (xy 330.469303 -55.105797)
			(xy 330.423453 -55.076331) (xy 330.382262 -55.04064) (xy 330.346571 -54.999449) (xy 330.317105 -54.953599)
			(xy 330.294463 -54.904022) (xy 330.279108 -54.851727) (xy 330.271352 -54.797779) (xy 330.270866 -54.770528)
			(xy 327.138945 -54.770528) (xy 327.1393 -54.791102) (xy 327.138814 -54.818353) (xy 327.131058 -54.872301)
			(xy 327.115703 -54.924596) (xy 327.093061 -54.974173) (xy 327.063595 -55.020023) (xy 327.027904 -55.061214)
			(xy 326.986713 -55.096905) (xy 326.940863 -55.126371) (xy 326.891286 -55.149013) (xy 326.838991 -55.164368)
			(xy 326.785043 -55.172124) (xy 326.730541 -55.172124) (xy 326.676593 -55.164368) (xy 326.624298 -55.149013)
			(xy 326.574721 -55.126371) (xy 326.528871 -55.096905) (xy 326.48768 -55.061214) (xy 326.451989 -55.020023)
			(xy 326.422523 -54.974173) (xy 326.399881 -54.924596) (xy 326.384526 -54.872301) (xy 326.37677 -54.818353)
			(xy 326.376284 -54.791102) (xy 324.478326 -54.791102) (xy 324.475234 -54.812611) (xy 324.459879 -54.864906)
			(xy 324.437237 -54.914483) (xy 324.407771 -54.960333) (xy 324.37208 -55.001524) (xy 324.330889 -55.037215)
			(xy 324.285039 -55.066681) (xy 324.235462 -55.089323) (xy 324.183167 -55.104678) (xy 324.129219 -55.112434)
			(xy 324.074717 -55.112434) (xy 324.020769 -55.104678) (xy 323.968474 -55.089323) (xy 323.918897 -55.066681)
			(xy 323.873047 -55.037215) (xy 323.831856 -55.001524) (xy 323.796165 -54.960333) (xy 323.766699 -54.914483)
			(xy 323.744057 -54.864906) (xy 323.728702 -54.812611) (xy 323.720946 -54.758663) (xy 323.72046 -54.731412)
			(xy 322.957952 -54.731412) (xy 322.957952 -57.002934) (xy 331.76337 -57.002934) (xy 331.763897 -56.974844)
			(xy 331.772119 -56.919268) (xy 331.788405 -56.8655) (xy 331.812403 -56.814703) (xy 331.843592 -56.767976)
			(xy 331.881299 -56.72633) (xy 331.924708 -56.690666) (xy 331.948536 -56.675782) (xy 331.957426 -56.670448)
			(xy 331.969618 -56.65343) (xy 331.989938 -56.560212) (xy 331.98562 -56.539638) (xy 331.979778 -56.531002)
			(xy 331.963774 -56.506941) (xy 331.938433 -56.455008) (xy 331.921208 -56.399849) (xy 331.912494 -56.342725)
			(xy 331.91196 -56.313832) (xy 331.912508 -56.286583) (xy 331.920259 -56.232639) (xy 331.935609 -56.180348)
			(xy 331.958244 -56.130773) (xy 331.987704 -56.084924) (xy 332.023389 -56.043734) (xy 332.064572 -56.008042)
			(xy 332.110416 -55.978574) (xy 332.159988 -55.955931) (xy 332.212277 -55.940573) (xy 332.266219 -55.932812)
			(xy 332.293468 -55.932324) (xy 332.320838 -55.932803) (xy 332.375017 -55.940617) (xy 332.42752 -55.956103)
			(xy 332.477267 -55.978942) (xy 332.523234 -56.008664) (xy 332.544166 -56.026304) (xy 332.54442 -56.026558)
			(xy 332.551492 -56.032166) (xy 332.56842 -56.038398) (xy 332.57744 -56.03875) (xy 332.644496 -56.03875)
			(xy 332.653514 -56.038402) (xy 332.670431 -56.032149) (xy 332.677516 -56.026558) (xy 332.677516 -56.026304)
			(xy 332.67777 -56.026304) (xy 332.698703 -56.008663) (xy 332.744671 -55.978939) (xy 332.794417 -55.956093)
			(xy 332.846919 -55.940597) (xy 332.901097 -55.932768) (xy 332.955839 -55.932768) (xy 333.010017 -55.940597)
			(xy 333.062519 -55.956093) (xy 333.112265 -55.978939) (xy 333.158233 -56.008663) (xy 333.179166 -56.026304)
			(xy 333.17942 -56.026558) (xy 333.186492 -56.032166) (xy 333.20342 -56.038398) (xy 333.21244 -56.03875)
			(xy 333.279496 -56.03875) (xy 333.288514 -56.038402) (xy 333.305431 -56.032149) (xy 333.312516 -56.026558)
			(xy 333.312516 -56.026304) (xy 333.31277 -56.026304) (xy 333.333703 -56.008666) (xy 333.379676 -55.978954)
			(xy 333.429423 -55.956118) (xy 333.481923 -55.940626) (xy 333.536099 -55.932798) (xy 333.563468 -55.932324)
			(xy 333.590725 -55.932721) (xy 333.644684 -55.940475) (xy 333.69699 -55.955829) (xy 333.746578 -55.978472)
			(xy 333.792439 -56.007941) (xy 333.833639 -56.043638) (xy 333.869339 -56.084835) (xy 333.898813 -56.130694)
			(xy 333.92146 -56.18028) (xy 333.936819 -56.232585) (xy 333.944577 -56.286543) (xy 333.944577 -56.341057)
			(xy 333.936819 -56.395015) (xy 333.92146 -56.44732) (xy 333.898813 -56.496906) (xy 333.869339 -56.542765)
			(xy 333.833639 -56.583962) (xy 333.792439 -56.619659) (xy 333.746578 -56.649128) (xy 333.69699 -56.671771)
			(xy 333.644684 -56.687125) (xy 333.590725 -56.694879) (xy 333.563468 -56.69534) (xy 333.536096 -56.694907)
			(xy 333.481915 -56.687084) (xy 333.429411 -56.671588) (xy 333.379665 -56.648738) (xy 333.3337 -56.619005)
			(xy 333.31277 -56.60136) (xy 333.312516 -56.601106) (xy 333.305429 -56.595521) (xy 333.288512 -56.589273)
			(xy 333.279496 -56.588914) (xy 333.21244 -56.588914) (xy 333.203425 -56.589287) (xy 333.186508 -56.595523)
			(xy 333.17942 -56.601106) (xy 333.17942 -56.60136) (xy 333.179166 -56.60136) (xy 333.158233 -56.619001)
			(xy 333.112265 -56.648725) (xy 333.062519 -56.671571) (xy 333.010017 -56.687067) (xy 332.955839 -56.694896)
			(xy 332.901097 -56.694896) (xy 332.846919 -56.687067) (xy 332.794417 -56.671571) (xy 332.744671 -56.648725)
			(xy 332.698703 -56.619001) (xy 332.67777 -56.60136) (xy 332.677516 -56.601106) (xy 332.670429 -56.595521)
			(xy 332.653512 -56.589273) (xy 332.644496 -56.588914) (xy 332.57744 -56.588914) (xy 332.568425 -56.589287)
			(xy 332.551508 -56.595523) (xy 332.54442 -56.601106) (xy 332.543912 -56.60136) (xy 332.531181 -56.612308)
			(xy 332.504087 -56.632147) (xy 332.48981 -56.640984) (xy 332.48092 -56.646318) (xy 332.468728 -56.663336)
			(xy 332.448408 -56.756554) (xy 332.452726 -56.777128) (xy 332.458568 -56.785764) (xy 332.474551 -56.809839)
			(xy 332.499899 -56.861766) (xy 332.517129 -56.916921) (xy 332.525849 -56.974042) (xy 332.526386 -57.002934)
			(xy 332.5259 -57.030185) (xy 332.518144 -57.084133) (xy 332.502789 -57.136428) (xy 332.480147 -57.186005)
			(xy 332.450681 -57.231855) (xy 332.41499 -57.273046) (xy 332.373799 -57.308737) (xy 332.327949 -57.338203)
			(xy 332.278372 -57.360845) (xy 332.226077 -57.3762) (xy 332.172129 -57.383956) (xy 332.117627 -57.383956)
			(xy 332.063679 -57.3762) (xy 332.011384 -57.360845) (xy 331.961807 -57.338203) (xy 331.915957 -57.308737)
			(xy 331.874766 -57.273046) (xy 331.839075 -57.231855) (xy 331.809609 -57.186005) (xy 331.786967 -57.136428)
			(xy 331.771612 -57.084133) (xy 331.763856 -57.030185) (xy 331.76337 -57.002934) (xy 322.957952 -57.002934)
			(xy 322.957952 -58.679334) (xy 332.19517 -58.679334) (xy 332.195603 -58.653019) (xy 332.202846 -58.600889)
			(xy 332.217173 -58.550246) (xy 332.238312 -58.502048) (xy 332.265863 -58.457205) (xy 332.299307 -58.416566)
			(xy 332.31836 -58.39841) (xy 332.325753 -58.390881) (xy 332.334284 -58.371607) (xy 332.33487 -58.361072)
			(xy 332.33487 -58.286396) (xy 332.334365 -58.275843) (xy 332.325814 -58.256548) (xy 332.31836 -58.249058)
			(xy 332.299283 -58.230924) (xy 332.26583 -58.190289) (xy 332.238274 -58.145444) (xy 332.21714 -58.097239)
			(xy 332.202827 -58.046588) (xy 332.195606 -57.994451) (xy 332.19517 -57.968134) (xy 332.195656 -57.940883)
			(xy 332.203412 -57.886935) (xy 332.218767 -57.83464) (xy 332.241409 -57.785063) (xy 332.270875 -57.739213)
			(xy 332.306566 -57.698022) (xy 332.347757 -57.662331) (xy 332.393607 -57.632865) (xy 332.443184 -57.610223)
			(xy 332.495479 -57.594868) (xy 332.549427 -57.587112) (xy 332.603929 -57.587112) (xy 332.657877 -57.594868)
			(xy 332.710172 -57.610223) (xy 332.759749 -57.632865) (xy 332.805599 -57.662331) (xy 332.84679 -57.698022)
			(xy 332.882481 -57.739213) (xy 332.911947 -57.785063) (xy 332.934589 -57.83464) (xy 332.949944 -57.886935)
			(xy 332.9577 -57.940883) (xy 332.958186 -57.968134) (xy 332.957746 -57.994449) (xy 332.950506 -58.046579)
			(xy 332.936182 -58.097222) (xy 332.915044 -58.145421) (xy 332.887493 -58.190264) (xy 332.85405 -58.230902)
			(xy 332.834996 -58.249058) (xy 332.82761 -58.256593) (xy 332.819077 -58.275863) (xy 332.818486 -58.286396)
			(xy 332.818486 -58.361072) (xy 332.819021 -58.371621) (xy 332.827553 -58.390916) (xy 332.834996 -58.39841)
			(xy 332.854049 -58.416569) (xy 332.887506 -58.457197) (xy 332.915066 -58.502037) (xy 332.936205 -58.550237)
			(xy 332.950522 -58.600884) (xy 332.957747 -58.653018) (xy 332.958186 -58.679334) (xy 332.9577 -58.706585)
			(xy 332.949944 -58.760533) (xy 332.934589 -58.812828) (xy 332.911947 -58.862405) (xy 332.882481 -58.908255)
			(xy 332.84679 -58.949446) (xy 332.805599 -58.985137) (xy 332.759749 -59.014603) (xy 332.710172 -59.037245)
			(xy 332.657877 -59.0526) (xy 332.603929 -59.060356) (xy 332.549427 -59.060356) (xy 332.495479 -59.0526)
			(xy 332.443184 -59.037245) (xy 332.393607 -59.014603) (xy 332.347757 -58.985137) (xy 332.306566 -58.949446)
			(xy 332.270875 -58.908255) (xy 332.241409 -58.862405) (xy 332.218767 -58.812828) (xy 332.203412 -58.760533)
			(xy 332.195656 -58.706585) (xy 332.19517 -58.679334) (xy 322.957952 -58.679334) (xy 322.957952 -60.019254)
			(xy 332.335561 -60.019254) (xy 332.335561 -59.964746) (xy 332.343319 -59.910793) (xy 332.358677 -59.858494)
			(xy 332.381321 -59.808912) (xy 332.410791 -59.763058) (xy 332.446488 -59.721865) (xy 332.487684 -59.686172)
			(xy 332.53354 -59.656706) (xy 332.583124 -59.634065) (xy 332.635425 -59.618712) (xy 332.689378 -59.610959)
			(xy 332.716632 -59.610498) (xy 332.744003 -59.610946) (xy 332.798183 -59.618768) (xy 332.850686 -59.634261)
			(xy 332.900433 -59.657107) (xy 332.946399 -59.686835) (xy 332.96733 -59.704478) (xy 332.967584 -59.704732)
			(xy 332.974668 -59.710322) (xy 332.991587 -59.716565) (xy 333.000604 -59.716924) (xy 333.06766 -59.716924)
			(xy 333.076674 -59.716543) (xy 333.093591 -59.710311) (xy 333.10068 -59.704732) (xy 333.10068 -59.704478)
			(xy 333.100934 -59.704478) (xy 333.121867 -59.686837) (xy 333.167835 -59.657113) (xy 333.217581 -59.634267)
			(xy 333.270083 -59.618771) (xy 333.324261 -59.610942) (xy 333.379003 -59.610942) (xy 333.433181 -59.618771)
			(xy 333.485683 -59.634267) (xy 333.535429 -59.657113) (xy 333.581397 -59.686837) (xy 333.60233 -59.704478)
			(xy 333.602584 -59.704732) (xy 333.609668 -59.710322) (xy 333.626587 -59.716565) (xy 333.635604 -59.716924)
			(xy 333.70266 -59.716924) (xy 333.711674 -59.716543) (xy 333.728591 -59.710311) (xy 333.73568 -59.704732)
			(xy 333.73568 -59.704478) (xy 333.735934 -59.704478) (xy 333.756877 -59.686853) (xy 333.802847 -59.65714)
			(xy 333.852592 -59.634301) (xy 333.90509 -59.618807) (xy 333.959264 -59.610975) (xy 333.986632 -59.610498)
			(xy 334.013882 -59.610974) (xy 334.067827 -59.618734) (xy 334.120119 -59.634092) (xy 334.169693 -59.656736)
			(xy 334.21554 -59.686203) (xy 334.256727 -59.721895) (xy 334.292416 -59.763086) (xy 334.32188 -59.808935)
			(xy 334.344519 -59.858511) (xy 334.359872 -59.910804) (xy 334.367628 -59.96475) (xy 334.367628 -60.01925)
			(xy 334.359872 -60.073196) (xy 334.344519 -60.125489) (xy 334.32188 -60.175065) (xy 334.292416 -60.220914)
			(xy 334.256727 -60.262105) (xy 334.21554 -60.297797) (xy 334.169693 -60.327264) (xy 334.120119 -60.349908)
			(xy 334.067827 -60.365266) (xy 334.013882 -60.373026) (xy 333.986632 -60.373514) (xy 333.959263 -60.373026)
			(xy 333.905085 -60.365213) (xy 333.852582 -60.349729) (xy 333.802835 -60.326892) (xy 333.756867 -60.297173)
			(xy 333.735934 -60.279534) (xy 333.73568 -60.27928) (xy 333.728605 -60.273677) (xy 333.711679 -60.267441)
			(xy 333.70266 -60.267088) (xy 333.635604 -60.267088) (xy 333.626588 -60.26745) (xy 333.609671 -60.273694)
			(xy 333.602584 -60.27928) (xy 333.60233 -60.279534) (xy 333.581397 -60.297175) (xy 333.535429 -60.326899)
			(xy 333.485683 -60.349745) (xy 333.433181 -60.365241) (xy 333.379003 -60.37307) (xy 333.324261 -60.37307)
			(xy 333.270083 -60.365241) (xy 333.217581 -60.349745) (xy 333.167835 -60.326899) (xy 333.121867 -60.297175)
			(xy 333.100934 -60.279534) (xy 333.10068 -60.27928) (xy 333.093605 -60.273677) (xy 333.076679 -60.267441)
			(xy 333.06766 -60.267088) (xy 333.000604 -60.267088) (xy 332.991588 -60.26745) (xy 332.974671 -60.273694)
			(xy 332.967584 -60.27928) (xy 332.967584 -60.279534) (xy 332.96733 -60.279534) (xy 332.946402 -60.297178)
			(xy 332.900427 -60.326888) (xy 332.850679 -60.349722) (xy 332.798178 -60.365212) (xy 332.744001 -60.37304)
			(xy 332.716632 -60.373514) (xy 332.689378 -60.373041) (xy 332.635425 -60.365288) (xy 332.583124 -60.349935)
			(xy 332.53354 -60.327294) (xy 332.487684 -60.297828) (xy 332.446488 -60.262135) (xy 332.410791 -60.220942)
			(xy 332.381321 -60.175088) (xy 332.358677 -60.125506) (xy 332.343319 -60.073207) (xy 332.335561 -60.019254)
			(xy 322.957952 -60.019254) (xy 322.957952 -65.248028) (xy 322.958968 -65.258442) (xy 322.960699 -65.265575)
			(xy 322.96766 -65.278491) (xy 322.972684 -65.283842) (xy 324.438518 -66.749422) (xy 324.438772 -66.749676)
			(xy 324.457234 -66.768977) (xy 324.488372 -66.812367) (xy 324.500748 -66.836036) (xy 324.50659 -66.84772)
			(xy 324.51294 -66.852292) (xy 324.513956 -66.8528) (xy 324.517258 -66.855086) (xy 324.520224 -66.857061)
			(xy 324.5266 -66.860243) (xy 324.529958 -66.861436) (xy 324.536054 -66.863468) (xy 324.579996 -66.868802)
			(xy 324.586092 -66.869056) (xy 324.621144 -66.869056) (xy 324.62652 -66.868897) (xy 324.637025 -66.866596)
			(xy 324.641972 -66.864484) (xy 324.651878 -66.860166) (xy 324.659244 -66.85153) (xy 324.677456 -66.831304)
			(xy 324.718628 -66.79571) (xy 324.76444 -66.766328) (xy 324.813964 -66.743756) (xy 324.866193 -66.728453)
			(xy 324.920067 -66.720729) (xy 324.94728 -66.720212) (xy 324.947534 -66.720212) (xy 324.962266 -66.720466)
			(xy 324.965568 -66.720466) (xy 324.984872 -66.72199) (xy 324.985126 -66.72199) (xy 324.996048 -66.72326)
			(xy 324.996302 -66.72326) (xy 325.003668 -66.724276) (xy 325.004176 -66.724276) (xy 325.029322 -66.729102)
			(xy 325.02983 -66.729102) (xy 325.048545 -66.733457) (xy 325.085062 -66.74542) (xy 325.102728 -66.752978)
			(xy 325.110856 -66.756788) (xy 325.123556 -66.763138) (xy 325.139807 -66.771777) (xy 325.170723 -66.791752)
			(xy 325.185278 -66.803016) (xy 325.192203 -66.808125) (xy 325.208429 -66.813826) (xy 325.217028 -66.814192)
			(xy 325.238364 -66.814192) (xy 325.243803 -66.814338) (xy 325.254432 -66.816651) (xy 325.259446 -66.818764)
			(xy 325.273162 -66.825114) (xy 325.277866 -66.82718) (xy 325.287847 -66.829614) (xy 325.292974 -66.82994)
			(xy 325.30161 -66.829432) (xy 325.308894 -66.828146) (xy 325.322315 -66.821943) (xy 325.328026 -66.81724)
			(xy 325.32828 -66.816986) (xy 325.34935 -66.798877) (xy 325.395743 -66.768315) (xy 325.446076 -66.744799)
			(xy 325.499286 -66.728827) (xy 325.554249 -66.720736) (xy 325.582026 -66.720212) (xy 325.582534 -66.720212)
			(xy 325.609782 -66.720701) (xy 325.663723 -66.728461) (xy 325.716011 -66.743818) (xy 325.765582 -66.76646)
			(xy 325.811425 -66.795925) (xy 325.852609 -66.831615) (xy 325.888295 -66.872802) (xy 325.917757 -66.918648)
			(xy 325.940394 -66.968221) (xy 325.955747 -67.02051) (xy 325.963502 -67.074452) (xy 325.963502 -67.128948)
			(xy 325.955747 -67.18289) (xy 325.940394 -67.235179) (xy 325.917757 -67.284752) (xy 325.888295 -67.330598)
			(xy 325.852609 -67.371785) (xy 325.811425 -67.407475) (xy 325.765582 -67.43694) (xy 325.716011 -67.459582)
			(xy 325.663723 -67.474939) (xy 325.609782 -67.482699) (xy 325.582534 -67.483228) (xy 325.556918 -67.482814)
			(xy 325.506147 -67.475954) (xy 325.456754 -67.462352) (xy 325.409629 -67.442255) (xy 325.365621 -67.416024)
			(xy 325.345298 -67.400424) (xy 325.345044 -67.40017) (xy 325.341996 -67.39763) (xy 325.335886 -67.393899)
			(xy 325.32222 -67.389651) (xy 325.315072 -67.389248) (xy 325.291704 -67.389248) (xy 325.286264 -67.389108)
			(xy 325.27563 -67.386805) (xy 325.270622 -67.384676) (xy 325.256906 -67.378326) (xy 325.252201 -67.376265)
			(xy 325.24222 -67.37384) (xy 325.237094 -67.3735) (xy 325.228458 -67.374008) (xy 325.22117 -67.375286)
			(xy 325.20774 -67.38148) (xy 325.202042 -67.3862) (xy 325.201788 -67.386454) (xy 325.180699 -67.40458)
			(xy 325.13426 -67.43517) (xy 325.083875 -67.4587) (xy 325.03061 -67.474673) (xy 324.975592 -67.482751)
			(xy 324.947788 -67.483228) (xy 324.938136 -67.483228) (xy 324.911472 -67.482064) (xy 324.858831 -67.473262)
			(xy 324.833234 -67.465702) (xy 324.807791 -67.457252) (xy 324.759381 -67.43422) (xy 324.714665 -67.404646)
			(xy 324.694296 -67.387216) (xy 324.688492 -67.382394) (xy 324.674807 -67.376054) (xy 324.667372 -67.37477)
			(xy 324.667118 -67.37477) (xy 324.660333 -67.374072) (xy 324.646818 -67.375885) (xy 324.640448 -67.378326)
			(xy 324.639432 -67.378834) (xy 324.577202 -67.407282) (xy 324.576694 -67.407282) (xy 324.556374 -67.416426)
			(xy 324.55485 -67.417188) (xy 324.549304 -67.419986) (xy 324.539665 -67.427819) (xy 324.5358 -67.432682)
			(xy 324.5358 -67.488054) (xy 328.97902 -67.488054) (xy 328.983091 -67.432432) (xy 328.995217 -67.377995)
			(xy 329.01514 -67.325904) (xy 329.042436 -67.277269) (xy 329.076522 -67.233126) (xy 329.116671 -67.194417)
			(xy 329.162029 -67.161966) (xy 329.211629 -67.136465) (xy 329.264413 -67.118458) (xy 329.319256 -67.108328)
			(xy 329.37499 -67.106291) (xy 329.430427 -67.112391) (xy 329.484384 -67.126497) (xy 329.535713 -67.148309)
			(xy 329.583319 -67.177363) (xy 329.626187 -67.213038) (xy 329.663404 -67.254575) (xy 329.694177 -67.301088)
			(xy 329.717849 -67.351585) (xy 329.733917 -67.404992) (xy 329.742037 -67.460168) (xy 329.742546 -67.488054)
			(xy 329.742037 -67.51594) (xy 329.738852 -67.537584) (xy 330.271118 -67.537584) (xy 330.275189 -67.481962)
			(xy 330.287315 -67.427525) (xy 330.307238 -67.375434) (xy 330.334534 -67.326799) (xy 330.36862 -67.282656)
			(xy 330.408769 -67.243947) (xy 330.454127 -67.211496) (xy 330.503727 -67.185995) (xy 330.556511 -67.167988)
			(xy 330.611354 -67.157858) (xy 330.667088 -67.155821) (xy 330.722525 -67.161921) (xy 330.776482 -67.176027)
			(xy 330.827811 -67.197839) (xy 330.875417 -67.226893) (xy 330.918285 -67.262568) (xy 330.955502 -67.304105)
			(xy 330.986275 -67.350618) (xy 331.009947 -67.401115) (xy 331.026015 -67.454522) (xy 331.034135 -67.509698)
			(xy 331.034644 -67.537584) (xy 331.034135 -67.56547) (xy 331.03009 -67.592956) (xy 331.545182 -67.592956)
			(xy 331.549253 -67.537334) (xy 331.561379 -67.482897) (xy 331.581302 -67.430806) (xy 331.608598 -67.382171)
			(xy 331.642684 -67.338028) (xy 331.682833 -67.299319) (xy 331.728191 -67.266868) (xy 331.777791 -67.241367)
			(xy 331.830575 -67.22336) (xy 331.885418 -67.21323) (xy 331.941152 -67.211193) (xy 331.996589 -67.217293)
			(xy 332.050546 -67.231399) (xy 332.101875 -67.253211) (xy 332.149481 -67.282265) (xy 332.192349 -67.31794)
			(xy 332.229566 -67.359477) (xy 332.260339 -67.40599) (xy 332.284011 -67.456487) (xy 332.300079 -67.509894)
			(xy 332.308196 -67.565051) (xy 334.646493 -67.565051) (xy 334.646493 -67.510549) (xy 334.65425 -67.456601)
			(xy 334.669606 -67.404307) (xy 334.692248 -67.35473) (xy 334.721715 -67.30888) (xy 334.757408 -67.267691)
			(xy 334.798599 -67.232001) (xy 334.844451 -67.202536) (xy 334.894029 -67.179897) (xy 334.946325 -67.164545)
			(xy 335.000273 -67.156792) (xy 335.027524 -67.15633) (xy 335.054895 -67.156775) (xy 335.109075 -67.164597)
			(xy 335.161579 -67.18009) (xy 335.211326 -67.202937) (xy 335.257291 -67.232666) (xy 335.278222 -67.25031)
			(xy 335.278476 -67.250564) (xy 335.28556 -67.256154) (xy 335.302479 -67.262397) (xy 335.311496 -67.262756)
			(xy 335.378552 -67.262756) (xy 335.387568 -67.262386) (xy 335.404485 -67.256148) (xy 335.411572 -67.250564)
			(xy 335.411572 -67.25031) (xy 335.411826 -67.25031) (xy 335.432776 -67.232694) (xy 335.478744 -67.202978)
			(xy 335.528487 -67.180138) (xy 335.580984 -67.164641) (xy 335.635156 -67.156807) (xy 335.662524 -67.15633)
			(xy 335.689777 -67.156742) (xy 335.743727 -67.164502) (xy 335.796024 -67.17986) (xy 335.845604 -67.202505)
			(xy 335.891456 -67.231975) (xy 335.932647 -67.26767) (xy 335.968339 -67.308864) (xy 335.997806 -67.354718)
			(xy 336.020448 -67.404298) (xy 336.035804 -67.456596) (xy 336.04356 -67.510547) (xy 336.04356 -67.565053)
			(xy 336.035804 -67.619004) (xy 336.020448 -67.671302) (xy 335.997806 -67.720882) (xy 335.968339 -67.766736)
			(xy 335.932647 -67.80793) (xy 335.891456 -67.843625) (xy 335.845604 -67.873095) (xy 335.796024 -67.89574)
			(xy 335.743727 -67.911098) (xy 335.689777 -67.918858) (xy 335.662524 -67.919346) (xy 335.635154 -67.918879)
			(xy 335.580974 -67.911063) (xy 335.52847 -67.895575) (xy 335.478724 -67.872733) (xy 335.432757 -67.843008)
			(xy 335.411826 -67.825366) (xy 335.411572 -67.825112) (xy 335.404468 -67.819551) (xy 335.387565 -67.813288)
			(xy 335.378552 -67.81292) (xy 335.311496 -67.81292) (xy 335.302478 -67.813271) (xy 335.285561 -67.819522)
			(xy 335.278476 -67.825112) (xy 335.278476 -67.825366) (xy 335.278222 -67.825366) (xy 335.257288 -67.843003)
			(xy 335.211316 -67.872716) (xy 335.161569 -67.895553) (xy 335.109069 -67.911045) (xy 335.054893 -67.918872)
			(xy 335.027524 -67.919346) (xy 335.000273 -67.918808) (xy 334.946325 -67.911055) (xy 334.894029 -67.895703)
			(xy 334.844451 -67.873064) (xy 334.798599 -67.843599) (xy 334.757408 -67.807909) (xy 334.721715 -67.76672)
			(xy 334.692248 -67.72087) (xy 334.669606 -67.671293) (xy 334.65425 -67.618999) (xy 334.646493 -67.565051)
			(xy 332.308196 -67.565051) (xy 332.308199 -67.56507) (xy 332.308708 -67.592956) (xy 332.308199 -67.620842)
			(xy 332.300079 -67.676018) (xy 332.284011 -67.729425) (xy 332.260339 -67.779922) (xy 332.229566 -67.826435)
			(xy 332.192349 -67.867972) (xy 332.149481 -67.903647) (xy 332.101875 -67.932701) (xy 332.050546 -67.954513)
			(xy 331.996589 -67.968619) (xy 331.941152 -67.974719) (xy 331.885418 -67.972682) (xy 331.830575 -67.962552)
			(xy 331.777791 -67.944545) (xy 331.728191 -67.919044) (xy 331.682833 -67.886593) (xy 331.642684 -67.847884)
			(xy 331.608598 -67.803741) (xy 331.581302 -67.755106) (xy 331.561379 -67.703015) (xy 331.549253 -67.648578)
			(xy 331.545182 -67.592956) (xy 331.03009 -67.592956) (xy 331.026015 -67.620646) (xy 331.009947 -67.674053)
			(xy 330.986275 -67.72455) (xy 330.955502 -67.771063) (xy 330.918285 -67.8126) (xy 330.875417 -67.848275)
			(xy 330.827811 -67.877329) (xy 330.776482 -67.899141) (xy 330.722525 -67.913247) (xy 330.667088 -67.919347)
			(xy 330.611354 -67.91731) (xy 330.556511 -67.90718) (xy 330.503727 -67.889173) (xy 330.454127 -67.863672)
			(xy 330.408769 -67.831221) (xy 330.36862 -67.792512) (xy 330.334534 -67.748369) (xy 330.307238 -67.699734)
			(xy 330.287315 -67.647643) (xy 330.275189 -67.593206) (xy 330.271118 -67.537584) (xy 329.738852 -67.537584)
			(xy 329.733917 -67.571116) (xy 329.717849 -67.624523) (xy 329.694177 -67.67502) (xy 329.663404 -67.721533)
			(xy 329.626187 -67.76307) (xy 329.583319 -67.798745) (xy 329.535713 -67.827799) (xy 329.484384 -67.849611)
			(xy 329.430427 -67.863717) (xy 329.37499 -67.869817) (xy 329.319256 -67.86778) (xy 329.264413 -67.85765)
			(xy 329.211629 -67.839643) (xy 329.162029 -67.814142) (xy 329.116671 -67.781691) (xy 329.076522 -67.742982)
			(xy 329.042436 -67.698839) (xy 329.01514 -67.650204) (xy 328.995217 -67.598113) (xy 328.983091 -67.543676)
			(xy 328.97902 -67.488054) (xy 324.5358 -67.488054) (xy 324.5358 -68.586604) (xy 326.825102 -68.586604)
			(xy 326.82557 -68.559234) (xy 326.833387 -68.505055) (xy 326.848876 -68.452552) (xy 326.871717 -68.402805)
			(xy 326.901441 -68.356838) (xy 326.919082 -68.335906) (xy 326.919336 -68.335652) (xy 326.924911 -68.328558)
			(xy 326.931164 -68.311647) (xy 326.931528 -68.302632) (xy 326.931528 -68.235576) (xy 326.931177 -68.226559)
			(xy 326.924925 -68.209642) (xy 326.919336 -68.202556) (xy 326.919082 -68.202556) (xy 326.919082 -68.202302)
			(xy 326.901428 -68.181382) (xy 326.871719 -68.135406) (xy 326.848886 -68.085655) (xy 326.833398 -68.033152)
			(xy 326.825574 -67.978974) (xy 326.825102 -67.951604) (xy 326.825559 -67.924351) (xy 326.833316 -67.870399)
			(xy 326.848672 -67.818101) (xy 326.871315 -67.76852) (xy 326.900783 -67.722666) (xy 326.936477 -67.681473)
			(xy 326.977671 -67.645779) (xy 327.023525 -67.616312) (xy 327.073106 -67.59367) (xy 327.125405 -67.578314)
			(xy 327.179357 -67.570559) (xy 327.20661 -67.570096) (xy 327.232924 -67.570558) (xy 327.285053 -67.577794)
			(xy 327.335696 -67.592114) (xy 327.383895 -67.613248) (xy 327.428738 -67.640795) (xy 327.469377 -67.674234)
			(xy 327.487534 -67.693286) (xy 327.495043 -67.700703) (xy 327.514333 -67.709219) (xy 327.524872 -67.709796)
			(xy 327.599548 -67.709796) (xy 327.610096 -67.709254) (xy 327.629392 -67.700728) (xy 327.636886 -67.693286)
			(xy 327.655053 -67.674242) (xy 327.69568 -67.640784) (xy 327.740518 -67.613224) (xy 327.788717 -67.592084)
			(xy 327.839362 -67.577764) (xy 327.891495 -67.570536) (xy 327.91781 -67.570096) (xy 327.94518 -67.570557)
			(xy 327.99936 -67.578376) (xy 328.051863 -67.593867) (xy 328.10161 -67.616709) (xy 328.147576 -67.646435)
			(xy 328.168508 -67.664076) (xy 328.168762 -67.66433) (xy 328.175853 -67.66991) (xy 328.192766 -67.67616)
			(xy 328.201782 -67.676522) (xy 328.268838 -67.676522) (xy 328.277856 -67.676179) (xy 328.294773 -67.669921)
			(xy 328.301858 -67.66433) (xy 328.301858 -67.664076) (xy 328.302112 -67.664076) (xy 328.323063 -67.646461)
			(xy 328.369031 -67.616746) (xy 328.418774 -67.593906) (xy 328.47127 -67.578409) (xy 328.525442 -67.570574)
			(xy 328.55281 -67.570096) (xy 328.580062 -67.570569) (xy 328.63401 -67.578326) (xy 328.686305 -67.593683)
			(xy 328.735883 -67.616326) (xy 328.781733 -67.645793) (xy 328.822924 -67.681486) (xy 328.858615 -67.722678)
			(xy 328.888081 -67.768529) (xy 328.910722 -67.818108) (xy 328.926077 -67.870404) (xy 328.933832 -67.924352)
			(xy 328.934318 -67.951604) (xy 328.933874 -67.978975) (xy 328.926054 -68.033156) (xy 328.910561 -68.08566)
			(xy 328.887714 -68.135407) (xy 328.857983 -68.181372) (xy 328.840338 -68.202302) (xy 328.840084 -68.202556)
			(xy 328.834508 -68.20965) (xy 328.828255 -68.226561) (xy 328.827892 -68.235576) (xy 328.827892 -68.302632)
			(xy 328.828236 -68.31165) (xy 328.834493 -68.328567) (xy 328.840084 -68.335652) (xy 328.840338 -68.335652)
			(xy 328.840338 -68.335906) (xy 328.858 -68.35682) (xy 328.887707 -68.402798) (xy 328.910538 -68.45255)
			(xy 328.926024 -68.505055) (xy 328.933847 -68.559234) (xy 328.934318 -68.586604) (xy 328.933826 -68.613855)
			(xy 328.926069 -68.667802) (xy 328.910714 -68.720096) (xy 328.894075 -68.75653) (xy 332.370176 -68.75653)
			(xy 332.370641 -68.72916) (xy 332.378456 -68.67498) (xy 332.393945 -68.622476) (xy 332.416787 -68.572729)
			(xy 332.446513 -68.526763) (xy 332.464156 -68.505832) (xy 332.46441 -68.505578) (xy 332.470013 -68.498503)
			(xy 332.47625 -68.481577) (xy 332.476602 -68.472558) (xy 332.476602 -68.405502) (xy 332.476244 -68.396485)
			(xy 332.469997 -68.379568) (xy 332.46441 -68.372482) (xy 332.464156 -68.372482) (xy 332.464156 -68.372228)
			(xy 332.446509 -68.351302) (xy 332.4168 -68.305327) (xy 332.393966 -68.255578) (xy 332.378477 -68.203076)
			(xy 332.370649 -68.148899) (xy 332.370176 -68.12153) (xy 332.370683 -68.094279) (xy 332.378436 -68.04033)
			(xy 332.393787 -67.988034) (xy 332.416425 -67.938455) (xy 332.445888 -67.892603) (xy 332.481577 -67.85141)
			(xy 332.522766 -67.815716) (xy 332.568615 -67.786247) (xy 332.618191 -67.763603) (xy 332.670485 -67.748245)
			(xy 332.724433 -67.740486) (xy 332.751684 -67.740022) (xy 332.779054 -67.740492) (xy 332.833233 -67.748308)
			(xy 332.885737 -67.763796) (xy 332.935483 -67.786637) (xy 332.98145 -67.816361) (xy 333.002382 -67.834002)
			(xy 333.002636 -67.834256) (xy 333.009732 -67.839829) (xy 333.026642 -67.846082) (xy 333.035656 -67.846448)
			(xy 333.102712 -67.846448) (xy 333.111731 -67.846108) (xy 333.128648 -67.83985) (xy 333.135732 -67.834256)
			(xy 333.135732 -67.834002) (xy 333.135986 -67.834002) (xy 333.156913 -67.816356) (xy 333.202887 -67.786645)
			(xy 333.252636 -67.763811) (xy 333.305138 -67.748321) (xy 333.359314 -67.740495) (xy 333.386684 -67.740022)
			(xy 333.412998 -67.740493) (xy 333.465127 -67.747726) (xy 333.515769 -67.762044) (xy 333.563969 -67.783176)
			(xy 333.608812 -67.810722) (xy 333.649452 -67.84416) (xy 333.667608 -67.863212) (xy 333.675123 -67.870621)
			(xy 333.694408 -67.879141) (xy 333.704946 -67.879722) (xy 333.779622 -67.879722) (xy 333.790167 -67.879158)
			(xy 333.809463 -67.870647) (xy 333.81696 -67.863212) (xy 333.835096 -67.844137) (xy 333.875729 -67.810681)
			(xy 333.920574 -67.783124) (xy 333.968779 -67.761989) (xy 334.01943 -67.747676) (xy 334.071567 -67.740457)
			(xy 334.097884 -67.740022) (xy 334.125138 -67.74047) (xy 334.179091 -67.748226) (xy 334.231391 -67.763581)
			(xy 334.280973 -67.786224) (xy 334.326828 -67.815693) (xy 334.368021 -67.851389) (xy 334.403715 -67.892584)
			(xy 334.433183 -67.938439) (xy 334.455824 -67.988022) (xy 334.471177 -68.040323) (xy 334.478931 -68.094276)
			(xy 334.479392 -68.12153) (xy 334.478945 -68.148901) (xy 334.471123 -68.203081) (xy 334.45563 -68.255584)
			(xy 334.432784 -68.305331) (xy 334.403055 -68.351297) (xy 334.385412 -68.372228) (xy 334.385158 -68.372482)
			(xy 334.379568 -68.379566) (xy 334.373324 -68.396485) (xy 334.372966 -68.405502) (xy 334.372966 -68.472558)
			(xy 334.37335 -68.481572) (xy 334.37958 -68.498489) (xy 334.385158 -68.505578) (xy 334.385412 -68.505578)
			(xy 334.385412 -68.505832) (xy 334.403035 -68.526777) (xy 334.432748 -68.572747) (xy 334.455587 -68.622491)
			(xy 334.471082 -68.674989) (xy 334.478915 -68.729162) (xy 334.479392 -68.75653) (xy 334.47895 -68.783783)
			(xy 334.471189 -68.837733) (xy 334.455829 -68.890029) (xy 334.433183 -68.939608) (xy 334.403713 -68.985459)
			(xy 334.368017 -69.026649) (xy 334.326822 -69.06234) (xy 334.280967 -69.091806) (xy 334.231386 -69.114445)
			(xy 334.179088 -69.129799) (xy 334.125137 -69.137553) (xy 334.097884 -69.138038) (xy 334.071569 -69.137601)
			(xy 334.019438 -69.130363) (xy 333.968794 -69.116039) (xy 333.920595 -69.094901) (xy 333.875752 -69.067349)
			(xy 333.835115 -69.033903) (xy 333.81696 -69.014848) (xy 333.809449 -69.007434) (xy 333.790161 -68.998915)
			(xy 333.779622 -68.998338) (xy 333.704946 -68.998338) (xy 333.694396 -68.998867) (xy 333.6751 -69.007401)
			(xy 333.667608 -69.014848) (xy 333.649451 -69.033902) (xy 333.60882 -69.067357) (xy 333.56398 -69.094915)
			(xy 333.51578 -69.116054) (xy 333.465133 -69.130372) (xy 333.413 -69.137598) (xy 333.386684 -69.138038)
			(xy 333.359313 -69.137596) (xy 333.305132 -69.129775) (xy 333.252628 -69.114281) (xy 333.202881 -69.091433)
			(xy 333.156916 -69.061703) (xy 333.135986 -69.044058) (xy 333.135732 -69.043804) (xy 333.12864 -69.038225)
			(xy 333.111727 -69.031974) (xy 333.102712 -69.031612) (xy 333.035656 -69.031612) (xy 333.026642 -69.031993)
			(xy 333.009724 -69.038224) (xy 333.002636 -69.043804) (xy 333.002636 -69.044058) (xy 333.002382 -69.044058)
			(xy 332.981424 -69.061666) (xy 332.935459 -69.091384) (xy 332.885718 -69.114226) (xy 332.833223 -69.129725)
			(xy 332.779052 -69.13756) (xy 332.751684 -69.138038) (xy 332.724434 -69.137537) (xy 332.670488 -69.129779)
			(xy 332.618195 -69.114424) (xy 332.56862 -69.091783) (xy 332.522771 -69.062318) (xy 332.481582 -69.026628)
			(xy 332.445891 -68.98544) (xy 332.416424 -68.939592) (xy 332.393781 -68.890018) (xy 332.378424 -68.837726)
			(xy 332.370664 -68.78378) (xy 332.370176 -68.75653) (xy 328.894075 -68.75653) (xy 328.888073 -68.769672)
			(xy 328.858607 -68.815522) (xy 328.822917 -68.856712) (xy 328.781727 -68.892404) (xy 328.735878 -68.92187)
			(xy 328.686302 -68.944512) (xy 328.634008 -68.959868) (xy 328.580061 -68.967626) (xy 328.55281 -68.968112)
			(xy 328.52544 -68.967637) (xy 328.471262 -68.959821) (xy 328.418759 -68.944334) (xy 328.369012 -68.921494)
			(xy 328.323044 -68.891772) (xy 328.302112 -68.874132) (xy 328.301858 -68.873878) (xy 328.294761 -68.868307)
			(xy 328.277852 -68.862052) (xy 328.268838 -68.861686) (xy 328.201782 -68.861686) (xy 328.192765 -68.862038)
			(xy 328.175848 -68.868289) (xy 328.168762 -68.873878) (xy 328.168762 -68.874132) (xy 328.168508 -68.874132)
			(xy 328.147588 -68.891786) (xy 328.101611 -68.921494) (xy 328.051861 -68.944327) (xy 327.999358 -68.959815)
			(xy 327.94518 -68.96764) (xy 327.91781 -68.968112) (xy 327.891496 -68.967634) (xy 327.839369 -68.960401)
			(xy 327.788726 -68.946084) (xy 327.740527 -68.924953) (xy 327.695683 -68.897409) (xy 327.655043 -68.863972)
			(xy 327.636886 -68.844922) (xy 327.629369 -68.837515) (xy 327.610086 -68.828993) (xy 327.599548 -68.828412)
			(xy 327.524872 -68.828412) (xy 327.514325 -68.828963) (xy 327.495029 -68.837483) (xy 327.487534 -68.844922)
			(xy 327.469408 -68.864007) (xy 327.428771 -68.89746) (xy 327.383925 -68.925015) (xy 327.335718 -68.946148)
			(xy 327.285066 -68.960459) (xy 327.232928 -68.967677) (xy 327.20661 -68.968112) (xy 327.179358 -68.967635)
			(xy 327.125407 -68.95988) (xy 327.07311 -68.944525) (xy 327.02353 -68.921884) (xy 326.977677 -68.892418)
			(xy 326.936485 -68.856725) (xy 326.900791 -68.815534) (xy 326.871322 -68.769682) (xy 326.84868 -68.720103)
			(xy 326.833323 -68.667806) (xy 326.825566 -68.613856) (xy 326.825102 -68.586604) (xy 324.5358 -68.586604)
			(xy 324.5358 -71.555864) (xy 329.39431 -71.555864) (xy 329.398381 -71.500242) (xy 329.410507 -71.445805)
			(xy 329.43043 -71.393714) (xy 329.457726 -71.345079) (xy 329.491812 -71.300936) (xy 329.531961 -71.262227)
			(xy 329.577319 -71.229776) (xy 329.626919 -71.204275) (xy 329.679703 -71.186268) (xy 329.734546 -71.176138)
			(xy 329.79028 -71.174101) (xy 329.845717 -71.180201) (xy 329.899674 -71.194307) (xy 329.951003 -71.216119)
			(xy 329.998609 -71.245173) (xy 330.041477 -71.280848) (xy 330.078694 -71.322385) (xy 330.109467 -71.368898)
			(xy 330.133139 -71.419395) (xy 330.149207 -71.472802) (xy 330.157327 -71.527978) (xy 330.157836 -71.555864)
			(xy 330.157327 -71.58375) (xy 330.151488 -71.623428) (xy 330.903324 -71.623428) (xy 330.907395 -71.567806)
			(xy 330.919521 -71.513369) (xy 330.939444 -71.461278) (xy 330.96674 -71.412643) (xy 331.000826 -71.3685)
			(xy 331.040975 -71.329791) (xy 331.086333 -71.29734) (xy 331.135933 -71.271839) (xy 331.188717 -71.253832)
			(xy 331.24356 -71.243702) (xy 331.299294 -71.241665) (xy 331.354731 -71.247765) (xy 331.408688 -71.261871)
			(xy 331.460017 -71.283683) (xy 331.507623 -71.312737) (xy 331.550491 -71.348412) (xy 331.587708 -71.389949)
			(xy 331.618481 -71.436462) (xy 331.642153 -71.486959) (xy 331.658221 -71.540366) (xy 331.666341 -71.595542)
			(xy 331.66685 -71.623428) (xy 331.666341 -71.651314) (xy 331.658221 -71.70649) (xy 331.642153 -71.759897)
			(xy 331.618481 -71.810394) (xy 331.587708 -71.856907) (xy 331.550491 -71.898444) (xy 331.507623 -71.934119)
			(xy 331.460017 -71.963173) (xy 331.408688 -71.984985) (xy 331.354731 -71.999091) (xy 331.299294 -72.005191)
			(xy 331.24356 -72.003154) (xy 331.188717 -71.993024) (xy 331.135933 -71.975017) (xy 331.086333 -71.949516)
			(xy 331.040975 -71.917065) (xy 331.000826 -71.878356) (xy 330.96674 -71.834213) (xy 330.939444 -71.785578)
			(xy 330.919521 -71.733487) (xy 330.907395 -71.67905) (xy 330.903324 -71.623428) (xy 330.151488 -71.623428)
			(xy 330.149207 -71.638926) (xy 330.133139 -71.692333) (xy 330.109467 -71.74283) (xy 330.078694 -71.789343)
			(xy 330.041477 -71.83088) (xy 329.998609 -71.866555) (xy 329.951003 -71.895609) (xy 329.899674 -71.917421)
			(xy 329.845717 -71.931527) (xy 329.79028 -71.937627) (xy 329.734546 -71.93559) (xy 329.679703 -71.92546)
			(xy 329.626919 -71.907453) (xy 329.577319 -71.881952) (xy 329.531961 -71.849501) (xy 329.491812 -71.810792)
			(xy 329.457726 -71.766649) (xy 329.43043 -71.718014) (xy 329.410507 -71.665923) (xy 329.398381 -71.611486)
			(xy 329.39431 -71.555864) (xy 324.5358 -71.555864) (xy 324.5358 -78.150664) (xy 336.40703 -78.150664)
			(xy 336.40703 -78.090736) (xy 336.414852 -78.031319) (xy 336.430363 -77.973433) (xy 336.453297 -77.918066)
			(xy 336.483261 -77.866166) (xy 336.519743 -77.818621) (xy 336.562119 -77.776245) (xy 336.609664 -77.739762)
			(xy 336.661564 -77.709797) (xy 336.716931 -77.686864) (xy 336.774817 -77.671353) (xy 336.834234 -77.66353)
			(xy 336.864198 -77.66304) (xy 337.727798 -77.66304) (xy 337.75777 -77.663413) (xy 337.817202 -77.671237)
			(xy 337.875104 -77.686751) (xy 337.930486 -77.709691) (xy 337.982399 -77.739663) (xy 338.029957 -77.776155)
			(xy 338.072344 -77.818542) (xy 338.108836 -77.866099) (xy 338.138808 -77.918013) (xy 338.161748 -77.973394)
			(xy 338.177263 -78.031296) (xy 338.185087 -78.090728) (xy 338.185087 -78.150672) (xy 338.177263 -78.210104)
			(xy 338.161748 -78.268006) (xy 338.138808 -78.323387) (xy 338.108836 -78.375301) (xy 338.072344 -78.422858)
			(xy 338.029957 -78.465245) (xy 337.982399 -78.501737) (xy 337.930486 -78.531709) (xy 337.875104 -78.554649)
			(xy 337.817202 -78.570163) (xy 337.75777 -78.577987) (xy 337.727798 -78.578456) (xy 336.864198 -78.578456)
			(xy 336.834234 -78.57787) (xy 336.774817 -78.570047) (xy 336.716931 -78.554536) (xy 336.661564 -78.531603)
			(xy 336.609664 -78.501638) (xy 336.562119 -78.465155) (xy 336.519743 -78.422779) (xy 336.483261 -78.375234)
			(xy 336.453297 -78.323334) (xy 336.430363 -78.267967) (xy 336.414852 -78.210081) (xy 336.40703 -78.150664)
			(xy 324.5358 -78.150664) (xy 324.5358 -78.912666) (xy 334.407009 -78.912666) (xy 334.407009 -78.852734)
			(xy 334.414832 -78.793315) (xy 334.430343 -78.735425) (xy 334.453278 -78.680055) (xy 334.483244 -78.628153)
			(xy 334.519729 -78.580606) (xy 334.562107 -78.538227) (xy 334.609654 -78.501743) (xy 334.661557 -78.471777)
			(xy 334.716927 -78.448843) (xy 334.774817 -78.433331) (xy 334.834236 -78.425509) (xy 334.864202 -78.42504)
			(xy 335.727802 -78.42504) (xy 335.757773 -78.425434) (xy 335.817201 -78.433258) (xy 335.8751 -78.448773)
			(xy 335.930479 -78.471711) (xy 335.982389 -78.501682) (xy 336.029944 -78.538172) (xy 336.072329 -78.580557)
			(xy 336.108819 -78.628112) (xy 336.13879 -78.680023) (xy 336.161728 -78.735402) (xy 336.177242 -78.793301)
			(xy 336.185066 -78.852729) (xy 336.185066 -78.912664) (xy 338.40703 -78.912664) (xy 338.40703 -78.852736)
			(xy 338.414852 -78.79332) (xy 338.430363 -78.735433) (xy 338.453296 -78.680067) (xy 338.48326 -78.628167)
			(xy 338.519742 -78.580622) (xy 338.562118 -78.538246) (xy 338.609662 -78.501763) (xy 338.661561 -78.471799)
			(xy 338.716928 -78.448865) (xy 338.774814 -78.433353) (xy 338.83423 -78.42553) (xy 338.864194 -78.42504)
			(xy 339.727794 -78.42504) (xy 339.757766 -78.425412) (xy 339.817199 -78.433236) (xy 339.875101 -78.44875)
			(xy 339.930483 -78.47169) (xy 339.982397 -78.501662) (xy 340.029955 -78.538153) (xy 340.072343 -78.580541)
			(xy 340.108835 -78.628098) (xy 340.138808 -78.680011) (xy 340.161748 -78.735393) (xy 340.177263 -78.793296)
			(xy 340.185087 -78.852728) (xy 340.185087 -78.912672) (xy 340.177263 -78.972104) (xy 340.161748 -79.030007)
			(xy 340.138808 -79.085389) (xy 340.108835 -79.137302) (xy 340.072343 -79.184859) (xy 340.029955 -79.227247)
			(xy 339.982397 -79.263738) (xy 339.930483 -79.29371) (xy 339.875101 -79.31665) (xy 339.817199 -79.332164)
			(xy 339.757766 -79.339988) (xy 339.727794 -79.340456) (xy 338.864194 -79.340456) (xy 338.83423 -79.33987)
			(xy 338.774814 -79.332047) (xy 338.716928 -79.316535) (xy 338.661561 -79.293601) (xy 338.609662 -79.263637)
			(xy 338.562118 -79.227154) (xy 338.519742 -79.184778) (xy 338.48326 -79.137233) (xy 338.453296 -79.085333)
			(xy 338.430363 -79.029967) (xy 338.414852 -78.97208) (xy 338.40703 -78.912664) (xy 336.185066 -78.912664)
			(xy 336.185066 -78.912671) (xy 336.177242 -78.972099) (xy 336.161728 -79.029998) (xy 336.13879 -79.085377)
			(xy 336.108819 -79.137288) (xy 336.072329 -79.184843) (xy 336.029944 -79.227228) (xy 335.982389 -79.263718)
			(xy 335.930479 -79.293689) (xy 335.8751 -79.316627) (xy 335.817201 -79.332142) (xy 335.757773 -79.339966)
			(xy 335.727802 -79.340456) (xy 334.864202 -79.340456) (xy 334.834236 -79.339891) (xy 334.774817 -79.332069)
			(xy 334.716927 -79.316557) (xy 334.661557 -79.293623) (xy 334.609654 -79.263657) (xy 334.562107 -79.227173)
			(xy 334.519729 -79.184794) (xy 334.483244 -79.137247) (xy 334.453278 -79.085345) (xy 334.430343 -79.029975)
			(xy 334.414832 -78.972085) (xy 334.407009 -78.912666) (xy 324.5358 -78.912666) (xy 324.5358 -83.98637)
			(xy 327.111612 -83.98637) (xy 327.115683 -83.930748) (xy 327.127809 -83.876311) (xy 327.147732 -83.82422)
			(xy 327.175028 -83.775585) (xy 327.209114 -83.731442) (xy 327.249263 -83.692733) (xy 327.294621 -83.660282)
			(xy 327.344221 -83.634781) (xy 327.397005 -83.616774) (xy 327.451848 -83.606644) (xy 327.507582 -83.604607)
			(xy 327.563019 -83.610707) (xy 327.616976 -83.624813) (xy 327.668305 -83.646625) (xy 327.715911 -83.675679)
			(xy 327.758779 -83.711354) (xy 327.795996 -83.752891) (xy 327.826769 -83.799404) (xy 327.850441 -83.849901)
			(xy 327.866509 -83.903308) (xy 327.874629 -83.958484) (xy 327.875138 -83.98637) (xy 327.874629 -84.014256)
			(xy 327.866509 -84.069432) (xy 327.850441 -84.122839) (xy 327.826769 -84.173336) (xy 327.795996 -84.219849)
			(xy 327.758779 -84.261386) (xy 327.715911 -84.297061) (xy 327.668305 -84.326115) (xy 327.616976 -84.347927)
			(xy 327.563019 -84.362033) (xy 327.507582 -84.368133) (xy 327.451848 -84.366096) (xy 327.397005 -84.355966)
			(xy 327.344221 -84.337959) (xy 327.294621 -84.312458) (xy 327.249263 -84.280007) (xy 327.209114 -84.241298)
			(xy 327.175028 -84.197155) (xy 327.147732 -84.14852) (xy 327.127809 -84.096429) (xy 327.115683 -84.041992)
			(xy 327.111612 -83.98637) (xy 324.5358 -83.98637) (xy 324.5358 -85.117251) (xy 327.913978 -85.117251)
			(xy 327.913978 -85.062749) (xy 327.921734 -85.008801) (xy 327.937089 -84.956506) (xy 327.959731 -84.906929)
			(xy 327.989197 -84.861079) (xy 328.024888 -84.819888) (xy 328.066079 -84.784197) (xy 328.111929 -84.754731)
			(xy 328.161506 -84.732089) (xy 328.213801 -84.716734) (xy 328.267749 -84.708978) (xy 328.295 -84.708492)
			(xy 328.321857 -84.708921) (xy 328.37504 -84.716451) (xy 328.426643 -84.731361) (xy 328.475646 -84.753359)
			(xy 328.521081 -84.782008) (xy 328.562052 -84.816744) (xy 328.580242 -84.836508) (xy 328.590656 -84.848446)
			(xy 328.621136 -84.855812) (xy 328.725022 -84.816442) (xy 328.734436 -84.812313) (xy 328.74925 -84.798095)
			(xy 328.75731 -84.77921) (xy 328.757788 -84.768944) (xy 328.757788 -82.778854) (xy 328.757355 -82.769063)
			(xy 328.750043 -82.7509) (xy 328.743564 -82.743548) (xy 328.687684 -82.685636) (xy 328.670158 -82.677508)
			(xy 328.660252 -82.677254) (xy 328.633764 -82.675621) (xy 328.581561 -82.666093) (xy 328.531181 -82.649424)
			(xy 328.483597 -82.625935) (xy 328.439727 -82.59608) (xy 328.400416 -82.560435) (xy 328.366423 -82.519687)
			(xy 328.338403 -82.474622) (xy 328.316898 -82.426109) (xy 328.302322 -82.375085) (xy 328.294955 -82.322533)
			(xy 328.294492 -82.296) (xy 328.294978 -82.268749) (xy 328.302734 -82.214801) (xy 328.318089 -82.162506)
			(xy 328.340731 -82.112929) (xy 328.370197 -82.067079) (xy 328.405888 -82.025888) (xy 328.447079 -81.990197)
			(xy 328.492929 -81.960731) (xy 328.542506 -81.938089) (xy 328.594801 -81.922734) (xy 328.648749 -81.914978)
			(xy 328.676 -81.914492) (xy 328.700892 -81.915254) (xy 328.709127 -81.915487) (xy 328.725063 -81.911352)
			(xy 328.732134 -81.907126) (xy 328.756772 -81.891124) (xy 328.763469 -81.886464) (xy 328.773697 -81.873763)
			(xy 328.776838 -81.866232) (xy 328.786439 -81.841885) (xy 328.812734 -81.796638) (xy 328.846357 -81.756535)
			(xy 328.865992 -81.739232) (xy 328.877723 -81.728589) (xy 328.896137 -81.702835) (xy 328.907661 -81.673347)
			(xy 328.911587 -81.641932) (xy 328.907677 -81.610515) (xy 328.896168 -81.581022) (xy 328.877767 -81.555259)
			(xy 328.865992 -81.544668) (xy 328.846114 -81.527138) (xy 328.812168 -81.486439) (xy 328.785749 -81.440496)
			(xy 328.767647 -81.390686) (xy 328.758406 -81.338501) (xy 328.757788 -81.312004) (xy 328.757788 -80.09128)
			(xy 328.757935 -80.08639) (xy 328.759847 -80.076798) (xy 328.761598 -80.07223) (xy 328.800206 -79.976472)
			(xy 328.802366 -79.971638) (xy 328.808384 -79.962928) (xy 328.812144 -79.9592) (xy 328.848466 -79.923894)
			(xy 328.848974 -79.923386) (xy 328.99985 -79.772256) (xy 329.017151 -79.755667) (xy 329.055929 -79.727499)
			(xy 329.098628 -79.705729) (xy 329.144201 -79.69089) (xy 329.191532 -79.683347) (xy 329.215496 -79.682848)
			(xy 342.663272 -79.682848) (xy 342.668163 -79.682984) (xy 342.677755 -79.684903) (xy 342.682322 -79.686658)
			(xy 342.77808 -79.725266) (xy 342.782912 -79.72743) (xy 342.791618 -79.73345) (xy 342.795352 -79.737204)
			(xy 342.830658 -79.773526) (xy 342.831166 -79.774034) (xy 344.048842 -80.991456) (xy 344.065527 -81.00872)
			(xy 344.093781 -81.047535) (xy 344.115614 -81.090292) (xy 344.130489 -81.135939) (xy 344.138039 -81.183352)
			(xy 344.138504 -81.207356) (xy 344.138504 -84.144612) (xy 345.879928 -84.144612) (xy 345.879928 -83.281012)
			(xy 345.880418 -83.251028) (xy 345.888246 -83.191572) (xy 345.903767 -83.133647) (xy 345.926716 -83.078243)
			(xy 345.9567 -83.026309) (xy 345.993206 -82.978733) (xy 346.035611 -82.936328) (xy 346.083187 -82.899822)
			(xy 346.135121 -82.869838) (xy 346.190525 -82.846889) (xy 346.24845 -82.831368) (xy 346.307906 -82.82354)
			(xy 346.367874 -82.82354) (xy 346.42733 -82.831368) (xy 346.485255 -82.846889) (xy 346.540659 -82.869838)
			(xy 346.592593 -82.899822) (xy 346.640169 -82.936328) (xy 346.682574 -82.978733) (xy 346.71908 -83.026309)
			(xy 346.749064 -83.078243) (xy 346.772013 -83.133647) (xy 346.787534 -83.191572) (xy 346.795362 -83.251028)
			(xy 346.795852 -83.281012) (xy 346.795852 -84.144612) (xy 346.795362 -84.174596) (xy 346.787534 -84.234052)
			(xy 346.772013 -84.291977) (xy 346.749064 -84.347381) (xy 346.71908 -84.399315) (xy 346.682574 -84.446891)
			(xy 346.640169 -84.489296) (xy 346.592593 -84.525802) (xy 346.540659 -84.555786) (xy 346.485255 -84.578735)
			(xy 346.42733 -84.594256) (xy 346.367874 -84.602084) (xy 346.307906 -84.602084) (xy 346.24845 -84.594256)
			(xy 346.190525 -84.578735) (xy 346.135121 -84.555786) (xy 346.083187 -84.525802) (xy 346.035611 -84.489296)
			(xy 345.993206 -84.446891) (xy 345.9567 -84.399315) (xy 345.926716 -84.347381) (xy 345.903767 -84.291977)
			(xy 345.888246 -84.234052) (xy 345.880418 -84.174596) (xy 345.879928 -84.144612) (xy 344.138504 -84.144612)
			(xy 344.138504 -86.144608) (xy 346.641928 -86.144608) (xy 346.641928 -85.281008) (xy 346.642418 -85.251024)
			(xy 346.650246 -85.191568) (xy 346.665767 -85.133643) (xy 346.688716 -85.078239) (xy 346.7187 -85.026305)
			(xy 346.755206 -84.978729) (xy 346.797611 -84.936324) (xy 346.845187 -84.899818) (xy 346.897121 -84.869834)
			(xy 346.952525 -84.846885) (xy 347.01045 -84.831364) (xy 347.069906 -84.823536) (xy 347.129874 -84.823536)
			(xy 347.18933 -84.831364) (xy 347.247255 -84.846885) (xy 347.302659 -84.869834) (xy 347.354593 -84.899818)
			(xy 347.402169 -84.936324) (xy 347.444574 -84.978729) (xy 347.48108 -85.026305) (xy 347.511064 -85.078239)
			(xy 347.534013 -85.133643) (xy 347.549534 -85.191568) (xy 347.557362 -85.251024) (xy 347.557852 -85.281008)
			(xy 347.557852 -86.144608) (xy 347.557362 -86.174592) (xy 347.549534 -86.234048) (xy 347.534013 -86.291973)
			(xy 347.511064 -86.347377) (xy 347.48108 -86.399311) (xy 347.444574 -86.446887) (xy 347.402169 -86.489292)
			(xy 347.354593 -86.525798) (xy 347.302659 -86.555782) (xy 347.247255 -86.578731) (xy 347.18933 -86.594252)
			(xy 347.129874 -86.60208) (xy 347.069906 -86.60208) (xy 347.01045 -86.594252) (xy 346.952525 -86.578731)
			(xy 346.897121 -86.555782) (xy 346.845187 -86.525798) (xy 346.797611 -86.489292) (xy 346.755206 -86.446887)
			(xy 346.7187 -86.399311) (xy 346.688716 -86.347377) (xy 346.665767 -86.291973) (xy 346.650246 -86.234048)
			(xy 346.642418 -86.174592) (xy 346.641928 -86.144608) (xy 344.138504 -86.144608) (xy 344.138504 -88.144604)
			(xy 345.879928 -88.144604) (xy 345.879928 -87.281004) (xy 345.880418 -87.25102) (xy 345.888246 -87.191564)
			(xy 345.903767 -87.133639) (xy 345.926716 -87.078235) (xy 345.9567 -87.026301) (xy 345.993206 -86.978725)
			(xy 346.035611 -86.93632) (xy 346.083187 -86.899814) (xy 346.135121 -86.86983) (xy 346.190525 -86.846881)
			(xy 346.24845 -86.83136) (xy 346.307906 -86.823532) (xy 346.367874 -86.823532) (xy 346.42733 -86.83136)
			(xy 346.485255 -86.846881) (xy 346.540659 -86.86983) (xy 346.592593 -86.899814) (xy 346.640169 -86.93632)
			(xy 346.682574 -86.978725) (xy 346.71908 -87.026301) (xy 346.749064 -87.078235) (xy 346.772013 -87.133639)
			(xy 346.787534 -87.191564) (xy 346.795362 -87.25102) (xy 346.795852 -87.281004) (xy 346.795852 -88.144604)
			(xy 346.795362 -88.174588) (xy 346.787534 -88.234044) (xy 346.772013 -88.291969) (xy 346.749064 -88.347373)
			(xy 346.71908 -88.399307) (xy 346.682574 -88.446883) (xy 346.640169 -88.489288) (xy 346.592593 -88.525794)
			(xy 346.540659 -88.555778) (xy 346.485255 -88.578727) (xy 346.42733 -88.594248) (xy 346.367874 -88.602076)
			(xy 346.307906 -88.602076) (xy 346.24845 -88.594248) (xy 346.190525 -88.578727) (xy 346.135121 -88.555778)
			(xy 346.083187 -88.525794) (xy 346.035611 -88.489288) (xy 345.993206 -88.446883) (xy 345.9567 -88.399307)
			(xy 345.926716 -88.347373) (xy 345.903767 -88.291969) (xy 345.888246 -88.234044) (xy 345.880418 -88.174588)
			(xy 345.879928 -88.144604) (xy 344.138504 -88.144604) (xy 344.138504 -90.1446) (xy 346.641928 -90.1446)
			(xy 346.641928 -89.281) (xy 346.642418 -89.251016) (xy 346.650246 -89.19156) (xy 346.665767 -89.133635)
			(xy 346.688716 -89.078231) (xy 346.7187 -89.026297) (xy 346.755206 -88.978721) (xy 346.797611 -88.936316)
			(xy 346.845187 -88.89981) (xy 346.897121 -88.869826) (xy 346.952525 -88.846877) (xy 347.01045 -88.831356)
			(xy 347.069906 -88.823528) (xy 347.129874 -88.823528) (xy 347.18933 -88.831356) (xy 347.247255 -88.846877)
			(xy 347.302659 -88.869826) (xy 347.354593 -88.89981) (xy 347.402169 -88.936316) (xy 347.444574 -88.978721)
			(xy 347.48108 -89.026297) (xy 347.511064 -89.078231) (xy 347.534013 -89.133635) (xy 347.549534 -89.19156)
			(xy 347.557362 -89.251016) (xy 347.557852 -89.281) (xy 347.557852 -90.1446) (xy 347.557362 -90.174584)
			(xy 347.549534 -90.23404) (xy 347.534013 -90.291965) (xy 347.511064 -90.347369) (xy 347.48108 -90.399303)
			(xy 347.444574 -90.446879) (xy 347.402169 -90.489284) (xy 347.354593 -90.52579) (xy 347.302659 -90.555774)
			(xy 347.247255 -90.578723) (xy 347.18933 -90.594244) (xy 347.129874 -90.602072) (xy 347.069906 -90.602072)
			(xy 347.01045 -90.594244) (xy 346.952525 -90.578723) (xy 346.897121 -90.555774) (xy 346.845187 -90.52579)
			(xy 346.797611 -90.489284) (xy 346.755206 -90.446879) (xy 346.7187 -90.399303) (xy 346.688716 -90.347369)
			(xy 346.665767 -90.291965) (xy 346.650246 -90.23404) (xy 346.642418 -90.174584) (xy 346.641928 -90.1446)
			(xy 344.138504 -90.1446) (xy 344.138504 -90.58275) (xy 344.138065 -90.606432) (xy 344.130723 -90.653223)
			(xy 344.116239 -90.698318) (xy 344.094961 -90.740633) (xy 344.0674 -90.779152) (xy 344.051128 -90.796364)
			(xy 344.048588 -90.798904) (xy 342.279732 -92.567506) (xy 342.262508 -92.583986) (xy 342.223866 -92.611898)
			(xy 342.181357 -92.633468) (xy 342.136013 -92.648173) (xy 342.088935 -92.655655) (xy 342.065102 -92.656152)
			(xy 330.404216 -92.656152) (xy 330.380711 -92.65575) (xy 330.334261 -92.648524) (xy 330.289469 -92.634256)
			(xy 330.247396 -92.613285) (xy 330.20904 -92.586106) (xy 330.191872 -92.570046) (xy 330.189332 -92.567506)
			(xy 330.188316 -92.566236) (xy 330.188062 -92.566236) (xy 328.84618 -91.2241) (xy 328.829742 -91.206853)
			(xy 328.801893 -91.168194) (xy 328.780379 -91.125684) (xy 328.765721 -91.08035) (xy 328.758272 -91.033292)
			(xy 328.757788 -91.00947) (xy 328.757788 -89.33561) (xy 328.757392 -89.326145) (xy 328.750476 -89.308525)
			(xy 328.744326 -89.30132) (xy 328.69124 -89.243408) (xy 328.674222 -89.23528) (xy 328.66457 -89.234518)
			(xy 328.637658 -89.23184) (xy 328.584938 -89.219777) (xy 328.53445 -89.200392) (xy 328.487204 -89.174072)
			(xy 328.444148 -89.141344) (xy 328.406144 -89.102865) (xy 328.373954 -89.059406) (xy 328.348223 -89.011837)
			(xy 328.329467 -88.961111) (xy 328.31806 -88.908245) (xy 328.314233 -88.854298) (xy 328.318061 -88.800352)
			(xy 328.329468 -88.747486) (xy 328.348225 -88.69676) (xy 328.373956 -88.649191) (xy 328.406146 -88.605732)
			(xy 328.44415 -88.567253) (xy 328.487207 -88.534526) (xy 328.534453 -88.508207) (xy 328.584941 -88.488822)
			(xy 328.637662 -88.47676) (xy 328.66457 -88.474042) (xy 328.674222 -88.47328) (xy 328.69124 -88.465152)
			(xy 328.744326 -88.40724) (xy 328.750392 -88.399984) (xy 328.757297 -88.382395) (xy 328.757788 -88.37295)
			(xy 328.757788 -86.401656) (xy 328.757448 -86.392863) (xy 328.751484 -86.376318) (xy 328.740275 -86.362766)
			(xy 328.732896 -86.357968) (xy 328.64552 -86.306406) (xy 328.61885 -86.306152) (xy 328.606912 -86.312756)
			(xy 328.578461 -86.327738) (xy 328.517782 -86.349003) (xy 328.454402 -86.359818) (xy 328.422254 -86.360508)
			(xy 328.422 -86.360508) (xy 328.394749 -86.360022) (xy 328.340801 -86.352266) (xy 328.288506 -86.336911)
			(xy 328.238929 -86.314269) (xy 328.193079 -86.284803) (xy 328.151888 -86.249112) (xy 328.116197 -86.207921)
			(xy 328.086731 -86.162071) (xy 328.064089 -86.112494) (xy 328.048734 -86.060199) (xy 328.040978 -86.006251)
			(xy 328.040978 -85.951749) (xy 328.048734 -85.897801) (xy 328.064089 -85.845506) (xy 328.086731 -85.795929)
			(xy 328.116197 -85.750079) (xy 328.151888 -85.708888) (xy 328.193079 -85.673197) (xy 328.238929 -85.643731)
			(xy 328.288506 -85.621089) (xy 328.340801 -85.605734) (xy 328.394749 -85.597978) (xy 328.422 -85.597492)
			(xy 328.422254 -85.597492) (xy 328.454404 -85.598166) (xy 328.517793 -85.608958) (xy 328.578468 -85.630242)
			(xy 328.606912 -85.645244) (xy 328.614791 -85.649178) (xy 328.632166 -85.65196) (xy 328.64945 -85.648656)
			(xy 328.657204 -85.644482) (xy 328.732896 -85.600032) (xy 328.740296 -85.595268) (xy 328.75149 -85.581698)
			(xy 328.757428 -85.56514) (xy 328.757788 -85.556344) (xy 328.757788 -85.411056) (xy 328.75729 -85.400786)
			(xy 328.749257 -85.381884) (xy 328.734455 -85.367645) (xy 328.725022 -85.363558) (xy 328.621136 -85.324188)
			(xy 328.590656 -85.331554) (xy 328.580242 -85.343492) (xy 328.562053 -85.363255) (xy 328.521078 -85.397983)
			(xy 328.475641 -85.426625) (xy 328.426638 -85.448617) (xy 328.375037 -85.463523) (xy 328.321856 -85.471051)
			(xy 328.295 -85.471508) (xy 328.267749 -85.471022) (xy 328.213801 -85.463266) (xy 328.161506 -85.447911)
			(xy 328.111929 -85.425269) (xy 328.066079 -85.395803) (xy 328.024888 -85.360112) (xy 327.989197 -85.318921)
			(xy 327.959731 -85.273071) (xy 327.937089 -85.223494) (xy 327.921734 -85.171199) (xy 327.913978 -85.117251)
			(xy 324.5358 -85.117251) (xy 324.5358 -89.084658) (xy 324.536816 -89.09431) (xy 324.538438 -89.101557)
			(xy 324.54527 -89.114735) (xy 324.550278 -89.120218) (xy 326.3392 -90.90914) (xy 326.349868 -90.91549)
			(xy 326.35571 -90.917268) (xy 326.38128 -90.925714) (xy 326.429935 -90.948789) (xy 326.474865 -90.978472)
			(xy 326.515178 -91.014174) (xy 326.550075 -91.055186) (xy 326.578862 -91.100695) (xy 326.60097 -91.149797)
			(xy 326.615959 -91.201519) (xy 326.623531 -91.254833) (xy 326.623934 -91.281758) (xy 326.623474 -91.309014)
			(xy 326.615722 -91.36297) (xy 326.60037 -91.415275) (xy 326.57773 -91.464862) (xy 326.548264 -91.510722)
			(xy 326.51257 -91.551922) (xy 326.471377 -91.587623) (xy 326.425522 -91.617098) (xy 326.375939 -91.639746)
			(xy 326.323637 -91.655108) (xy 326.269681 -91.662869) (xy 326.242426 -91.663266) (xy 326.242426 -91.66352)
			(xy 326.215491 -91.663059) (xy 326.162157 -91.655487) (xy 326.110418 -91.64049) (xy 326.061301 -91.618366)
			(xy 326.015784 -91.589555) (xy 325.974772 -91.554629) (xy 325.939078 -91.514283) (xy 325.909412 -91.469318)
			(xy 325.886365 -91.420628) (xy 325.877936 -91.395042) (xy 325.877936 -91.394788) (xy 325.87592 -91.388956)
			(xy 325.86949 -91.37843) (xy 325.865236 -91.37396) (xy 323.969126 -89.47785) (xy 323.951012 -89.45907)
			(xy 323.920326 -89.416873) (xy 323.896625 -89.370392) (xy 323.880495 -89.320774) (xy 323.872333 -89.269241)
			(xy 323.871844 -89.243154) (xy 323.871844 -81.753202) (xy 323.871418 -81.74411) (xy 323.86497 -81.727103)
			(xy 323.852991 -81.713416) (xy 323.845174 -81.708752) (xy 323.840094 -81.70672) (xy 323.833062 -81.703996)
			(xy 323.818069 -81.702437) (xy 323.81063 -81.703672) (xy 323.804026 -81.704942) (xy 323.790818 -81.712054)
			(xy 321.9577 -83.545172) (xy 321.938929 -83.563203) (xy 321.896812 -83.593782) (xy 321.850435 -83.617406)
			(xy 321.800938 -83.633497) (xy 321.749535 -83.641659) (xy 321.723512 -83.6422) (xy 321.056254 -83.6422)
			(xy 321.052237 -83.645307) (xy 321.045453 -83.652861) (xy 321.042792 -83.657186) (xy 320.999612 -83.73491)
			(xy 320.997003 -83.740396) (xy 320.99417 -83.752205) (xy 320.994024 -83.758278) (xy 320.994278 -83.772248)
			(xy 320.997834 -83.778598) (xy 321.00012 -83.786472) (xy 321.003422 -83.79206) (xy 321.016005 -83.814195)
			(xy 321.035841 -83.861087) (xy 321.049272 -83.910198) (xy 321.05606 -83.960659) (xy 321.056508 -83.986116)
			(xy 321.056508 -83.99145) (xy 321.055492 -84.015326) (xy 321.055238 -84.017358) (xy 321.055238 -84.018882)
			(xy 321.054476 -84.026502) (xy 321.051174 -84.050632) (xy 321.048654 -84.064622) (xy 321.041786 -84.09221)
			(xy 321.037458 -84.10575) (xy 321.037458 -84.106004) (xy 321.035934 -84.110322) (xy 321.034918 -84.113116)
			(xy 321.034664 -84.113624) (xy 321.032886 -84.11845) (xy 321.032886 -84.118704) (xy 321.030965 -84.124402)
			(xy 321.029546 -84.136338) (xy 321.030092 -84.142326) (xy 321.031362 -84.153756) (xy 321.080892 -84.228432)
			(xy 321.084702 -84.231988) (xy 321.093084 -84.24037) (xy 321.096566 -84.243654) (xy 321.104493 -84.249016)
			(xy 321.108832 -84.251038) (xy 321.117722 -84.254848) (xy 321.12712 -84.255356) (xy 321.155598 -84.257117)
			(xy 321.211598 -84.26804) (xy 321.265345 -84.287186) (xy 321.315639 -84.314126) (xy 321.361357 -84.34826)
			(xy 321.401479 -84.388826) (xy 321.418712 -84.411566) (xy 321.422268 -84.415884) (xy 321.425824 -84.420964)
			(xy 321.426078 -84.421472) (xy 321.431666 -84.430108) (xy 321.446015 -84.452917) (xy 321.468852 -84.501726)
			(xy 321.484598 -84.553261) (xy 321.49294 -84.606499) (xy 321.493712 -84.660381) (xy 321.486898 -84.713835)
			(xy 321.472635 -84.765801) (xy 321.451205 -84.815243) (xy 321.423034 -84.861181) (xy 321.388684 -84.9027)
			(xy 321.348835 -84.938976) (xy 321.304281 -84.969287) (xy 321.280282 -84.981542) (xy 321.274694 -84.984336)
			(xy 321.267768 -84.989292) (xy 321.257396 -85.002789) (xy 321.254374 -85.010752) (xy 321.235578 -85.084666)
			(xy 321.235578 -85.085174) (xy 321.233038 -85.094318) (xy 321.234308 -85.104224) (xy 321.235021 -85.108882)
			(xy 321.237958 -85.117833) (xy 321.24015 -85.122004) (xy 321.242182 -85.125814) (xy 321.244214 -85.128608)
			(xy 321.244722 -85.129116) (xy 321.244976 -85.129624) (xy 321.245484 -85.130386) (xy 321.24777 -85.133942)
			(xy 321.262559 -85.157281) (xy 321.285987 -85.207319) (xy 321.301958 -85.260211) (xy 321.310139 -85.314853)
			(xy 321.310762 -85.342476) (xy 321.310762 -85.346286) (xy 321.310254 -85.358224) (xy 321.308806 -85.384747)
			(xy 321.299481 -85.437039) (xy 321.282993 -85.487532) (xy 321.25966 -85.53525) (xy 321.229933 -85.57927)
			(xy 321.194388 -85.61874) (xy 321.15371 -85.652898) (xy 321.108688 -85.681083) (xy 321.060191 -85.70275)
			(xy 321.009157 -85.71748) (xy 320.956573 -85.724989) (xy 320.930016 -85.725508) (xy 320.929 -85.725508)
			(xy 320.899524 -85.724959) (xy 320.841274 -85.715891) (xy 320.785112 -85.69797) (xy 320.732375 -85.671624)
			(xy 320.684318 -85.637479) (xy 320.642086 -85.596347) (xy 320.623946 -85.573108) (xy 320.615056 -85.560916)
			(xy 320.599675 -85.538155) (xy 320.574902 -85.489124) (xy 320.557413 -85.437048) (xy 320.547569 -85.383004)
			(xy 320.545573 -85.328106) (xy 320.551466 -85.27349) (xy 320.565127 -85.220281) (xy 320.586273 -85.169581)
			(xy 320.614467 -85.122434) (xy 320.649129 -85.079816) (xy 320.689541 -85.042606) (xy 320.734869 -85.011573)
			(xy 320.759328 -84.999068) (xy 320.764916 -84.996274) (xy 320.771852 -84.991325) (xy 320.782244 -84.977835)
			(xy 320.785236 -84.969858) (xy 320.804032 -84.895944) (xy 320.804032 -84.895436) (xy 320.806572 -84.886292)
			(xy 320.805302 -84.876386) (xy 320.80459 -84.871728) (xy 320.801655 -84.862775) (xy 320.79946 -84.858606)
			(xy 320.797428 -84.854796) (xy 320.795142 -84.851748) (xy 320.794888 -84.851494) (xy 320.794634 -84.850986)
			(xy 320.794126 -84.850224) (xy 320.79184 -84.846668) (xy 320.777003 -84.823247) (xy 320.753518 -84.773025)
			(xy 320.737543 -84.719934) (xy 320.729415 -84.665092) (xy 320.728848 -84.637372) (xy 320.728848 -84.628228)
			(xy 320.72961 -84.614512) (xy 320.72961 -84.614258) (xy 320.731388 -84.592922) (xy 320.733723 -84.574528)
			(xy 320.741479 -84.538268) (xy 320.746882 -84.520532) (xy 320.749676 -84.51215) (xy 320.750184 -84.51088)
			(xy 320.750946 -84.509102) (xy 320.752978 -84.503514) (xy 320.755981 -84.493122) (xy 320.754136 -84.471595)
			(xy 320.749422 -84.461858) (xy 320.74739 -84.45881) (xy 320.704718 -84.394548) (xy 320.700908 -84.390992)
			(xy 320.692526 -84.38261) (xy 320.689646 -84.379801) (xy 320.683139 -84.375071) (xy 320.679572 -84.373212)
			(xy 320.66738 -84.368132) (xy 320.658236 -84.367624) (xy 320.631786 -84.366012) (xy 320.579678 -84.35639)
			(xy 320.529402 -84.339648) (xy 320.481929 -84.316106) (xy 320.438172 -84.28622) (xy 320.398973 -84.250563)
			(xy 320.365088 -84.209824) (xy 320.337169 -84.164786) (xy 320.315754 -84.116316) (xy 320.301255 -84.065349)
			(xy 320.293951 -84.012865) (xy 320.293492 -83.98637) (xy 320.293492 -83.980528) (xy 320.293768 -83.968356)
			(xy 320.295676 -83.94408) (xy 320.297302 -83.932014) (xy 320.29908 -83.920838) (xy 320.29908 -83.92033)
			(xy 320.301112 -83.91017) (xy 320.307716 -83.882992) (xy 320.312792 -83.865719) (xy 320.325765 -83.832133)
			(xy 320.333624 -83.815936) (xy 320.346324 -83.792568) (xy 320.347848 -83.790028) (xy 320.349626 -83.78698)
			(xy 320.354198 -83.771232) (xy 320.356317 -83.761507) (xy 320.353832 -83.741777) (xy 320.349372 -83.732878)
			(xy 320.307716 -83.658202) (xy 320.307462 -83.657948) (xy 320.304776 -83.653419) (xy 320.297864 -83.64548)
			(xy 320.293746 -83.6422) (xy 319.56502 -83.6422) (xy 319.559011 -83.642371) (xy 319.547332 -83.645201)
			(xy 319.541906 -83.647788) (xy 319.538431 -83.649626) (xy 319.532049 -83.654216) (xy 319.529206 -83.656932)
			(xy 318.862456 -84.323682) (xy 318.859748 -84.326532) (xy 318.855152 -84.332908) (xy 318.853312 -84.336382)
			(xy 318.850732 -84.34181) (xy 318.847917 -84.353489) (xy 318.847724 -84.359496) (xy 318.847724 -84.394294)
			(xy 318.851967 -84.399762) (xy 318.862788 -84.408383) (xy 318.86906 -84.411312) (xy 318.954912 -84.447888)
			(xy 318.96177 -84.450174) (xy 318.967331 -84.451477) (xy 318.978742 -84.451871) (xy 318.984376 -84.450936)
			(xy 318.991742 -84.449666) (xy 319.004442 -84.442808) (xy 319.010538 -84.436966) (xy 319.032081 -84.416581)
			(xy 319.080302 -84.382054) (xy 319.133285 -84.355404) (xy 319.189753 -84.337272) (xy 319.248346 -84.328096)
			(xy 319.278 -84.327492) (xy 319.305251 -84.327978) (xy 319.359199 -84.335734) (xy 319.411494 -84.351089)
			(xy 319.461071 -84.373731) (xy 319.506921 -84.403197) (xy 319.548112 -84.438888) (xy 319.583803 -84.480079)
			(xy 319.613269 -84.525929) (xy 319.635911 -84.575506) (xy 319.651266 -84.627801) (xy 319.659022 -84.681749)
			(xy 319.659022 -84.736251) (xy 319.651266 -84.790199) (xy 319.635911 -84.842494) (xy 319.613269 -84.892071)
			(xy 319.583803 -84.937921) (xy 319.548112 -84.979112) (xy 319.506921 -85.014803) (xy 319.461071 -85.044269)
			(xy 319.411494 -85.066911) (xy 319.359199 -85.082266) (xy 319.305251 -85.090022) (xy 319.278 -85.090508)
			(xy 319.249296 -85.08999) (xy 319.192536 -85.081391) (xy 319.137704 -85.064386) (xy 319.086038 -85.03936)
			(xy 319.038703 -85.006878) (xy 319.017396 -84.987638) (xy 319.010538 -84.981034) (xy 318.986662 -84.971382)
			(xy 318.977813 -84.968653) (xy 318.959315 -84.969033) (xy 318.950594 -84.972144) (xy 318.949832 -84.972398)
			(xy 318.86906 -85.006434) (xy 318.862778 -85.009346) (xy 318.851955 -85.017972) (xy 318.847724 -85.023452)
			(xy 318.847724 -85.40623) (xy 318.856106 -85.415374) (xy 318.914526 -85.464396) (xy 318.91478 -85.46465)
			(xy 318.916812 -85.466174) (xy 318.92344 -85.470782) (xy 318.93872 -85.475959) (xy 318.946784 -85.476334)
			(xy 318.952118 -85.476334) (xy 318.956182 -85.475572) (xy 318.971693 -85.473189) (xy 319.002974 -85.470648)
			(xy 319.018666 -85.470492) (xy 319.01892 -85.470492) (xy 319.019682 -85.470492) (xy 319.026794 -85.470492)
			(xy 319.053915 -85.471167) (xy 319.10756 -85.479245) (xy 319.159521 -85.494841) (xy 319.208748 -85.51764)
			(xy 319.254249 -85.547182) (xy 319.295106 -85.582872) (xy 319.330496 -85.62399) (xy 319.359704 -85.669706)
			(xy 319.382142 -85.719099) (xy 319.397357 -85.771172) (xy 319.405041 -85.824875) (xy 319.405508 -85.852)
			(xy 319.405099 -85.877617) (xy 319.398246 -85.928392) (xy 319.384651 -85.97779) (xy 319.364558 -86.02492)
			(xy 319.338331 -86.068933) (xy 319.322704 -86.089236) (xy 319.32245 -86.08949) (xy 319.31991 -86.092538)
			(xy 319.316173 -86.098647) (xy 319.311909 -86.112311) (xy 319.311528 -86.119462) (xy 319.311528 -86.14283)
			(xy 319.311385 -86.14827) (xy 319.309079 -86.158902) (xy 319.306956 -86.163912) (xy 319.300606 -86.177628)
			(xy 319.298536 -86.182331) (xy 319.296094 -86.192311) (xy 319.29578 -86.19744) (xy 319.296288 -86.206076)
			(xy 319.29757 -86.213362) (xy 319.303769 -86.226788) (xy 319.30848 -86.232492) (xy 319.308734 -86.232746)
			(xy 319.326844 -86.253815) (xy 319.357409 -86.300208) (xy 319.380927 -86.350541) (xy 319.396903 -86.403751)
			(xy 319.404999 -86.458714) (xy 319.405508 -86.486492) (xy 319.405508 -86.487) (xy 319.405022 -86.514251)
			(xy 319.401965 -86.535514) (xy 319.655696 -86.535514) (xy 319.659767 -86.479892) (xy 319.671893 -86.425455)
			(xy 319.691816 -86.373364) (xy 319.719112 -86.324729) (xy 319.753198 -86.280586) (xy 319.793347 -86.241877)
			(xy 319.838705 -86.209426) (xy 319.888305 -86.183925) (xy 319.941089 -86.165918) (xy 319.995932 -86.155788)
			(xy 320.051666 -86.153751) (xy 320.107103 -86.159851) (xy 320.16106 -86.173957) (xy 320.212389 -86.195769)
			(xy 320.259995 -86.224823) (xy 320.302863 -86.260498) (xy 320.34008 -86.302035) (xy 320.370853 -86.348548)
			(xy 320.394525 -86.399045) (xy 320.410593 -86.452452) (xy 320.418713 -86.507628) (xy 320.419222 -86.535514)
			(xy 320.418713 -86.5634) (xy 320.410593 -86.618576) (xy 320.394525 -86.671983) (xy 320.370853 -86.72248)
			(xy 320.34008 -86.768993) (xy 320.302863 -86.81053) (xy 320.259995 -86.846205) (xy 320.212389 -86.875259)
			(xy 320.16106 -86.897071) (xy 320.107103 -86.911177) (xy 320.051666 -86.917277) (xy 319.995932 -86.91524)
			(xy 319.941089 -86.90511) (xy 319.888305 -86.887103) (xy 319.838705 -86.861602) (xy 319.793347 -86.829151)
			(xy 319.753198 -86.790442) (xy 319.719112 -86.746299) (xy 319.691816 -86.697664) (xy 319.671893 -86.645573)
			(xy 319.659767 -86.591136) (xy 319.655696 -86.535514) (xy 319.401965 -86.535514) (xy 319.397266 -86.568199)
			(xy 319.381911 -86.620494) (xy 319.359269 -86.670071) (xy 319.329803 -86.715921) (xy 319.294112 -86.757112)
			(xy 319.252921 -86.792803) (xy 319.207071 -86.822269) (xy 319.157494 -86.844911) (xy 319.105199 -86.860266)
			(xy 319.051251 -86.868022) (xy 319.024 -86.868508) (xy 319.023746 -86.868508) (xy 318.999457 -86.868111)
			(xy 318.951276 -86.861912) (xy 318.904272 -86.849647) (xy 318.859204 -86.831515) (xy 318.837818 -86.819994)
			(xy 318.835278 -86.818724) (xy 318.642492 -86.818724) (xy 318.61647 -86.818192) (xy 318.565072 -86.810017)
			(xy 318.515581 -86.793915) (xy 318.469212 -86.770282) (xy 318.427103 -86.739698) (xy 318.408304 -86.721696)
			(xy 318.281304 -86.594696) (xy 318.263274 -86.575924) (xy 318.232698 -86.533806) (xy 318.209076 -86.48743)
			(xy 318.192987 -86.437933) (xy 318.184826 -86.386531) (xy 318.184276 -86.360508) (xy 318.184276 -84.235544)
			(xy 318.183889 -84.226016) (xy 318.176945 -84.20827) (xy 318.164001 -84.194285) (xy 318.155574 -84.189824)
			(xy 318.152526 -84.188554) (xy 318.145355 -84.18585) (xy 318.130103 -84.184437) (xy 318.122554 -84.18576)
			(xy 318.11595 -84.18703) (xy 318.10325 -84.193888) (xy 317.160148 -85.136736) (xy 317.154896 -85.142401)
			(xy 317.147779 -85.156103) (xy 317.146178 -85.16366) (xy 317.145416 -85.17255) (xy 317.145416 -93.460824)
			(xy 332.40218 -93.460824) (xy 332.402666 -93.433573) (xy 332.410422 -93.379625) (xy 332.425777 -93.32733)
			(xy 332.448419 -93.277753) (xy 332.477885 -93.231903) (xy 332.513576 -93.190712) (xy 332.554767 -93.155021)
			(xy 332.600617 -93.125555) (xy 332.650194 -93.102913) (xy 332.702489 -93.087558) (xy 332.756437 -93.079802)
			(xy 332.810939 -93.079802) (xy 332.864887 -93.087558) (xy 332.917182 -93.102913) (xy 332.966759 -93.125555)
			(xy 332.982156 -93.13545) (xy 351.144584 -93.13545) (xy 351.148655 -93.079828) (xy 351.160781 -93.025391)
			(xy 351.180704 -92.9733) (xy 351.208 -92.924665) (xy 351.242086 -92.880522) (xy 351.282235 -92.841813)
			(xy 351.327593 -92.809362) (xy 351.377193 -92.783861) (xy 351.429977 -92.765854) (xy 351.48482 -92.755724)
			(xy 351.540554 -92.753687) (xy 351.595991 -92.759787) (xy 351.649948 -92.773893) (xy 351.701277 -92.795705)
			(xy 351.748883 -92.824759) (xy 351.791751 -92.860434) (xy 351.828968 -92.901971) (xy 351.859741 -92.948484)
			(xy 351.883413 -92.998981) (xy 351.899481 -93.052388) (xy 351.907601 -93.107564) (xy 351.90811 -93.13545)
			(xy 351.907601 -93.163336) (xy 351.899481 -93.218512) (xy 351.883413 -93.271919) (xy 351.859741 -93.322416)
			(xy 351.828968 -93.368929) (xy 351.791751 -93.410466) (xy 351.748883 -93.446141) (xy 351.701277 -93.475195)
			(xy 351.649948 -93.497007) (xy 351.595991 -93.511113) (xy 351.540554 -93.517213) (xy 351.48482 -93.515176)
			(xy 351.429977 -93.505046) (xy 351.377193 -93.487039) (xy 351.327593 -93.461538) (xy 351.282235 -93.429087)
			(xy 351.242086 -93.390378) (xy 351.208 -93.346235) (xy 351.180704 -93.2976) (xy 351.160781 -93.245509)
			(xy 351.148655 -93.191072) (xy 351.144584 -93.13545) (xy 332.982156 -93.13545) (xy 333.012609 -93.155021)
			(xy 333.0538 -93.190712) (xy 333.089491 -93.231903) (xy 333.118957 -93.277753) (xy 333.141599 -93.32733)
			(xy 333.156954 -93.379625) (xy 333.16471 -93.433573) (xy 333.165196 -93.460824) (xy 333.165196 -93.461332)
			(xy 333.164683 -93.487984) (xy 333.157222 -93.540765) (xy 333.14249 -93.591994) (xy 333.120775 -93.640676)
			(xy 333.10703 -93.663516) (xy 333.100196 -93.675215) (xy 333.092338 -93.701133) (xy 333.09158 -93.728205)
			(xy 333.097974 -93.754522) (xy 333.111069 -93.778229) (xy 333.129943 -93.797652) (xy 333.153263 -93.811423)
			(xy 333.166212 -93.815408) (xy 333.192774 -93.823156) (xy 333.243499 -93.845255) (xy 333.290498 -93.874453)
			(xy 333.332784 -93.910135) (xy 333.369471 -93.951553) (xy 333.399788 -93.997838) (xy 333.423098 -94.048018)
			(xy 333.438913 -94.101039) (xy 333.446901 -94.155789) (xy 333.44739 -94.183454) (xy 333.446904 -94.210705)
			(xy 333.445344 -94.221554) (xy 336.16976 -94.221554) (xy 336.173831 -94.165932) (xy 336.185957 -94.111495)
			(xy 336.20588 -94.059404) (xy 336.233176 -94.010769) (xy 336.267262 -93.966626) (xy 336.307411 -93.927917)
			(xy 336.352769 -93.895466) (xy 336.402369 -93.869965) (xy 336.455153 -93.851958) (xy 336.509996 -93.841828)
			(xy 336.56573 -93.839791) (xy 336.621167 -93.845891) (xy 336.675124 -93.859997) (xy 336.726453 -93.881809)
			(xy 336.774059 -93.910863) (xy 336.816927 -93.946538) (xy 336.854144 -93.988075) (xy 336.884917 -94.034588)
			(xy 336.908589 -94.085085) (xy 336.924657 -94.138492) (xy 336.932777 -94.193668) (xy 336.933286 -94.221554)
			(xy 336.932777 -94.24944) (xy 336.924657 -94.304616) (xy 336.908589 -94.358023) (xy 336.884917 -94.40852)
			(xy 336.854144 -94.455033) (xy 336.816927 -94.49657) (xy 336.774059 -94.532245) (xy 336.726453 -94.561299)
			(xy 336.675124 -94.583111) (xy 336.621167 -94.597217) (xy 336.56573 -94.603317) (xy 336.509996 -94.60128)
			(xy 336.455153 -94.59115) (xy 336.402369 -94.573143) (xy 336.352769 -94.547642) (xy 336.307411 -94.515191)
			(xy 336.267262 -94.476482) (xy 336.233176 -94.432339) (xy 336.20588 -94.383704) (xy 336.185957 -94.331613)
			(xy 336.173831 -94.277176) (xy 336.16976 -94.221554) (xy 333.445344 -94.221554) (xy 333.439148 -94.264653)
			(xy 333.423793 -94.316948) (xy 333.401151 -94.366525) (xy 333.371685 -94.412375) (xy 333.335994 -94.453566)
			(xy 333.294803 -94.489257) (xy 333.248953 -94.518723) (xy 333.199376 -94.541365) (xy 333.147081 -94.55672)
			(xy 333.093133 -94.564476) (xy 333.038631 -94.564476) (xy 332.984683 -94.55672) (xy 332.932388 -94.541365)
			(xy 332.882811 -94.518723) (xy 332.836961 -94.489257) (xy 332.79577 -94.453566) (xy 332.760079 -94.412375)
			(xy 332.730613 -94.366525) (xy 332.707971 -94.316948) (xy 332.692616 -94.264653) (xy 332.68486 -94.210705)
			(xy 332.684374 -94.183454) (xy 332.684374 -94.182946) (xy 332.684866 -94.156293) (xy 332.692332 -94.103511)
			(xy 332.70707 -94.052282) (xy 332.728792 -94.003601) (xy 332.74254 -93.980762) (xy 332.74936 -93.969059)
			(xy 332.757206 -93.943143) (xy 332.757959 -93.916077) (xy 332.751565 -93.889766) (xy 332.738475 -93.866063)
			(xy 332.719611 -93.846639) (xy 332.696302 -93.83286) (xy 332.683358 -93.82887) (xy 332.656812 -93.821071)
			(xy 332.606092 -93.798974) (xy 332.559097 -93.769781) (xy 332.516813 -93.734104) (xy 332.480126 -93.692693)
			(xy 332.449808 -93.646416) (xy 332.426493 -93.596244) (xy 332.410671 -93.54323) (xy 332.402675 -93.488486)
			(xy 332.40218 -93.460824) (xy 317.145416 -93.460824) (xy 317.145416 -94.428818) (xy 321.675758 -94.428818)
			(xy 321.679829 -94.373196) (xy 321.691955 -94.318759) (xy 321.711878 -94.266668) (xy 321.739174 -94.218033)
			(xy 321.77326 -94.17389) (xy 321.813409 -94.135181) (xy 321.858767 -94.10273) (xy 321.908367 -94.077229)
			(xy 321.961151 -94.059222) (xy 322.015994 -94.049092) (xy 322.071728 -94.047055) (xy 322.127165 -94.053155)
			(xy 322.181122 -94.067261) (xy 322.232451 -94.089073) (xy 322.280057 -94.118127) (xy 322.322925 -94.153802)
			(xy 322.360142 -94.195339) (xy 322.390915 -94.241852) (xy 322.394378 -94.24924) (xy 327.636122 -94.24924)
			(xy 327.640193 -94.193618) (xy 327.652319 -94.139181) (xy 327.672242 -94.08709) (xy 327.699538 -94.038455)
			(xy 327.733624 -93.994312) (xy 327.773773 -93.955603) (xy 327.819131 -93.923152) (xy 327.868731 -93.897651)
			(xy 327.921515 -93.879644) (xy 327.976358 -93.869514) (xy 328.032092 -93.867477) (xy 328.087529 -93.873577)
			(xy 328.141486 -93.887683) (xy 328.192815 -93.909495) (xy 328.240421 -93.938549) (xy 328.283289 -93.974224)
			(xy 328.320506 -94.015761) (xy 328.351279 -94.062274) (xy 328.374951 -94.112771) (xy 328.391019 -94.166178)
			(xy 328.399139 -94.221354) (xy 328.399648 -94.24924) (xy 328.399574 -94.253304) (xy 328.652122 -94.253304)
			(xy 328.656193 -94.197682) (xy 328.668319 -94.143245) (xy 328.688242 -94.091154) (xy 328.715538 -94.042519)
			(xy 328.749624 -93.998376) (xy 328.789773 -93.959667) (xy 328.835131 -93.927216) (xy 328.884731 -93.901715)
			(xy 328.937515 -93.883708) (xy 328.992358 -93.873578) (xy 329.048092 -93.871541) (xy 329.103529 -93.877641)
			(xy 329.157486 -93.891747) (xy 329.208815 -93.913559) (xy 329.256421 -93.942613) (xy 329.299289 -93.978288)
			(xy 329.336506 -94.019825) (xy 329.367279 -94.066338) (xy 329.390951 -94.116835) (xy 329.407019 -94.170242)
			(xy 329.415139 -94.225418) (xy 329.415648 -94.253304) (xy 329.415139 -94.28119) (xy 329.407019 -94.336366)
			(xy 329.390951 -94.389773) (xy 329.367279 -94.44027) (xy 329.336506 -94.486783) (xy 329.299289 -94.52832)
			(xy 329.256421 -94.563995) (xy 329.208815 -94.593049) (xy 329.157486 -94.614861) (xy 329.103529 -94.628967)
			(xy 329.048092 -94.635067) (xy 328.992358 -94.63303) (xy 328.937515 -94.6229) (xy 328.884731 -94.604893)
			(xy 328.835131 -94.579392) (xy 328.789773 -94.546941) (xy 328.749624 -94.508232) (xy 328.715538 -94.464089)
			(xy 328.688242 -94.415454) (xy 328.668319 -94.363363) (xy 328.656193 -94.308926) (xy 328.652122 -94.253304)
			(xy 328.399574 -94.253304) (xy 328.399139 -94.277126) (xy 328.391019 -94.332302) (xy 328.374951 -94.385709)
			(xy 328.351279 -94.436206) (xy 328.320506 -94.482719) (xy 328.283289 -94.524256) (xy 328.240421 -94.559931)
			(xy 328.192815 -94.588985) (xy 328.141486 -94.610797) (xy 328.087529 -94.624903) (xy 328.032092 -94.631003)
			(xy 327.976358 -94.628966) (xy 327.921515 -94.618836) (xy 327.868731 -94.600829) (xy 327.819131 -94.575328)
			(xy 327.773773 -94.542877) (xy 327.733624 -94.504168) (xy 327.699538 -94.460025) (xy 327.672242 -94.41139)
			(xy 327.652319 -94.359299) (xy 327.640193 -94.304862) (xy 327.636122 -94.24924) (xy 322.394378 -94.24924)
			(xy 322.414587 -94.292349) (xy 322.430655 -94.345756) (xy 322.438775 -94.400932) (xy 322.439284 -94.428818)
			(xy 322.438775 -94.456704) (xy 322.430655 -94.51188) (xy 322.414587 -94.565287) (xy 322.390915 -94.615784)
			(xy 322.360142 -94.662297) (xy 322.322925 -94.703834) (xy 322.280057 -94.739509) (xy 322.232451 -94.768563)
			(xy 322.181122 -94.790375) (xy 322.127165 -94.804481) (xy 322.071728 -94.810581) (xy 322.015994 -94.808544)
			(xy 321.961151 -94.798414) (xy 321.908367 -94.780407) (xy 321.858767 -94.754906) (xy 321.813409 -94.722455)
			(xy 321.77326 -94.683746) (xy 321.739174 -94.639603) (xy 321.711878 -94.590968) (xy 321.691955 -94.538877)
			(xy 321.679829 -94.48444) (xy 321.675758 -94.428818) (xy 317.145416 -94.428818) (xy 317.145416 -94.87389)
			(xy 338.405861 -94.87389) (xy 338.405861 -94.81391) (xy 338.413691 -94.754443) (xy 338.429215 -94.696507)
			(xy 338.45217 -94.641093) (xy 338.482161 -94.58915) (xy 338.518676 -94.541565) (xy 338.561089 -94.499155)
			(xy 338.608676 -94.462643) (xy 338.660622 -94.432655) (xy 338.716037 -94.409705) (xy 338.773975 -94.394184)
			(xy 338.833442 -94.386359) (xy 338.863432 -94.385892) (xy 339.727032 -94.385892) (xy 339.757012 -94.386476)
			(xy 339.816458 -94.394306) (xy 339.874374 -94.409828) (xy 339.929769 -94.432777) (xy 339.981694 -94.462759)
			(xy 339.984135 -94.464632) (xy 342.457784 -94.464632) (xy 342.461855 -94.40901) (xy 342.473981 -94.354573)
			(xy 342.493904 -94.302482) (xy 342.5212 -94.253847) (xy 342.555286 -94.209704) (xy 342.595435 -94.170995)
			(xy 342.640793 -94.138544) (xy 342.690393 -94.113043) (xy 342.743177 -94.095036) (xy 342.79802 -94.084906)
			(xy 342.853754 -94.082869) (xy 342.909191 -94.088969) (xy 342.963148 -94.103075) (xy 343.014477 -94.124887)
			(xy 343.062083 -94.153941) (xy 343.104951 -94.189616) (xy 343.142168 -94.231153) (xy 343.172941 -94.277666)
			(xy 343.196613 -94.328163) (xy 343.212681 -94.38157) (xy 343.220801 -94.436746) (xy 343.22131 -94.464632)
			(xy 343.220801 -94.492518) (xy 343.212681 -94.547694) (xy 343.196613 -94.601101) (xy 343.172941 -94.651598)
			(xy 343.142168 -94.698111) (xy 343.104951 -94.739648) (xy 343.062083 -94.775323) (xy 343.014477 -94.804377)
			(xy 342.963148 -94.826189) (xy 342.909191 -94.840295) (xy 342.853754 -94.846395) (xy 342.79802 -94.844358)
			(xy 342.743177 -94.834228) (xy 342.690393 -94.816221) (xy 342.640793 -94.79072) (xy 342.595435 -94.758269)
			(xy 342.555286 -94.71956) (xy 342.5212 -94.675417) (xy 342.493904 -94.626782) (xy 342.473981 -94.574691)
			(xy 342.461855 -94.520254) (xy 342.457784 -94.464632) (xy 339.984135 -94.464632) (xy 340.029262 -94.499262)
			(xy 340.071659 -94.541662) (xy 340.108159 -94.589232) (xy 340.138137 -94.64116) (xy 340.161082 -94.696556)
			(xy 340.1766 -94.754473) (xy 340.184426 -94.81392) (xy 340.184426 -94.87388) (xy 340.1766 -94.933327)
			(xy 340.161082 -94.991244) (xy 340.138137 -95.04664) (xy 340.108159 -95.098568) (xy 340.071659 -95.146138)
			(xy 340.029262 -95.188538) (xy 339.981694 -95.225041) (xy 339.929769 -95.255023) (xy 339.874374 -95.277972)
			(xy 339.816458 -95.293494) (xy 339.757012 -95.301324) (xy 339.727032 -95.301816) (xy 338.863432 -95.301816)
			(xy 338.833442 -95.301441) (xy 338.773975 -95.293616) (xy 338.716037 -95.278095) (xy 338.660622 -95.255145)
			(xy 338.608676 -95.225157) (xy 338.561089 -95.188645) (xy 338.518676 -95.146235) (xy 338.482161 -95.09865)
			(xy 338.45217 -95.046707) (xy 338.429215 -94.991293) (xy 338.413691 -94.933357) (xy 338.405861 -94.87389)
			(xy 317.145416 -94.87389) (xy 317.145416 -95.801942) (xy 320.841368 -95.801942) (xy 320.845439 -95.74632)
			(xy 320.857565 -95.691883) (xy 320.877488 -95.639792) (xy 320.904784 -95.591157) (xy 320.93887 -95.547014)
			(xy 320.979019 -95.508305) (xy 321.024377 -95.475854) (xy 321.073977 -95.450353) (xy 321.126761 -95.432346)
			(xy 321.181604 -95.422216) (xy 321.237338 -95.420179) (xy 321.292775 -95.426279) (xy 321.346732 -95.440385)
			(xy 321.398061 -95.462197) (xy 321.445667 -95.491251) (xy 321.488535 -95.526926) (xy 321.525752 -95.568463)
			(xy 321.556525 -95.614976) (xy 321.580197 -95.665473) (xy 321.596265 -95.71888) (xy 321.604385 -95.774056)
			(xy 321.604894 -95.801942) (xy 321.604385 -95.829828) (xy 321.601873 -95.8469) (xy 323.324726 -95.8469)
			(xy 323.328797 -95.791278) (xy 323.340923 -95.736841) (xy 323.360846 -95.68475) (xy 323.388142 -95.636115)
			(xy 323.422228 -95.591972) (xy 323.462377 -95.553263) (xy 323.507735 -95.520812) (xy 323.557335 -95.495311)
			(xy 323.610119 -95.477304) (xy 323.664962 -95.467174) (xy 323.720696 -95.465137) (xy 323.776133 -95.471237)
			(xy 323.83009 -95.485343) (xy 323.881419 -95.507155) (xy 323.929025 -95.536209) (xy 323.971893 -95.571884)
			(xy 324.00911 -95.613421) (xy 324.039883 -95.659934) (xy 324.063555 -95.710431) (xy 324.079623 -95.763838)
			(xy 324.085231 -95.801942) (xy 324.915528 -95.801942) (xy 324.919599 -95.74632) (xy 324.931725 -95.691883)
			(xy 324.951648 -95.639792) (xy 324.978944 -95.591157) (xy 325.01303 -95.547014) (xy 325.053179 -95.508305)
			(xy 325.098537 -95.475854) (xy 325.148137 -95.450353) (xy 325.200921 -95.432346) (xy 325.255764 -95.422216)
			(xy 325.311498 -95.420179) (xy 325.366935 -95.426279) (xy 325.420892 -95.440385) (xy 325.472221 -95.462197)
			(xy 325.519827 -95.491251) (xy 325.562695 -95.526926) (xy 325.599912 -95.568463) (xy 325.630685 -95.614976)
			(xy 325.654357 -95.665473) (xy 325.670425 -95.71888) (xy 325.678545 -95.774056) (xy 325.679054 -95.801942)
			(xy 325.921368 -95.801942) (xy 325.925439 -95.74632) (xy 325.937565 -95.691883) (xy 325.957488 -95.639792)
			(xy 325.984784 -95.591157) (xy 326.01887 -95.547014) (xy 326.059019 -95.508305) (xy 326.104377 -95.475854)
			(xy 326.153977 -95.450353) (xy 326.206761 -95.432346) (xy 326.261604 -95.422216) (xy 326.317338 -95.420179)
			(xy 326.372775 -95.426279) (xy 326.426732 -95.440385) (xy 326.478061 -95.462197) (xy 326.525667 -95.491251)
			(xy 326.568535 -95.526926) (xy 326.605752 -95.568463) (xy 326.636525 -95.614976) (xy 326.660197 -95.665473)
			(xy 326.676265 -95.71888) (xy 326.684385 -95.774056) (xy 326.684894 -95.801942) (xy 326.684385 -95.829828)
			(xy 326.67724 -95.878379) (xy 331.320012 -95.878379) (xy 331.327765 -95.824422) (xy 331.343118 -95.772116)
			(xy 331.365759 -95.722529) (xy 331.395226 -95.676668) (xy 331.43092 -95.635467) (xy 331.472115 -95.599766)
			(xy 331.517971 -95.570291) (xy 331.567554 -95.547641) (xy 331.619857 -95.532279) (xy 331.673813 -95.524517)
			(xy 331.728325 -95.524513) (xy 331.782283 -95.532266) (xy 331.834588 -95.54762) (xy 331.884176 -95.570261)
			(xy 331.930036 -95.599729) (xy 331.971236 -95.635424) (xy 332.006937 -95.676619) (xy 332.036412 -95.722475)
			(xy 332.05906 -95.772059) (xy 332.074422 -95.824362) (xy 332.082183 -95.878318) (xy 332.082648 -95.905574)
			(xy 332.082648 -95.906082) (xy 332.082565 -95.916454) (xy 332.081423 -95.937166) (xy 332.080362 -95.947484)
			(xy 332.0793 -95.96203) (xy 332.084505 -95.990715) (xy 332.097592 -96.016765) (xy 332.117497 -96.038065)
			(xy 332.142604 -96.052883) (xy 332.170871 -96.060014) (xy 332.200002 -96.058881) (xy 332.213966 -96.054672)
			(xy 332.243575 -96.045318) (xy 332.304841 -96.035236) (xy 332.335886 -96.034606) (xy 332.33614 -96.034606)
			(xy 332.363387 -96.035121) (xy 332.417327 -96.042882) (xy 332.469613 -96.05824) (xy 332.519182 -96.080883)
			(xy 332.565023 -96.110349) (xy 332.606205 -96.146039) (xy 332.641888 -96.187226) (xy 332.671347 -96.233073)
			(xy 332.693982 -96.282645) (xy 332.709331 -96.334934) (xy 332.717083 -96.388874) (xy 332.71708 -96.44337)
			(xy 332.709322 -96.497309) (xy 332.693966 -96.549596) (xy 332.671326 -96.599166) (xy 332.641862 -96.645009)
			(xy 332.606174 -96.686192) (xy 332.564988 -96.721878) (xy 332.519143 -96.751339) (xy 332.469572 -96.773975)
			(xy 332.417284 -96.789328) (xy 332.363344 -96.797082) (xy 332.308848 -96.797082) (xy 332.254908 -96.789326)
			(xy 332.20262 -96.773973) (xy 332.15305 -96.751335) (xy 332.107206 -96.721873) (xy 332.066021 -96.686187)
			(xy 332.030333 -96.645002) (xy 332.00087 -96.599159) (xy 331.978231 -96.549589) (xy 331.962876 -96.497302)
			(xy 331.955119 -96.443362) (xy 331.954632 -96.416114) (xy 331.954632 -96.415606) (xy 331.954714 -96.405234)
			(xy 331.955857 -96.384522) (xy 331.956918 -96.374204) (xy 331.958018 -96.359659) (xy 331.952809 -96.330969)
			(xy 331.939716 -96.304915) (xy 331.919804 -96.283613) (xy 331.894691 -96.268796) (xy 331.866417 -96.261667)
			(xy 331.83728 -96.262805) (xy 331.823314 -96.267016) (xy 331.793707 -96.276374) (xy 331.732439 -96.286453)
			(xy 331.701394 -96.287082) (xy 331.70114 -96.287082) (xy 331.673884 -96.286688) (xy 331.619926 -96.278936)
			(xy 331.567621 -96.263583) (xy 331.518033 -96.240943) (xy 331.472171 -96.211476) (xy 331.430971 -96.175783)
			(xy 331.395269 -96.134589) (xy 331.365793 -96.088734) (xy 331.343143 -96.03915) (xy 331.32778 -95.986848)
			(xy 331.320017 -95.932891) (xy 331.320012 -95.878379) (xy 326.67724 -95.878379) (xy 326.676265 -95.885004)
			(xy 326.660197 -95.938411) (xy 326.636525 -95.988908) (xy 326.605752 -96.035421) (xy 326.568535 -96.076958)
			(xy 326.525667 -96.112633) (xy 326.478061 -96.141687) (xy 326.426732 -96.163499) (xy 326.372775 -96.177605)
			(xy 326.317338 -96.183705) (xy 326.261604 -96.181668) (xy 326.206761 -96.171538) (xy 326.153977 -96.153531)
			(xy 326.104377 -96.12803) (xy 326.059019 -96.095579) (xy 326.01887 -96.05687) (xy 325.984784 -96.012727)
			(xy 325.957488 -95.964092) (xy 325.937565 -95.912001) (xy 325.925439 -95.857564) (xy 325.921368 -95.801942)
			(xy 325.679054 -95.801942) (xy 325.678545 -95.829828) (xy 325.670425 -95.885004) (xy 325.654357 -95.938411)
			(xy 325.630685 -95.988908) (xy 325.599912 -96.035421) (xy 325.562695 -96.076958) (xy 325.519827 -96.112633)
			(xy 325.472221 -96.141687) (xy 325.420892 -96.163499) (xy 325.366935 -96.177605) (xy 325.311498 -96.183705)
			(xy 325.255764 -96.181668) (xy 325.200921 -96.171538) (xy 325.148137 -96.153531) (xy 325.098537 -96.12803)
			(xy 325.053179 -96.095579) (xy 325.01303 -96.05687) (xy 324.978944 -96.012727) (xy 324.951648 -95.964092)
			(xy 324.931725 -95.912001) (xy 324.919599 -95.857564) (xy 324.915528 -95.801942) (xy 324.085231 -95.801942)
			(xy 324.087743 -95.819014) (xy 324.088252 -95.8469) (xy 324.087743 -95.874786) (xy 324.079623 -95.929962)
			(xy 324.063555 -95.983369) (xy 324.039883 -96.033866) (xy 324.00911 -96.080379) (xy 323.971893 -96.121916)
			(xy 323.929025 -96.157591) (xy 323.881419 -96.186645) (xy 323.83009 -96.208457) (xy 323.776133 -96.222563)
			(xy 323.720696 -96.228663) (xy 323.664962 -96.226626) (xy 323.610119 -96.216496) (xy 323.557335 -96.198489)
			(xy 323.507735 -96.172988) (xy 323.462377 -96.140537) (xy 323.422228 -96.101828) (xy 323.388142 -96.057685)
			(xy 323.360846 -96.00905) (xy 323.340923 -95.956959) (xy 323.328797 -95.902522) (xy 323.324726 -95.8469)
			(xy 321.601873 -95.8469) (xy 321.596265 -95.885004) (xy 321.580197 -95.938411) (xy 321.556525 -95.988908)
			(xy 321.525752 -96.035421) (xy 321.488535 -96.076958) (xy 321.445667 -96.112633) (xy 321.398061 -96.141687)
			(xy 321.346732 -96.163499) (xy 321.292775 -96.177605) (xy 321.237338 -96.183705) (xy 321.181604 -96.181668)
			(xy 321.126761 -96.171538) (xy 321.073977 -96.153531) (xy 321.024377 -96.12803) (xy 320.979019 -96.095579)
			(xy 320.93887 -96.05687) (xy 320.904784 -96.012727) (xy 320.877488 -95.964092) (xy 320.857565 -95.912001)
			(xy 320.845439 -95.857564) (xy 320.841368 -95.801942) (xy 317.145416 -95.801942) (xy 317.145416 -96.374966)
			(xy 326.62698 -96.374966) (xy 326.631051 -96.319344) (xy 326.643177 -96.264907) (xy 326.6631 -96.212816)
			(xy 326.690396 -96.164181) (xy 326.724482 -96.120038) (xy 326.764631 -96.081329) (xy 326.809989 -96.048878)
			(xy 326.859589 -96.023377) (xy 326.912373 -96.00537) (xy 326.967216 -95.99524) (xy 327.02295 -95.993203)
			(xy 327.078387 -95.999303) (xy 327.132344 -96.013409) (xy 327.183673 -96.035221) (xy 327.231279 -96.064275)
			(xy 327.274147 -96.09995) (xy 327.311364 -96.141487) (xy 327.342137 -96.188) (xy 327.365809 -96.238497)
			(xy 327.380808 -96.288352) (xy 328.052174 -96.288352) (xy 328.056245 -96.23273) (xy 328.068371 -96.178293)
			(xy 328.088294 -96.126202) (xy 328.11559 -96.077567) (xy 328.149676 -96.033424) (xy 328.189825 -95.994715)
			(xy 328.235183 -95.962264) (xy 328.284783 -95.936763) (xy 328.337567 -95.918756) (xy 328.39241 -95.908626)
			(xy 328.448144 -95.906589) (xy 328.503581 -95.912689) (xy 328.557538 -95.926795) (xy 328.608867 -95.948607)
			(xy 328.656473 -95.977661) (xy 328.699341 -96.013336) (xy 328.736558 -96.054873) (xy 328.767331 -96.101386)
			(xy 328.791003 -96.151883) (xy 328.807071 -96.20529) (xy 328.815191 -96.260466) (xy 328.815422 -96.273112)
			(xy 329.397866 -96.273112) (xy 329.401937 -96.21749) (xy 329.414063 -96.163053) (xy 329.433986 -96.110962)
			(xy 329.461282 -96.062327) (xy 329.495368 -96.018184) (xy 329.535517 -95.979475) (xy 329.580875 -95.947024)
			(xy 329.630475 -95.921523) (xy 329.683259 -95.903516) (xy 329.738102 -95.893386) (xy 329.793836 -95.891349)
			(xy 329.849273 -95.897449) (xy 329.90323 -95.911555) (xy 329.954559 -95.933367) (xy 330.002165 -95.962421)
			(xy 330.045033 -95.998096) (xy 330.08225 -96.039633) (xy 330.113023 -96.086146) (xy 330.136695 -96.136643)
			(xy 330.152763 -96.19005) (xy 330.160883 -96.245226) (xy 330.161392 -96.273112) (xy 330.160883 -96.300998)
			(xy 330.152763 -96.356174) (xy 330.136695 -96.409581) (xy 330.113023 -96.460078) (xy 330.08225 -96.506591)
			(xy 330.045033 -96.548128) (xy 330.002165 -96.583803) (xy 329.954559 -96.612857) (xy 329.90323 -96.634669)
			(xy 329.849273 -96.648775) (xy 329.793836 -96.654875) (xy 329.738102 -96.652838) (xy 329.683259 -96.642708)
			(xy 329.630475 -96.624701) (xy 329.580875 -96.5992) (xy 329.535517 -96.566749) (xy 329.495368 -96.52804)
			(xy 329.461282 -96.483897) (xy 329.433986 -96.435262) (xy 329.414063 -96.383171) (xy 329.401937 -96.328734)
			(xy 329.397866 -96.273112) (xy 328.815422 -96.273112) (xy 328.8157 -96.288352) (xy 328.815191 -96.316238)
			(xy 328.807071 -96.371414) (xy 328.791003 -96.424821) (xy 328.767331 -96.475318) (xy 328.736558 -96.521831)
			(xy 328.699341 -96.563368) (xy 328.656473 -96.599043) (xy 328.608867 -96.628097) (xy 328.557538 -96.649909)
			(xy 328.503581 -96.664015) (xy 328.448144 -96.670115) (xy 328.39241 -96.668078) (xy 328.337567 -96.657948)
			(xy 328.284783 -96.639941) (xy 328.235183 -96.61444) (xy 328.189825 -96.581989) (xy 328.149676 -96.54328)
			(xy 328.11559 -96.499137) (xy 328.088294 -96.450502) (xy 328.068371 -96.398411) (xy 328.056245 -96.343974)
			(xy 328.052174 -96.288352) (xy 327.380808 -96.288352) (xy 327.381877 -96.291904) (xy 327.389997 -96.34708)
			(xy 327.390506 -96.374966) (xy 327.389997 -96.402852) (xy 327.381877 -96.458028) (xy 327.365809 -96.511435)
			(xy 327.342137 -96.561932) (xy 327.311364 -96.608445) (xy 327.274147 -96.649982) (xy 327.231279 -96.685657)
			(xy 327.183673 -96.714711) (xy 327.132344 -96.736523) (xy 327.078387 -96.750629) (xy 327.02295 -96.756729)
			(xy 326.967216 -96.754692) (xy 326.912373 -96.744562) (xy 326.859589 -96.726555) (xy 326.809989 -96.701054)
			(xy 326.764631 -96.668603) (xy 326.724482 -96.629894) (xy 326.690396 -96.585751) (xy 326.6631 -96.537116)
			(xy 326.643177 -96.485025) (xy 326.631051 -96.430588) (xy 326.62698 -96.374966) (xy 317.145416 -96.374966)
			(xy 317.145416 -97.953576) (xy 320.542918 -97.953576) (xy 320.546989 -97.897954) (xy 320.559115 -97.843517)
			(xy 320.579038 -97.791426) (xy 320.606334 -97.742791) (xy 320.64042 -97.698648) (xy 320.680569 -97.659939)
			(xy 320.725927 -97.627488) (xy 320.775527 -97.601987) (xy 320.828311 -97.58398) (xy 320.883154 -97.57385)
			(xy 320.938888 -97.571813) (xy 320.994325 -97.577913) (xy 321.048282 -97.592019) (xy 321.099611 -97.613831)
			(xy 321.147217 -97.642885) (xy 321.190085 -97.67856) (xy 321.227302 -97.720097) (xy 321.258075 -97.76661)
			(xy 321.281747 -97.817107) (xy 321.282991 -97.821242) (xy 321.857368 -97.821242) (xy 321.861439 -97.76562)
			(xy 321.873565 -97.711183) (xy 321.893488 -97.659092) (xy 321.920784 -97.610457) (xy 321.95487 -97.566314)
			(xy 321.995019 -97.527605) (xy 322.040377 -97.495154) (xy 322.089977 -97.469653) (xy 322.142761 -97.451646)
			(xy 322.197604 -97.441516) (xy 322.253338 -97.439479) (xy 322.308775 -97.445579) (xy 322.362732 -97.459685)
			(xy 322.414061 -97.481497) (xy 322.461667 -97.510551) (xy 322.504535 -97.546226) (xy 322.541752 -97.587763)
			(xy 322.572525 -97.634276) (xy 322.596197 -97.684773) (xy 322.612265 -97.73818) (xy 322.620385 -97.793356)
			(xy 322.620894 -97.821242) (xy 322.620397 -97.848448) (xy 323.12842 -97.848448) (xy 323.12842 -97.793952)
			(xy 323.136175 -97.740012) (xy 323.151528 -97.687724) (xy 323.174166 -97.638153) (xy 323.203627 -97.592309)
			(xy 323.239313 -97.551123) (xy 323.280497 -97.515436) (xy 323.326341 -97.485972) (xy 323.375911 -97.463333)
			(xy 323.428198 -97.447978) (xy 323.482138 -97.440221) (xy 323.509386 -97.439734) (xy 323.538303 -97.44025)
			(xy 323.595475 -97.448977) (xy 323.650675 -97.466235) (xy 323.702636 -97.491627) (xy 323.75017 -97.524572)
			(xy 323.792186 -97.564314) (xy 323.810376 -97.5868) (xy 323.818003 -97.595586) (xy 323.838889 -97.605781)
			(xy 323.850508 -97.606358) (xy 323.930264 -97.606358) (xy 323.941901 -97.605856) (xy 323.962811 -97.595642)
			(xy 323.970396 -97.5868) (xy 323.988589 -97.564318) (xy 324.030609 -97.524583) (xy 324.078143 -97.491644)
			(xy 324.130104 -97.466255) (xy 324.185301 -97.448999) (xy 324.24247 -97.440269) (xy 324.271386 -97.439734)
			(xy 324.298643 -97.440112) (xy 324.352601 -97.447868) (xy 324.404906 -97.463225) (xy 324.454494 -97.485869)
			(xy 324.500354 -97.51534) (xy 324.541553 -97.551037) (xy 324.577252 -97.592235) (xy 324.606724 -97.638094)
			(xy 324.62937 -97.687681) (xy 324.644729 -97.739985) (xy 324.652487 -97.793943) (xy 324.652487 -97.821242)
			(xy 324.905368 -97.821242) (xy 324.909439 -97.76562) (xy 324.921565 -97.711183) (xy 324.941488 -97.659092)
			(xy 324.968784 -97.610457) (xy 325.00287 -97.566314) (xy 325.043019 -97.527605) (xy 325.088377 -97.495154)
			(xy 325.137977 -97.469653) (xy 325.190761 -97.451646) (xy 325.245604 -97.441516) (xy 325.301338 -97.439479)
			(xy 325.356775 -97.445579) (xy 325.410732 -97.459685) (xy 325.462061 -97.481497) (xy 325.509667 -97.510551)
			(xy 325.552535 -97.546226) (xy 325.589752 -97.587763) (xy 325.620525 -97.634276) (xy 325.644197 -97.684773)
			(xy 325.660265 -97.73818) (xy 325.668385 -97.793356) (xy 325.668894 -97.821242) (xy 325.668385 -97.849128)
			(xy 325.660265 -97.904304) (xy 325.644197 -97.957711) (xy 325.620525 -98.008208) (xy 325.589752 -98.054721)
			(xy 325.552535 -98.096258) (xy 325.509667 -98.131933) (xy 325.462061 -98.160987) (xy 325.410732 -98.182799)
			(xy 325.356775 -98.196905) (xy 325.301338 -98.203005) (xy 325.245604 -98.200968) (xy 325.190761 -98.190838)
			(xy 325.137977 -98.172831) (xy 325.088377 -98.14733) (xy 325.043019 -98.114879) (xy 325.00287 -98.07617)
			(xy 324.968784 -98.032027) (xy 324.941488 -97.983392) (xy 324.921565 -97.931301) (xy 324.909439 -97.876864)
			(xy 324.905368 -97.821242) (xy 324.652487 -97.821242) (xy 324.652487 -97.848457) (xy 324.644729 -97.902415)
			(xy 324.62937 -97.954719) (xy 324.606724 -98.004306) (xy 324.577252 -98.050165) (xy 324.541553 -98.091363)
			(xy 324.500354 -98.12706) (xy 324.454494 -98.156531) (xy 324.404906 -98.179175) (xy 324.352601 -98.194532)
			(xy 324.298643 -98.202288) (xy 324.271386 -98.20275) (xy 324.24247 -98.202189) (xy 324.1853 -98.193471)
			(xy 324.130102 -98.176223) (xy 324.078139 -98.15084) (xy 324.030605 -98.117902) (xy 323.988587 -98.078167)
			(xy 323.970396 -98.055684) (xy 323.962784 -98.046882) (xy 323.941887 -98.036696) (xy 323.930264 -98.036126)
			(xy 323.850508 -98.036126) (xy 323.838877 -98.036675) (xy 323.817967 -98.046856) (xy 323.810376 -98.055684)
			(xy 323.792194 -98.078176) (xy 323.750173 -98.117911) (xy 323.702637 -98.15085) (xy 323.650673 -98.176237)
			(xy 323.595474 -98.193491) (xy 323.538303 -98.202217) (xy 323.509386 -98.20275) (xy 323.482138 -98.202179)
			(xy 323.428198 -98.194422) (xy 323.375911 -98.179067) (xy 323.326341 -98.156428) (xy 323.280497 -98.126964)
			(xy 323.239313 -98.091277) (xy 323.203627 -98.050091) (xy 323.174166 -98.004247) (xy 323.151528 -97.954676)
			(xy 323.136175 -97.902388) (xy 323.12842 -97.848448) (xy 322.620397 -97.848448) (xy 322.620385 -97.849128)
			(xy 322.612265 -97.904304) (xy 322.596197 -97.957711) (xy 322.572525 -98.008208) (xy 322.541752 -98.054721)
			(xy 322.504535 -98.096258) (xy 322.461667 -98.131933) (xy 322.414061 -98.160987) (xy 322.362732 -98.182799)
			(xy 322.308775 -98.196905) (xy 322.253338 -98.203005) (xy 322.197604 -98.200968) (xy 322.142761 -98.190838)
			(xy 322.089977 -98.172831) (xy 322.040377 -98.14733) (xy 321.995019 -98.114879) (xy 321.95487 -98.07617)
			(xy 321.920784 -98.032027) (xy 321.893488 -97.983392) (xy 321.873565 -97.931301) (xy 321.861439 -97.876864)
			(xy 321.857368 -97.821242) (xy 321.282991 -97.821242) (xy 321.297815 -97.870514) (xy 321.305935 -97.92569)
			(xy 321.306444 -97.953576) (xy 321.305935 -97.981462) (xy 321.297815 -98.036638) (xy 321.281747 -98.090045)
			(xy 321.258075 -98.140542) (xy 321.227302 -98.187055) (xy 321.190085 -98.228592) (xy 321.147217 -98.264267)
			(xy 321.099611 -98.293321) (xy 321.048282 -98.315133) (xy 320.994325 -98.329239) (xy 320.938888 -98.335339)
			(xy 320.883154 -98.333302) (xy 320.828311 -98.323172) (xy 320.775527 -98.305165) (xy 320.725927 -98.279664)
			(xy 320.680569 -98.247213) (xy 320.64042 -98.208504) (xy 320.606334 -98.164361) (xy 320.579038 -98.115726)
			(xy 320.559115 -98.063635) (xy 320.546989 -98.009198) (xy 320.542918 -97.953576) (xy 317.145416 -97.953576)
			(xy 317.145416 -98.759518) (xy 331.371194 -98.759518) (xy 331.371672 -98.732148) (xy 331.379487 -98.67797)
			(xy 331.394974 -98.625467) (xy 331.417813 -98.57572) (xy 331.447534 -98.529752) (xy 331.465174 -98.50882)
			(xy 331.465428 -98.508566) (xy 331.470996 -98.501467) (xy 331.477253 -98.48456) (xy 331.47762 -98.475546)
			(xy 331.47762 -98.40849) (xy 331.477263 -98.399473) (xy 331.471015 -98.382557) (xy 331.465428 -98.37547)
			(xy 331.465174 -98.37547) (xy 331.465174 -98.375216) (xy 331.447549 -98.35427) (xy 331.41782 -98.308306)
			(xy 331.394971 -98.258562) (xy 331.379471 -98.206061) (xy 331.37164 -98.151884) (xy 331.371638 -98.097143)
			(xy 331.379465 -98.042965) (xy 331.394961 -97.990464) (xy 331.417807 -97.940718) (xy 331.447533 -97.894752)
			(xy 331.465174 -97.87382) (xy 331.465428 -97.873566) (xy 331.470996 -97.866467) (xy 331.477253 -97.84956)
			(xy 331.47762 -97.840546) (xy 331.47762 -97.77349) (xy 331.477263 -97.764473) (xy 331.471015 -97.747557)
			(xy 331.465428 -97.74047) (xy 331.465174 -97.74047) (xy 331.465174 -97.740216) (xy 331.447525 -97.719292)
			(xy 331.417815 -97.673317) (xy 331.394982 -97.623567) (xy 331.379493 -97.571065) (xy 331.371667 -97.516888)
			(xy 331.371194 -97.489518) (xy 331.37168 -97.462267) (xy 331.379436 -97.408319) (xy 331.394791 -97.356024)
			(xy 331.417433 -97.306447) (xy 331.446899 -97.260597) (xy 331.48259 -97.219406) (xy 331.523781 -97.183715)
			(xy 331.569631 -97.154249) (xy 331.619208 -97.131607) (xy 331.671503 -97.116252) (xy 331.725451 -97.108496)
			(xy 331.779953 -97.108496) (xy 331.833901 -97.116252) (xy 331.886196 -97.131607) (xy 331.935773 -97.154249)
			(xy 331.981623 -97.183715) (xy 332.022814 -97.219406) (xy 332.058505 -97.260597) (xy 332.087971 -97.306447)
			(xy 332.110613 -97.356024) (xy 332.125968 -97.408319) (xy 332.133724 -97.462267) (xy 332.13421 -97.489518)
			(xy 332.133752 -97.516888) (xy 332.125932 -97.571068) (xy 332.110441 -97.623571) (xy 332.087597 -97.673318)
			(xy 332.057872 -97.719284) (xy 332.04023 -97.740216) (xy 332.039976 -97.74047) (xy 332.034393 -97.747559)
			(xy 332.028145 -97.764474) (xy 332.027784 -97.77349) (xy 332.027784 -97.840546) (xy 332.02817 -97.84956)
			(xy 332.034398 -97.866477) (xy 332.039976 -97.873566) (xy 332.04023 -97.873566) (xy 332.04023 -97.87382)
			(xy 332.05789 -97.894738) (xy 332.087617 -97.940707) (xy 332.110464 -97.990455) (xy 332.125961 -98.04296)
			(xy 332.133789 -98.097142) (xy 332.133787 -98.151886) (xy 332.125955 -98.206066) (xy 332.110455 -98.25857)
			(xy 332.087604 -98.308317) (xy 332.057874 -98.354284) (xy 332.04023 -98.375216) (xy 332.039976 -98.37547)
			(xy 332.034393 -98.382559) (xy 332.028145 -98.399474) (xy 332.027784 -98.40849) (xy 332.027784 -98.475546)
			(xy 332.02817 -98.48456) (xy 332.034398 -98.501477) (xy 332.036031 -98.503552) (xy 333.025963 -98.503552)
			(xy 333.025963 -98.449048) (xy 333.03372 -98.395097) (xy 333.049076 -98.3428) (xy 333.071718 -98.293221)
			(xy 333.101186 -98.247369) (xy 333.13688 -98.206177) (xy 333.178072 -98.170484) (xy 333.223924 -98.141017)
			(xy 333.273504 -98.118375) (xy 333.325801 -98.103019) (xy 333.379752 -98.095263) (xy 333.407004 -98.0948)
			(xy 333.433318 -98.095265) (xy 333.485447 -98.1025) (xy 333.536089 -98.11682) (xy 333.584288 -98.137953)
			(xy 333.629132 -98.165499) (xy 333.669771 -98.198938) (xy 333.687928 -98.21799) (xy 333.695439 -98.225404)
			(xy 333.714727 -98.233922) (xy 333.725266 -98.2345) (xy 333.799942 -98.2345) (xy 333.81049 -98.233953)
			(xy 333.829785 -98.225431) (xy 333.83728 -98.21799) (xy 333.85545 -98.198949) (xy 333.896077 -98.165491)
			(xy 333.940914 -98.13793) (xy 333.989112 -98.116789) (xy 334.039757 -98.102469) (xy 334.091889 -98.095241)
			(xy 334.118204 -98.0948) (xy 334.145456 -98.09527) (xy 334.199404 -98.103027) (xy 334.251699 -98.118383)
			(xy 334.301277 -98.141025) (xy 334.347128 -98.170492) (xy 334.388319 -98.206184) (xy 334.424011 -98.247375)
			(xy 334.453477 -98.293226) (xy 334.473172 -98.336354) (xy 335.049368 -98.336354) (xy 335.049849 -98.308984)
			(xy 335.057661 -98.254805) (xy 335.073145 -98.202301) (xy 335.095984 -98.152554) (xy 335.125707 -98.106587)
			(xy 335.143348 -98.085656) (xy 335.143602 -98.085402) (xy 335.149194 -98.078319) (xy 335.155437 -98.0614)
			(xy 335.155794 -98.052382) (xy 335.155794 -97.985326) (xy 335.155426 -97.97631) (xy 335.149186 -97.959393)
			(xy 335.143602 -97.952306) (xy 335.143348 -97.952306) (xy 335.143348 -97.952052) (xy 335.125661 -97.931156)
			(xy 335.095937 -97.885182) (xy 335.073093 -97.83543) (xy 335.057599 -97.782922) (xy 335.049775 -97.728738)
			(xy 335.049779 -97.673992) (xy 335.057614 -97.61981) (xy 335.073117 -97.567305) (xy 335.09597 -97.517557)
			(xy 335.125703 -97.471588) (xy 335.143348 -97.450656) (xy 335.143602 -97.450402) (xy 335.149194 -97.443319)
			(xy 335.155437 -97.4264) (xy 335.155794 -97.417382) (xy 335.155794 -97.350326) (xy 335.155426 -97.34131)
			(xy 335.149186 -97.324393) (xy 335.143602 -97.317306) (xy 335.143348 -97.317306) (xy 335.143348 -97.317052)
			(xy 335.125727 -97.296105) (xy 335.096011 -97.250137) (xy 335.073171 -97.200393) (xy 335.057676 -97.147896)
			(xy 335.049844 -97.093722) (xy 335.049368 -97.066354) (xy 335.049854 -97.039103) (xy 335.05761 -96.985155)
			(xy 335.072965 -96.93286) (xy 335.095607 -96.883283) (xy 335.125073 -96.837433) (xy 335.160764 -96.796242)
			(xy 335.201955 -96.760551) (xy 335.247805 -96.731085) (xy 335.297382 -96.708443) (xy 335.349677 -96.693088)
			(xy 335.403625 -96.685332) (xy 335.458127 -96.685332) (xy 335.512075 -96.693088) (xy 335.56437 -96.708443)
			(xy 335.613947 -96.731085) (xy 335.659797 -96.760551) (xy 335.700988 -96.796242) (xy 335.736679 -96.837433)
			(xy 335.766145 -96.883283) (xy 335.788787 -96.93286) (xy 335.804142 -96.985155) (xy 335.811898 -97.039103)
			(xy 335.812384 -97.066354) (xy 335.811895 -97.093723) (xy 335.804083 -97.147902) (xy 335.7886 -97.200405)
			(xy 335.765763 -97.250152) (xy 335.736043 -97.29612) (xy 335.718404 -97.317052) (xy 335.71815 -97.317306)
			(xy 335.712549 -97.324382) (xy 335.706312 -97.341307) (xy 335.705958 -97.350326) (xy 335.705958 -97.417382)
			(xy 335.706311 -97.4264) (xy 335.71256 -97.443317) (xy 335.71815 -97.450402) (xy 335.718404 -97.450402)
			(xy 335.718404 -97.450656) (xy 335.735998 -97.471626) (xy 335.765723 -97.517588) (xy 335.788569 -97.567328)
			(xy 335.804067 -97.619824) (xy 335.8119 -97.673997) (xy 335.811904 -97.728733) (xy 335.804082 -97.782908)
			(xy 335.788593 -97.835407) (xy 335.765756 -97.885151) (xy 335.73604 -97.931119) (xy 335.718404 -97.952052)
			(xy 335.71815 -97.952306) (xy 335.712549 -97.959382) (xy 335.706312 -97.976307) (xy 335.705958 -97.985326)
			(xy 335.705958 -98.052382) (xy 335.706311 -98.0614) (xy 335.71256 -98.078317) (xy 335.71815 -98.085402)
			(xy 335.718404 -98.085402) (xy 335.718404 -98.085656) (xy 335.736037 -98.106593) (xy 335.765749 -98.152565)
			(xy 335.788586 -98.202311) (xy 335.792404 -98.215249) (xy 337.158596 -98.215249) (xy 337.158596 -98.160751)
			(xy 337.166352 -98.106807) (xy 337.181705 -98.054516) (xy 337.204344 -98.004942) (xy 337.233808 -97.959095)
			(xy 337.269496 -97.917907) (xy 337.310682 -97.882217) (xy 337.356528 -97.852752) (xy 337.406101 -97.830111)
			(xy 337.458391 -97.814755) (xy 337.512335 -97.806997) (xy 337.539584 -97.80651) (xy 337.569852 -97.807077)
			(xy 337.629627 -97.816648) (xy 337.687141 -97.835535) (xy 337.740952 -97.863266) (xy 337.78971 -97.899145)
			(xy 337.811364 -97.920302) (xy 337.818785 -97.927252) (xy 337.837527 -97.935099) (xy 337.847686 -97.935542)
			(xy 337.919822 -97.935542) (xy 337.929984 -97.935129) (xy 337.94872 -97.927256) (xy 337.956144 -97.920302)
			(xy 337.977796 -97.899144) (xy 338.026551 -97.863261) (xy 338.080363 -97.83553) (xy 338.137879 -97.816648)
			(xy 338.197656 -97.807089) (xy 338.227924 -97.80651) (xy 338.25776 -97.807056) (xy 338.316701 -97.816363)
			(xy 338.373475 -97.83473) (xy 338.426699 -97.861709) (xy 338.475075 -97.896644) (xy 338.496656 -97.917254)
			(xy 338.503768 -97.924366) (xy 338.52231 -97.931986) (xy 338.614004 -97.931986) (xy 338.632546 -97.924366)
			(xy 338.639658 -97.917254) (xy 338.661247 -97.896655) (xy 338.709619 -97.861718) (xy 338.762841 -97.834741)
			(xy 338.819615 -97.816382) (xy 338.878556 -97.807088) (xy 338.90839 -97.80651) (xy 338.935645 -97.806936)
			(xy 338.989599 -97.814692) (xy 339.041901 -97.830048) (xy 339.091485 -97.852691) (xy 339.137341 -97.88216)
			(xy 339.178537 -97.917856) (xy 339.214234 -97.959051) (xy 339.243704 -98.004907) (xy 339.266348 -98.05449)
			(xy 339.281705 -98.106791) (xy 339.289463 -98.160745) (xy 339.289463 -98.215255) (xy 339.281705 -98.269209)
			(xy 339.266348 -98.32151) (xy 339.243704 -98.371093) (xy 339.214234 -98.416949) (xy 339.178537 -98.458144)
			(xy 339.137341 -98.49384) (xy 339.091485 -98.523309) (xy 339.041901 -98.545952) (xy 338.989599 -98.561308)
			(xy 338.935645 -98.569064) (xy 338.90839 -98.569526) (xy 338.878555 -98.56896) (xy 338.819615 -98.559657)
			(xy 338.762842 -98.541294) (xy 338.709617 -98.514319) (xy 338.66124 -98.47939) (xy 338.639658 -98.458782)
			(xy 338.632546 -98.45167) (xy 338.614004 -98.44405) (xy 338.52231 -98.44405) (xy 338.503768 -98.45167)
			(xy 338.496656 -98.458782) (xy 338.475094 -98.479412) (xy 338.426716 -98.514346) (xy 338.373487 -98.541319)
			(xy 338.316707 -98.559671) (xy 338.25776 -98.568954) (xy 338.227924 -98.569526) (xy 338.197657 -98.568944)
			(xy 338.137883 -98.559375) (xy 338.080369 -98.540491) (xy 338.026558 -98.512763) (xy 337.977799 -98.476889)
			(xy 337.956144 -98.455734) (xy 337.948716 -98.448792) (xy 337.92998 -98.440939) (xy 337.919822 -98.440494)
			(xy 337.847686 -98.440494) (xy 337.837523 -98.440902) (xy 337.818786 -98.448778) (xy 337.811364 -98.455734)
			(xy 337.789714 -98.476895) (xy 337.740958 -98.512776) (xy 337.687146 -98.540506) (xy 337.629629 -98.559387)
			(xy 337.569852 -98.568947) (xy 337.539584 -98.569526) (xy 337.512335 -98.569003) (xy 337.458391 -98.561245)
			(xy 337.406101 -98.545889) (xy 337.356528 -98.523248) (xy 337.310682 -98.493783) (xy 337.269496 -98.458093)
			(xy 337.233808 -98.416905) (xy 337.204344 -98.371058) (xy 337.181705 -98.321484) (xy 337.166352 -98.269193)
			(xy 337.158596 -98.215249) (xy 335.792404 -98.215249) (xy 335.804079 -98.25481) (xy 335.811909 -98.308985)
			(xy 335.812384 -98.336354) (xy 335.811898 -98.363605) (xy 335.804142 -98.417553) (xy 335.788787 -98.469848)
			(xy 335.766145 -98.519425) (xy 335.736679 -98.565275) (xy 335.700988 -98.606466) (xy 335.659797 -98.642157)
			(xy 335.613947 -98.671623) (xy 335.56437 -98.694265) (xy 335.512075 -98.70962) (xy 335.458127 -98.717376)
			(xy 335.403625 -98.717376) (xy 335.349677 -98.70962) (xy 335.297382 -98.694265) (xy 335.247805 -98.671623)
			(xy 335.201955 -98.642157) (xy 335.160764 -98.606466) (xy 335.125073 -98.565275) (xy 335.095607 -98.519425)
			(xy 335.072965 -98.469848) (xy 335.05761 -98.417553) (xy 335.049854 -98.363605) (xy 335.049368 -98.336354)
			(xy 334.473172 -98.336354) (xy 334.476118 -98.342804) (xy 334.491474 -98.3951) (xy 334.49923 -98.449048)
			(xy 334.49923 -98.503552) (xy 334.491474 -98.5575) (xy 334.476118 -98.609796) (xy 334.453477 -98.659374)
			(xy 334.424011 -98.705225) (xy 334.388319 -98.746416) (xy 334.347128 -98.782108) (xy 334.301277 -98.811575)
			(xy 334.251699 -98.834217) (xy 334.199404 -98.849573) (xy 334.145456 -98.85733) (xy 334.118204 -98.857816)
			(xy 334.09189 -98.857341) (xy 334.039762 -98.850107) (xy 333.98912 -98.835789) (xy 333.940921 -98.814658)
			(xy 333.896077 -98.787113) (xy 333.855437 -98.753677) (xy 333.83728 -98.734626) (xy 333.829764 -98.727217)
			(xy 333.81048 -98.718696) (xy 333.799942 -98.718116) (xy 333.725266 -98.718116) (xy 333.714718 -98.718663)
			(xy 333.695422 -98.727185) (xy 333.687928 -98.734626) (xy 333.669757 -98.753666) (xy 333.62913 -98.787123)
			(xy 333.584293 -98.814684) (xy 333.536095 -98.835825) (xy 333.485451 -98.850146) (xy 333.433319 -98.857375)
			(xy 333.407004 -98.857816) (xy 333.379752 -98.857337) (xy 333.325801 -98.849581) (xy 333.273504 -98.834225)
			(xy 333.223924 -98.811583) (xy 333.178072 -98.782116) (xy 333.13688 -98.746423) (xy 333.101186 -98.705231)
			(xy 333.071718 -98.659379) (xy 333.049076 -98.6098) (xy 333.03372 -98.557503) (xy 333.025963 -98.503552)
			(xy 332.036031 -98.503552) (xy 332.039976 -98.508566) (xy 332.04023 -98.509074) (xy 332.051175 -98.521807)
			(xy 332.071016 -98.548899) (xy 332.079854 -98.563176) (xy 332.085188 -98.572066) (xy 332.102206 -98.584258)
			(xy 332.195424 -98.604578) (xy 332.215998 -98.60026) (xy 332.224634 -98.594418) (xy 332.248689 -98.578403)
			(xy 332.300623 -98.553064) (xy 332.355784 -98.535842) (xy 332.412911 -98.527132) (xy 332.441804 -98.5266)
			(xy 332.469056 -98.52707) (xy 332.523004 -98.534827) (xy 332.575299 -98.550183) (xy 332.624877 -98.572825)
			(xy 332.670728 -98.602292) (xy 332.711919 -98.637984) (xy 332.747611 -98.679175) (xy 332.777077 -98.725026)
			(xy 332.799718 -98.774604) (xy 332.815074 -98.8269) (xy 332.82283 -98.880848) (xy 332.82283 -98.935352)
			(xy 332.815074 -98.9893) (xy 332.799718 -99.041596) (xy 332.777077 -99.091174) (xy 332.747611 -99.137025)
			(xy 332.711919 -99.178216) (xy 332.670728 -99.213908) (xy 332.624877 -99.243375) (xy 332.575299 -99.266017)
			(xy 332.523004 -99.281373) (xy 332.469056 -99.28913) (xy 332.441804 -99.289616) (xy 332.413713 -99.289119)
			(xy 332.358135 -99.280892) (xy 332.304367 -99.264601) (xy 332.253569 -99.240599) (xy 332.206842 -99.209405)
			(xy 332.165197 -99.171693) (xy 332.129535 -99.12828) (xy 332.114652 -99.10445) (xy 332.109318 -99.09556)
			(xy 332.0923 -99.083368) (xy 331.999082 -99.063048) (xy 331.978508 -99.067366) (xy 331.969872 -99.073208)
			(xy 331.945818 -99.089223) (xy 331.893883 -99.114562) (xy 331.838722 -99.131784) (xy 331.781595 -99.140494)
			(xy 331.752702 -99.141026) (xy 331.725452 -99.14052) (xy 331.671506 -99.132765) (xy 331.619212 -99.117411)
			(xy 331.569636 -99.094771) (xy 331.523787 -99.065307) (xy 331.482597 -99.029617) (xy 331.446905 -98.988429)
			(xy 331.417439 -98.942581) (xy 331.394796 -98.893007) (xy 331.37944 -98.840714) (xy 331.371681 -98.786768)
			(xy 331.371194 -98.759518) (xy 317.145416 -98.759518) (xy 317.145416 -99.449382) (xy 320.106038 -99.449382)
			(xy 320.110109 -99.39376) (xy 320.122235 -99.339323) (xy 320.142158 -99.287232) (xy 320.169454 -99.238597)
			(xy 320.20354 -99.194454) (xy 320.243689 -99.155745) (xy 320.289047 -99.123294) (xy 320.338647 -99.097793)
			(xy 320.391431 -99.079786) (xy 320.446274 -99.069656) (xy 320.502008 -99.067619) (xy 320.557445 -99.073719)
			(xy 320.611402 -99.087825) (xy 320.662731 -99.109637) (xy 320.710337 -99.138691) (xy 320.753205 -99.174366)
			(xy 320.790422 -99.215903) (xy 320.821195 -99.262416) (xy 320.844867 -99.312913) (xy 320.860935 -99.36632)
			(xy 320.869055 -99.421496) (xy 320.869564 -99.449382) (xy 320.869397 -99.458526) (xy 325.838564 -99.458526)
			(xy 325.842635 -99.402904) (xy 325.854761 -99.348467) (xy 325.874684 -99.296376) (xy 325.90198 -99.247741)
			(xy 325.936066 -99.203598) (xy 325.976215 -99.164889) (xy 326.021573 -99.132438) (xy 326.071173 -99.106937)
			(xy 326.123957 -99.08893) (xy 326.1788 -99.0788) (xy 326.234534 -99.076763) (xy 326.289971 -99.082863)
			(xy 326.343928 -99.096969) (xy 326.395257 -99.118781) (xy 326.442863 -99.147835) (xy 326.485731 -99.18351)
			(xy 326.522948 -99.225047) (xy 326.553721 -99.27156) (xy 326.577393 -99.322057) (xy 326.593461 -99.375464)
			(xy 326.601581 -99.43064) (xy 326.60209 -99.458526) (xy 326.601581 -99.486412) (xy 326.593461 -99.541588)
			(xy 326.577393 -99.594995) (xy 326.553721 -99.645492) (xy 326.522948 -99.692005) (xy 326.485731 -99.733542)
			(xy 326.442863 -99.769217) (xy 326.395257 -99.798271) (xy 326.343928 -99.820083) (xy 326.289971 -99.834189)
			(xy 326.234534 -99.840289) (xy 326.1788 -99.838252) (xy 326.123957 -99.828122) (xy 326.071173 -99.810115)
			(xy 326.021573 -99.784614) (xy 325.976215 -99.752163) (xy 325.936066 -99.713454) (xy 325.90198 -99.669311)
			(xy 325.874684 -99.620676) (xy 325.854761 -99.568585) (xy 325.842635 -99.514148) (xy 325.838564 -99.458526)
			(xy 320.869397 -99.458526) (xy 320.869055 -99.477268) (xy 320.860935 -99.532444) (xy 320.844867 -99.585851)
			(xy 320.821195 -99.636348) (xy 320.790422 -99.682861) (xy 320.753205 -99.724398) (xy 320.710337 -99.760073)
			(xy 320.662731 -99.789127) (xy 320.611402 -99.810939) (xy 320.557445 -99.825045) (xy 320.502008 -99.831145)
			(xy 320.446274 -99.829108) (xy 320.391431 -99.818978) (xy 320.338647 -99.800971) (xy 320.289047 -99.77547)
			(xy 320.243689 -99.743019) (xy 320.20354 -99.70431) (xy 320.169454 -99.660167) (xy 320.142158 -99.611532)
			(xy 320.122235 -99.559441) (xy 320.110109 -99.505004) (xy 320.106038 -99.449382) (xy 317.145416 -99.449382)
			(xy 317.145416 -101.18985) (xy 329.19339 -101.18985) (xy 329.19339 -101.13535) (xy 329.201146 -101.081404)
			(xy 329.216501 -101.029111) (xy 329.239141 -100.979536) (xy 329.268606 -100.933687) (xy 329.304297 -100.892498)
			(xy 329.345485 -100.856808) (xy 329.391334 -100.827342) (xy 329.440909 -100.804702) (xy 329.493202 -100.789347)
			(xy 329.547148 -100.78159) (xy 329.574398 -100.781104) (xy 329.601768 -100.78157) (xy 329.655947 -100.789388)
			(xy 329.708451 -100.804877) (xy 329.758197 -100.827719) (xy 329.804164 -100.857443) (xy 329.825096 -100.875084)
			(xy 329.82535 -100.875338) (xy 329.832444 -100.880914) (xy 329.849355 -100.887166) (xy 329.85837 -100.88753)
			(xy 329.925426 -100.88753) (xy 329.934443 -100.887179) (xy 329.95136 -100.880927) (xy 329.958446 -100.875338)
			(xy 329.958446 -100.875084) (xy 329.9587 -100.875084) (xy 329.979619 -100.857429) (xy 330.025596 -100.82772)
			(xy 330.075347 -100.804887) (xy 330.12785 -100.7894) (xy 330.182028 -100.781576) (xy 330.209398 -100.781104)
			(xy 330.236652 -100.781543) (xy 330.290605 -100.7893) (xy 330.342905 -100.804656) (xy 330.392487 -100.827299)
			(xy 330.438341 -100.856768) (xy 330.479536 -100.892463) (xy 330.515231 -100.933657) (xy 330.5447 -100.979512)
			(xy 330.567343 -101.029094) (xy 330.5827 -101.081393) (xy 330.590457 -101.135346) (xy 330.590457 -101.189854)
			(xy 330.5827 -101.243807) (xy 330.567343 -101.296106) (xy 330.5447 -101.345688) (xy 330.515231 -101.391543)
			(xy 330.479536 -101.432737) (xy 330.438341 -101.468432) (xy 330.392487 -101.497901) (xy 330.342905 -101.520544)
			(xy 330.290605 -101.5359) (xy 330.236652 -101.543657) (xy 330.209398 -101.54412) (xy 330.182027 -101.543675)
			(xy 330.127846 -101.535855) (xy 330.075342 -101.520362) (xy 330.025595 -101.497515) (xy 329.97963 -101.467784)
			(xy 329.9587 -101.45014) (xy 329.958446 -101.449886) (xy 329.951352 -101.444311) (xy 329.934441 -101.438058)
			(xy 329.925426 -101.437694) (xy 329.85837 -101.437694) (xy 329.849352 -101.438038) (xy 329.832435 -101.444295)
			(xy 329.82535 -101.449886) (xy 329.82535 -101.45014) (xy 329.825096 -101.45014) (xy 329.804182 -101.467801)
			(xy 329.758203 -101.497508) (xy 329.708451 -101.520339) (xy 329.655947 -101.535826) (xy 329.601768 -101.543649)
			(xy 329.574398 -101.54412) (xy 329.547148 -101.54361) (xy 329.493202 -101.535853) (xy 329.440909 -101.520498)
			(xy 329.391334 -101.497858) (xy 329.345485 -101.468392) (xy 329.304297 -101.432702) (xy 329.268606 -101.391513)
			(xy 329.239141 -101.345664) (xy 329.216501 -101.296089) (xy 329.201146 -101.243796) (xy 329.19339 -101.18985)
			(xy 317.145416 -101.18985) (xy 317.145416 -101.579172) (xy 319.970656 -101.579172) (xy 319.974727 -101.52355)
			(xy 319.986853 -101.469113) (xy 320.006776 -101.417022) (xy 320.034072 -101.368387) (xy 320.068158 -101.324244)
			(xy 320.108307 -101.285535) (xy 320.153665 -101.253084) (xy 320.203265 -101.227583) (xy 320.256049 -101.209576)
			(xy 320.310892 -101.199446) (xy 320.366626 -101.197409) (xy 320.422063 -101.203509) (xy 320.47602 -101.217615)
			(xy 320.527349 -101.239427) (xy 320.574955 -101.268481) (xy 320.617823 -101.304156) (xy 320.65504 -101.345693)
			(xy 320.685813 -101.392206) (xy 320.709485 -101.442703) (xy 320.725553 -101.49611) (xy 320.733673 -101.551286)
			(xy 320.734182 -101.579172) (xy 320.733673 -101.607058) (xy 320.725553 -101.662234) (xy 320.709485 -101.715641)
			(xy 320.685813 -101.766138) (xy 320.65504 -101.812651) (xy 320.617823 -101.854188) (xy 320.597905 -101.870764)
			(xy 325.439022 -101.870764) (xy 325.443093 -101.815142) (xy 325.455219 -101.760705) (xy 325.475142 -101.708614)
			(xy 325.502438 -101.659979) (xy 325.536524 -101.615836) (xy 325.576673 -101.577127) (xy 325.622031 -101.544676)
			(xy 325.671631 -101.519175) (xy 325.724415 -101.501168) (xy 325.779258 -101.491038) (xy 325.834992 -101.489001)
			(xy 325.890429 -101.495101) (xy 325.944386 -101.509207) (xy 325.995715 -101.531019) (xy 326.043321 -101.560073)
			(xy 326.086189 -101.595748) (xy 326.123406 -101.637285) (xy 326.154179 -101.683798) (xy 326.177851 -101.734295)
			(xy 326.193919 -101.787702) (xy 326.202039 -101.842878) (xy 326.202548 -101.870764) (xy 326.202039 -101.89865)
			(xy 326.193919 -101.953826) (xy 326.177851 -102.007233) (xy 326.154179 -102.05773) (xy 326.123406 -102.104243)
			(xy 326.099924 -102.130451) (xy 328.743052 -102.130451) (xy 328.743052 -102.075949) (xy 328.750808 -102.022001)
			(xy 328.766162 -101.969707) (xy 328.788801 -101.920129) (xy 328.818265 -101.874277) (xy 328.853954 -101.833086)
			(xy 328.895142 -101.797392) (xy 328.94099 -101.767922) (xy 328.990565 -101.745277) (xy 329.042858 -101.729917)
			(xy 329.096805 -101.722155) (xy 329.124056 -101.721666) (xy 329.151426 -101.722142) (xy 329.205605 -101.729955)
			(xy 329.258109 -101.745441) (xy 329.307856 -101.768281) (xy 329.353823 -101.798005) (xy 329.374754 -101.815646)
			(xy 329.375008 -101.8159) (xy 329.382088 -101.821496) (xy 329.39901 -101.827737) (xy 329.408028 -101.828092)
			(xy 329.475084 -101.828092) (xy 329.4841 -101.827729) (xy 329.501017 -101.821486) (xy 329.508104 -101.8159)
			(xy 329.508104 -101.815646) (xy 329.508358 -101.815646) (xy 329.529301 -101.79802) (xy 329.57527 -101.768305)
			(xy 329.625015 -101.745466) (xy 329.677513 -101.729972) (xy 329.731687 -101.722141) (xy 329.759056 -101.721666)
			(xy 329.786309 -101.722178) (xy 329.840261 -101.72993) (xy 329.892561 -101.745281) (xy 329.942143 -101.767919)
			(xy 329.987998 -101.797384) (xy 330.029194 -101.833075) (xy 330.06489 -101.874266) (xy 330.09436 -101.920118)
			(xy 330.117004 -101.969698) (xy 330.132361 -102.021996) (xy 330.140119 -102.075947) (xy 330.140119 -102.130453)
			(xy 330.132361 -102.184404) (xy 330.117004 -102.236702) (xy 330.09436 -102.286282) (xy 330.06489 -102.332134)
			(xy 330.029194 -102.373325) (xy 329.987998 -102.409016) (xy 329.942143 -102.438481) (xy 329.892561 -102.461119)
			(xy 329.840261 -102.47647) (xy 329.786309 -102.484222) (xy 329.759056 -102.484682) (xy 329.731687 -102.484187)
			(xy 329.677509 -102.476377) (xy 329.625006 -102.460895) (xy 329.575258 -102.438059) (xy 329.52929 -102.408341)
			(xy 329.508358 -102.390702) (xy 329.508104 -102.390448) (xy 329.501025 -102.384851) (xy 329.484102 -102.378612)
			(xy 329.475084 -102.378256) (xy 329.408028 -102.378256) (xy 329.399011 -102.378614) (xy 329.382093 -102.38486)
			(xy 329.375008 -102.390448) (xy 329.375008 -102.390702) (xy 329.374754 -102.390702) (xy 329.353813 -102.40833)
			(xy 329.307842 -102.438043) (xy 329.258097 -102.460881) (xy 329.205599 -102.476375) (xy 329.151425 -102.484206)
			(xy 329.124056 -102.484682) (xy 329.096805 -102.484245) (xy 329.042858 -102.476483) (xy 328.990565 -102.461123)
			(xy 328.94099 -102.438478) (xy 328.895142 -102.409008) (xy 328.853954 -102.373314) (xy 328.818265 -102.332123)
			(xy 328.788801 -102.286271) (xy 328.766162 -102.236693) (xy 328.750808 -102.184399) (xy 328.743052 -102.130451)
			(xy 326.099924 -102.130451) (xy 326.086189 -102.14578) (xy 326.043321 -102.181455) (xy 325.995715 -102.210509)
			(xy 325.944386 -102.232321) (xy 325.890429 -102.246427) (xy 325.834992 -102.252527) (xy 325.779258 -102.25049)
			(xy 325.724415 -102.24036) (xy 325.671631 -102.222353) (xy 325.622031 -102.196852) (xy 325.576673 -102.164401)
			(xy 325.536524 -102.125692) (xy 325.502438 -102.081549) (xy 325.475142 -102.032914) (xy 325.455219 -101.980823)
			(xy 325.443093 -101.926386) (xy 325.439022 -101.870764) (xy 320.597905 -101.870764) (xy 320.574955 -101.889863)
			(xy 320.527349 -101.918917) (xy 320.47602 -101.940729) (xy 320.422063 -101.954835) (xy 320.366626 -101.960935)
			(xy 320.310892 -101.958898) (xy 320.256049 -101.948768) (xy 320.203265 -101.930761) (xy 320.153665 -101.90526)
			(xy 320.108307 -101.872809) (xy 320.068158 -101.8341) (xy 320.034072 -101.789957) (xy 320.006776 -101.741322)
			(xy 319.986853 -101.689231) (xy 319.974727 -101.634794) (xy 319.970656 -101.579172) (xy 317.145416 -101.579172)
			(xy 317.145416 -103.13924) (xy 321.707 -103.13924) (xy 321.711071 -103.083618) (xy 321.723197 -103.029181)
			(xy 321.74312 -102.97709) (xy 321.770416 -102.928455) (xy 321.804502 -102.884312) (xy 321.844651 -102.845603)
			(xy 321.890009 -102.813152) (xy 321.939609 -102.787651) (xy 321.992393 -102.769644) (xy 322.047236 -102.759514)
			(xy 322.10297 -102.757477) (xy 322.158407 -102.763577) (xy 322.212364 -102.777683) (xy 322.263693 -102.799495)
			(xy 322.311299 -102.828549) (xy 322.354167 -102.864224) (xy 322.391384 -102.905761) (xy 322.422157 -102.952274)
			(xy 322.445829 -103.002771) (xy 322.461897 -103.056178) (xy 322.470017 -103.111354) (xy 322.470526 -103.13924)
			(xy 322.470017 -103.167126) (xy 322.461897 -103.222302) (xy 322.445829 -103.275709) (xy 322.422157 -103.326206)
			(xy 322.391384 -103.372719) (xy 322.354167 -103.414256) (xy 322.311299 -103.449931) (xy 322.263693 -103.478985)
			(xy 322.212364 -103.500797) (xy 322.158407 -103.514903) (xy 322.10297 -103.521003) (xy 322.047236 -103.518966)
			(xy 321.992393 -103.508836) (xy 321.939609 -103.490829) (xy 321.890009 -103.465328) (xy 321.844651 -103.432877)
			(xy 321.804502 -103.394168) (xy 321.770416 -103.350025) (xy 321.74312 -103.30139) (xy 321.723197 -103.249299)
			(xy 321.711071 -103.194862) (xy 321.707 -103.13924) (xy 317.145416 -103.13924) (xy 317.145416 -104.674924)
			(xy 320.759326 -104.674924) (xy 320.763397 -104.619302) (xy 320.775523 -104.564865) (xy 320.795446 -104.512774)
			(xy 320.822742 -104.464139) (xy 320.856828 -104.419996) (xy 320.896977 -104.381287) (xy 320.942335 -104.348836)
			(xy 320.991935 -104.323335) (xy 321.044719 -104.305328) (xy 321.099562 -104.295198) (xy 321.155296 -104.293161)
			(xy 321.210733 -104.299261) (xy 321.26469 -104.313367) (xy 321.316019 -104.335179) (xy 321.363625 -104.364233)
			(xy 321.406493 -104.399908) (xy 321.44371 -104.441445) (xy 321.474483 -104.487958) (xy 321.498155 -104.538455)
			(xy 321.514223 -104.591862) (xy 321.522343 -104.647038) (xy 321.522852 -104.674924) (xy 321.522343 -104.70281)
			(xy 321.514223 -104.757986) (xy 321.498155 -104.811393) (xy 321.474483 -104.86189) (xy 321.44371 -104.908403)
			(xy 321.406493 -104.94994) (xy 321.363625 -104.985615) (xy 321.316019 -105.014669) (xy 321.26469 -105.036481)
			(xy 321.210733 -105.050587) (xy 321.155296 -105.056687) (xy 321.099562 -105.05465) (xy 321.044719 -105.04452)
			(xy 320.991935 -105.026513) (xy 320.942335 -105.001012) (xy 320.896977 -104.968561) (xy 320.856828 -104.929852)
			(xy 320.822742 -104.885709) (xy 320.795446 -104.837074) (xy 320.775523 -104.784983) (xy 320.763397 -104.730546)
			(xy 320.759326 -104.674924) (xy 317.145416 -104.674924) (xy 317.145416 -107.210352) (xy 317.942722 -107.210352)
			(xy 317.943237 -107.181613) (xy 317.951865 -107.124786) (xy 317.968918 -107.069896) (xy 317.994011 -107.018185)
			(xy 318.026576 -106.970822) (xy 318.045846 -106.949494) (xy 318.05245 -106.942636) (xy 318.059562 -106.924602)
			(xy 318.059562 -106.835702) (xy 318.05245 -106.817668) (xy 318.045846 -106.81081) (xy 318.026527 -106.789525)
			(xy 317.993961 -106.742156) (xy 317.968871 -106.690438) (xy 317.951823 -106.63554) (xy 317.943204 -106.578707)
			(xy 317.94321 -106.521223) (xy 317.951839 -106.464391) (xy 317.968896 -106.409497) (xy 317.993996 -106.357783)
			(xy 318.026571 -106.31042) (xy 318.045846 -106.289094) (xy 318.05245 -106.282236) (xy 318.059562 -106.264202)
			(xy 318.059562 -106.175302) (xy 318.05245 -106.157268) (xy 318.045846 -106.15041) (xy 318.026554 -106.129101)
			(xy 317.99399 -106.081735) (xy 317.968902 -106.030018) (xy 317.951856 -105.975123) (xy 317.943239 -105.918292)
			(xy 317.942722 -105.889552) (xy 317.943208 -105.862301) (xy 317.950964 -105.808353) (xy 317.966319 -105.756058)
			(xy 317.988961 -105.706481) (xy 318.018427 -105.660631) (xy 318.054118 -105.61944) (xy 318.095309 -105.583749)
			(xy 318.141159 -105.554283) (xy 318.190736 -105.531641) (xy 318.243031 -105.516286) (xy 318.296979 -105.50853)
			(xy 318.351481 -105.50853) (xy 318.405429 -105.516286) (xy 318.457724 -105.531641) (xy 318.507301 -105.554283)
			(xy 318.553151 -105.583749) (xy 318.594342 -105.61944) (xy 318.630033 -105.660631) (xy 318.659499 -105.706481)
			(xy 318.682141 -105.756058) (xy 318.697496 -105.808353) (xy 318.705252 -105.862301) (xy 318.705738 -105.889552)
			(xy 318.705236 -105.918292) (xy 318.696606 -105.975119) (xy 318.679551 -106.03001) (xy 318.654455 -106.081721)
			(xy 318.621886 -106.129083) (xy 318.602614 -106.15041) (xy 318.59601 -106.157268) (xy 318.588898 -106.175302)
			(xy 318.588898 -106.264202) (xy 318.59601 -106.282236) (xy 318.602614 -106.289094) (xy 318.621836 -106.310463)
			(xy 318.654399 -106.357819) (xy 318.679491 -106.409524) (xy 318.696543 -106.464408) (xy 318.705169 -106.521229)
			(xy 318.705174 -106.578701) (xy 318.696558 -106.635523) (xy 318.679517 -106.69041) (xy 318.654434 -106.74212)
			(xy 318.62188 -106.789482) (xy 318.602614 -106.81081) (xy 318.59601 -106.817668) (xy 318.588898 -106.835702)
			(xy 318.588898 -106.924602) (xy 318.59601 -106.942636) (xy 318.602614 -106.949494) (xy 318.621901 -106.970807)
			(xy 318.654467 -107.018172) (xy 318.67389 -107.058206) (xy 321.773804 -107.058206) (xy 321.77433 -107.029467)
			(xy 321.782952 -106.97264) (xy 321.800001 -106.917749) (xy 321.825093 -106.866037) (xy 321.857657 -106.818675)
			(xy 321.876928 -106.797348) (xy 321.883532 -106.79049) (xy 321.890644 -106.772456) (xy 321.890644 -106.683556)
			(xy 321.883532 -106.665522) (xy 321.876928 -106.658664) (xy 321.857663 -106.637332) (xy 321.825097 -106.589971)
			(xy 321.800005 -106.53826) (xy 321.782954 -106.48337) (xy 321.774331 -106.426543) (xy 321.77433 -106.369066)
			(xy 321.782952 -106.312239) (xy 321.800002 -106.257348) (xy 321.825093 -106.205637) (xy 321.857657 -106.158275)
			(xy 321.876928 -106.136948) (xy 321.883532 -106.13009) (xy 321.890644 -106.112056) (xy 321.890644 -106.023156)
			(xy 321.883532 -106.005122) (xy 321.876928 -105.998264) (xy 321.857659 -105.976936) (xy 321.825092 -105.929574)
			(xy 321.8 -105.877863) (xy 321.782949 -105.822972) (xy 321.774325 -105.766145) (xy 321.773804 -105.737406)
			(xy 321.77429 -105.710155) (xy 321.782046 -105.656207) (xy 321.797401 -105.603912) (xy 321.820043 -105.554335)
			(xy 321.849509 -105.508485) (xy 321.8852 -105.467294) (xy 321.926391 -105.431603) (xy 321.972241 -105.402137)
			(xy 322.021818 -105.379495) (xy 322.074113 -105.36414) (xy 322.128061 -105.356384) (xy 322.182563 -105.356384)
			(xy 322.236511 -105.36414) (xy 322.288806 -105.379495) (xy 322.338383 -105.402137) (xy 322.384233 -105.431603)
			(xy 322.425424 -105.467294) (xy 322.461115 -105.508485) (xy 322.490581 -105.554335) (xy 322.513223 -105.603912)
			(xy 322.528578 -105.656207) (xy 322.536334 -105.710155) (xy 322.53682 -105.737406) (xy 322.536295 -105.766145)
			(xy 322.527672 -105.822972) (xy 322.510622 -105.877862) (xy 322.485531 -105.929574) (xy 322.452966 -105.976937)
			(xy 322.433696 -105.998264) (xy 322.427092 -106.005122) (xy 322.41998 -106.023156) (xy 322.41998 -106.112056)
			(xy 322.427092 -106.13009) (xy 322.433696 -106.136948) (xy 322.452972 -106.15827) (xy 322.485535 -106.205634)
			(xy 322.510625 -106.257347) (xy 322.527674 -106.312238) (xy 322.536295 -106.369065) (xy 322.536295 -106.426543)
			(xy 322.527672 -106.483371) (xy 322.510622 -106.538262) (xy 322.485531 -106.589974) (xy 322.452966 -106.637337)
			(xy 322.433696 -106.658664) (xy 322.427092 -106.665522) (xy 322.41998 -106.683556) (xy 322.41998 -106.772456)
			(xy 322.427092 -106.79049) (xy 322.433696 -106.797348) (xy 322.452958 -106.818683) (xy 322.485528 -106.866041)
			(xy 322.510623 -106.917751) (xy 322.527676 -106.972641) (xy 322.536299 -107.029467) (xy 322.53682 -107.058206)
			(xy 322.536334 -107.085457) (xy 322.528578 -107.139405) (xy 322.513223 -107.1917) (xy 322.490581 -107.241277)
			(xy 322.461115 -107.287127) (xy 322.425424 -107.328318) (xy 322.384233 -107.364009) (xy 322.338383 -107.393475)
			(xy 322.288806 -107.416117) (xy 322.236511 -107.431472) (xy 322.182563 -107.439228) (xy 322.128061 -107.439228)
			(xy 322.074113 -107.431472) (xy 322.021818 -107.416117) (xy 321.972241 -107.393475) (xy 321.926391 -107.364009)
			(xy 321.8852 -107.328318) (xy 321.849509 -107.287127) (xy 321.820043 -107.241277) (xy 321.797401 -107.1917)
			(xy 321.782046 -107.139405) (xy 321.77429 -107.085457) (xy 321.773804 -107.058206) (xy 318.67389 -107.058206)
			(xy 318.679557 -107.069887) (xy 318.696604 -107.124781) (xy 318.705221 -107.181612) (xy 318.705738 -107.210352)
			(xy 318.705252 -107.237603) (xy 318.697496 -107.291551) (xy 318.682141 -107.343846) (xy 318.659499 -107.393423)
			(xy 318.630033 -107.439273) (xy 318.594342 -107.480464) (xy 318.553151 -107.516155) (xy 318.507301 -107.545621)
			(xy 318.457724 -107.568263) (xy 318.405429 -107.583618) (xy 318.351481 -107.591374) (xy 318.296979 -107.591374)
			(xy 318.243031 -107.583618) (xy 318.190736 -107.568263) (xy 318.141159 -107.545621) (xy 318.095309 -107.516155)
			(xy 318.054118 -107.480464) (xy 318.018427 -107.439273) (xy 317.988961 -107.393423) (xy 317.966319 -107.343846)
			(xy 317.950964 -107.291551) (xy 317.943208 -107.237603) (xy 317.942722 -107.210352) (xy 317.145416 -107.210352)
			(xy 317.145416 -108.379006) (xy 322.662804 -108.379006) (xy 322.66333 -108.350267) (xy 322.671952 -108.29344)
			(xy 322.689001 -108.238549) (xy 322.714093 -108.186837) (xy 322.746657 -108.139475) (xy 322.765928 -108.118148)
			(xy 322.772532 -108.11129) (xy 322.779644 -108.093256) (xy 322.779644 -108.004356) (xy 322.772532 -107.986322)
			(xy 322.765928 -107.979464) (xy 322.746663 -107.958132) (xy 322.714097 -107.910771) (xy 322.689005 -107.85906)
			(xy 322.671954 -107.80417) (xy 322.663331 -107.747343) (xy 322.66333 -107.689866) (xy 322.671952 -107.633039)
			(xy 322.689002 -107.578148) (xy 322.714093 -107.526437) (xy 322.746657 -107.479075) (xy 322.765928 -107.457748)
			(xy 322.772532 -107.45089) (xy 322.779644 -107.432856) (xy 322.779644 -107.343956) (xy 322.772532 -107.325922)
			(xy 322.765928 -107.319064) (xy 322.746663 -107.297732) (xy 322.714097 -107.250371) (xy 322.689005 -107.19866)
			(xy 322.671954 -107.14377) (xy 322.663331 -107.086943) (xy 322.66333 -107.029466) (xy 322.671952 -106.972639)
			(xy 322.689002 -106.917748) (xy 322.714093 -106.866037) (xy 322.746657 -106.818675) (xy 322.765928 -106.797348)
			(xy 322.772532 -106.79049) (xy 322.779644 -106.772456) (xy 322.779644 -106.683556) (xy 322.772532 -106.665522)
			(xy 322.765928 -106.658664) (xy 322.746663 -106.637332) (xy 322.714097 -106.589971) (xy 322.689005 -106.53826)
			(xy 322.671954 -106.48337) (xy 322.663331 -106.426543) (xy 322.66333 -106.369066) (xy 322.671952 -106.312239)
			(xy 322.689002 -106.257348) (xy 322.714093 -106.205637) (xy 322.746657 -106.158275) (xy 322.765928 -106.136948)
			(xy 322.772532 -106.13009) (xy 322.779644 -106.112056) (xy 322.779644 -106.023156) (xy 322.772532 -106.005122)
			(xy 322.765928 -105.998264) (xy 322.746663 -105.976932) (xy 322.714097 -105.929571) (xy 322.689005 -105.87786)
			(xy 322.671954 -105.82297) (xy 322.663331 -105.766143) (xy 322.66333 -105.708666) (xy 322.671952 -105.651839)
			(xy 322.689002 -105.596948) (xy 322.714093 -105.545237) (xy 322.746657 -105.497875) (xy 322.765928 -105.476548)
			(xy 322.772532 -105.46969) (xy 322.779644 -105.451656) (xy 322.779644 -105.362756) (xy 322.772532 -105.344722)
			(xy 322.765928 -105.337864) (xy 322.746663 -105.316532) (xy 322.714097 -105.269171) (xy 322.689005 -105.21746)
			(xy 322.671954 -105.16257) (xy 322.663331 -105.105743) (xy 322.66333 -105.048266) (xy 322.671952 -104.991439)
			(xy 322.689002 -104.936548) (xy 322.714093 -104.884837) (xy 322.746657 -104.837475) (xy 322.765928 -104.816148)
			(xy 322.772532 -104.80929) (xy 322.779644 -104.791256) (xy 322.779644 -104.702356) (xy 322.772532 -104.684322)
			(xy 322.765928 -104.677464) (xy 322.746663 -104.656132) (xy 322.714097 -104.608771) (xy 322.689005 -104.55706)
			(xy 322.671954 -104.50217) (xy 322.663331 -104.445343) (xy 322.66333 -104.387866) (xy 322.671952 -104.331039)
			(xy 322.689002 -104.276148) (xy 322.714093 -104.224437) (xy 322.746657 -104.177075) (xy 322.765928 -104.155748)
			(xy 322.772532 -104.14889) (xy 322.779644 -104.130856) (xy 322.779644 -104.041956) (xy 322.772532 -104.023922)
			(xy 322.765928 -104.017064) (xy 322.746663 -103.995732) (xy 322.714097 -103.948371) (xy 322.689005 -103.89666)
			(xy 322.671954 -103.84177) (xy 322.663331 -103.784943) (xy 322.66333 -103.727466) (xy 322.671952 -103.670639)
			(xy 322.689002 -103.615748) (xy 322.714093 -103.564037) (xy 322.746657 -103.516675) (xy 322.765928 -103.495348)
			(xy 322.772532 -103.48849) (xy 322.779644 -103.470456) (xy 322.779644 -103.381556) (xy 322.772532 -103.363522)
			(xy 322.765928 -103.356664) (xy 322.746659 -103.335336) (xy 322.714092 -103.287974) (xy 322.689 -103.236263)
			(xy 322.671949 -103.181372) (xy 322.663325 -103.124545) (xy 322.662804 -103.095806) (xy 322.663245 -103.068599)
			(xy 322.67097 -103.014735) (xy 322.686276 -102.962517) (xy 322.708854 -102.913007) (xy 322.738244 -102.867212)
			(xy 322.773848 -102.826063) (xy 322.814943 -102.790395) (xy 322.837556 -102.775258) (xy 322.845938 -102.769924)
			(xy 322.857114 -102.753668) (xy 322.875402 -102.674674) (xy 322.87721 -102.665045) (xy 322.874213 -102.645704)
			(xy 322.86956 -102.637082) (xy 322.869306 -102.637082) (xy 322.869306 -102.636574) (xy 322.856101 -102.614063)
			(xy 322.835245 -102.566221) (xy 322.821095 -102.515987) (xy 322.813911 -102.464294) (xy 322.813426 -102.4382)
			(xy 322.813912 -102.410949) (xy 322.821668 -102.357001) (xy 322.837023 -102.304706) (xy 322.859665 -102.255129)
			(xy 322.889131 -102.209279) (xy 322.924822 -102.168088) (xy 322.966013 -102.132397) (xy 323.011863 -102.102931)
			(xy 323.06144 -102.080289) (xy 323.113735 -102.064934) (xy 323.167683 -102.057178) (xy 323.222185 -102.057178)
			(xy 323.276133 -102.064934) (xy 323.328428 -102.080289) (xy 323.378005 -102.102931) (xy 323.423855 -102.132397)
			(xy 323.465046 -102.168088) (xy 323.500737 -102.209279) (xy 323.530203 -102.255129) (xy 323.552845 -102.304706)
			(xy 323.5682 -102.357001) (xy 323.575956 -102.410949) (xy 323.576442 -102.4382) (xy 323.575984 -102.465407)
			(xy 323.56826 -102.519269) (xy 323.552955 -102.571485) (xy 323.530379 -102.620994) (xy 323.500993 -102.666789)
			(xy 323.465392 -102.70794) (xy 323.424301 -102.743609) (xy 323.40169 -102.758748) (xy 323.393308 -102.764082)
			(xy 323.382132 -102.780338) (xy 323.363844 -102.859332) (xy 323.36204 -102.868962) (xy 323.365036 -102.888302)
			(xy 323.369686 -102.896924) (xy 323.36994 -102.896924) (xy 323.36994 -102.897432) (xy 323.383152 -102.919939)
			(xy 323.404005 -102.967783) (xy 323.418153 -103.018018) (xy 323.425335 -103.069712) (xy 323.42582 -103.095806)
			(xy 323.425295 -103.124545) (xy 323.416672 -103.181372) (xy 323.399622 -103.236262) (xy 323.374531 -103.287974)
			(xy 323.341966 -103.335337) (xy 323.322696 -103.356664) (xy 323.316092 -103.363522) (xy 323.30898 -103.381556)
			(xy 323.30898 -103.470456) (xy 323.316092 -103.48849) (xy 323.322696 -103.495348) (xy 323.341972 -103.51667)
			(xy 323.374535 -103.564034) (xy 323.399625 -103.615747) (xy 323.416674 -103.670638) (xy 323.425295 -103.727465)
			(xy 323.425295 -103.784943) (xy 323.416672 -103.841771) (xy 323.399622 -103.896662) (xy 323.374531 -103.948374)
			(xy 323.341966 -103.995737) (xy 323.322696 -104.017064) (xy 323.31707 -104.022906) (xy 328.065892 -104.022906)
			(xy 328.066366 -103.996592) (xy 328.0736 -103.944464) (xy 328.087918 -103.893822) (xy 328.109049 -103.845623)
			(xy 328.136594 -103.800779) (xy 328.170031 -103.760139) (xy 328.189082 -103.741982) (xy 328.196491 -103.734467)
			(xy 328.205012 -103.715182) (xy 328.205592 -103.704644) (xy 328.205592 -103.629968) (xy 328.205042 -103.619421)
			(xy 328.196522 -103.600125) (xy 328.189082 -103.59263) (xy 328.170045 -103.574456) (xy 328.136586 -103.53383)
			(xy 328.109025 -103.488994) (xy 328.087884 -103.440796) (xy 328.073563 -103.390152) (xy 328.066333 -103.338021)
			(xy 328.065892 -103.311706) (xy 328.066361 -103.284453) (xy 328.074117 -103.230503) (xy 328.089472 -103.178205)
			(xy 328.112114 -103.128625) (xy 328.141582 -103.082772) (xy 328.177275 -103.041579) (xy 328.218467 -103.005885)
			(xy 328.264319 -102.976417) (xy 328.313899 -102.953774) (xy 328.366197 -102.938418) (xy 328.420147 -102.930661)
			(xy 328.4474 -102.930198) (xy 328.475065 -102.930711) (xy 328.529814 -102.938711) (xy 328.582836 -102.954527)
			(xy 328.633019 -102.97783) (xy 328.679315 -103.008131) (xy 328.720753 -103.044796) (xy 328.756466 -103.087057)
			(xy 328.771504 -103.110284) (xy 328.77813 -103.11997) (xy 328.797999 -103.132408) (xy 328.809604 -103.13416)
			(xy 328.889614 -103.142034) (xy 328.901253 -103.142672) (xy 328.923091 -103.134588) (xy 328.931524 -103.12654)
			(xy 328.931778 -103.126286) (xy 328.949884 -103.107731) (xy 328.990211 -103.07515) (xy 329.03458 -103.048334)
			(xy 329.082173 -103.027777) (xy 329.132113 -103.013858) (xy 329.183478 -103.006834) (xy 329.2094 -103.006398)
			(xy 329.236653 -103.006855) (xy 329.290605 -103.014612) (xy 329.342903 -103.029969) (xy 329.392483 -103.052612)
			(xy 329.438337 -103.08208) (xy 329.47953 -103.117775) (xy 329.515223 -103.158968) (xy 329.544691 -103.204822)
			(xy 329.567333 -103.254403) (xy 329.582689 -103.306701) (xy 329.590445 -103.360653) (xy 329.590908 -103.387906)
			(xy 329.590443 -103.415276) (xy 329.582625 -103.469455) (xy 329.567135 -103.521958) (xy 329.544293 -103.571705)
			(xy 329.514569 -103.617672) (xy 329.496928 -103.638604) (xy 329.496674 -103.638858) (xy 329.491096 -103.64595)
			(xy 329.484845 -103.662863) (xy 329.484482 -103.671878) (xy 329.484482 -103.685654) (xy 340.692671 -103.685654)
			(xy 340.692671 -103.631146) (xy 340.700429 -103.577194) (xy 340.715787 -103.524895) (xy 340.738431 -103.475315)
			(xy 340.767901 -103.429462) (xy 340.803598 -103.38827) (xy 340.844794 -103.352577) (xy 340.89065 -103.323112)
			(xy 340.940233 -103.300473) (xy 340.992533 -103.285121) (xy 341.046486 -103.277369) (xy 341.07374 -103.276908)
			(xy 341.100055 -103.277346) (xy 341.152185 -103.284587) (xy 341.202828 -103.298911) (xy 341.251027 -103.320049)
			(xy 341.29587 -103.347601) (xy 341.336508 -103.381044) (xy 341.354664 -103.400098) (xy 341.362197 -103.407485)
			(xy 341.381469 -103.416018) (xy 341.392002 -103.416608) (xy 341.466678 -103.416608) (xy 341.477227 -103.416078)
			(xy 341.496523 -103.407543) (xy 341.504016 -103.400098) (xy 341.523836 -103.37931) (xy 341.568608 -103.343335)
			(xy 341.618266 -103.314475) (xy 341.671688 -103.293382) (xy 341.727667 -103.280533) (xy 341.78494 -103.276218)
			(xy 341.842213 -103.280533) (xy 341.898192 -103.293382) (xy 341.951614 -103.314475) (xy 342.001272 -103.343335)
			(xy 342.046044 -103.37931) (xy 342.065864 -103.400098) (xy 342.073397 -103.407485) (xy 342.092669 -103.416018)
			(xy 342.103202 -103.416608) (xy 342.177878 -103.416608) (xy 342.188427 -103.416078) (xy 342.207723 -103.407543)
			(xy 342.215216 -103.400098) (xy 342.23337 -103.381041) (xy 342.274 -103.347584) (xy 342.318841 -103.320026)
			(xy 342.367042 -103.298887) (xy 342.41769 -103.28457) (xy 342.469824 -103.277346) (xy 342.49614 -103.276908)
			(xy 342.523391 -103.277365) (xy 342.577336 -103.285126) (xy 342.629628 -103.300485) (xy 342.679203 -103.32313)
			(xy 342.72505 -103.352598) (xy 342.766237 -103.388291) (xy 342.801926 -103.429482) (xy 342.83139 -103.475333)
			(xy 342.854029 -103.524909) (xy 342.869383 -103.577203) (xy 342.877138 -103.631149) (xy 342.877138 -103.685651)
			(xy 342.869383 -103.739597) (xy 342.854029 -103.791891) (xy 342.83139 -103.841467) (xy 342.801926 -103.887318)
			(xy 342.766237 -103.928509) (xy 342.72505 -103.964202) (xy 342.679203 -103.99367) (xy 342.629628 -104.016315)
			(xy 342.577336 -104.031674) (xy 342.523391 -104.039435) (xy 342.49614 -104.039924) (xy 342.469825 -104.039489)
			(xy 342.417695 -104.032246) (xy 342.367052 -104.01792) (xy 342.318854 -103.996782) (xy 342.274011 -103.969231)
			(xy 342.233372 -103.935787) (xy 342.215216 -103.916734) (xy 342.207686 -103.909342) (xy 342.188413 -103.900811)
			(xy 342.177878 -103.900224) (xy 342.103202 -103.900224) (xy 342.09265 -103.900734) (xy 342.073354 -103.909282)
			(xy 342.065864 -103.916734) (xy 342.046044 -103.937522) (xy 342.001272 -103.973497) (xy 341.951614 -104.002357)
			(xy 341.898192 -104.02345) (xy 341.842213 -104.036299) (xy 341.78494 -104.040614) (xy 341.727667 -104.036299)
			(xy 341.671688 -104.02345) (xy 341.618266 -104.002357) (xy 341.568608 -103.973497) (xy 341.523836 -103.937522)
			(xy 341.504016 -103.916734) (xy 341.496486 -103.909342) (xy 341.477213 -103.900811) (xy 341.466678 -103.900224)
			(xy 341.392002 -103.900224) (xy 341.38145 -103.900734) (xy 341.362154 -103.909282) (xy 341.354664 -103.916734)
			(xy 341.336526 -103.935806) (xy 341.295891 -103.969261) (xy 341.251047 -103.996817) (xy 341.202843 -104.017952)
			(xy 341.152193 -104.032266) (xy 341.100057 -104.039487) (xy 341.07374 -104.039924) (xy 341.046486 -104.039431)
			(xy 340.992533 -104.031679) (xy 340.940233 -104.016327) (xy 340.89065 -103.993688) (xy 340.844794 -103.964223)
			(xy 340.803598 -103.92853) (xy 340.767901 -103.887338) (xy 340.738431 -103.841485) (xy 340.715787 -103.791905)
			(xy 340.700429 -103.739606) (xy 340.692671 -103.685654) (xy 329.484482 -103.685654) (xy 329.484482 -103.738934)
			(xy 329.484826 -103.747952) (xy 329.491083 -103.764869) (xy 329.496674 -103.771954) (xy 329.496928 -103.771954)
			(xy 329.496928 -103.772208) (xy 329.514589 -103.793123) (xy 329.544296 -103.839101) (xy 329.567128 -103.888853)
			(xy 329.582614 -103.941357) (xy 329.590437 -103.995536) (xy 329.590908 -104.022906) (xy 329.590428 -104.050157)
			(xy 329.58267 -104.104105) (xy 329.567315 -104.1564) (xy 329.544673 -104.205977) (xy 329.515206 -104.251828)
			(xy 329.479514 -104.293018) (xy 329.438323 -104.328709) (xy 329.392472 -104.358176) (xy 329.342895 -104.380817)
			(xy 329.290599 -104.396172) (xy 329.236651 -104.403928) (xy 329.2094 -104.404414) (xy 329.180481 -104.403928)
			(xy 329.123307 -104.395197) (xy 329.068106 -104.377935) (xy 329.016144 -104.352537) (xy 328.968611 -104.319586)
			(xy 328.926598 -104.279837) (xy 328.90841 -104.257348) (xy 328.900798 -104.248546) (xy 328.879901 -104.238362)
			(xy 328.868278 -104.23779) (xy 328.788522 -104.23779) (xy 328.776894 -104.23836) (xy 328.755985 -104.248527)
			(xy 328.74839 -104.257348) (xy 328.730217 -104.279846) (xy 328.688192 -104.319578) (xy 328.640653 -104.352514)
			(xy 328.588688 -104.3779) (xy 328.533488 -104.395153) (xy 328.476317 -104.40388) (xy 328.4474 -104.404414)
			(xy 328.420149 -104.403922) (xy 328.366202 -104.396166) (xy 328.313908 -104.380811) (xy 328.264331 -104.35817)
			(xy 328.218481 -104.328705) (xy 328.177291 -104.293014) (xy 328.141599 -104.251824) (xy 328.112133 -104.205975)
			(xy 328.089491 -104.156398) (xy 328.074135 -104.104104) (xy 328.066378 -104.050157) (xy 328.065892 -104.022906)
			(xy 323.31707 -104.022906) (xy 323.316092 -104.023922) (xy 323.30898 -104.041956) (xy 323.30898 -104.130856)
			(xy 323.316092 -104.14889) (xy 323.322696 -104.155748) (xy 323.341972 -104.17707) (xy 323.374535 -104.224434)
			(xy 323.399625 -104.276147) (xy 323.416674 -104.331038) (xy 323.425295 -104.387865) (xy 323.425295 -104.445343)
			(xy 323.416672 -104.502171) (xy 323.399622 -104.557062) (xy 323.374531 -104.608774) (xy 323.341966 -104.656137)
			(xy 323.322696 -104.677464) (xy 323.316092 -104.684322) (xy 323.30898 -104.702356) (xy 323.30898 -104.791256)
			(xy 323.316092 -104.80929) (xy 323.322696 -104.816148) (xy 323.341972 -104.83747) (xy 323.374535 -104.884834)
			(xy 323.399625 -104.936547) (xy 323.416674 -104.991438) (xy 323.425295 -105.048265) (xy 323.425295 -105.08445)
			(xy 327.943972 -105.08445) (xy 327.943972 -105.02995) (xy 327.951728 -104.976003) (xy 327.967082 -104.92371)
			(xy 327.989721 -104.874134) (xy 328.019185 -104.828284) (xy 328.054874 -104.787094) (xy 328.096062 -104.751402)
			(xy 328.141909 -104.721934) (xy 328.191484 -104.699291) (xy 328.243776 -104.683934) (xy 328.297722 -104.676174)
			(xy 328.324972 -104.675686) (xy 328.352341 -104.676172) (xy 328.40652 -104.683985) (xy 328.459022 -104.69947)
			(xy 328.50877 -104.722307) (xy 328.554737 -104.752027) (xy 328.57567 -104.769666) (xy 328.575924 -104.76992)
			(xy 328.582998 -104.775525) (xy 328.599924 -104.78176) (xy 328.608944 -104.782112) (xy 328.676 -104.782112)
			(xy 328.685017 -104.781752) (xy 328.701933 -104.775506) (xy 328.70902 -104.76992) (xy 328.70902 -104.769666)
			(xy 328.709274 -104.769666) (xy 328.730207 -104.752025) (xy 328.776175 -104.722301) (xy 328.825921 -104.699455)
			(xy 328.878423 -104.683959) (xy 328.932601 -104.67613) (xy 328.987343 -104.67613) (xy 329.041521 -104.683959)
			(xy 329.094023 -104.699455) (xy 329.143769 -104.722301) (xy 329.189737 -104.752025) (xy 329.21067 -104.769666)
			(xy 329.210924 -104.76992) (xy 329.217998 -104.775525) (xy 329.234924 -104.78176) (xy 329.243944 -104.782112)
			(xy 329.311 -104.782112) (xy 329.320017 -104.781752) (xy 329.336933 -104.775506) (xy 329.34402 -104.76992)
			(xy 329.34402 -104.769666) (xy 329.344274 -104.769666) (xy 329.365207 -104.752025) (xy 329.411175 -104.722301)
			(xy 329.460921 -104.699455) (xy 329.513423 -104.683959) (xy 329.567601 -104.67613) (xy 329.622343 -104.67613)
			(xy 329.676521 -104.683959) (xy 329.729023 -104.699455) (xy 329.778769 -104.722301) (xy 329.824737 -104.752025)
			(xy 329.84567 -104.769666) (xy 329.845924 -104.76992) (xy 329.852998 -104.775525) (xy 329.869924 -104.78176)
			(xy 329.878944 -104.782112) (xy 329.946 -104.782112) (xy 329.955017 -104.781752) (xy 329.971933 -104.775506)
			(xy 329.97902 -104.76992) (xy 329.97902 -104.769666) (xy 329.979274 -104.769666) (xy 330.000201 -104.75202)
			(xy 330.046176 -104.722311) (xy 330.095924 -104.699477) (xy 330.148426 -104.683987) (xy 330.202603 -104.67616)
			(xy 330.229972 -104.675686) (xy 330.257226 -104.676159) (xy 330.311179 -104.683913) (xy 330.363479 -104.699266)
			(xy 330.413062 -104.721907) (xy 330.458918 -104.751374) (xy 330.500113 -104.787067) (xy 330.535809 -104.82826)
			(xy 330.56528 -104.874113) (xy 330.587924 -104.923695) (xy 330.603281 -104.975994) (xy 330.611039 -105.029946)
			(xy 330.611039 -105.084454) (xy 330.603281 -105.138406) (xy 330.587924 -105.190705) (xy 330.56528 -105.240287)
			(xy 330.535809 -105.28614) (xy 330.500113 -105.327333) (xy 330.458918 -105.363026) (xy 330.413062 -105.392493)
			(xy 330.363479 -105.415134) (xy 330.311179 -105.430487) (xy 330.257226 -105.438241) (xy 330.229972 -105.438702)
			(xy 330.202601 -105.438252) (xy 330.148421 -105.43043) (xy 330.095918 -105.414937) (xy 330.046172 -105.392092)
			(xy 330.000205 -105.362365) (xy 329.979274 -105.344722) (xy 329.97902 -105.344468) (xy 329.971935 -105.33888)
			(xy 329.955017 -105.332635) (xy 329.946 -105.332276) (xy 329.878944 -105.332276) (xy 329.86993 -105.332659)
			(xy 329.853013 -105.338889) (xy 329.845924 -105.344468) (xy 329.84567 -105.344722) (xy 329.824737 -105.362363)
			(xy 329.778769 -105.392087) (xy 329.729023 -105.414933) (xy 329.676521 -105.430429) (xy 329.622343 -105.438258)
			(xy 329.567601 -105.438258) (xy 329.513423 -105.430429) (xy 329.460921 -105.414933) (xy 329.411175 -105.392087)
			(xy 329.365207 -105.362363) (xy 329.344274 -105.344722) (xy 329.34402 -105.344468) (xy 329.336935 -105.33888)
			(xy 329.320017 -105.332635) (xy 329.311 -105.332276) (xy 329.243944 -105.332276) (xy 329.23493 -105.332659)
			(xy 329.218013 -105.338889) (xy 329.210924 -105.344468) (xy 329.210924 -105.344722) (xy 329.21067 -105.344722)
			(xy 329.189737 -105.362363) (xy 329.143769 -105.392087) (xy 329.094023 -105.414933) (xy 329.041521 -105.430429)
			(xy 328.987343 -105.438258) (xy 328.932601 -105.438258) (xy 328.878423 -105.430429) (xy 328.825921 -105.414933)
			(xy 328.776175 -105.392087) (xy 328.730207 -105.362363) (xy 328.709274 -105.344722) (xy 328.70902 -105.344468)
			(xy 328.701935 -105.33888) (xy 328.685017 -105.332635) (xy 328.676 -105.332276) (xy 328.608944 -105.332276)
			(xy 328.59993 -105.332659) (xy 328.583013 -105.338889) (xy 328.575924 -105.344468) (xy 328.575924 -105.344722)
			(xy 328.57567 -105.344722) (xy 328.554725 -105.362345) (xy 328.508756 -105.392059) (xy 328.459011 -105.414897)
			(xy 328.406514 -105.430392) (xy 328.35234 -105.438225) (xy 328.324972 -105.438702) (xy 328.297722 -105.438226)
			(xy 328.243776 -105.430466) (xy 328.191484 -105.415109) (xy 328.141909 -105.392466) (xy 328.096062 -105.362998)
			(xy 328.054874 -105.327306) (xy 328.019185 -105.286116) (xy 327.989721 -105.240266) (xy 327.967082 -105.19069)
			(xy 327.951728 -105.138397) (xy 327.943972 -105.08445) (xy 323.425295 -105.08445) (xy 323.425295 -105.105743)
			(xy 323.416672 -105.162571) (xy 323.399622 -105.217462) (xy 323.374531 -105.269174) (xy 323.341966 -105.316537)
			(xy 323.322696 -105.337864) (xy 323.316092 -105.344722) (xy 323.30898 -105.362756) (xy 323.30898 -105.451656)
			(xy 323.316092 -105.46969) (xy 323.322696 -105.476548) (xy 323.341972 -105.49787) (xy 323.374535 -105.545234)
			(xy 323.399625 -105.596947) (xy 323.416674 -105.651838) (xy 323.425295 -105.708665) (xy 323.425295 -105.766143)
			(xy 323.416672 -105.822971) (xy 323.399622 -105.877862) (xy 323.374531 -105.929574) (xy 323.341966 -105.976937)
			(xy 323.322696 -105.998264) (xy 323.316092 -106.005122) (xy 323.30898 -106.023156) (xy 323.30898 -106.112056)
			(xy 323.316092 -106.13009) (xy 323.322696 -106.136948) (xy 323.341972 -106.15827) (xy 323.374535 -106.205634)
			(xy 323.399625 -106.257347) (xy 323.416674 -106.312238) (xy 323.425295 -106.369065) (xy 323.425295 -106.426543)
			(xy 323.416672 -106.483371) (xy 323.399622 -106.538262) (xy 323.374531 -106.589974) (xy 323.341966 -106.637337)
			(xy 323.322696 -106.658664) (xy 323.316092 -106.665522) (xy 323.30898 -106.683556) (xy 323.30898 -106.772456)
			(xy 323.316092 -106.79049) (xy 323.322696 -106.797348) (xy 323.327305 -106.802446) (xy 340.620928 -106.802446)
			(xy 340.620928 -106.747954) (xy 340.628682 -106.694017) (xy 340.644033 -106.641733) (xy 340.666668 -106.592165)
			(xy 340.696127 -106.546323) (xy 340.731809 -106.505139) (xy 340.772989 -106.469452) (xy 340.818828 -106.439989)
			(xy 340.868393 -106.417348) (xy 340.920676 -106.401991) (xy 340.974612 -106.394231) (xy 341.001858 -106.393742)
			(xy 341.028174 -106.394157) (xy 341.080305 -106.401401) (xy 341.130949 -106.415729) (xy 341.179149 -106.436871)
			(xy 341.223991 -106.464427) (xy 341.264627 -106.497876) (xy 341.282782 -106.516932) (xy 341.290317 -106.524318)
			(xy 341.309587 -106.532854) (xy 341.32012 -106.533442) (xy 341.394796 -106.533442) (xy 341.405345 -106.532912)
			(xy 341.42464 -106.524376) (xy 341.432134 -106.516932) (xy 341.451954 -106.496144) (xy 341.496726 -106.460169)
			(xy 341.546384 -106.431309) (xy 341.599806 -106.410216) (xy 341.655785 -106.397367) (xy 341.713058 -106.393052)
			(xy 341.770331 -106.397367) (xy 341.82631 -106.410216) (xy 341.879732 -106.431309) (xy 341.92939 -106.460169)
			(xy 341.974162 -106.496144) (xy 341.993982 -106.516932) (xy 342.001517 -106.524318) (xy 342.020787 -106.532854)
			(xy 342.03132 -106.533442) (xy 342.105996 -106.533442) (xy 342.116545 -106.532912) (xy 342.13584 -106.524376)
			(xy 342.143334 -106.516932) (xy 342.161486 -106.497873) (xy 342.202116 -106.464415) (xy 342.246957 -106.436856)
			(xy 342.295158 -106.415718) (xy 342.345807 -106.401402) (xy 342.397942 -106.394179) (xy 342.424258 -106.393742)
			(xy 342.451516 -106.394102) (xy 342.505479 -106.401855) (xy 342.557789 -106.41721) (xy 342.607381 -106.439853)
			(xy 342.653245 -106.469324) (xy 342.694448 -106.505022) (xy 342.730151 -106.546221) (xy 342.759627 -106.592082)
			(xy 342.782276 -106.641672) (xy 342.797636 -106.69398) (xy 342.805395 -106.747942) (xy 342.805395 -106.802458)
			(xy 342.797636 -106.85642) (xy 342.782276 -106.908728) (xy 342.759627 -106.958318) (xy 342.730151 -107.004179)
			(xy 342.694448 -107.045378) (xy 342.653245 -107.081076) (xy 342.607381 -107.110547) (xy 342.557789 -107.13319)
			(xy 342.505479 -107.148545) (xy 342.451516 -107.156298) (xy 342.424258 -107.156758) (xy 342.397942 -107.156332)
			(xy 342.345812 -107.149091) (xy 342.295168 -107.134764) (xy 342.246968 -107.113624) (xy 342.202126 -107.08607)
			(xy 342.161489 -107.052623) (xy 342.143334 -107.033568) (xy 342.135793 -107.026189) (xy 342.116528 -107.017649)
			(xy 342.105996 -107.017058) (xy 342.03132 -107.017058) (xy 342.020772 -107.017597) (xy 342.001477 -107.026127)
			(xy 341.993982 -107.033568) (xy 341.974162 -107.054356) (xy 341.92939 -107.090331) (xy 341.879732 -107.119191)
			(xy 341.82631 -107.140284) (xy 341.770331 -107.153133) (xy 341.713058 -107.157448) (xy 341.655785 -107.153133)
			(xy 341.599806 -107.140284) (xy 341.546384 -107.119191) (xy 341.496726 -107.090331) (xy 341.451954 -107.054356)
			(xy 341.432134 -107.033568) (xy 341.424593 -107.026189) (xy 341.405328 -107.017649) (xy 341.394796 -107.017058)
			(xy 341.32012 -107.017058) (xy 341.309572 -107.017597) (xy 341.290277 -107.026127) (xy 341.282782 -107.033568)
			(xy 341.264622 -107.052619) (xy 341.223994 -107.086078) (xy 341.179155 -107.113638) (xy 341.130955 -107.134778)
			(xy 341.080308 -107.149095) (xy 341.028174 -107.15632) (xy 341.001858 -107.156758) (xy 340.974612 -107.156169)
			(xy 340.920676 -107.148409) (xy 340.868393 -107.133052) (xy 340.818828 -107.110411) (xy 340.772989 -107.080948)
			(xy 340.731809 -107.045261) (xy 340.696127 -107.004077) (xy 340.666668 -106.958235) (xy 340.644033 -106.908667)
			(xy 340.628682 -106.856383) (xy 340.620928 -106.802446) (xy 323.327305 -106.802446) (xy 323.341972 -106.81867)
			(xy 323.374535 -106.866034) (xy 323.399625 -106.917747) (xy 323.416674 -106.972638) (xy 323.425295 -107.029465)
			(xy 323.425295 -107.086943) (xy 323.416672 -107.143771) (xy 323.399622 -107.198662) (xy 323.374531 -107.250374)
			(xy 323.341966 -107.297737) (xy 323.322696 -107.319064) (xy 323.316092 -107.325922) (xy 323.30898 -107.343956)
			(xy 323.30898 -107.432856) (xy 323.316092 -107.45089) (xy 323.322696 -107.457748) (xy 323.341972 -107.47907)
			(xy 323.374535 -107.526434) (xy 323.399625 -107.578147) (xy 323.416674 -107.633038) (xy 323.425295 -107.689865)
			(xy 323.425295 -107.740249) (xy 327.884296 -107.740249) (xy 327.884296 -107.685751) (xy 327.892052 -107.631807)
			(xy 327.907405 -107.579517) (xy 327.930044 -107.529943) (xy 327.959507 -107.484096) (xy 327.995195 -107.442908)
			(xy 328.036381 -107.407218) (xy 328.082227 -107.377753) (xy 328.1318 -107.355112) (xy 328.18409 -107.339756)
			(xy 328.238033 -107.331997) (xy 328.265282 -107.33151) (xy 328.292652 -107.331984) (xy 328.346831 -107.3398)
			(xy 328.399334 -107.355287) (xy 328.449081 -107.378127) (xy 328.495048 -107.40785) (xy 328.51598 -107.42549)
			(xy 328.516234 -107.425744) (xy 328.523331 -107.431314) (xy 328.54024 -107.43757) (xy 328.549254 -107.437936)
			(xy 328.61631 -107.437936) (xy 328.625326 -107.437576) (xy 328.642243 -107.43133) (xy 328.64933 -107.425744)
			(xy 328.64933 -107.42549) (xy 328.649584 -107.42549) (xy 328.670517 -107.407849) (xy 328.716485 -107.378125)
			(xy 328.766231 -107.355279) (xy 328.818733 -107.339783) (xy 328.872911 -107.331954) (xy 328.927653 -107.331954)
			(xy 328.981831 -107.339783) (xy 329.034333 -107.355279) (xy 329.084079 -107.378125) (xy 329.130047 -107.407849)
			(xy 329.15098 -107.42549) (xy 329.151234 -107.425744) (xy 329.158331 -107.431314) (xy 329.17524 -107.43757)
			(xy 329.184254 -107.437936) (xy 329.25131 -107.437936) (xy 329.260326 -107.437576) (xy 329.277243 -107.43133)
			(xy 329.28433 -107.425744) (xy 329.28433 -107.42549) (xy 329.284584 -107.42549) (xy 329.305517 -107.407849)
			(xy 329.351485 -107.378125) (xy 329.401231 -107.355279) (xy 329.453733 -107.339783) (xy 329.507911 -107.331954)
			(xy 329.562653 -107.331954) (xy 329.616831 -107.339783) (xy 329.669333 -107.355279) (xy 329.719079 -107.378125)
			(xy 329.765047 -107.407849) (xy 329.78598 -107.42549) (xy 329.786234 -107.425744) (xy 329.793331 -107.431314)
			(xy 329.81024 -107.43757) (xy 329.819254 -107.437936) (xy 329.88631 -107.437936) (xy 329.895326 -107.437576)
			(xy 329.912243 -107.43133) (xy 329.91933 -107.425744) (xy 329.91933 -107.42549) (xy 329.919584 -107.42549)
			(xy 329.94051 -107.407843) (xy 329.986485 -107.378133) (xy 330.036234 -107.355299) (xy 330.088736 -107.339809)
			(xy 330.142912 -107.331983) (xy 330.170282 -107.33151) (xy 330.197537 -107.331936) (xy 330.251492 -107.339691)
			(xy 330.303795 -107.355046) (xy 330.35338 -107.377689) (xy 330.399237 -107.407158) (xy 330.440434 -107.442853)
			(xy 330.476132 -107.484048) (xy 330.505603 -107.529904) (xy 330.528248 -107.579488) (xy 330.543605 -107.63179)
			(xy 330.551363 -107.685745) (xy 330.551363 -107.740255) (xy 330.543605 -107.79421) (xy 330.528248 -107.846512)
			(xy 330.505603 -107.896096) (xy 330.476132 -107.941952) (xy 330.440434 -107.983147) (xy 330.399237 -108.018842)
			(xy 330.35338 -108.048311) (xy 330.303795 -108.070954) (xy 330.251492 -108.086309) (xy 330.197537 -108.094064)
			(xy 330.170282 -108.094526) (xy 330.142911 -108.094089) (xy 330.088729 -108.086267) (xy 330.036225 -108.070772)
			(xy 329.986479 -108.047923) (xy 329.940514 -108.018191) (xy 329.919584 -108.000546) (xy 329.91933 -108.000292)
			(xy 329.91224 -107.994711) (xy 329.895326 -107.988461) (xy 329.88631 -107.9881) (xy 329.819254 -107.9881)
			(xy 329.81024 -107.988483) (xy 329.793323 -107.994713) (xy 329.786234 -108.000292) (xy 329.78598 -108.000546)
			(xy 329.765047 -108.018187) (xy 329.719079 -108.047911) (xy 329.669333 -108.070757) (xy 329.616831 -108.086253)
			(xy 329.562653 -108.094082) (xy 329.507911 -108.094082) (xy 329.453733 -108.086253) (xy 329.401231 -108.070757)
			(xy 329.351485 -108.047911) (xy 329.305517 -108.018187) (xy 329.284584 -108.000546) (xy 329.28433 -108.000292)
			(xy 329.27724 -107.994711) (xy 329.260326 -107.988461) (xy 329.25131 -107.9881) (xy 329.184254 -107.9881)
			(xy 329.17524 -107.988483) (xy 329.158323 -107.994713) (xy 329.151234 -108.000292) (xy 329.151234 -108.000546)
			(xy 329.15098 -108.000546) (xy 329.130047 -108.018187) (xy 329.084079 -108.047911) (xy 329.034333 -108.070757)
			(xy 328.981831 -108.086253) (xy 328.927653 -108.094082) (xy 328.872911 -108.094082) (xy 328.818733 -108.086253)
			(xy 328.766231 -108.070757) (xy 328.716485 -108.047911) (xy 328.670517 -108.018187) (xy 328.649584 -108.000546)
			(xy 328.64933 -108.000292) (xy 328.64224 -107.994711) (xy 328.625326 -107.988461) (xy 328.61631 -107.9881)
			(xy 328.549254 -107.9881) (xy 328.54024 -107.988483) (xy 328.523323 -107.994713) (xy 328.516234 -108.000292)
			(xy 328.516234 -108.000546) (xy 328.51598 -108.000546) (xy 328.495022 -108.018153) (xy 328.449057 -108.047871)
			(xy 328.399316 -108.070714) (xy 328.346821 -108.086213) (xy 328.29265 -108.094048) (xy 328.265282 -108.094526)
			(xy 328.238033 -108.094003) (xy 328.18409 -108.086244) (xy 328.1318 -108.070888) (xy 328.082227 -108.048247)
			(xy 328.036381 -108.018782) (xy 327.995195 -107.983092) (xy 327.959507 -107.941904) (xy 327.930044 -107.896057)
			(xy 327.907405 -107.846483) (xy 327.892052 -107.794193) (xy 327.884296 -107.740249) (xy 323.425295 -107.740249)
			(xy 323.425295 -107.747343) (xy 323.416672 -107.804171) (xy 323.399622 -107.859062) (xy 323.374531 -107.910774)
			(xy 323.341966 -107.958137) (xy 323.322696 -107.979464) (xy 323.316092 -107.986322) (xy 323.30898 -108.004356)
			(xy 323.30898 -108.093256) (xy 323.316092 -108.11129) (xy 323.322696 -108.118148) (xy 323.341958 -108.139483)
			(xy 323.374528 -108.186841) (xy 323.399623 -108.238551) (xy 323.416676 -108.293441) (xy 323.425299 -108.350267)
			(xy 323.42582 -108.379006) (xy 323.425334 -108.406257) (xy 323.417578 -108.460205) (xy 323.402223 -108.5125)
			(xy 323.379581 -108.562077) (xy 323.374807 -108.569506) (xy 339.061044 -108.569506) (xy 339.061503 -108.542135)
			(xy 339.069321 -108.487956) (xy 339.084811 -108.435452) (xy 339.107655 -108.385705) (xy 339.137381 -108.339739)
			(xy 339.155024 -108.318808) (xy 339.155278 -108.318554) (xy 339.160857 -108.311463) (xy 339.167106 -108.294549)
			(xy 339.16747 -108.285534) (xy 339.16747 -108.218478) (xy 339.16713 -108.209459) (xy 339.160871 -108.192542)
			(xy 339.155278 -108.185458) (xy 339.155024 -108.185458) (xy 339.155024 -108.185204) (xy 339.137377 -108.164278)
			(xy 339.107666 -108.118304) (xy 339.084831 -108.068555) (xy 339.069342 -108.016053) (xy 339.061516 -107.961876)
			(xy 339.061044 -107.934506) (xy 339.06153 -107.907255) (xy 339.069286 -107.853307) (xy 339.084641 -107.801012)
			(xy 339.107283 -107.751435) (xy 339.136749 -107.705585) (xy 339.17244 -107.664394) (xy 339.213631 -107.628703)
			(xy 339.259481 -107.599237) (xy 339.309058 -107.576595) (xy 339.361353 -107.56124) (xy 339.415301 -107.553484)
			(xy 339.469803 -107.553484) (xy 339.523751 -107.56124) (xy 339.576046 -107.576595) (xy 339.625623 -107.599237)
			(xy 339.671473 -107.628703) (xy 339.712664 -107.664394) (xy 339.748355 -107.705585) (xy 339.777821 -107.751435)
			(xy 339.800463 -107.801012) (xy 339.814452 -107.848654) (xy 345.240608 -107.848654) (xy 345.244679 -107.793032)
			(xy 345.256805 -107.738595) (xy 345.276728 -107.686504) (xy 345.304024 -107.637869) (xy 345.33811 -107.593726)
			(xy 345.378259 -107.555017) (xy 345.423617 -107.522566) (xy 345.473217 -107.497065) (xy 345.526001 -107.479058)
			(xy 345.580844 -107.468928) (xy 345.636578 -107.466891) (xy 345.692015 -107.472991) (xy 345.745972 -107.487097)
			(xy 345.797301 -107.508909) (xy 345.844907 -107.537963) (xy 345.887775 -107.573638) (xy 345.924992 -107.615175)
			(xy 345.955765 -107.661688) (xy 345.979437 -107.712185) (xy 345.995505 -107.765592) (xy 346.003625 -107.820768)
			(xy 346.004134 -107.848654) (xy 346.003625 -107.87654) (xy 345.995505 -107.931716) (xy 345.979437 -107.985123)
			(xy 345.955765 -108.03562) (xy 345.924992 -108.082133) (xy 345.887775 -108.12367) (xy 345.844907 -108.159345)
			(xy 345.797301 -108.188399) (xy 345.745972 -108.210211) (xy 345.692015 -108.224317) (xy 345.636578 -108.230417)
			(xy 345.580844 -108.22838) (xy 345.526001 -108.21825) (xy 345.473217 -108.200243) (xy 345.423617 -108.174742)
			(xy 345.378259 -108.142291) (xy 345.33811 -108.103582) (xy 345.304024 -108.059439) (xy 345.276728 -108.010804)
			(xy 345.256805 -107.958713) (xy 345.244679 -107.904276) (xy 345.240608 -107.848654) (xy 339.814452 -107.848654)
			(xy 339.815818 -107.853307) (xy 339.823574 -107.907255) (xy 339.82406 -107.934506) (xy 339.823607 -107.961877)
			(xy 339.815788 -108.016057) (xy 339.800296 -108.068561) (xy 339.777451 -108.118307) (xy 339.747723 -108.164273)
			(xy 339.73008 -108.185204) (xy 339.729826 -108.185458) (xy 339.724242 -108.192546) (xy 339.717996 -108.209462)
			(xy 339.717634 -108.218478) (xy 339.717634 -108.285534) (xy 339.717967 -108.294553) (xy 339.724231 -108.311471)
			(xy 339.729826 -108.318554) (xy 339.73008 -108.318554) (xy 339.73008 -108.318808) (xy 339.747733 -108.339729)
			(xy 339.777444 -108.385704) (xy 339.800277 -108.435455) (xy 339.815765 -108.487958) (xy 339.823589 -108.542136)
			(xy 339.82406 -108.569506) (xy 339.823574 -108.596757) (xy 339.815818 -108.650705) (xy 339.800463 -108.703)
			(xy 339.777821 -108.752577) (xy 339.748355 -108.798427) (xy 339.712664 -108.839618) (xy 339.671473 -108.875309)
			(xy 339.625623 -108.904775) (xy 339.576046 -108.927417) (xy 339.523751 -108.942772) (xy 339.469803 -108.950528)
			(xy 339.415301 -108.950528) (xy 339.361353 -108.942772) (xy 339.309058 -108.927417) (xy 339.259481 -108.904775)
			(xy 339.213631 -108.875309) (xy 339.17244 -108.839618) (xy 339.136749 -108.798427) (xy 339.107283 -108.752577)
			(xy 339.084641 -108.703) (xy 339.069286 -108.650705) (xy 339.06153 -108.596757) (xy 339.061044 -108.569506)
			(xy 323.374807 -108.569506) (xy 323.350115 -108.607927) (xy 323.314424 -108.649118) (xy 323.273233 -108.684809)
			(xy 323.227383 -108.714275) (xy 323.177806 -108.736917) (xy 323.125511 -108.752272) (xy 323.071563 -108.760028)
			(xy 323.017061 -108.760028) (xy 322.963113 -108.752272) (xy 322.910818 -108.736917) (xy 322.861241 -108.714275)
			(xy 322.815391 -108.684809) (xy 322.7742 -108.649118) (xy 322.738509 -108.607927) (xy 322.709043 -108.562077)
			(xy 322.686401 -108.5125) (xy 322.671046 -108.460205) (xy 322.66329 -108.406257) (xy 322.662804 -108.379006)
			(xy 317.145416 -108.379006) (xy 317.145416 -109.502448) (xy 341.614504 -109.502448) (xy 341.618575 -109.446826)
			(xy 341.630701 -109.392389) (xy 341.650624 -109.340298) (xy 341.67792 -109.291663) (xy 341.712006 -109.24752)
			(xy 341.752155 -109.208811) (xy 341.797513 -109.17636) (xy 341.847113 -109.150859) (xy 341.899897 -109.132852)
			(xy 341.95474 -109.122722) (xy 342.010474 -109.120685) (xy 342.065911 -109.126785) (xy 342.119868 -109.140891)
			(xy 342.171197 -109.162703) (xy 342.218803 -109.191757) (xy 342.261671 -109.227432) (xy 342.298888 -109.268969)
			(xy 342.329661 -109.315482) (xy 342.353333 -109.365979) (xy 342.369401 -109.419386) (xy 342.377521 -109.474562)
			(xy 342.37803 -109.502448) (xy 342.377521 -109.530334) (xy 342.369401 -109.58551) (xy 342.353333 -109.638917)
			(xy 342.329661 -109.689414) (xy 342.298888 -109.735927) (xy 342.261671 -109.777464) (xy 342.249688 -109.787436)
			(xy 348.959932 -109.787436) (xy 348.960418 -109.760185) (xy 348.968174 -109.706237) (xy 348.983529 -109.653942)
			(xy 349.006171 -109.604365) (xy 349.035637 -109.558515) (xy 349.071328 -109.517324) (xy 349.112519 -109.481633)
			(xy 349.158369 -109.452167) (xy 349.207946 -109.429525) (xy 349.260241 -109.41417) (xy 349.314189 -109.406414)
			(xy 349.368691 -109.406414) (xy 349.422639 -109.41417) (xy 349.474934 -109.429525) (xy 349.524511 -109.452167)
			(xy 349.570361 -109.481633) (xy 349.611552 -109.517324) (xy 349.647243 -109.558515) (xy 349.676709 -109.604365)
			(xy 349.699351 -109.653942) (xy 349.714706 -109.706237) (xy 349.722462 -109.760185) (xy 349.722948 -109.787436)
			(xy 349.722475 -109.815341) (xy 349.714327 -109.870555) (xy 349.698225 -109.923993) (xy 349.674513 -109.974516)
			(xy 349.643695 -110.021047) (xy 349.606429 -110.062594) (xy 349.58528 -110.080806) (xy 349.57639 -110.088172)
			(xy 349.566738 -110.109) (xy 349.568008 -110.211108) (xy 349.578168 -110.231682) (xy 349.587312 -110.238794)
			(xy 349.609606 -110.257002) (xy 349.64901 -110.298958) (xy 349.681665 -110.346357) (xy 349.706829 -110.398124)
			(xy 349.72393 -110.453084) (xy 349.732582 -110.509989) (xy 349.733108 -110.538768) (xy 349.732622 -110.566019)
			(xy 349.724866 -110.619967) (xy 349.709511 -110.672262) (xy 349.686869 -110.721839) (xy 349.657403 -110.767689)
			(xy 349.621712 -110.80888) (xy 349.580521 -110.844571) (xy 349.534671 -110.874037) (xy 349.485094 -110.896679)
			(xy 349.432799 -110.912034) (xy 349.378851 -110.91979) (xy 349.324349 -110.91979) (xy 349.270401 -110.912034)
			(xy 349.218106 -110.896679) (xy 349.168529 -110.874037) (xy 349.122679 -110.844571) (xy 349.081488 -110.80888)
			(xy 349.045797 -110.767689) (xy 349.016331 -110.721839) (xy 348.993689 -110.672262) (xy 348.978334 -110.619967)
			(xy 348.970578 -110.566019) (xy 348.970092 -110.538768) (xy 348.970553 -110.510862) (xy 348.978702 -110.455648)
			(xy 348.994805 -110.402209) (xy 349.018519 -110.351685) (xy 349.04934 -110.305154) (xy 349.086609 -110.263608)
			(xy 349.10776 -110.245398) (xy 349.11665 -110.238032) (xy 349.126302 -110.217204) (xy 349.125032 -110.115096)
			(xy 349.114872 -110.094522) (xy 349.105728 -110.08741) (xy 349.083444 -110.06919) (xy 349.044037 -110.027237)
			(xy 349.01138 -109.979841) (xy 348.986215 -109.928076) (xy 348.969111 -109.873119) (xy 348.960459 -109.816215)
			(xy 348.959932 -109.787436) (xy 342.249688 -109.787436) (xy 342.218803 -109.813139) (xy 342.171197 -109.842193)
			(xy 342.119868 -109.864005) (xy 342.065911 -109.878111) (xy 342.010474 -109.884211) (xy 341.95474 -109.882174)
			(xy 341.899897 -109.872044) (xy 341.847113 -109.854037) (xy 341.797513 -109.828536) (xy 341.752155 -109.796085)
			(xy 341.712006 -109.757376) (xy 341.67792 -109.713233) (xy 341.650624 -109.664598) (xy 341.630701 -109.612507)
			(xy 341.618575 -109.55807) (xy 341.614504 -109.502448) (xy 317.145416 -109.502448) (xy 317.145416 -110.621572)
			(xy 322.761102 -110.621572) (xy 322.76155 -110.595257) (xy 322.768789 -110.543128) (xy 322.783112 -110.492485)
			(xy 322.804248 -110.444286) (xy 322.831797 -110.399443) (xy 322.865239 -110.358804) (xy 322.884292 -110.340648)
			(xy 322.891717 -110.333147) (xy 322.900228 -110.313851) (xy 322.900802 -110.30331) (xy 322.900802 -110.228634)
			(xy 322.900267 -110.218085) (xy 322.891736 -110.19879) (xy 322.884292 -110.191296) (xy 322.86524 -110.173137)
			(xy 322.831783 -110.132508) (xy 322.804224 -110.087668) (xy 322.783085 -110.039468) (xy 322.768767 -109.988821)
			(xy 322.761541 -109.936688) (xy 322.761102 -109.910372) (xy 322.761588 -109.883121) (xy 322.769344 -109.829173)
			(xy 322.784699 -109.776878) (xy 322.807341 -109.727301) (xy 322.836807 -109.681451) (xy 322.872498 -109.64026)
			(xy 322.913689 -109.604569) (xy 322.959539 -109.575103) (xy 323.009116 -109.552461) (xy 323.061411 -109.537106)
			(xy 323.115359 -109.52935) (xy 323.169861 -109.52935) (xy 323.223809 -109.537106) (xy 323.276104 -109.552461)
			(xy 323.325681 -109.575103) (xy 323.371531 -109.604569) (xy 323.412722 -109.64026) (xy 323.448413 -109.681451)
			(xy 323.477879 -109.727301) (xy 323.500521 -109.776878) (xy 323.515876 -109.829173) (xy 323.523632 -109.883121)
			(xy 323.524118 -109.910372) (xy 323.523693 -109.936687) (xy 323.516449 -109.988817) (xy 323.502121 -110.039461)
			(xy 323.48098 -110.087659) (xy 323.453427 -110.132502) (xy 323.419982 -110.17314) (xy 323.400928 -110.191296)
			(xy 323.39353 -110.198821) (xy 323.385003 -110.218098) (xy 323.384418 -110.228634) (xy 323.384418 -110.30331)
			(xy 323.384923 -110.313863) (xy 323.393475 -110.333158) (xy 323.400928 -110.340648) (xy 323.420005 -110.358782)
			(xy 323.453459 -110.399417) (xy 323.481015 -110.444262) (xy 323.502149 -110.492467) (xy 323.516462 -110.543118)
			(xy 323.523682 -110.595255) (xy 323.524118 -110.621572) (xy 323.523632 -110.648823) (xy 323.515876 -110.702771)
			(xy 323.500521 -110.755066) (xy 323.477879 -110.804643) (xy 323.448413 -110.850493) (xy 323.412722 -110.891684)
			(xy 323.371531 -110.927375) (xy 323.325681 -110.956841) (xy 323.276104 -110.979483) (xy 323.223809 -110.994838)
			(xy 323.169861 -111.002594) (xy 323.115359 -111.002594) (xy 323.061411 -110.994838) (xy 323.009116 -110.979483)
			(xy 322.959539 -110.956841) (xy 322.913689 -110.927375) (xy 322.872498 -110.891684) (xy 322.836807 -110.850493)
			(xy 322.807341 -110.804643) (xy 322.784699 -110.755066) (xy 322.769344 -110.702771) (xy 322.761588 -110.648823)
			(xy 322.761102 -110.621572) (xy 317.145416 -110.621572) (xy 317.145416 -112.297972) (xy 325.26986 -112.297972)
			(xy 325.27029 -112.271657) (xy 325.277529 -112.219526) (xy 325.291855 -112.168881) (xy 325.312994 -112.120682)
			(xy 325.340548 -112.07584) (xy 325.373994 -112.035203) (xy 325.39305 -112.017048) (xy 325.400469 -112.009541)
			(xy 325.408985 -111.99025) (xy 325.40956 -111.97971) (xy 325.40956 -111.905034) (xy 325.409038 -111.894483)
			(xy 325.400499 -111.875187) (xy 325.39305 -111.867696) (xy 325.37399 -111.849545) (xy 325.340535 -111.808913)
			(xy 325.312978 -111.764072) (xy 325.291841 -111.71587) (xy 325.277524 -111.665222) (xy 325.270299 -111.613088)
			(xy 325.26986 -111.586772) (xy 325.270346 -111.559521) (xy 325.278102 -111.505573) (xy 325.293457 -111.453278)
			(xy 325.316099 -111.403701) (xy 325.345565 -111.357851) (xy 325.381256 -111.31666) (xy 325.422447 -111.280969)
			(xy 325.468297 -111.251503) (xy 325.517874 -111.228861) (xy 325.570169 -111.213506) (xy 325.624117 -111.20575)
			(xy 325.678619 -111.20575) (xy 325.732567 -111.213506) (xy 325.784862 -111.228861) (xy 325.834439 -111.251503)
			(xy 325.880289 -111.280969) (xy 325.92148 -111.31666) (xy 325.957171 -111.357851) (xy 325.986637 -111.403701)
			(xy 326.009279 -111.453278) (xy 326.024634 -111.505573) (xy 326.03239 -111.559521) (xy 326.032876 -111.586772)
			(xy 326.032464 -111.613088) (xy 326.025219 -111.665219) (xy 326.01089 -111.715863) (xy 325.989747 -111.764062)
			(xy 325.962191 -111.808904) (xy 325.928742 -111.849541) (xy 325.909686 -111.867696) (xy 325.902282 -111.875215)
			(xy 325.893759 -111.894497) (xy 325.893176 -111.905034) (xy 325.893176 -111.97971) (xy 325.893693 -111.990261)
			(xy 325.902238 -112.009556) (xy 325.909686 -112.017048) (xy 325.928755 -112.03519) (xy 325.962212 -112.075822)
			(xy 325.989769 -112.120665) (xy 326.010905 -112.168869) (xy 326.025219 -112.219519) (xy 326.03244 -112.271655)
			(xy 326.032876 -112.297972) (xy 327.30186 -112.297972) (xy 327.30229 -112.271657) (xy 327.309529 -112.219526)
			(xy 327.323855 -112.168881) (xy 327.344994 -112.120682) (xy 327.372548 -112.07584) (xy 327.405994 -112.035203)
			(xy 327.42505 -112.017048) (xy 327.432469 -112.009541) (xy 327.440985 -111.99025) (xy 327.44156 -111.97971)
			(xy 327.44156 -111.905034) (xy 327.441038 -111.894483) (xy 327.432499 -111.875187) (xy 327.42505 -111.867696)
			(xy 327.40599 -111.849545) (xy 327.372535 -111.808913) (xy 327.344978 -111.764072) (xy 327.323841 -111.71587)
			(xy 327.309524 -111.665222) (xy 327.302299 -111.613088) (xy 327.30186 -111.586772) (xy 327.302346 -111.559521)
			(xy 327.310102 -111.505573) (xy 327.325457 -111.453278) (xy 327.348099 -111.403701) (xy 327.377565 -111.357851)
			(xy 327.413256 -111.31666) (xy 327.454447 -111.280969) (xy 327.500297 -111.251503) (xy 327.549874 -111.228861)
			(xy 327.602169 -111.213506) (xy 327.656117 -111.20575) (xy 327.710619 -111.20575) (xy 327.764567 -111.213506)
			(xy 327.816862 -111.228861) (xy 327.866439 -111.251503) (xy 327.912289 -111.280969) (xy 327.95348 -111.31666)
			(xy 327.989171 -111.357851) (xy 328.018637 -111.403701) (xy 328.041279 -111.453278) (xy 328.056634 -111.505573)
			(xy 328.06439 -111.559521) (xy 328.064876 -111.586772) (xy 328.064464 -111.613088) (xy 328.057219 -111.665219)
			(xy 328.04289 -111.715863) (xy 328.021747 -111.764062) (xy 327.994191 -111.808904) (xy 327.960742 -111.849541)
			(xy 327.941686 -111.867696) (xy 327.934282 -111.875215) (xy 327.925759 -111.894497) (xy 327.925176 -111.905034)
			(xy 327.925176 -111.97971) (xy 327.925693 -111.990261) (xy 327.934238 -112.009556) (xy 327.941686 -112.017048)
			(xy 327.960755 -112.03519) (xy 327.962752 -112.037615) (xy 329.756103 -112.037615) (xy 329.760416 -111.980345)
			(xy 329.773262 -111.924368) (xy 329.79435 -111.870948) (xy 329.823205 -111.821291) (xy 329.859175 -111.776519)
			(xy 329.87996 -111.756698) (xy 329.887358 -111.749174) (xy 329.895886 -111.729896) (xy 329.89647 -111.71936)
			(xy 329.89647 -111.644684) (xy 329.895972 -111.63413) (xy 329.887416 -111.614835) (xy 329.87996 -111.607346)
			(xy 329.860878 -111.589218) (xy 329.827424 -111.548581) (xy 329.79987 -111.503735) (xy 329.778736 -111.455529)
			(xy 329.764425 -111.404877) (xy 329.757206 -111.35274) (xy 329.75677 -111.326422) (xy 329.757256 -111.299171)
			(xy 329.765012 -111.245223) (xy 329.780367 -111.192928) (xy 329.803009 -111.143351) (xy 329.832475 -111.097501)
			(xy 329.868166 -111.05631) (xy 329.909357 -111.020619) (xy 329.955207 -110.991153) (xy 330.004784 -110.968511)
			(xy 330.057079 -110.953156) (xy 330.111027 -110.9454) (xy 330.165529 -110.9454) (xy 330.219477 -110.953156)
			(xy 330.271772 -110.968511) (xy 330.321349 -110.991153) (xy 330.367199 -111.020619) (xy 330.40839 -111.05631)
			(xy 330.444081 -111.097501) (xy 330.473547 -111.143351) (xy 330.496189 -111.192928) (xy 330.511544 -111.245223)
			(xy 330.5193 -111.299171) (xy 330.519786 -111.326422) (xy 330.519338 -111.352737) (xy 330.5121 -111.404866)
			(xy 330.497777 -111.455509) (xy 330.476641 -111.503708) (xy 330.449091 -111.548551) (xy 330.415649 -111.58919)
			(xy 330.396596 -111.607346) (xy 330.389172 -111.614848) (xy 330.380661 -111.634143) (xy 330.380086 -111.644684)
			(xy 330.380086 -111.71936) (xy 330.380627 -111.729908) (xy 330.389154 -111.749203) (xy 330.396596 -111.756698)
			(xy 330.417407 -111.776495) (xy 330.453384 -111.82127) (xy 330.482245 -111.870931) (xy 330.503337 -111.924356)
			(xy 330.516186 -111.980339) (xy 330.520499 -112.037615) (xy 332.294318 -112.037615) (xy 332.298631 -111.980344)
			(xy 332.311478 -111.924367) (xy 332.332567 -111.870947) (xy 332.361424 -111.82129) (xy 332.397396 -111.776518)
			(xy 332.418182 -111.756698) (xy 332.425584 -111.749177) (xy 332.434109 -111.729897) (xy 332.434692 -111.71936)
			(xy 332.434692 -111.644684) (xy 332.434188 -111.634131) (xy 332.425635 -111.614836) (xy 332.418182 -111.607346)
			(xy 332.399104 -111.589213) (xy 332.365649 -111.548578) (xy 332.338094 -111.503733) (xy 332.316959 -111.455528)
			(xy 332.302647 -111.404877) (xy 332.295428 -111.352739) (xy 332.294992 -111.326422) (xy 332.295478 -111.299171)
			(xy 332.303234 -111.245223) (xy 332.318589 -111.192928) (xy 332.341231 -111.143351) (xy 332.370697 -111.097501)
			(xy 332.406388 -111.05631) (xy 332.447579 -111.020619) (xy 332.493429 -110.991153) (xy 332.543006 -110.968511)
			(xy 332.595301 -110.953156) (xy 332.649249 -110.9454) (xy 332.703751 -110.9454) (xy 332.757699 -110.953156)
			(xy 332.809994 -110.968511) (xy 332.859571 -110.991153) (xy 332.905421 -111.020619) (xy 332.946612 -111.05631)
			(xy 332.982303 -111.097501) (xy 333.011769 -111.143351) (xy 333.034411 -111.192928) (xy 333.049766 -111.245223)
			(xy 333.057522 -111.299171) (xy 333.058008 -111.326422) (xy 333.057553 -111.352736) (xy 333.050315 -111.404865)
			(xy 333.035993 -111.455508) (xy 333.014859 -111.503707) (xy 332.987311 -111.54855) (xy 332.95387 -111.58919)
			(xy 332.934818 -111.607346) (xy 332.927397 -111.614851) (xy 332.918883 -111.634144) (xy 332.918308 -111.644684)
			(xy 332.918308 -111.71936) (xy 332.918843 -111.729909) (xy 332.927374 -111.749205) (xy 332.934818 -111.756698)
			(xy 332.955628 -111.776496) (xy 332.991603 -111.821272) (xy 333.020462 -111.870933) (xy 333.041553 -111.924357)
			(xy 333.054401 -111.98034) (xy 333.055424 -111.993923) (xy 336.497253 -111.993923) (xy 336.501565 -111.936653)
			(xy 336.514411 -111.880675) (xy 336.535502 -111.827255) (xy 336.564359 -111.777599) (xy 336.600333 -111.732829)
			(xy 336.62112 -111.71301) (xy 336.628522 -111.705489) (xy 336.637046 -111.686208) (xy 336.63763 -111.675672)
			(xy 336.63763 -111.600996) (xy 336.637108 -111.590446) (xy 336.628567 -111.571151) (xy 336.62112 -111.563658)
			(xy 336.600364 -111.543805) (xy 336.564385 -111.499039) (xy 336.535522 -111.449386) (xy 336.514425 -111.395969)
			(xy 336.501572 -111.339993) (xy 336.497253 -111.282723) (xy 336.501565 -111.225453) (xy 336.514411 -111.169475)
			(xy 336.535502 -111.116055) (xy 336.564359 -111.066399) (xy 336.600333 -111.021629) (xy 336.62112 -111.00181)
			(xy 336.628522 -110.994289) (xy 336.637046 -110.975008) (xy 336.63763 -110.964472) (xy 336.63763 -110.889796)
			(xy 336.637108 -110.879246) (xy 336.628567 -110.859951) (xy 336.62112 -110.852458) (xy 336.602055 -110.834312)
			(xy 336.568598 -110.793681) (xy 336.54104 -110.748839) (xy 336.519903 -110.700636) (xy 336.505588 -110.649986)
			(xy 336.498366 -110.597851) (xy 336.49793 -110.571534) (xy 336.498387 -110.54428) (xy 336.50614 -110.490327)
			(xy 336.521494 -110.438027) (xy 336.544135 -110.388444) (xy 336.573603 -110.342589) (xy 336.609298 -110.301395)
			(xy 336.650492 -110.265701) (xy 336.696348 -110.236233) (xy 336.745931 -110.213593) (xy 336.798231 -110.19824)
			(xy 336.852184 -110.190487) (xy 336.879438 -110.190026) (xy 336.905753 -110.19046) (xy 336.957884 -110.1977)
			(xy 337.008527 -110.212025) (xy 337.056726 -110.233164) (xy 337.101569 -110.260717) (xy 337.142207 -110.294161)
			(xy 337.160362 -110.313216) (xy 337.167894 -110.320605) (xy 337.187166 -110.329136) (xy 337.1977 -110.329726)
			(xy 337.272376 -110.329726) (xy 337.282925 -110.32919) (xy 337.30222 -110.320659) (xy 337.309714 -110.313216)
			(xy 337.327873 -110.294164) (xy 337.368502 -110.260706) (xy 337.413341 -110.233146) (xy 337.461541 -110.212007)
			(xy 337.512188 -110.197689) (xy 337.564322 -110.190464) (xy 337.590638 -110.190026) (xy 337.617892 -110.190443)
			(xy 337.671844 -110.198205) (xy 337.724142 -110.213567) (xy 337.773721 -110.236215) (xy 337.813342 -110.261683)
			(xy 339.114448 -110.261683) (xy 339.114448 -110.209717) (xy 339.122577 -110.158392) (xy 339.138635 -110.108969)
			(xy 339.162226 -110.062667) (xy 339.192769 -110.020626) (xy 339.229514 -109.98388) (xy 339.271554 -109.953334)
			(xy 339.317854 -109.929741) (xy 339.367276 -109.913681) (xy 339.418601 -109.905549) (xy 339.444584 -109.905038)
			(xy 339.47123 -109.905495) (xy 339.523833 -109.914032) (xy 339.574384 -109.930903) (xy 339.62157 -109.955671)
			(xy 339.664168 -109.987694) (xy 339.701072 -110.026139) (xy 339.716618 -110.047786) (xy 339.724982 -110.059072)
			(xy 339.746655 -110.076927) (xy 339.772369 -110.08821) (xy 339.800184 -110.092068) (xy 339.827999 -110.08821)
			(xy 339.853713 -110.076927) (xy 339.875386 -110.059072) (xy 339.88375 -110.047786) (xy 339.899313 -110.026158)
			(xy 339.936232 -109.987742) (xy 339.978833 -109.955743) (xy 340.026014 -109.930989) (xy 340.076553 -109.91412)
			(xy 340.129144 -109.905574) (xy 340.155784 -109.905038) (xy 340.181778 -109.905428) (xy 340.233125 -109.913558)
			(xy 340.282569 -109.929622) (xy 340.328891 -109.953222) (xy 340.37095 -109.983778) (xy 340.407712 -110.020538)
			(xy 340.43827 -110.062596) (xy 340.461872 -110.108916) (xy 340.477938 -110.158359) (xy 340.486071 -110.209706)
			(xy 340.486071 -110.261694) (xy 340.477938 -110.313041) (xy 340.461872 -110.362484) (xy 340.43827 -110.408804)
			(xy 340.407712 -110.450862) (xy 340.37095 -110.487622) (xy 340.332365 -110.515654) (xy 343.028014 -110.515654)
			(xy 343.032085 -110.460032) (xy 343.044211 -110.405595) (xy 343.064134 -110.353504) (xy 343.09143 -110.304869)
			(xy 343.125516 -110.260726) (xy 343.165665 -110.222017) (xy 343.211023 -110.189566) (xy 343.260623 -110.164065)
			(xy 343.313407 -110.146058) (xy 343.36825 -110.135928) (xy 343.423984 -110.133891) (xy 343.479421 -110.139991)
			(xy 343.533378 -110.154097) (xy 343.584707 -110.175909) (xy 343.632313 -110.204963) (xy 343.675181 -110.240638)
			(xy 343.712398 -110.282175) (xy 343.743171 -110.328688) (xy 343.766843 -110.379185) (xy 343.782911 -110.432592)
			(xy 343.791031 -110.487768) (xy 343.79154 -110.515654) (xy 343.791031 -110.54354) (xy 343.782911 -110.598716)
			(xy 343.766843 -110.652123) (xy 343.743171 -110.70262) (xy 343.712398 -110.749133) (xy 343.675181 -110.79067)
			(xy 343.632313 -110.826345) (xy 343.584707 -110.855399) (xy 343.533378 -110.877211) (xy 343.479421 -110.891317)
			(xy 343.423984 -110.897417) (xy 343.36825 -110.89538) (xy 343.313407 -110.88525) (xy 343.260623 -110.867243)
			(xy 343.211023 -110.841742) (xy 343.165665 -110.809291) (xy 343.125516 -110.770582) (xy 343.09143 -110.726439)
			(xy 343.064134 -110.677804) (xy 343.044211 -110.625713) (xy 343.032085 -110.571276) (xy 343.028014 -110.515654)
			(xy 340.332365 -110.515654) (xy 340.328891 -110.518178) (xy 340.282569 -110.541778) (xy 340.233125 -110.557842)
			(xy 340.181778 -110.565972) (xy 340.155784 -110.566454) (xy 340.12914 -110.56595) (xy 340.076539 -110.557423)
			(xy 340.025989 -110.540562) (xy 339.978802 -110.515803) (xy 339.936203 -110.483788) (xy 339.899297 -110.44535)
			(xy 339.88375 -110.423706) (xy 339.875386 -110.41242) (xy 339.853713 -110.394565) (xy 339.827999 -110.383282)
			(xy 339.800184 -110.379424) (xy 339.772369 -110.383282) (xy 339.746655 -110.394565) (xy 339.724982 -110.41242)
			(xy 339.716618 -110.423706) (xy 339.701011 -110.4453) (xy 339.664101 -110.483718) (xy 339.621509 -110.515721)
			(xy 339.574337 -110.540481) (xy 339.523805 -110.557357) (xy 339.471222 -110.565912) (xy 339.444584 -110.566454)
			(xy 339.418601 -110.565851) (xy 339.367276 -110.557719) (xy 339.317854 -110.541659) (xy 339.271554 -110.518066)
			(xy 339.229514 -110.48752) (xy 339.192769 -110.450774) (xy 339.162226 -110.408733) (xy 339.138635 -110.362431)
			(xy 339.122577 -110.313008) (xy 339.114448 -110.261683) (xy 337.813342 -110.261683) (xy 337.819573 -110.265688)
			(xy 337.860764 -110.301387) (xy 337.896455 -110.342584) (xy 337.92592 -110.388442) (xy 337.948558 -110.438026)
			(xy 337.96391 -110.490327) (xy 337.971663 -110.54428) (xy 337.972146 -110.571534) (xy 337.971718 -110.59785)
			(xy 337.964478 -110.64998) (xy 337.950152 -110.700625) (xy 337.929012 -110.748824) (xy 337.901458 -110.793666)
			(xy 337.868012 -110.834303) (xy 337.848956 -110.852458) (xy 337.841579 -110.860001) (xy 337.833039 -110.879264)
			(xy 337.832446 -110.889796) (xy 337.832446 -110.964472) (xy 337.832963 -110.975023) (xy 337.841505 -110.994319)
			(xy 337.848956 -111.00181) (xy 337.869776 -111.021597) (xy 337.905747 -111.066376) (xy 337.934603 -111.116039)
			(xy 337.9527 -111.161885) (xy 339.114423 -111.161885) (xy 339.114423 -111.109915) (xy 339.122553 -111.058586)
			(xy 339.138612 -111.00916) (xy 339.162205 -110.962855) (xy 339.192751 -110.92081) (xy 339.229498 -110.884061)
			(xy 339.271541 -110.853513) (xy 339.317845 -110.829918) (xy 339.36727 -110.813857) (xy 339.418599 -110.805725)
			(xy 339.444584 -110.805214) (xy 339.471229 -110.805681) (xy 339.523832 -110.814218) (xy 339.574382 -110.831088)
			(xy 339.621568 -110.855854) (xy 339.664166 -110.887874) (xy 339.701071 -110.926316) (xy 339.716618 -110.947962)
			(xy 339.724982 -110.959248) (xy 339.746655 -110.977103) (xy 339.772369 -110.988386) (xy 339.800184 -110.992244)
			(xy 339.827999 -110.988386) (xy 339.853713 -110.977103) (xy 339.875386 -110.959248) (xy 339.88375 -110.947962)
			(xy 339.899306 -110.926329) (xy 339.936227 -110.887914) (xy 339.97883 -110.855916) (xy 340.026012 -110.831163)
			(xy 340.076552 -110.814296) (xy 340.129144 -110.80575) (xy 340.155784 -110.805214) (xy 340.181776 -110.805652)
			(xy 340.23312 -110.813782) (xy 340.28256 -110.829844) (xy 340.328878 -110.853442) (xy 340.370935 -110.883996)
			(xy 340.407693 -110.920753) (xy 340.438249 -110.962808) (xy 340.46185 -111.009126) (xy 340.477914 -111.058565)
			(xy 340.486047 -111.109908) (xy 340.486047 -111.161892) (xy 340.477914 -111.213235) (xy 340.46185 -111.262674)
			(xy 340.438249 -111.308992) (xy 340.407693 -111.351047) (xy 340.370935 -111.387804) (xy 340.328878 -111.418358)
			(xy 340.28256 -111.441956) (xy 340.23312 -111.458018) (xy 340.181776 -111.466148) (xy 340.155784 -111.46663)
			(xy 340.129139 -111.466136) (xy 340.076537 -111.457609) (xy 340.025987 -111.440746) (xy 339.9788 -111.415985)
			(xy 339.936201 -111.383968) (xy 339.899296 -111.345527) (xy 339.88375 -111.323882) (xy 339.875386 -111.312596)
			(xy 339.853713 -111.294741) (xy 339.827999 -111.283458) (xy 339.800184 -111.2796) (xy 339.772369 -111.283458)
			(xy 339.746655 -111.294741) (xy 339.724982 -111.312596) (xy 339.716618 -111.323882) (xy 339.701033 -111.345493)
			(xy 339.664116 -111.383906) (xy 339.621519 -111.415905) (xy 339.574343 -111.440661) (xy 339.523808 -111.457534)
			(xy 339.471222 -111.466088) (xy 339.444584 -111.46663) (xy 339.418599 -111.466075) (xy 339.36727 -111.457943)
			(xy 339.317845 -111.441882) (xy 339.271541 -111.418287) (xy 339.229498 -111.387739) (xy 339.192751 -111.35099)
			(xy 339.162205 -111.308945) (xy 339.138612 -111.26264) (xy 339.122553 -111.213214) (xy 339.114423 -111.161885)
			(xy 337.9527 -111.161885) (xy 337.955692 -111.169465) (xy 337.968537 -111.225448) (xy 337.972849 -111.282723)
			(xy 337.96853 -111.339998) (xy 337.955678 -111.395979) (xy 337.934583 -111.449403) (xy 337.905721 -111.499063)
			(xy 337.869745 -111.543837) (xy 337.848956 -111.563658) (xy 337.841579 -111.571201) (xy 337.833039 -111.590464)
			(xy 337.832446 -111.600996) (xy 337.832446 -111.675672) (xy 337.832963 -111.686223) (xy 337.841505 -111.705519)
			(xy 337.848956 -111.71301) (xy 337.869776 -111.732797) (xy 337.905747 -111.777576) (xy 337.934603 -111.827239)
			(xy 337.955692 -111.880665) (xy 337.968537 -111.936648) (xy 337.972849 -111.993923) (xy 337.96853 -112.051198)
			(xy 337.9661 -112.061783) (xy 339.114446 -112.061783) (xy 339.114446 -112.009817) (xy 339.122575 -111.958491)
			(xy 339.138633 -111.909069) (xy 339.162224 -111.862766) (xy 339.192768 -111.820725) (xy 339.229512 -111.783978)
			(xy 339.271553 -111.753432) (xy 339.317854 -111.729839) (xy 339.367275 -111.713779) (xy 339.418601 -111.705647)
			(xy 339.444584 -111.705136) (xy 339.47123 -111.705594) (xy 339.523833 -111.714131) (xy 339.574384 -111.731002)
			(xy 339.62157 -111.75577) (xy 339.664168 -111.787792) (xy 339.701072 -111.826237) (xy 339.716618 -111.847884)
			(xy 339.724982 -111.85917) (xy 339.746655 -111.877025) (xy 339.772369 -111.888308) (xy 339.800184 -111.892166)
			(xy 339.827999 -111.888308) (xy 339.853713 -111.877025) (xy 339.875386 -111.85917) (xy 339.88375 -111.847884)
			(xy 339.899312 -111.826256) (xy 339.936231 -111.78784) (xy 339.978832 -111.755841) (xy 340.026013 -111.731087)
			(xy 340.076553 -111.714218) (xy 340.129144 -111.705672) (xy 340.155784 -111.705136) (xy 340.181778 -111.70553)
			(xy 340.233125 -111.71366) (xy 340.282568 -111.729723) (xy 340.32889 -111.753323) (xy 340.370949 -111.783879)
			(xy 340.372724 -111.785654) (xy 341.657684 -111.785654) (xy 341.661755 -111.730032) (xy 341.673881 -111.675595)
			(xy 341.693804 -111.623504) (xy 341.7211 -111.574869) (xy 341.755186 -111.530726) (xy 341.795335 -111.492017)
			(xy 341.840693 -111.459566) (xy 341.890293 -111.434065) (xy 341.943077 -111.416058) (xy 341.99792 -111.405928)
			(xy 342.053654 -111.403891) (xy 342.109091 -111.409991) (xy 342.163048 -111.424097) (xy 342.214377 -111.445909)
			(xy 342.261983 -111.474963) (xy 342.304851 -111.510638) (xy 342.342068 -111.552175) (xy 342.372841 -111.598688)
			(xy 342.396513 -111.649185) (xy 342.412581 -111.702592) (xy 342.420701 -111.757768) (xy 342.42121 -111.785654)
			(xy 342.420701 -111.81354) (xy 342.412581 -111.868716) (xy 342.396513 -111.922123) (xy 342.372841 -111.97262)
			(xy 342.342068 -112.019133) (xy 342.304851 -112.06067) (xy 342.261983 -112.096345) (xy 342.214377 -112.125399)
			(xy 342.163048 -112.147211) (xy 342.109091 -112.161317) (xy 342.053654 -112.167417) (xy 341.99792 -112.16538)
			(xy 341.943077 -112.15525) (xy 341.890293 -112.137243) (xy 341.840693 -112.111742) (xy 341.795335 -112.079291)
			(xy 341.755186 -112.040582) (xy 341.7211 -111.996439) (xy 341.693804 -111.947804) (xy 341.673881 -111.895713)
			(xy 341.661755 -111.841276) (xy 341.657684 -111.785654) (xy 340.372724 -111.785654) (xy 340.40771 -111.820639)
			(xy 340.438268 -111.862697) (xy 340.461871 -111.909017) (xy 340.477936 -111.95846) (xy 340.486069 -112.009806)
			(xy 340.486069 -112.061794) (xy 340.477936 -112.11314) (xy 340.461871 -112.162583) (xy 340.438268 -112.208903)
			(xy 340.40771 -112.250961) (xy 340.370949 -112.287721) (xy 340.358237 -112.296956) (xy 343.094816 -112.296956)
			(xy 343.098887 -112.241334) (xy 343.111013 -112.186897) (xy 343.130936 -112.134806) (xy 343.158232 -112.086171)
			(xy 343.192318 -112.042028) (xy 343.232467 -112.003319) (xy 343.277825 -111.970868) (xy 343.327425 -111.945367)
			(xy 343.380209 -111.92736) (xy 343.435052 -111.91723) (xy 343.490786 -111.915193) (xy 343.546223 -111.921293)
			(xy 343.60018 -111.935399) (xy 343.651509 -111.957211) (xy 343.699115 -111.986265) (xy 343.741983 -112.02194)
			(xy 343.7792 -112.063477) (xy 343.809973 -112.10999) (xy 343.833645 -112.160487) (xy 343.849713 -112.213894)
			(xy 343.857833 -112.26907) (xy 343.858342 -112.296956) (xy 343.857833 -112.324842) (xy 343.849713 -112.380018)
			(xy 343.833645 -112.433425) (xy 343.809973 -112.483922) (xy 343.7792 -112.530435) (xy 343.741983 -112.571972)
			(xy 343.699115 -112.607647) (xy 343.651509 -112.636701) (xy 343.60018 -112.658513) (xy 343.546223 -112.672619)
			(xy 343.490786 -112.678719) (xy 343.435052 -112.676682) (xy 343.380209 -112.666552) (xy 343.327425 -112.648545)
			(xy 343.277825 -112.623044) (xy 343.232467 -112.590593) (xy 343.192318 -112.551884) (xy 343.158232 -112.507741)
			(xy 343.130936 -112.459106) (xy 343.111013 -112.407015) (xy 343.098887 -112.352578) (xy 343.094816 -112.296956)
			(xy 340.358237 -112.296956) (xy 340.32889 -112.318277) (xy 340.282568 -112.341877) (xy 340.233125 -112.35794)
			(xy 340.181778 -112.36607) (xy 340.155784 -112.366552) (xy 340.12914 -112.366049) (xy 340.076538 -112.357522)
			(xy 340.025989 -112.34066) (xy 339.978802 -112.315901) (xy 339.936203 -112.283887) (xy 339.899297 -112.245448)
			(xy 339.88375 -112.223804) (xy 339.875386 -112.212518) (xy 339.853713 -112.194663) (xy 339.827999 -112.18338)
			(xy 339.800184 -112.179522) (xy 339.772369 -112.18338) (xy 339.746655 -112.194663) (xy 339.724982 -112.212518)
			(xy 339.716618 -112.223804) (xy 339.70101 -112.245398) (xy 339.664101 -112.283816) (xy 339.621509 -112.315819)
			(xy 339.574337 -112.340579) (xy 339.523805 -112.357455) (xy 339.471221 -112.36601) (xy 339.444584 -112.366552)
			(xy 339.418601 -112.365953) (xy 339.367275 -112.357821) (xy 339.317854 -112.341761) (xy 339.271553 -112.318168)
			(xy 339.229512 -112.287622) (xy 339.192768 -112.250875) (xy 339.162224 -112.208834) (xy 339.138633 -112.162531)
			(xy 339.122575 -112.113109) (xy 339.114446 -112.061783) (xy 337.9661 -112.061783) (xy 337.955678 -112.107179)
			(xy 337.934583 -112.160603) (xy 337.905721 -112.210263) (xy 337.869745 -112.255037) (xy 337.848956 -112.274858)
			(xy 337.841579 -112.282401) (xy 337.833039 -112.301664) (xy 337.832446 -112.312196) (xy 337.832446 -112.386872)
			(xy 337.832963 -112.397423) (xy 337.841505 -112.416719) (xy 337.848956 -112.42421) (xy 337.86802 -112.442357)
			(xy 337.901474 -112.48299) (xy 337.929031 -112.527832) (xy 337.950167 -112.576034) (xy 337.964483 -112.626683)
			(xy 337.971708 -112.678818) (xy 337.972146 -112.705134) (xy 337.971654 -112.732384) (xy 337.963894 -112.78633)
			(xy 337.948536 -112.838622) (xy 337.925894 -112.888197) (xy 337.896428 -112.934045) (xy 337.872387 -112.961789)
			(xy 339.114368 -112.961789) (xy 339.114368 -112.909811) (xy 339.122498 -112.858473) (xy 339.13856 -112.809038)
			(xy 339.162157 -112.762725) (xy 339.192708 -112.720674) (xy 339.229461 -112.683919) (xy 339.271512 -112.653365)
			(xy 339.317824 -112.629766) (xy 339.367257 -112.613702) (xy 339.418595 -112.605569) (xy 339.444584 -112.605058)
			(xy 339.47123 -112.605507) (xy 339.523835 -112.614044) (xy 339.574386 -112.630917) (xy 339.621572 -112.655686)
			(xy 339.66417 -112.68771) (xy 339.701073 -112.726158) (xy 339.716618 -112.747806) (xy 339.724982 -112.759092)
			(xy 339.746655 -112.776947) (xy 339.772369 -112.78823) (xy 339.800184 -112.792088) (xy 339.827999 -112.78823)
			(xy 339.853713 -112.776947) (xy 339.875386 -112.759092) (xy 339.88375 -112.747806) (xy 339.899289 -112.726161)
			(xy 339.936216 -112.687749) (xy 339.978822 -112.655755) (xy 340.026008 -112.631004) (xy 340.07655 -112.614139)
			(xy 340.129143 -112.605594) (xy 340.155784 -112.605058) (xy 340.181771 -112.605608) (xy 340.233107 -112.613736)
			(xy 340.282538 -112.629795) (xy 340.328849 -112.65339) (xy 340.370898 -112.683939) (xy 340.407651 -112.72069)
			(xy 340.438202 -112.762737) (xy 340.461798 -112.809047) (xy 340.47786 -112.858478) (xy 340.485991 -112.909813)
			(xy 340.485991 -112.961787) (xy 340.47786 -113.013122) (xy 340.461798 -113.062553) (xy 340.438202 -113.108863)
			(xy 340.407651 -113.15091) (xy 340.370898 -113.187661) (xy 340.328849 -113.21821) (xy 340.282538 -113.241805)
			(xy 340.233107 -113.257864) (xy 340.181771 -113.265992) (xy 340.155784 -113.266474) (xy 340.12914 -113.265961)
			(xy 340.07654 -113.257435) (xy 340.025991 -113.240575) (xy 339.978804 -113.215817) (xy 339.936205 -113.183805)
			(xy 339.899297 -113.145369) (xy 339.88375 -113.123726) (xy 339.875386 -113.11244) (xy 339.853713 -113.094585)
			(xy 339.827999 -113.083302) (xy 339.800184 -113.079444) (xy 339.772369 -113.083302) (xy 339.746655 -113.094585)
			(xy 339.724982 -113.11244) (xy 339.716618 -113.123726) (xy 339.701017 -113.145325) (xy 339.664105 -113.183741)
			(xy 339.621512 -113.215743) (xy 339.574339 -113.240502) (xy 339.523806 -113.257377) (xy 339.471222 -113.265932)
			(xy 339.444584 -113.266474) (xy 339.418595 -113.266031) (xy 339.367257 -113.257898) (xy 339.317824 -113.241834)
			(xy 339.271512 -113.218235) (xy 339.229461 -113.187681) (xy 339.192708 -113.150926) (xy 339.162157 -113.108875)
			(xy 339.13856 -113.062562) (xy 339.122498 -113.013127) (xy 339.114368 -112.961789) (xy 337.872387 -112.961789)
			(xy 337.860737 -112.975234) (xy 337.819549 -113.010925) (xy 337.773701 -113.040392) (xy 337.724126 -113.063035)
			(xy 337.671834 -113.078393) (xy 337.617888 -113.086154) (xy 337.590638 -113.086642) (xy 337.564322 -113.086234)
			(xy 337.51219 -113.07899) (xy 337.461545 -113.06466) (xy 337.413346 -113.043517) (xy 337.368504 -113.015959)
			(xy 337.327868 -112.982509) (xy 337.309714 -112.963452) (xy 337.302182 -112.956062) (xy 337.28291 -112.947529)
			(xy 337.272376 -112.946942) (xy 337.1977 -112.946942) (xy 337.187147 -112.947445) (xy 337.167851 -112.955997)
			(xy 337.160362 -112.963452) (xy 337.142228 -112.982529) (xy 337.101593 -113.015982) (xy 337.056747 -113.043537)
			(xy 337.008543 -113.064671) (xy 336.957892 -113.078985) (xy 336.905755 -113.086205) (xy 336.879438 -113.086642)
			(xy 336.852188 -113.086109) (xy 336.798241 -113.078359) (xy 336.745946 -113.063009) (xy 336.696369 -113.040373)
			(xy 336.650517 -113.010913) (xy 336.609325 -112.975226) (xy 336.573631 -112.934041) (xy 336.544161 -112.888195)
			(xy 336.521516 -112.838621) (xy 336.506157 -112.786329) (xy 336.498396 -112.732384) (xy 336.49793 -112.705134)
			(xy 336.498344 -112.678818) (xy 336.505588 -112.626687) (xy 336.519917 -112.576043) (xy 336.54106 -112.527844)
			(xy 336.568616 -112.483002) (xy 336.602064 -112.442365) (xy 336.62112 -112.42421) (xy 336.628522 -112.416689)
			(xy 336.637046 -112.397408) (xy 336.63763 -112.386872) (xy 336.63763 -112.312196) (xy 336.637108 -112.301646)
			(xy 336.628567 -112.282351) (xy 336.62112 -112.274858) (xy 336.600364 -112.255005) (xy 336.564385 -112.210239)
			(xy 336.535522 -112.160586) (xy 336.514425 -112.107169) (xy 336.501572 -112.051193) (xy 336.497253 -111.993923)
			(xy 333.055424 -111.993923) (xy 333.058714 -112.037615) (xy 333.054396 -112.09489) (xy 333.041544 -112.150871)
			(xy 333.020449 -112.204294) (xy 332.991586 -112.253953) (xy 332.955607 -112.298726) (xy 332.934818 -112.318546)
			(xy 332.927397 -112.326051) (xy 332.918883 -112.345344) (xy 332.918308 -112.355884) (xy 332.918308 -112.43056)
			(xy 332.918843 -112.441109) (xy 332.927374 -112.460405) (xy 332.934818 -112.467898) (xy 332.953869 -112.486058)
			(xy 332.987326 -112.526687) (xy 333.014885 -112.571527) (xy 333.036024 -112.619726) (xy 333.050343 -112.670373)
			(xy 333.057569 -112.722506) (xy 333.058008 -112.748822) (xy 333.057522 -112.776073) (xy 333.049766 -112.830021)
			(xy 333.034411 -112.882316) (xy 333.011769 -112.931893) (xy 332.982303 -112.977743) (xy 332.946612 -113.018934)
			(xy 332.905421 -113.054625) (xy 332.859571 -113.084091) (xy 332.809994 -113.106733) (xy 332.757699 -113.122088)
			(xy 332.703751 -113.129844) (xy 332.649249 -113.129844) (xy 332.595301 -113.122088) (xy 332.543006 -113.106733)
			(xy 332.493429 -113.084091) (xy 332.447579 -113.054625) (xy 332.406388 -113.018934) (xy 332.370697 -112.977743)
			(xy 332.341231 -112.931893) (xy 332.318589 -112.882316) (xy 332.303234 -112.830021) (xy 332.295478 -112.776073)
			(xy 332.294992 -112.748822) (xy 332.295477 -112.722509) (xy 332.302708 -112.670381) (xy 332.317024 -112.619739)
			(xy 332.338153 -112.57154) (xy 332.365696 -112.526696) (xy 332.399132 -112.486055) (xy 332.418182 -112.467898)
			(xy 332.425584 -112.460377) (xy 332.434109 -112.441097) (xy 332.434692 -112.43056) (xy 332.434692 -112.355884)
			(xy 332.434188 -112.345331) (xy 332.425635 -112.326036) (xy 332.418182 -112.318546) (xy 332.397416 -112.298704)
			(xy 332.361441 -112.253935) (xy 332.33258 -112.20428) (xy 332.311487 -112.150861) (xy 332.298636 -112.094885)
			(xy 332.294318 -112.037615) (xy 330.520499 -112.037615) (xy 330.516181 -112.094891) (xy 330.503328 -112.150872)
			(xy 330.482232 -112.204296) (xy 330.453367 -112.253954) (xy 330.417387 -112.298727) (xy 330.396596 -112.318546)
			(xy 330.389172 -112.326048) (xy 330.380661 -112.345343) (xy 330.380086 -112.355884) (xy 330.380086 -112.43056)
			(xy 330.380627 -112.441108) (xy 330.389154 -112.460403) (xy 330.396596 -112.467898) (xy 330.415643 -112.486062)
			(xy 330.449101 -112.52669) (xy 330.476661 -112.571528) (xy 330.497801 -112.619728) (xy 330.51212 -112.670374)
			(xy 330.519347 -112.722506) (xy 330.519786 -112.748822) (xy 330.5193 -112.776073) (xy 330.511544 -112.830021)
			(xy 330.496189 -112.882316) (xy 330.473547 -112.931893) (xy 330.444081 -112.977743) (xy 330.40839 -113.018934)
			(xy 330.367199 -113.054625) (xy 330.321349 -113.084091) (xy 330.271772 -113.106733) (xy 330.219477 -113.122088)
			(xy 330.165529 -113.129844) (xy 330.111027 -113.129844) (xy 330.057079 -113.122088) (xy 330.004784 -113.106733)
			(xy 329.955207 -113.084091) (xy 329.909357 -113.054625) (xy 329.868166 -113.018934) (xy 329.832475 -112.977743)
			(xy 329.803009 -112.931893) (xy 329.780367 -112.882316) (xy 329.765012 -112.830021) (xy 329.757256 -112.776073)
			(xy 329.75677 -112.748822) (xy 329.757262 -112.722509) (xy 329.764493 -112.670382) (xy 329.778808 -112.61974)
			(xy 329.799936 -112.571541) (xy 329.827477 -112.526697) (xy 329.860911 -112.486056) (xy 329.87996 -112.467898)
			(xy 329.887358 -112.460374) (xy 329.895886 -112.441096) (xy 329.89647 -112.43056) (xy 329.89647 -112.355884)
			(xy 329.895972 -112.34533) (xy 329.887416 -112.326035) (xy 329.87996 -112.318546) (xy 329.859195 -112.298703)
			(xy 329.823222 -112.253933) (xy 329.794363 -112.204279) (xy 329.773271 -112.15086) (xy 329.760421 -112.094884)
			(xy 329.756103 -112.037615) (xy 327.962752 -112.037615) (xy 327.994212 -112.075822) (xy 328.021769 -112.120665)
			(xy 328.042905 -112.168869) (xy 328.057219 -112.219519) (xy 328.06444 -112.271655) (xy 328.064876 -112.297972)
			(xy 328.06439 -112.325223) (xy 328.056634 -112.379171) (xy 328.041279 -112.431466) (xy 328.018637 -112.481043)
			(xy 327.989171 -112.526893) (xy 327.95348 -112.568084) (xy 327.912289 -112.603775) (xy 327.866439 -112.633241)
			(xy 327.816862 -112.655883) (xy 327.764567 -112.671238) (xy 327.710619 -112.678994) (xy 327.656117 -112.678994)
			(xy 327.602169 -112.671238) (xy 327.549874 -112.655883) (xy 327.500297 -112.633241) (xy 327.454447 -112.603775)
			(xy 327.413256 -112.568084) (xy 327.377565 -112.526893) (xy 327.348099 -112.481043) (xy 327.325457 -112.431466)
			(xy 327.310102 -112.379171) (xy 327.302346 -112.325223) (xy 327.30186 -112.297972) (xy 326.032876 -112.297972)
			(xy 326.03239 -112.325223) (xy 326.024634 -112.379171) (xy 326.009279 -112.431466) (xy 325.986637 -112.481043)
			(xy 325.957171 -112.526893) (xy 325.92148 -112.568084) (xy 325.880289 -112.603775) (xy 325.834439 -112.633241)
			(xy 325.784862 -112.655883) (xy 325.732567 -112.671238) (xy 325.678619 -112.678994) (xy 325.624117 -112.678994)
			(xy 325.570169 -112.671238) (xy 325.517874 -112.655883) (xy 325.468297 -112.633241) (xy 325.422447 -112.603775)
			(xy 325.381256 -112.568084) (xy 325.345565 -112.526893) (xy 325.316099 -112.481043) (xy 325.293457 -112.431466)
			(xy 325.278102 -112.379171) (xy 325.270346 -112.325223) (xy 325.26986 -112.297972) (xy 317.145416 -112.297972)
			(xy 317.145416 -114.084612) (xy 321.649282 -114.084612) (xy 321.649288 -114.03011) (xy 321.65705 -113.976164)
			(xy 321.672411 -113.923871) (xy 321.695057 -113.874297) (xy 321.724528 -113.82845) (xy 321.760223 -113.787264)
			(xy 321.801417 -113.751578) (xy 321.84727 -113.722117) (xy 321.896849 -113.699481) (xy 321.949145 -113.684132)
			(xy 322.003093 -113.676382) (xy 322.030344 -113.675922) (xy 322.064564 -113.676721) (xy 322.131897 -113.688991)
			(xy 322.164202 -113.700306) (xy 322.172392 -113.702978) (xy 322.189602 -113.703321) (xy 322.205949 -113.697929)
			(xy 322.21297 -113.69294) (xy 322.291964 -113.632488) (xy 322.302378 -113.608358) (xy 322.301108 -113.595404)
			(xy 322.29933 -113.558574) (xy 322.299731 -113.531319) (xy 322.307492 -113.477364) (xy 322.322854 -113.425062)
			(xy 322.345502 -113.375479) (xy 322.374976 -113.329624) (xy 322.410676 -113.288431) (xy 322.451876 -113.252738)
			(xy 322.497736 -113.223271) (xy 322.547322 -113.200631) (xy 322.599626 -113.185279) (xy 322.653583 -113.177526)
			(xy 322.680838 -113.177066) (xy 322.709754 -113.177604) (xy 322.766926 -113.186326) (xy 322.822125 -113.203578)
			(xy 322.874088 -113.228966) (xy 322.921622 -113.261907) (xy 322.963638 -113.301647) (xy 322.981828 -113.324132)
			(xy 322.989427 -113.332947) (xy 323.010334 -113.343125) (xy 323.02196 -113.34369) (xy 323.101716 -113.34369)
			(xy 323.113348 -113.343149) (xy 323.134258 -113.332962) (xy 323.141848 -113.324132) (xy 323.160076 -113.30168)
			(xy 323.202087 -113.261941) (xy 323.249614 -113.228998) (xy 323.301568 -113.203604) (xy 323.35676 -113.186341)
			(xy 323.413924 -113.177605) (xy 323.442838 -113.177066) (xy 323.470089 -113.177542) (xy 323.524036 -113.185303)
			(xy 323.576329 -113.200662) (xy 323.625905 -113.223306) (xy 323.671754 -113.252774) (xy 323.712943 -113.288466)
			(xy 323.748634 -113.329656) (xy 323.7781 -113.375506) (xy 323.800742 -113.425082) (xy 323.816099 -113.477376)
			(xy 323.823858 -113.531323) (xy 323.824346 -113.558574) (xy 323.824161 -113.568734) (xy 343.089736 -113.568734)
			(xy 343.093807 -113.513112) (xy 343.105933 -113.458675) (xy 343.125856 -113.406584) (xy 343.153152 -113.357949)
			(xy 343.187238 -113.313806) (xy 343.227387 -113.275097) (xy 343.272745 -113.242646) (xy 343.322345 -113.217145)
			(xy 343.375129 -113.199138) (xy 343.429972 -113.189008) (xy 343.485706 -113.186971) (xy 343.541143 -113.193071)
			(xy 343.5951 -113.207177) (xy 343.646429 -113.228989) (xy 343.694035 -113.258043) (xy 343.736903 -113.293718)
			(xy 343.77412 -113.335255) (xy 343.804893 -113.381768) (xy 343.828565 -113.432265) (xy 343.844633 -113.485672)
			(xy 343.852753 -113.540848) (xy 343.853262 -113.568734) (xy 343.852753 -113.59662) (xy 343.844633 -113.651796)
			(xy 343.828565 -113.705203) (xy 343.804893 -113.7557) (xy 343.77412 -113.802213) (xy 343.736903 -113.84375)
			(xy 343.694035 -113.879425) (xy 343.646429 -113.908479) (xy 343.5951 -113.930291) (xy 343.541143 -113.944397)
			(xy 343.485706 -113.950497) (xy 343.429972 -113.94846) (xy 343.375129 -113.93833) (xy 343.322345 -113.920323)
			(xy 343.272745 -113.894822) (xy 343.227387 -113.862371) (xy 343.187238 -113.823662) (xy 343.153152 -113.779519)
			(xy 343.125856 -113.730884) (xy 343.105933 -113.678793) (xy 343.093807 -113.624356) (xy 343.089736 -113.568734)
			(xy 323.824161 -113.568734) (xy 323.823808 -113.58812) (xy 323.814708 -113.646506) (xy 323.796706 -113.702788)
			(xy 323.770234 -113.755618) (xy 323.735926 -113.80373) (xy 323.694604 -113.84597) (xy 323.647258 -113.881327)
			(xy 323.6214 -113.895632) (xy 323.611313 -113.901734) (xy 323.597673 -113.920928) (xy 323.595238 -113.932462)
			(xy 323.580506 -114.025172) (xy 323.587872 -114.048032) (xy 323.596254 -114.056414) (xy 323.603701 -114.064122)
			(xy 323.617806 -114.080261) (xy 323.624448 -114.088672) (xy 323.632032 -114.097503) (xy 323.652951 -114.107671)
			(xy 323.66458 -114.10823) (xy 323.744336 -114.10823) (xy 323.755972 -114.107722) (xy 323.776883 -114.097513)
			(xy 323.784468 -114.088672) (xy 323.80267 -114.066198) (xy 323.844688 -114.026463) (xy 323.892221 -113.993524)
			(xy 323.94418 -113.968134) (xy 323.999375 -113.950876) (xy 324.056543 -113.942143) (xy 324.085458 -113.941606)
			(xy 324.112714 -113.942038) (xy 324.166671 -113.94979) (xy 324.218976 -113.965143) (xy 324.268564 -113.987784)
			(xy 324.314424 -114.017252) (xy 324.327376 -114.028474) (xy 337.205064 -114.028474) (xy 337.209135 -113.972852)
			(xy 337.221261 -113.918415) (xy 337.241184 -113.866324) (xy 337.26848 -113.817689) (xy 337.302566 -113.773546)
			(xy 337.342715 -113.734837) (xy 337.388073 -113.702386) (xy 337.437673 -113.676885) (xy 337.490457 -113.658878)
			(xy 337.5453 -113.648748) (xy 337.601034 -113.646711) (xy 337.656471 -113.652811) (xy 337.710428 -113.666917)
			(xy 337.761757 -113.688729) (xy 337.809363 -113.717783) (xy 337.852231 -113.753458) (xy 337.889448 -113.794995)
			(xy 337.920221 -113.841508) (xy 337.943893 -113.892005) (xy 337.959961 -113.945412) (xy 337.968081 -114.000588)
			(xy 337.96859 -114.028474) (xy 337.968081 -114.05636) (xy 337.959961 -114.111536) (xy 337.943893 -114.164943)
			(xy 337.920221 -114.21544) (xy 337.889448 -114.261953) (xy 337.852231 -114.30349) (xy 337.809363 -114.339165)
			(xy 337.761757 -114.368219) (xy 337.710428 -114.390031) (xy 337.656471 -114.404137) (xy 337.601034 -114.410237)
			(xy 337.5453 -114.4082) (xy 337.490457 -114.39807) (xy 337.437673 -114.380063) (xy 337.388073 -114.354562)
			(xy 337.342715 -114.322111) (xy 337.302566 -114.283402) (xy 337.26848 -114.239259) (xy 337.241184 -114.190624)
			(xy 337.221261 -114.138533) (xy 337.209135 -114.084096) (xy 337.205064 -114.028474) (xy 324.327376 -114.028474)
			(xy 324.355623 -114.052947) (xy 324.391322 -114.094143) (xy 324.420795 -114.14) (xy 324.443442 -114.189584)
			(xy 324.458801 -114.241888) (xy 324.466559 -114.295844) (xy 324.466559 -114.350356) (xy 324.458801 -114.404312)
			(xy 324.443442 -114.456616) (xy 324.420795 -114.5062) (xy 324.391322 -114.552057) (xy 324.355623 -114.593253)
			(xy 324.314424 -114.628948) (xy 324.268564 -114.658416) (xy 324.218976 -114.681057) (xy 324.166671 -114.69641)
			(xy 324.112714 -114.704162) (xy 324.085458 -114.704622) (xy 324.056541 -114.704091) (xy 323.999369 -114.695369)
			(xy 323.944169 -114.678115) (xy 323.892207 -114.652726) (xy 323.844673 -114.619783) (xy 323.802657 -114.580042)
			(xy 323.784468 -114.557556) (xy 323.776872 -114.548737) (xy 323.755963 -114.538562) (xy 323.744336 -114.537998)
			(xy 323.66458 -114.537998) (xy 323.652949 -114.538541) (xy 323.632039 -114.548727) (xy 323.624448 -114.557556)
			(xy 323.606219 -114.580007) (xy 323.564208 -114.619747) (xy 323.516682 -114.652691) (xy 323.464728 -114.678085)
			(xy 323.409536 -114.695348) (xy 323.352372 -114.704084) (xy 323.323458 -114.704622) (xy 323.296206 -114.704161)
			(xy 323.242258 -114.696399) (xy 323.189964 -114.68104) (xy 323.140388 -114.658395) (xy 323.094538 -114.628925)
			(xy 323.053349 -114.593231) (xy 323.017658 -114.552039) (xy 322.988192 -114.506188) (xy 322.965551 -114.45661)
			(xy 322.950195 -114.404314) (xy 322.942437 -114.350366) (xy 322.94195 -114.323114) (xy 322.942428 -114.293565)
			(xy 322.951532 -114.235174) (xy 322.969541 -114.178888) (xy 322.996022 -114.126056) (xy 323.030341 -114.077944)
			(xy 323.071675 -114.035707) (xy 323.119032 -114.000356) (xy 323.144896 -113.986056) (xy 323.154987 -113.979959)
			(xy 323.168625 -113.960762) (xy 323.171058 -113.949226) (xy 323.18579 -113.856516) (xy 323.178424 -113.833656)
			(xy 323.170042 -113.825274) (xy 323.162595 -113.817567) (xy 323.14849 -113.801427) (xy 323.141848 -113.793016)
			(xy 323.134225 -113.784226) (xy 323.113336 -113.774036) (xy 323.101716 -113.773458) (xy 323.02196 -113.773458)
			(xy 323.010324 -113.773968) (xy 322.989413 -113.784175) (xy 322.981828 -113.793016) (xy 322.963625 -113.815489)
			(xy 322.921607 -113.855225) (xy 322.874075 -113.888164) (xy 322.822116 -113.913554) (xy 322.766921 -113.930813)
			(xy 322.709753 -113.939545) (xy 322.680838 -113.940082) (xy 322.646618 -113.939287) (xy 322.579285 -113.927015)
			(xy 322.54698 -113.915698) (xy 322.538794 -113.913011) (xy 322.521581 -113.912674) (xy 322.505233 -113.918072)
			(xy 322.498212 -113.923064) (xy 322.419218 -113.983516) (xy 322.408804 -114.007646) (xy 322.410074 -114.0206)
			(xy 322.411852 -114.05743) (xy 322.411313 -114.084681) (xy 322.403552 -114.138627) (xy 322.388193 -114.19092)
			(xy 322.365548 -114.240495) (xy 322.336078 -114.286342) (xy 322.300383 -114.327529) (xy 322.259191 -114.363217)
			(xy 322.213338 -114.392679) (xy 322.16376 -114.415315) (xy 322.111464 -114.430666) (xy 322.057516 -114.438417)
			(xy 322.003014 -114.438412) (xy 321.949068 -114.430651) (xy 321.896775 -114.415291) (xy 321.847201 -114.392645)
			(xy 321.801354 -114.363175) (xy 321.760167 -114.32748) (xy 321.72448 -114.286287) (xy 321.695019 -114.240434)
			(xy 321.672383 -114.190855) (xy 321.657033 -114.13856) (xy 321.649282 -114.084612) (xy 317.145416 -114.084612)
			(xy 317.145416 -114.147346) (xy 317.145848 -114.157412) (xy 317.153576 -114.176003) (xy 317.160402 -114.183414)
			(xy 318.377752 -115.400836) (xy 319.461134 -115.400836) (xy 319.461589 -115.373582) (xy 319.469342 -115.319629)
			(xy 319.484696 -115.267328) (xy 319.507337 -115.217745) (xy 319.536805 -115.17189) (xy 319.5725 -115.130696)
			(xy 319.613695 -115.095002) (xy 319.659551 -115.065534) (xy 319.709134 -115.042894) (xy 319.761435 -115.027541)
			(xy 319.815388 -115.019788) (xy 319.842642 -115.019328) (xy 319.869553 -115.019771) (xy 319.92284 -115.027354)
			(xy 319.974532 -115.042349) (xy 320.023604 -115.064459) (xy 320.069082 -115.093245) (xy 320.110065 -115.128135)
			(xy 320.145738 -115.168439) (xy 320.175394 -115.213355) (xy 320.198444 -115.261992) (xy 320.206878 -115.287552)
			(xy 320.206878 -115.287806) (xy 320.208862 -115.293497) (xy 320.215155 -115.303774) (xy 320.219324 -115.308126)
			(xy 320.281554 -115.370356) (xy 321.561204 -115.370356) (xy 321.565275 -115.314734) (xy 321.577401 -115.260297)
			(xy 321.597324 -115.208206) (xy 321.62462 -115.159571) (xy 321.658706 -115.115428) (xy 321.698855 -115.076719)
			(xy 321.744213 -115.044268) (xy 321.793813 -115.018767) (xy 321.846597 -115.00076) (xy 321.90144 -114.99063)
			(xy 321.957174 -114.988593) (xy 322.012611 -114.994693) (xy 322.066568 -115.008799) (xy 322.07162 -115.010946)
			(xy 338.819742 -115.010946) (xy 338.823813 -114.955324) (xy 338.835939 -114.900887) (xy 338.855862 -114.848796)
			(xy 338.883158 -114.800161) (xy 338.917244 -114.756018) (xy 338.957393 -114.717309) (xy 339.002751 -114.684858)
			(xy 339.052351 -114.659357) (xy 339.105135 -114.64135) (xy 339.159978 -114.63122) (xy 339.215712 -114.629183)
			(xy 339.271149 -114.635283) (xy 339.325106 -114.649389) (xy 339.376435 -114.671201) (xy 339.424041 -114.700255)
			(xy 339.466909 -114.73593) (xy 339.504126 -114.777467) (xy 339.534899 -114.82398) (xy 339.558571 -114.874477)
			(xy 339.574639 -114.927884) (xy 339.582759 -114.98306) (xy 339.583268 -115.010946) (xy 339.582759 -115.038832)
			(xy 339.579835 -115.058698) (xy 340.186262 -115.058698) (xy 340.190333 -115.003076) (xy 340.202459 -114.948639)
			(xy 340.222382 -114.896548) (xy 340.249678 -114.847913) (xy 340.283764 -114.80377) (xy 340.323913 -114.765061)
			(xy 340.369271 -114.73261) (xy 340.418871 -114.707109) (xy 340.471655 -114.689102) (xy 340.526498 -114.678972)
			(xy 340.582232 -114.676935) (xy 340.637669 -114.683035) (xy 340.691626 -114.697141) (xy 340.742955 -114.718953)
			(xy 340.790561 -114.748007) (xy 340.833429 -114.783682) (xy 340.870646 -114.825219) (xy 340.901419 -114.871732)
			(xy 340.925091 -114.922229) (xy 340.941159 -114.975636) (xy 340.943328 -114.990372) (xy 341.564974 -114.990372)
			(xy 341.569045 -114.93475) (xy 341.581171 -114.880313) (xy 341.601094 -114.828222) (xy 341.62839 -114.779587)
			(xy 341.662476 -114.735444) (xy 341.702625 -114.696735) (xy 341.747983 -114.664284) (xy 341.797583 -114.638783)
			(xy 341.850367 -114.620776) (xy 341.90521 -114.610646) (xy 341.960944 -114.608609) (xy 342.016381 -114.614709)
			(xy 342.070338 -114.628815) (xy 342.121667 -114.650627) (xy 342.169273 -114.679681) (xy 342.212141 -114.715356)
			(xy 342.249358 -114.756893) (xy 342.280131 -114.803406) (xy 342.303803 -114.853903) (xy 342.319871 -114.90731)
			(xy 342.327721 -114.960654) (xy 343.091768 -114.960654) (xy 343.095839 -114.905032) (xy 343.107965 -114.850595)
			(xy 343.127888 -114.798504) (xy 343.155184 -114.749869) (xy 343.18927 -114.705726) (xy 343.229419 -114.667017)
			(xy 343.274777 -114.634566) (xy 343.324377 -114.609065) (xy 343.377161 -114.591058) (xy 343.432004 -114.580928)
			(xy 343.487738 -114.578891) (xy 343.543175 -114.584991) (xy 343.597132 -114.599097) (xy 343.648461 -114.620909)
			(xy 343.696067 -114.649963) (xy 343.738935 -114.685638) (xy 343.776152 -114.727175) (xy 343.806925 -114.773688)
			(xy 343.830597 -114.824185) (xy 343.846665 -114.877592) (xy 343.854785 -114.932768) (xy 343.855294 -114.960654)
			(xy 343.854785 -114.98854) (xy 343.846665 -115.043716) (xy 343.830597 -115.097123) (xy 343.806925 -115.14762)
			(xy 343.776152 -115.194133) (xy 343.738935 -115.23567) (xy 343.696067 -115.271345) (xy 343.648461 -115.300399)
			(xy 343.597132 -115.322211) (xy 343.543175 -115.336317) (xy 343.487738 -115.342417) (xy 343.432004 -115.34038)
			(xy 343.377161 -115.33025) (xy 343.324377 -115.312243) (xy 343.274777 -115.286742) (xy 343.229419 -115.254291)
			(xy 343.18927 -115.215582) (xy 343.155184 -115.171439) (xy 343.127888 -115.122804) (xy 343.107965 -115.070713)
			(xy 343.095839 -115.016276) (xy 343.091768 -114.960654) (xy 342.327721 -114.960654) (xy 342.327991 -114.962486)
			(xy 342.3285 -114.990372) (xy 342.327991 -115.018258) (xy 342.319871 -115.073434) (xy 342.303803 -115.126841)
			(xy 342.280131 -115.177338) (xy 342.249358 -115.223851) (xy 342.212141 -115.265388) (xy 342.169273 -115.301063)
			(xy 342.121667 -115.330117) (xy 342.070338 -115.351929) (xy 342.016381 -115.366035) (xy 341.960944 -115.372135)
			(xy 341.90521 -115.370098) (xy 341.850367 -115.359968) (xy 341.797583 -115.341961) (xy 341.747983 -115.31646)
			(xy 341.702625 -115.284009) (xy 341.662476 -115.2453) (xy 341.62839 -115.201157) (xy 341.601094 -115.152522)
			(xy 341.581171 -115.100431) (xy 341.569045 -115.045994) (xy 341.564974 -114.990372) (xy 340.943328 -114.990372)
			(xy 340.949279 -115.030812) (xy 340.949788 -115.058698) (xy 340.949279 -115.086584) (xy 340.941159 -115.14176)
			(xy 340.925091 -115.195167) (xy 340.901419 -115.245664) (xy 340.870646 -115.292177) (xy 340.833429 -115.333714)
			(xy 340.790561 -115.369389) (xy 340.742955 -115.398443) (xy 340.691626 -115.420255) (xy 340.637669 -115.434361)
			(xy 340.582232 -115.440461) (xy 340.526498 -115.438424) (xy 340.471655 -115.428294) (xy 340.418871 -115.410287)
			(xy 340.369271 -115.384786) (xy 340.323913 -115.352335) (xy 340.283764 -115.313626) (xy 340.249678 -115.269483)
			(xy 340.222382 -115.220848) (xy 340.202459 -115.168757) (xy 340.190333 -115.11432) (xy 340.186262 -115.058698)
			(xy 339.579835 -115.058698) (xy 339.574639 -115.094008) (xy 339.558571 -115.147415) (xy 339.534899 -115.197912)
			(xy 339.504126 -115.244425) (xy 339.466909 -115.285962) (xy 339.424041 -115.321637) (xy 339.376435 -115.350691)
			(xy 339.325106 -115.372503) (xy 339.271149 -115.386609) (xy 339.215712 -115.392709) (xy 339.159978 -115.390672)
			(xy 339.105135 -115.380542) (xy 339.052351 -115.362535) (xy 339.002751 -115.337034) (xy 338.957393 -115.304583)
			(xy 338.917244 -115.265874) (xy 338.883158 -115.221731) (xy 338.855862 -115.173096) (xy 338.835939 -115.121005)
			(xy 338.823813 -115.066568) (xy 338.819742 -115.010946) (xy 322.07162 -115.010946) (xy 322.117897 -115.030611)
			(xy 322.165503 -115.059665) (xy 322.208371 -115.09534) (xy 322.245588 -115.136877) (xy 322.276361 -115.18339)
			(xy 322.300033 -115.233887) (xy 322.316101 -115.287294) (xy 322.324221 -115.34247) (xy 322.32473 -115.370356)
			(xy 322.324221 -115.398242) (xy 322.316101 -115.453418) (xy 322.300033 -115.506825) (xy 322.276361 -115.557322)
			(xy 322.245588 -115.603835) (xy 322.208371 -115.645372) (xy 322.165503 -115.681047) (xy 322.117897 -115.710101)
			(xy 322.066568 -115.731913) (xy 322.012611 -115.746019) (xy 321.957174 -115.752119) (xy 321.90144 -115.750082)
			(xy 321.846597 -115.739952) (xy 321.793813 -115.721945) (xy 321.744213 -115.696444) (xy 321.698855 -115.663993)
			(xy 321.658706 -115.625284) (xy 321.62462 -115.581141) (xy 321.597324 -115.532506) (xy 321.577401 -115.480415)
			(xy 321.565275 -115.425978) (xy 321.561204 -115.370356) (xy 320.281554 -115.370356) (xy 320.743834 -115.832636)
			(xy 325.17918 -115.832636) (xy 325.183251 -115.777014) (xy 325.195377 -115.722577) (xy 325.2153 -115.670486)
			(xy 325.242596 -115.621851) (xy 325.276682 -115.577708) (xy 325.316831 -115.538999) (xy 325.362189 -115.506548)
			(xy 325.411789 -115.481047) (xy 325.464573 -115.46304) (xy 325.519416 -115.45291) (xy 325.57515 -115.450873)
			(xy 325.630587 -115.456973) (xy 325.684544 -115.471079) (xy 325.735873 -115.492891) (xy 325.783479 -115.521945)
			(xy 325.826347 -115.55762) (xy 325.863564 -115.599157) (xy 325.894337 -115.64567) (xy 325.918009 -115.696167)
			(xy 325.934077 -115.749574) (xy 325.942197 -115.80475) (xy 325.942706 -115.832636) (xy 325.942197 -115.860522)
			(xy 325.934077 -115.915698) (xy 325.918009 -115.969105) (xy 325.894337 -116.019602) (xy 325.863564 -116.066115)
			(xy 325.826347 -116.107652) (xy 325.783479 -116.143327) (xy 325.735873 -116.172381) (xy 325.684544 -116.194193)
			(xy 325.630587 -116.208299) (xy 325.57515 -116.214399) (xy 325.519416 -116.212362) (xy 325.464573 -116.202232)
			(xy 325.411789 -116.184225) (xy 325.362189 -116.158724) (xy 325.316831 -116.126273) (xy 325.276682 -116.087564)
			(xy 325.242596 -116.043421) (xy 325.2153 -115.994786) (xy 325.195377 -115.942695) (xy 325.183251 -115.888258)
			(xy 325.17918 -115.832636) (xy 320.743834 -115.832636) (xy 321.446652 -116.535454) (xy 321.455803 -116.543494)
			(xy 321.479 -116.550799) (xy 321.491102 -116.549424) (xy 321.585336 -116.532914) (xy 321.604894 -116.518182)
			(xy 321.610228 -116.50726) (xy 321.610228 -116.506752) (xy 321.622179 -116.482607) (xy 321.651832 -116.43763)
			(xy 321.687516 -116.397271) (xy 321.728522 -116.362331) (xy 321.774034 -116.333507) (xy 321.823148 -116.31137)
			(xy 321.874888 -116.296361) (xy 321.928224 -116.288778) (xy 321.95516 -116.288312) (xy 321.982413 -116.288793)
			(xy 322.036364 -116.296545) (xy 322.088663 -116.311897) (xy 322.138244 -116.334536) (xy 322.184098 -116.364002)
			(xy 322.225292 -116.399694) (xy 322.260986 -116.440885) (xy 322.290455 -116.486738) (xy 322.313096 -116.536318)
			(xy 322.328451 -116.588616) (xy 322.334282 -116.62918) (xy 337.337906 -116.62918) (xy 337.341977 -116.573558)
			(xy 337.354103 -116.519121) (xy 337.374026 -116.46703) (xy 337.401322 -116.418395) (xy 337.435408 -116.374252)
			(xy 337.475557 -116.335543) (xy 337.520915 -116.303092) (xy 337.570515 -116.277591) (xy 337.623299 -116.259584)
			(xy 337.678142 -116.249454) (xy 337.733876 -116.247417) (xy 337.789313 -116.253517) (xy 337.84327 -116.267623)
			(xy 337.894599 -116.289435) (xy 337.942205 -116.318489) (xy 337.985073 -116.354164) (xy 338.02229 -116.395701)
			(xy 338.053063 -116.442214) (xy 338.076735 -116.492711) (xy 338.092803 -116.546118) (xy 338.100923 -116.601294)
			(xy 338.101432 -116.62918) (xy 338.100923 -116.657066) (xy 338.092803 -116.712242) (xy 338.076735 -116.765649)
			(xy 338.053063 -116.816146) (xy 338.02229 -116.862659) (xy 337.985073 -116.904196) (xy 337.942205 -116.939871)
			(xy 337.894599 -116.968925) (xy 337.84327 -116.990737) (xy 337.789313 -117.004843) (xy 337.733876 -117.010943)
			(xy 337.678142 -117.008906) (xy 337.623299 -116.998776) (xy 337.570515 -116.980769) (xy 337.520915 -116.955268)
			(xy 337.475557 -116.922817) (xy 337.435408 -116.884108) (xy 337.401322 -116.839965) (xy 337.374026 -116.79133)
			(xy 337.354103 -116.739239) (xy 337.341977 -116.684802) (xy 337.337906 -116.62918) (xy 322.334282 -116.62918)
			(xy 322.336206 -116.642567) (xy 322.336668 -116.66982) (xy 322.336223 -116.696772) (xy 322.328652 -116.750141)
			(xy 322.313636 -116.80191) (xy 322.291475 -116.851047) (xy 322.262611 -116.896571) (xy 322.22762 -116.937573)
			(xy 322.1872 -116.973236) (xy 322.142158 -117.002846) (xy 322.117974 -117.014752) (xy 322.11772 -117.014752)
			(xy 322.107119 -117.020666) (xy 322.092524 -117.040013) (xy 322.08978 -117.051836) (xy 322.075556 -117.133878)
			(xy 322.074124 -117.145985) (xy 322.081436 -117.169206) (xy 322.089526 -117.178328) (xy 322.301625 -117.390446)
			(xy 322.942518 -117.390446) (xy 322.942518 -117.335954) (xy 322.950273 -117.282015) (xy 322.965624 -117.229729)
			(xy 322.98826 -117.18016) (xy 323.017719 -117.134317) (xy 323.053402 -117.093132) (xy 323.094583 -117.057444)
			(xy 323.140423 -117.02798) (xy 323.18999 -117.005339) (xy 323.242274 -116.989982) (xy 323.296212 -116.982221)
			(xy 323.323458 -116.981732) (xy 323.352374 -116.982268) (xy 323.409545 -116.990992) (xy 323.464744 -117.008245)
			(xy 323.516706 -117.033634) (xy 323.564241 -117.066575) (xy 323.606258 -117.106313) (xy 323.624448 -117.128798)
			(xy 323.632044 -117.137617) (xy 323.652953 -117.147794) (xy 323.66458 -117.148356) (xy 323.744336 -117.148356)
			(xy 323.755971 -117.147839) (xy 323.776881 -117.137636) (xy 323.784468 -117.128798) (xy 323.802677 -117.106329)
			(xy 323.844693 -117.066593) (xy 323.892224 -117.033653) (xy 323.944182 -117.008262) (xy 323.999376 -116.991002)
			(xy 324.056543 -116.982269) (xy 324.085458 -116.981732) (xy 324.112716 -116.982112) (xy 324.166677 -116.989865)
			(xy 324.218985 -117.005219) (xy 324.268576 -117.027862) (xy 324.314439 -117.057332) (xy 324.355641 -117.093029)
			(xy 324.363966 -117.102636) (xy 325.17918 -117.102636) (xy 325.183251 -117.047014) (xy 325.195377 -116.992577)
			(xy 325.2153 -116.940486) (xy 325.242596 -116.891851) (xy 325.276682 -116.847708) (xy 325.316831 -116.808999)
			(xy 325.362189 -116.776548) (xy 325.411789 -116.751047) (xy 325.464573 -116.73304) (xy 325.519416 -116.72291)
			(xy 325.57515 -116.720873) (xy 325.630587 -116.726973) (xy 325.684544 -116.741079) (xy 325.735873 -116.762891)
			(xy 325.783479 -116.791945) (xy 325.826347 -116.82762) (xy 325.863564 -116.869157) (xy 325.894337 -116.91567)
			(xy 325.918009 -116.966167) (xy 325.934077 -117.019574) (xy 325.942197 -117.07475) (xy 325.942706 -117.102636)
			(xy 325.942197 -117.130522) (xy 325.934077 -117.185698) (xy 325.918009 -117.239105) (xy 325.913756 -117.248178)
			(xy 339.938866 -117.248178) (xy 339.942937 -117.192556) (xy 339.955063 -117.138119) (xy 339.974986 -117.086028)
			(xy 340.002282 -117.037393) (xy 340.036368 -116.99325) (xy 340.076517 -116.954541) (xy 340.121875 -116.92209)
			(xy 340.171475 -116.896589) (xy 340.224259 -116.878582) (xy 340.279102 -116.868452) (xy 340.334836 -116.866415)
			(xy 340.390273 -116.872515) (xy 340.44423 -116.886621) (xy 340.495559 -116.908433) (xy 340.543165 -116.937487)
			(xy 340.586033 -116.973162) (xy 340.62325 -117.014699) (xy 340.654023 -117.061212) (xy 340.677695 -117.111709)
			(xy 340.693763 -117.165116) (xy 340.701883 -117.220292) (xy 340.702392 -117.248178) (xy 340.954866 -117.248178)
			(xy 340.958937 -117.192556) (xy 340.971063 -117.138119) (xy 340.990986 -117.086028) (xy 341.018282 -117.037393)
			(xy 341.052368 -116.99325) (xy 341.092517 -116.954541) (xy 341.137875 -116.92209) (xy 341.187475 -116.896589)
			(xy 341.240259 -116.878582) (xy 341.295102 -116.868452) (xy 341.350836 -116.866415) (xy 341.406273 -116.872515)
			(xy 341.46023 -116.886621) (xy 341.511559 -116.908433) (xy 341.559165 -116.937487) (xy 341.602033 -116.973162)
			(xy 341.63925 -117.014699) (xy 341.670023 -117.061212) (xy 341.693695 -117.111709) (xy 341.709763 -117.165116)
			(xy 341.717883 -117.220292) (xy 341.718392 -117.248178) (xy 341.970866 -117.248178) (xy 341.974937 -117.192556)
			(xy 341.987063 -117.138119) (xy 342.006986 -117.086028) (xy 342.034282 -117.037393) (xy 342.068368 -116.99325)
			(xy 342.108517 -116.954541) (xy 342.153875 -116.92209) (xy 342.203475 -116.896589) (xy 342.256259 -116.878582)
			(xy 342.311102 -116.868452) (xy 342.366836 -116.866415) (xy 342.422273 -116.872515) (xy 342.47623 -116.886621)
			(xy 342.527559 -116.908433) (xy 342.575165 -116.937487) (xy 342.618033 -116.973162) (xy 342.65525 -117.014699)
			(xy 342.686023 -117.061212) (xy 342.709695 -117.111709) (xy 342.725763 -117.165116) (xy 342.733883 -117.220292)
			(xy 342.734392 -117.248178) (xy 342.733883 -117.276064) (xy 342.725763 -117.33124) (xy 342.709695 -117.384647)
			(xy 342.686023 -117.435144) (xy 342.65525 -117.481657) (xy 342.618033 -117.523194) (xy 342.575165 -117.558869)
			(xy 342.527559 -117.587923) (xy 342.47623 -117.609735) (xy 342.422273 -117.623841) (xy 342.366836 -117.629941)
			(xy 342.311102 -117.627904) (xy 342.256259 -117.617774) (xy 342.203475 -117.599767) (xy 342.153875 -117.574266)
			(xy 342.108517 -117.541815) (xy 342.068368 -117.503106) (xy 342.034282 -117.458963) (xy 342.006986 -117.410328)
			(xy 341.987063 -117.358237) (xy 341.974937 -117.3038) (xy 341.970866 -117.248178) (xy 341.718392 -117.248178)
			(xy 341.717883 -117.276064) (xy 341.709763 -117.33124) (xy 341.693695 -117.384647) (xy 341.670023 -117.435144)
			(xy 341.63925 -117.481657) (xy 341.602033 -117.523194) (xy 341.559165 -117.558869) (xy 341.511559 -117.587923)
			(xy 341.46023 -117.609735) (xy 341.406273 -117.623841) (xy 341.350836 -117.629941) (xy 341.295102 -117.627904)
			(xy 341.240259 -117.617774) (xy 341.187475 -117.599767) (xy 341.137875 -117.574266) (xy 341.092517 -117.541815)
			(xy 341.052368 -117.503106) (xy 341.018282 -117.458963) (xy 340.990986 -117.410328) (xy 340.971063 -117.358237)
			(xy 340.958937 -117.3038) (xy 340.954866 -117.248178) (xy 340.702392 -117.248178) (xy 340.701883 -117.276064)
			(xy 340.693763 -117.33124) (xy 340.677695 -117.384647) (xy 340.654023 -117.435144) (xy 340.62325 -117.481657)
			(xy 340.586033 -117.523194) (xy 340.543165 -117.558869) (xy 340.495559 -117.587923) (xy 340.44423 -117.609735)
			(xy 340.390273 -117.623841) (xy 340.334836 -117.629941) (xy 340.279102 -117.627904) (xy 340.224259 -117.617774)
			(xy 340.171475 -117.599767) (xy 340.121875 -117.574266) (xy 340.076517 -117.541815) (xy 340.036368 -117.503106)
			(xy 340.002282 -117.458963) (xy 339.974986 -117.410328) (xy 339.955063 -117.358237) (xy 339.942937 -117.3038)
			(xy 339.938866 -117.248178) (xy 325.913756 -117.248178) (xy 325.894337 -117.289602) (xy 325.863564 -117.336115)
			(xy 325.826347 -117.377652) (xy 325.783479 -117.413327) (xy 325.735873 -117.442381) (xy 325.684544 -117.464193)
			(xy 325.630587 -117.478299) (xy 325.57515 -117.484399) (xy 325.519416 -117.482362) (xy 325.464573 -117.472232)
			(xy 325.411789 -117.454225) (xy 325.362189 -117.428724) (xy 325.316831 -117.396273) (xy 325.276682 -117.357564)
			(xy 325.242596 -117.313421) (xy 325.2153 -117.264786) (xy 325.195377 -117.212695) (xy 325.183251 -117.158258)
			(xy 325.17918 -117.102636) (xy 324.363966 -117.102636) (xy 324.391343 -117.134227) (xy 324.420818 -117.180087)
			(xy 324.443466 -117.229675) (xy 324.458826 -117.281982) (xy 324.466585 -117.335942) (xy 324.466585 -117.390458)
			(xy 324.458826 -117.444418) (xy 324.443466 -117.496725) (xy 324.420818 -117.546313) (xy 324.391343 -117.592173)
			(xy 324.355641 -117.633371) (xy 324.314439 -117.669068) (xy 324.268576 -117.698538) (xy 324.218985 -117.721181)
			(xy 324.166677 -117.736535) (xy 324.112716 -117.744288) (xy 324.085458 -117.744748) (xy 324.056542 -117.744208)
			(xy 323.999371 -117.735486) (xy 323.944171 -117.718234) (xy 323.892209 -117.692847) (xy 323.844675 -117.659906)
			(xy 323.802658 -117.620167) (xy 323.784468 -117.597682) (xy 323.776868 -117.588867) (xy 323.755962 -117.578688)
			(xy 323.744336 -117.578124) (xy 323.66458 -117.578124) (xy 323.652947 -117.578657) (xy 323.632037 -117.588849)
			(xy 323.624448 -117.597682) (xy 323.606225 -117.620139) (xy 323.564213 -117.659876) (xy 323.516685 -117.692819)
			(xy 323.464729 -117.718212) (xy 323.409537 -117.735474) (xy 323.352372 -117.74421) (xy 323.323458 -117.744748)
			(xy 323.296212 -117.744179) (xy 323.242274 -117.736418) (xy 323.18999 -117.721061) (xy 323.140423 -117.69842)
			(xy 323.094583 -117.668956) (xy 323.053402 -117.633268) (xy 323.017719 -117.592083) (xy 322.98826 -117.54624)
			(xy 322.965624 -117.496671) (xy 322.950273 -117.444385) (xy 322.942518 -117.390446) (xy 322.301625 -117.390446)
			(xy 323.378971 -118.467886) (xy 329.682346 -118.467886) (xy 329.686417 -118.412264) (xy 329.698543 -118.357827)
			(xy 329.718466 -118.305736) (xy 329.745762 -118.257101) (xy 329.779848 -118.212958) (xy 329.819997 -118.174249)
			(xy 329.865355 -118.141798) (xy 329.914955 -118.116297) (xy 329.967739 -118.09829) (xy 330.022582 -118.08816)
			(xy 330.078316 -118.086123) (xy 330.133753 -118.092223) (xy 330.18771 -118.106329) (xy 330.239039 -118.128141)
			(xy 330.286645 -118.157195) (xy 330.329513 -118.19287) (xy 330.36673 -118.234407) (xy 330.397503 -118.28092)
			(xy 330.421175 -118.331417) (xy 330.437243 -118.384824) (xy 330.445363 -118.44) (xy 330.445872 -118.467886)
			(xy 330.445363 -118.495772) (xy 330.437243 -118.550948) (xy 330.421175 -118.604355) (xy 330.397503 -118.654852)
			(xy 330.36673 -118.701365) (xy 330.329513 -118.742902) (xy 330.308679 -118.76024) (xy 334.764378 -118.76024)
			(xy 334.768449 -118.704618) (xy 334.780575 -118.650181) (xy 334.800498 -118.59809) (xy 334.827794 -118.549455)
			(xy 334.86188 -118.505312) (xy 334.902029 -118.466603) (xy 334.947387 -118.434152) (xy 334.996987 -118.408651)
			(xy 335.049771 -118.390644) (xy 335.104614 -118.380514) (xy 335.160348 -118.378477) (xy 335.215785 -118.384577)
			(xy 335.269742 -118.398683) (xy 335.321071 -118.420495) (xy 335.368677 -118.449549) (xy 335.411545 -118.485224)
			(xy 335.448762 -118.526761) (xy 335.479535 -118.573274) (xy 335.503207 -118.623771) (xy 335.519275 -118.677178)
			(xy 335.527395 -118.732354) (xy 335.527904 -118.76024) (xy 335.527395 -118.788126) (xy 335.519275 -118.843302)
			(xy 335.503207 -118.896709) (xy 335.479535 -118.947206) (xy 335.448762 -118.993719) (xy 335.411545 -119.035256)
			(xy 335.368677 -119.070931) (xy 335.321071 -119.099985) (xy 335.269742 -119.121797) (xy 335.215785 -119.135903)
			(xy 335.160348 -119.142003) (xy 335.104614 -119.139966) (xy 335.049771 -119.129836) (xy 334.996987 -119.111829)
			(xy 334.947387 -119.086328) (xy 334.902029 -119.053877) (xy 334.86188 -119.015168) (xy 334.827794 -118.971025)
			(xy 334.800498 -118.92239) (xy 334.780575 -118.870299) (xy 334.768449 -118.815862) (xy 334.764378 -118.76024)
			(xy 330.308679 -118.76024) (xy 330.286645 -118.778577) (xy 330.239039 -118.807631) (xy 330.18771 -118.829443)
			(xy 330.133753 -118.843549) (xy 330.078316 -118.849649) (xy 330.022582 -118.847612) (xy 329.967739 -118.837482)
			(xy 329.914955 -118.819475) (xy 329.865355 -118.793974) (xy 329.819997 -118.761523) (xy 329.779848 -118.722814)
			(xy 329.745762 -118.678671) (xy 329.718466 -118.630036) (xy 329.698543 -118.577945) (xy 329.686417 -118.523508)
			(xy 329.682346 -118.467886) (xy 323.378971 -118.467886) (xy 324.31856 -119.407557) (xy 326.699509 -119.407557)
			(xy 326.699509 -119.353043) (xy 326.707268 -119.299083) (xy 326.722627 -119.246777) (xy 326.745274 -119.197189)
			(xy 326.774748 -119.151329) (xy 326.810449 -119.11013) (xy 326.85165 -119.074432) (xy 326.897512 -119.044962)
			(xy 326.947101 -119.022318) (xy 326.999408 -119.006962) (xy 327.053369 -118.999207) (xy 327.080626 -118.998746)
			(xy 327.107997 -118.999186) (xy 327.162178 -119.007008) (xy 327.214682 -119.022503) (xy 327.264428 -119.045351)
			(xy 327.310394 -119.075082) (xy 327.331324 -119.092726) (xy 327.331578 -119.09298) (xy 327.33866 -119.098573)
			(xy 327.355581 -119.104814) (xy 327.364598 -119.105172) (xy 327.431654 -119.105172) (xy 327.440669 -119.104799)
			(xy 327.457587 -119.098563) (xy 327.464674 -119.09298) (xy 327.464674 -119.092726) (xy 327.464928 -119.092726)
			(xy 327.48588 -119.075111) (xy 327.531847 -119.045395) (xy 327.581589 -119.022554) (xy 327.634086 -119.007057)
			(xy 327.688258 -118.999223) (xy 327.715626 -118.998746) (xy 327.742873 -118.999326) (xy 327.796811 -119.007085)
			(xy 327.849096 -119.02244) (xy 327.898664 -119.04508) (xy 327.944506 -119.074543) (xy 327.985688 -119.11023)
			(xy 328.021372 -119.151415) (xy 328.050833 -119.197259) (xy 328.073469 -119.246828) (xy 328.088821 -119.299114)
			(xy 328.096576 -119.353053) (xy 328.096576 -119.407547) (xy 328.088821 -119.461486) (xy 328.084258 -119.477028)
			(xy 331.808072 -119.477028) (xy 331.812143 -119.421406) (xy 331.824269 -119.366969) (xy 331.844192 -119.314878)
			(xy 331.871488 -119.266243) (xy 331.905574 -119.2221) (xy 331.945723 -119.183391) (xy 331.991081 -119.15094)
			(xy 332.040681 -119.125439) (xy 332.093465 -119.107432) (xy 332.148308 -119.097302) (xy 332.204042 -119.095265)
			(xy 332.259479 -119.101365) (xy 332.313436 -119.115471) (xy 332.364765 -119.137283) (xy 332.412371 -119.166337)
			(xy 332.455239 -119.202012) (xy 332.492456 -119.243549) (xy 332.523229 -119.290062) (xy 332.546901 -119.340559)
			(xy 332.562969 -119.393966) (xy 332.571089 -119.449142) (xy 332.571598 -119.477028) (xy 332.571089 -119.504914)
			(xy 332.562969 -119.56009) (xy 332.546901 -119.613497) (xy 332.523229 -119.663994) (xy 332.492456 -119.710507)
			(xy 332.455239 -119.752044) (xy 332.426164 -119.77624) (xy 332.735934 -119.77624) (xy 332.740005 -119.720618)
			(xy 332.752131 -119.666181) (xy 332.772054 -119.61409) (xy 332.79935 -119.565455) (xy 332.833436 -119.521312)
			(xy 332.873585 -119.482603) (xy 332.918943 -119.450152) (xy 332.968543 -119.424651) (xy 333.021327 -119.406644)
			(xy 333.07617 -119.396514) (xy 333.131904 -119.394477) (xy 333.187341 -119.400577) (xy 333.241298 -119.414683)
			(xy 333.292627 -119.436495) (xy 333.340233 -119.465549) (xy 333.383101 -119.501224) (xy 333.420318 -119.542761)
			(xy 333.451091 -119.589274) (xy 333.474763 -119.639771) (xy 333.490831 -119.693178) (xy 333.494607 -119.718836)
			(xy 339.736428 -119.718836) (xy 339.740499 -119.663214) (xy 339.752625 -119.608777) (xy 339.772548 -119.556686)
			(xy 339.799844 -119.508051) (xy 339.83393 -119.463908) (xy 339.874079 -119.425199) (xy 339.919437 -119.392748)
			(xy 339.969037 -119.367247) (xy 340.021821 -119.34924) (xy 340.076664 -119.33911) (xy 340.132398 -119.337073)
			(xy 340.187835 -119.343173) (xy 340.241792 -119.357279) (xy 340.293121 -119.379091) (xy 340.340727 -119.408145)
			(xy 340.383595 -119.44382) (xy 340.420812 -119.485357) (xy 340.451585 -119.53187) (xy 340.475257 -119.582367)
			(xy 340.491325 -119.635774) (xy 340.499445 -119.69095) (xy 340.499954 -119.718836) (xy 340.499445 -119.746722)
			(xy 340.491325 -119.801898) (xy 340.475257 -119.855305) (xy 340.451585 -119.905802) (xy 340.420812 -119.952315)
			(xy 340.383595 -119.993852) (xy 340.340727 -120.029527) (xy 340.293121 -120.058581) (xy 340.241792 -120.080393)
			(xy 340.187835 -120.094499) (xy 340.132398 -120.100599) (xy 340.076664 -120.098562) (xy 340.021821 -120.088432)
			(xy 339.969037 -120.070425) (xy 339.919437 -120.044924) (xy 339.874079 -120.012473) (xy 339.83393 -119.973764)
			(xy 339.799844 -119.929621) (xy 339.772548 -119.880986) (xy 339.752625 -119.828895) (xy 339.740499 -119.774458)
			(xy 339.736428 -119.718836) (xy 333.494607 -119.718836) (xy 333.498951 -119.748354) (xy 333.49946 -119.77624)
			(xy 333.498951 -119.804126) (xy 333.490831 -119.859302) (xy 333.474763 -119.912709) (xy 333.451091 -119.963206)
			(xy 333.420318 -120.009719) (xy 333.383101 -120.051256) (xy 333.340233 -120.086931) (xy 333.292627 -120.115985)
			(xy 333.241298 -120.137797) (xy 333.187341 -120.151903) (xy 333.131904 -120.158003) (xy 333.07617 -120.155966)
			(xy 333.021327 -120.145836) (xy 332.968543 -120.127829) (xy 332.918943 -120.102328) (xy 332.873585 -120.069877)
			(xy 332.833436 -120.031168) (xy 332.79935 -119.987025) (xy 332.772054 -119.93839) (xy 332.752131 -119.886299)
			(xy 332.740005 -119.831862) (xy 332.735934 -119.77624) (xy 332.426164 -119.77624) (xy 332.412371 -119.787719)
			(xy 332.364765 -119.816773) (xy 332.313436 -119.838585) (xy 332.259479 -119.852691) (xy 332.204042 -119.858791)
			(xy 332.148308 -119.856754) (xy 332.093465 -119.846624) (xy 332.040681 -119.828617) (xy 331.991081 -119.803116)
			(xy 331.945723 -119.770665) (xy 331.905574 -119.731956) (xy 331.871488 -119.687813) (xy 331.844192 -119.639178)
			(xy 331.824269 -119.587087) (xy 331.812143 -119.53265) (xy 331.808072 -119.477028) (xy 328.084258 -119.477028)
			(xy 328.073469 -119.513772) (xy 328.050833 -119.563341) (xy 328.021372 -119.609185) (xy 327.985688 -119.65037)
			(xy 327.944506 -119.686057) (xy 327.898664 -119.71552) (xy 327.849096 -119.73816) (xy 327.796811 -119.753515)
			(xy 327.742873 -119.761274) (xy 327.715626 -119.761762) (xy 327.688256 -119.76129) (xy 327.634077 -119.753475)
			(xy 327.581573 -119.737988) (xy 327.531826 -119.715147) (xy 327.48586 -119.685423) (xy 327.464928 -119.667782)
			(xy 327.464674 -119.667528) (xy 327.457577 -119.661958) (xy 327.440668 -119.655703) (xy 327.431654 -119.655336)
			(xy 327.364598 -119.655336) (xy 327.35558 -119.655684) (xy 327.338663 -119.661937) (xy 327.331578 -119.667528)
			(xy 327.331578 -119.667782) (xy 327.331324 -119.667782) (xy 327.310391 -119.685421) (xy 327.264419 -119.715133)
			(xy 327.214672 -119.737969) (xy 327.162171 -119.753461) (xy 327.107995 -119.761288) (xy 327.080626 -119.761762)
			(xy 327.053369 -119.761393) (xy 326.999408 -119.753638) (xy 326.947101 -119.738282) (xy 326.897512 -119.715638)
			(xy 326.85165 -119.686168) (xy 326.810449 -119.65047) (xy 326.774748 -119.609271) (xy 326.745274 -119.563411)
			(xy 326.722627 -119.513823) (xy 326.707268 -119.461517) (xy 326.699509 -119.407557) (xy 324.31856 -119.407557)
			(xy 324.804041 -119.89308) (xy 329.76896 -119.89308) (xy 329.773031 -119.837458) (xy 329.785157 -119.783021)
			(xy 329.80508 -119.73093) (xy 329.832376 -119.682295) (xy 329.866462 -119.638152) (xy 329.906611 -119.599443)
			(xy 329.951969 -119.566992) (xy 330.001569 -119.541491) (xy 330.054353 -119.523484) (xy 330.109196 -119.513354)
			(xy 330.16493 -119.511317) (xy 330.220367 -119.517417) (xy 330.274324 -119.531523) (xy 330.325653 -119.553335)
			(xy 330.373259 -119.582389) (xy 330.416127 -119.618064) (xy 330.453344 -119.659601) (xy 330.484117 -119.706114)
			(xy 330.507789 -119.756611) (xy 330.523857 -119.810018) (xy 330.531977 -119.865194) (xy 330.532486 -119.89308)
			(xy 330.531977 -119.920966) (xy 330.523857 -119.976142) (xy 330.507789 -120.029549) (xy 330.484117 -120.080046)
			(xy 330.453344 -120.126559) (xy 330.416127 -120.168096) (xy 330.373259 -120.203771) (xy 330.325653 -120.232825)
			(xy 330.274324 -120.254637) (xy 330.220367 -120.268743) (xy 330.16493 -120.274843) (xy 330.109196 -120.272806)
			(xy 330.054353 -120.262676) (xy 330.001569 -120.244669) (xy 329.951969 -120.219168) (xy 329.906611 -120.186717)
			(xy 329.866462 -120.148008) (xy 329.832376 -120.103865) (xy 329.80508 -120.05523) (xy 329.785157 -120.003139)
			(xy 329.773031 -119.948702) (xy 329.76896 -119.89308) (xy 324.804041 -119.89308) (xy 324.995794 -120.08485)
			(xy 325.003208 -120.091673) (xy 325.021796 -120.099404) (xy 325.031862 -120.099836) (xy 325.857616 -120.099836)
			(xy 325.88364 -120.100364) (xy 325.935044 -120.108527) (xy 325.984542 -120.124621) (xy 326.030918 -120.148249)
			(xy 326.073034 -120.178831) (xy 326.091804 -120.196864) (xy 326.387945 -120.493028) (xy 331.804008 -120.493028)
			(xy 331.808079 -120.437406) (xy 331.820205 -120.382969) (xy 331.840128 -120.330878) (xy 331.867424 -120.282243)
			(xy 331.90151 -120.2381) (xy 331.941659 -120.199391) (xy 331.987017 -120.16694) (xy 332.036617 -120.141439)
			(xy 332.089401 -120.123432) (xy 332.144244 -120.113302) (xy 332.199978 -120.111265) (xy 332.255415 -120.117365)
			(xy 332.309372 -120.131471) (xy 332.360701 -120.153283) (xy 332.408307 -120.182337) (xy 332.451175 -120.218012)
			(xy 332.488392 -120.259549) (xy 332.519165 -120.306062) (xy 332.542837 -120.356559) (xy 332.558905 -120.409966)
			(xy 332.567025 -120.465142) (xy 332.567534 -120.493028) (xy 332.567025 -120.520914) (xy 332.558905 -120.57609)
			(xy 332.542837 -120.629497) (xy 332.519165 -120.679994) (xy 332.488392 -120.726507) (xy 332.451175 -120.768044)
			(xy 332.4221 -120.79224) (xy 332.735934 -120.79224) (xy 332.740005 -120.736618) (xy 332.752131 -120.682181)
			(xy 332.772054 -120.63009) (xy 332.79935 -120.581455) (xy 332.833436 -120.537312) (xy 332.873585 -120.498603)
			(xy 332.918943 -120.466152) (xy 332.968543 -120.440651) (xy 333.021327 -120.422644) (xy 333.07617 -120.412514)
			(xy 333.131904 -120.410477) (xy 333.187341 -120.416577) (xy 333.241298 -120.430683) (xy 333.292627 -120.452495)
			(xy 333.340233 -120.481549) (xy 333.383101 -120.517224) (xy 333.420318 -120.558761) (xy 333.451091 -120.605274)
			(xy 333.474763 -120.655771) (xy 333.490831 -120.709178) (xy 333.498951 -120.764354) (xy 333.49946 -120.79224)
			(xy 334.891378 -120.79224) (xy 334.895449 -120.736618) (xy 334.907575 -120.682181) (xy 334.927498 -120.63009)
			(xy 334.954794 -120.581455) (xy 334.98888 -120.537312) (xy 335.029029 -120.498603) (xy 335.074387 -120.466152)
			(xy 335.123987 -120.440651) (xy 335.176771 -120.422644) (xy 335.231614 -120.412514) (xy 335.287348 -120.410477)
			(xy 335.342785 -120.416577) (xy 335.396742 -120.430683) (xy 335.448071 -120.452495) (xy 335.495677 -120.481549)
			(xy 335.538545 -120.517224) (xy 335.546679 -120.526302) (xy 338.193378 -120.526302) (xy 338.197449 -120.47068)
			(xy 338.209575 -120.416243) (xy 338.229498 -120.364152) (xy 338.256794 -120.315517) (xy 338.29088 -120.271374)
			(xy 338.331029 -120.232665) (xy 338.376387 -120.200214) (xy 338.425987 -120.174713) (xy 338.478771 -120.156706)
			(xy 338.533614 -120.146576) (xy 338.589348 -120.144539) (xy 338.644785 -120.150639) (xy 338.698742 -120.164745)
			(xy 338.750071 -120.186557) (xy 338.797677 -120.215611) (xy 338.840545 -120.251286) (xy 338.877762 -120.292823)
			(xy 338.908535 -120.339336) (xy 338.932207 -120.389833) (xy 338.948275 -120.44324) (xy 338.956395 -120.498416)
			(xy 338.956904 -120.526302) (xy 338.956395 -120.554188) (xy 338.948275 -120.609364) (xy 338.932207 -120.662771)
			(xy 338.908535 -120.713268) (xy 338.877762 -120.759781) (xy 338.840545 -120.801318) (xy 338.797677 -120.836993)
			(xy 338.750071 -120.866047) (xy 338.698742 -120.887859) (xy 338.644785 -120.901965) (xy 338.589348 -120.908065)
			(xy 338.533614 -120.906028) (xy 338.478771 -120.895898) (xy 338.425987 -120.877891) (xy 338.376387 -120.85239)
			(xy 338.331029 -120.819939) (xy 338.29088 -120.78123) (xy 338.256794 -120.737087) (xy 338.229498 -120.688452)
			(xy 338.209575 -120.636361) (xy 338.197449 -120.581924) (xy 338.193378 -120.526302) (xy 335.546679 -120.526302)
			(xy 335.575762 -120.558761) (xy 335.606535 -120.605274) (xy 335.630207 -120.655771) (xy 335.646275 -120.709178)
			(xy 335.654395 -120.764354) (xy 335.654904 -120.79224) (xy 335.654395 -120.820126) (xy 335.646275 -120.875302)
			(xy 335.630207 -120.928709) (xy 335.606535 -120.979206) (xy 335.575762 -121.025719) (xy 335.538545 -121.067256)
			(xy 335.495677 -121.102931) (xy 335.448071 -121.131985) (xy 335.396742 -121.153797) (xy 335.342785 -121.167903)
			(xy 335.287348 -121.174003) (xy 335.231614 -121.171966) (xy 335.176771 -121.161836) (xy 335.123987 -121.143829)
			(xy 335.074387 -121.118328) (xy 335.029029 -121.085877) (xy 334.98888 -121.047168) (xy 334.954794 -121.003025)
			(xy 334.927498 -120.95439) (xy 334.907575 -120.902299) (xy 334.895449 -120.847862) (xy 334.891378 -120.79224)
			(xy 333.49946 -120.79224) (xy 333.498951 -120.820126) (xy 333.490831 -120.875302) (xy 333.474763 -120.928709)
			(xy 333.451091 -120.979206) (xy 333.420318 -121.025719) (xy 333.383101 -121.067256) (xy 333.340233 -121.102931)
			(xy 333.292627 -121.131985) (xy 333.241298 -121.153797) (xy 333.187341 -121.167903) (xy 333.131904 -121.174003)
			(xy 333.07617 -121.171966) (xy 333.021327 -121.161836) (xy 332.968543 -121.143829) (xy 332.918943 -121.118328)
			(xy 332.873585 -121.085877) (xy 332.833436 -121.047168) (xy 332.79935 -121.003025) (xy 332.772054 -120.95439)
			(xy 332.752131 -120.902299) (xy 332.740005 -120.847862) (xy 332.735934 -120.79224) (xy 332.4221 -120.79224)
			(xy 332.408307 -120.803719) (xy 332.360701 -120.832773) (xy 332.309372 -120.854585) (xy 332.255415 -120.868691)
			(xy 332.199978 -120.874791) (xy 332.144244 -120.872754) (xy 332.089401 -120.862624) (xy 332.036617 -120.844617)
			(xy 331.987017 -120.819116) (xy 331.941659 -120.786665) (xy 331.90151 -120.747956) (xy 331.867424 -120.703813)
			(xy 331.840128 -120.655178) (xy 331.820205 -120.603087) (xy 331.808079 -120.54865) (xy 331.804008 -120.493028)
			(xy 326.387945 -120.493028) (xy 327.133631 -121.238772) (xy 329.7842 -121.238772) (xy 329.788271 -121.18315)
			(xy 329.800397 -121.128713) (xy 329.82032 -121.076622) (xy 329.847616 -121.027987) (xy 329.881702 -120.983844)
			(xy 329.921851 -120.945135) (xy 329.967209 -120.912684) (xy 330.016809 -120.887183) (xy 330.069593 -120.869176)
			(xy 330.124436 -120.859046) (xy 330.18017 -120.857009) (xy 330.235607 -120.863109) (xy 330.289564 -120.877215)
			(xy 330.340893 -120.899027) (xy 330.388499 -120.928081) (xy 330.431367 -120.963756) (xy 330.468584 -121.005293)
			(xy 330.499357 -121.051806) (xy 330.523029 -121.102303) (xy 330.539097 -121.15571) (xy 330.547217 -121.210886)
			(xy 330.547726 -121.238772) (xy 330.547217 -121.266658) (xy 330.539097 -121.321834) (xy 330.523029 -121.375241)
			(xy 330.499357 -121.425738) (xy 330.468584 -121.472251) (xy 330.431367 -121.513788) (xy 330.388499 -121.549463)
			(xy 330.340893 -121.578517) (xy 330.289564 -121.600329) (xy 330.235607 -121.614435) (xy 330.18017 -121.620535)
			(xy 330.124436 -121.618498) (xy 330.069593 -121.608368) (xy 330.016809 -121.590361) (xy 329.967209 -121.56486)
			(xy 329.921851 -121.532409) (xy 329.881702 -121.4937) (xy 329.847616 -121.449557) (xy 329.82032 -121.400922)
			(xy 329.800397 -121.348831) (xy 329.788271 -121.294394) (xy 329.7842 -121.238772) (xy 327.133631 -121.238772)
			(xy 329.343004 -123.448318) (xy 329.350407 -123.455155) (xy 329.369004 -123.462876) (xy 329.379072 -123.463304)
			(xy 329.822048 -123.463304) (xy 329.828197 -123.463099) (xy 329.840138 -123.460154) (xy 329.84567 -123.457462)
			(xy 329.873198 -123.44363) (xy 329.931615 -123.424065) (xy 329.992414 -123.414131) (xy 330.023216 -123.41352)
			(xy 330.023724 -123.41352) (xy 330.034096 -123.4136) (xy 330.054808 -123.414744) (xy 330.065126 -123.415806)
			(xy 330.07808 -123.41733) (xy 330.101956 -123.407424) (xy 330.163932 -123.330208) (xy 330.168974 -123.323365)
			(xy 330.174613 -123.30734) (xy 330.174729 -123.290352) (xy 330.172314 -123.282202) (xy 330.162954 -123.252595)
			(xy 330.152876 -123.191327) (xy 330.152248 -123.160282) (xy 330.152248 -123.160028) (xy 330.152725 -123.132772)
			(xy 330.160479 -123.078814) (xy 330.175834 -123.02651) (xy 330.198476 -122.976922) (xy 330.227945 -122.931063)
			(xy 330.263641 -122.889864) (xy 330.304837 -122.854164) (xy 330.350694 -122.824691) (xy 330.40028 -122.802045)
			(xy 330.452583 -122.786686) (xy 330.50654 -122.778927) (xy 330.561052 -122.778927) (xy 330.615009 -122.786684)
			(xy 330.667313 -122.802042) (xy 330.716899 -122.824688) (xy 330.762757 -122.85416) (xy 330.803953 -122.889858)
			(xy 330.83965 -122.931056) (xy 330.86912 -122.976915) (xy 330.891763 -123.026502) (xy 330.907119 -123.078807)
			(xy 330.914874 -123.132764) (xy 330.914872 -123.187276) (xy 330.907111 -123.241233) (xy 330.891749 -123.293535)
			(xy 330.869101 -123.34312) (xy 330.839626 -123.388976) (xy 330.803925 -123.43017) (xy 330.762725 -123.465864)
			(xy 330.716863 -123.495332) (xy 330.667275 -123.517972) (xy 330.61497 -123.533324) (xy 330.561012 -123.541076)
			(xy 330.533756 -123.541536) (xy 330.533248 -123.541536) (xy 330.522876 -123.541459) (xy 330.502164 -123.540313)
			(xy 330.491846 -123.53925) (xy 330.478892 -123.537726) (xy 330.455016 -123.547632) (xy 330.39304 -123.624848)
			(xy 330.388032 -123.631714) (xy 330.382377 -123.647726) (xy 330.382248 -123.664706) (xy 330.384658 -123.672854)
			(xy 330.39401 -123.702463) (xy 330.404093 -123.763729) (xy 330.404724 -123.794774) (xy 330.404724 -123.795028)
			(xy 330.404248 -123.822279) (xy 330.396488 -123.876226) (xy 330.381131 -123.92852) (xy 330.358487 -123.978097)
			(xy 330.32902 -124.023946) (xy 330.293327 -124.065136) (xy 330.252137 -124.100827) (xy 330.206286 -124.130293)
			(xy 330.156709 -124.152935) (xy 330.104415 -124.168291) (xy 330.050467 -124.176049) (xy 330.023216 -124.176536)
			(xy 329.992414 -124.17591) (xy 329.931614 -124.165991) (xy 329.873199 -124.146424) (xy 329.84567 -124.132594)
			(xy 329.84015 -124.129869) (xy 329.828202 -124.126919) (xy 329.822048 -124.126752) (xy 329.220068 -124.126752)
			(xy 329.194044 -124.126238) (xy 329.142639 -124.118071) (xy 329.093141 -124.101975) (xy 329.046765 -124.078344)
			(xy 329.004649 -124.047759) (xy 328.98588 -124.029724) (xy 328.425302 -123.469146) (xy 328.416085 -123.460939)
			(xy 328.392601 -123.453496) (xy 328.380344 -123.454922) (xy 328.298556 -123.4694) (xy 328.286575 -123.472273)
			(xy 328.267068 -123.487259) (xy 328.261218 -123.498102) (xy 328.249376 -123.522474) (xy 328.219822 -123.56789)
			(xy 328.184138 -123.608666) (xy 328.143043 -123.643982) (xy 328.097363 -123.673126) (xy 328.048019 -123.695513)
			(xy 327.996003 -123.710691) (xy 327.942363 -123.718355) (xy 327.91527 -123.718828) (xy 327.887898 -123.718397)
			(xy 327.833717 -123.710573) (xy 327.781213 -123.695077) (xy 327.731466 -123.672227) (xy 327.685502 -123.642494)
			(xy 327.664572 -123.624848) (xy 327.664318 -123.624594) (xy 327.657231 -123.619008) (xy 327.640315 -123.612761)
			(xy 327.631298 -123.612402) (xy 327.564242 -123.612402) (xy 327.555227 -123.612779) (xy 327.53831 -123.619013)
			(xy 327.531222 -123.624594) (xy 327.531222 -123.624848) (xy 327.530968 -123.624848) (xy 327.510035 -123.642489)
			(xy 327.464067 -123.672213) (xy 327.414321 -123.695059) (xy 327.361819 -123.710555) (xy 327.307641 -123.718384)
			(xy 327.252899 -123.718384) (xy 327.198721 -123.710555) (xy 327.146219 -123.695059) (xy 327.096473 -123.672213)
			(xy 327.050505 -123.642489) (xy 327.029572 -123.624848) (xy 327.029318 -123.624594) (xy 327.022231 -123.619008)
			(xy 327.005315 -123.612761) (xy 326.996298 -123.612402) (xy 326.929242 -123.612402) (xy 326.920227 -123.612779)
			(xy 326.90331 -123.619013) (xy 326.896222 -123.624594) (xy 326.896222 -123.624848) (xy 326.895968 -123.624848)
			(xy 326.875014 -123.642461) (xy 326.829048 -123.672178) (xy 326.779306 -123.69502) (xy 326.72681 -123.710517)
			(xy 326.672638 -123.718351) (xy 326.64527 -123.718828) (xy 326.618022 -123.7183) (xy 326.56408 -123.71054)
			(xy 326.511792 -123.695183) (xy 326.462221 -123.672542) (xy 326.416377 -123.643076) (xy 326.375192 -123.607386)
			(xy 326.339506 -123.566199) (xy 326.310044 -123.520353) (xy 326.287406 -123.47078) (xy 326.272053 -123.418491)
			(xy 326.264298 -123.364548) (xy 326.264298 -123.310052) (xy 326.272053 -123.256109) (xy 326.287406 -123.20382)
			(xy 326.310044 -123.154247) (xy 326.339506 -123.108401) (xy 326.375192 -123.067214) (xy 326.416377 -123.031524)
			(xy 326.462221 -123.002058) (xy 326.511792 -122.979417) (xy 326.56408 -122.96406) (xy 326.618022 -122.9563)
			(xy 326.64527 -122.955812) (xy 326.67264 -122.956293) (xy 326.726818 -122.964107) (xy 326.779321 -122.979592)
			(xy 326.829068 -123.002431) (xy 326.875036 -123.032152) (xy 326.895968 -123.049792) (xy 326.896222 -123.050046)
			(xy 326.903294 -123.055653) (xy 326.920222 -123.061886) (xy 326.929242 -123.062238) (xy 326.996298 -123.062238)
			(xy 327.005314 -123.061872) (xy 327.02223 -123.055629) (xy 327.029318 -123.050046) (xy 327.029318 -123.049792)
			(xy 327.029572 -123.049792) (xy 327.050505 -123.032151) (xy 327.096473 -123.002427) (xy 327.146219 -122.979581)
			(xy 327.198721 -122.964085) (xy 327.252899 -122.956256) (xy 327.307641 -122.956256) (xy 327.361819 -122.964085)
			(xy 327.414321 -122.979581) (xy 327.464067 -123.002427) (xy 327.510035 -123.032151) (xy 327.530968 -123.049792)
			(xy 327.531222 -123.050046) (xy 327.538294 -123.055653) (xy 327.555222 -123.061886) (xy 327.564242 -123.062238)
			(xy 327.631298 -123.062238) (xy 327.640314 -123.061872) (xy 327.65723 -123.055629) (xy 327.664318 -123.050046)
			(xy 327.664318 -123.049792) (xy 327.664572 -123.049792) (xy 327.685155 -123.032454) (xy 327.730281 -123.003132)
			(xy 327.754488 -122.991372) (xy 327.765475 -122.985703) (xy 327.780512 -122.966106) (xy 327.78319 -122.954034)
			(xy 327.797668 -122.872246) (xy 327.799092 -122.859985) (xy 327.79167 -122.836489) (xy 327.783444 -122.827288)
			(xy 325.73468 -120.77827) (xy 325.727284 -120.771424) (xy 325.708682 -120.763709) (xy 325.698612 -120.763284)
			(xy 325.049896 -120.763284) (xy 325.03805 -120.763906) (xy 325.01686 -120.7745) (xy 325.009256 -120.783604)
			(xy 324.960488 -120.848628) (xy 324.953872 -120.858475) (xy 324.949635 -120.881786) (xy 324.95236 -120.893332)
			(xy 324.95998 -120.924574) (xy 324.962266 -120.936258) (xy 324.976744 -120.955054) (xy 325.060818 -120.99544)
			(xy 325.071632 -121.000003) (xy 325.095071 -120.999743) (xy 325.105776 -120.994932) (xy 325.106284 -120.994932)
			(xy 325.13334 -120.981644) (xy 325.190617 -120.962868) (xy 325.250136 -120.953351) (xy 325.280274 -120.952768)
			(xy 325.307525 -120.953279) (xy 325.361473 -120.961032) (xy 325.413769 -120.976384) (xy 325.463347 -120.999021)
			(xy 325.509199 -121.028485) (xy 325.550391 -121.064173) (xy 325.586085 -121.105361) (xy 325.615555 -121.151209)
			(xy 325.638199 -121.200785) (xy 325.653557 -121.253078) (xy 325.661317 -121.307025) (xy 325.661782 -121.334276)
			(xy 325.661306 -121.361646) (xy 325.653491 -121.415825) (xy 325.638005 -121.468328) (xy 325.615165 -121.518075)
			(xy 325.585442 -121.564042) (xy 325.567802 -121.584974) (xy 325.567548 -121.585228) (xy 325.561979 -121.592327)
			(xy 325.555723 -121.609234) (xy 325.555356 -121.618248) (xy 325.555356 -121.685304) (xy 325.555699 -121.694323)
			(xy 325.561955 -121.71124) (xy 325.567548 -121.718324) (xy 325.567802 -121.718324) (xy 325.567802 -121.718578)
			(xy 325.585445 -121.739507) (xy 325.615156 -121.785481) (xy 325.637991 -121.835229) (xy 325.653481 -121.88773)
			(xy 325.661309 -121.941907) (xy 325.661782 -121.969276) (xy 325.661322 -121.996529) (xy 325.653568 -122.050482)
			(xy 325.638214 -122.102781) (xy 325.615572 -122.152363) (xy 325.586104 -122.198218) (xy 325.55041 -122.239411)
			(xy 325.509216 -122.275105) (xy 325.463361 -122.304573) (xy 325.413779 -122.327214) (xy 325.36148 -122.342568)
			(xy 325.307527 -122.350322) (xy 325.280274 -122.350784) (xy 325.251151 -122.350239) (xy 325.193579 -122.341409)
			(xy 325.13802 -122.323927) (xy 325.085764 -122.2982) (xy 325.038028 -122.264827) (xy 324.995922 -122.224584)
			(xy 324.960424 -122.178406) (xy 324.932361 -122.127367) (xy 324.912385 -122.072655) (xy 324.906132 -122.044206)
			(xy 324.903846 -122.032522) (xy 324.889368 -122.013726) (xy 324.805294 -121.97334) (xy 324.794479 -121.968779)
			(xy 324.77104 -121.969034) (xy 324.760336 -121.973848) (xy 324.759828 -121.973848) (xy 324.732769 -121.98713)
			(xy 324.675494 -122.005909) (xy 324.615975 -122.015428) (xy 324.585838 -122.016012) (xy 324.558586 -122.015509)
			(xy 324.504637 -122.007758) (xy 324.45234 -121.992407) (xy 324.40276 -121.969769) (xy 324.356907 -121.940305)
			(xy 324.315714 -121.904616) (xy 324.28002 -121.863426) (xy 324.250551 -121.817577) (xy 324.227908 -121.767999)
			(xy 324.212551 -121.715704) (xy 324.204794 -121.661756) (xy 324.20433 -121.634504) (xy 324.204791 -121.607134)
			(xy 324.212609 -121.552954) (xy 324.228099 -121.50045) (xy 324.250942 -121.450704) (xy 324.280668 -121.404737)
			(xy 324.29831 -121.383806) (xy 324.298564 -121.383552) (xy 324.304143 -121.37646) (xy 324.310392 -121.359547)
			(xy 324.310756 -121.350532) (xy 324.310756 -121.283476) (xy 324.31042 -121.274457) (xy 324.304159 -121.257539)
			(xy 324.298564 -121.250456) (xy 324.29831 -121.250456) (xy 324.29831 -121.250202) (xy 324.28066 -121.229279)
			(xy 324.250949 -121.183304) (xy 324.228115 -121.133554) (xy 324.212627 -121.081051) (xy 324.204802 -121.026874)
			(xy 324.20433 -120.999504) (xy 324.204839 -120.972112) (xy 324.212662 -120.917888) (xy 324.228162 -120.865342)
			(xy 324.251021 -120.815554) (xy 324.280768 -120.769549) (xy 324.316791 -120.728273) (xy 324.358348 -120.692575)
			(xy 324.404585 -120.66319) (xy 324.429374 -120.651524) (xy 324.441058 -120.64619) (xy 324.456298 -120.626886)
			(xy 324.47357 -120.532144) (xy 324.475058 -120.519914) (xy 324.467752 -120.496425) (xy 324.4596 -120.487186)
			(xy 319.749932 -115.777518) (xy 319.745543 -115.773397) (xy 319.735276 -115.767115) (xy 319.729612 -115.765072)
			(xy 319.729104 -115.765072) (xy 319.703563 -115.756617) (xy 319.654961 -115.733545) (xy 319.610082 -115.703874)
			(xy 319.569816 -115.668194) (xy 319.534961 -115.627211) (xy 319.506209 -115.581738) (xy 319.484129 -115.532678)
			(xy 319.469159 -115.481002) (xy 319.461597 -115.427736) (xy 319.461134 -115.400836) (xy 318.377752 -115.400836)
			(xy 321.450462 -118.473728) (xy 321.457308 -118.481126) (xy 321.465039 -118.499725) (xy 321.465448 -118.509796)
			(xy 321.465448 -122.192034) (xy 321.650614 -122.192034) (xy 321.651097 -122.164664) (xy 321.65891 -122.110486)
			(xy 321.674395 -122.057983) (xy 321.697233 -122.008236) (xy 321.726954 -121.962268) (xy 321.744594 -121.941336)
			(xy 321.744848 -121.941082) (xy 321.750454 -121.934009) (xy 321.756688 -121.917082) (xy 321.75704 -121.908062)
			(xy 321.75704 -121.841006) (xy 321.756693 -121.831988) (xy 321.75044 -121.81507) (xy 321.744848 -121.807986)
			(xy 321.744594 -121.807986) (xy 321.744594 -121.807732) (xy 321.726988 -121.786772) (xy 321.697264 -121.740808)
			(xy 321.674419 -121.691066) (xy 321.658922 -121.638568) (xy 321.65109 -121.584394) (xy 321.651087 -121.529657)
			(xy 321.658911 -121.475482) (xy 321.674401 -121.422982) (xy 321.69724 -121.373237) (xy 321.726957 -121.327269)
			(xy 321.744594 -121.306336) (xy 321.744848 -121.306082) (xy 321.750454 -121.299009) (xy 321.756688 -121.282082)
			(xy 321.75704 -121.273062) (xy 321.75704 -121.206006) (xy 321.756693 -121.196988) (xy 321.75044 -121.18007)
			(xy 321.744848 -121.172986) (xy 321.744594 -121.172986) (xy 321.744594 -121.172732) (xy 321.726988 -121.151772)
			(xy 321.697264 -121.105808) (xy 321.674419 -121.056066) (xy 321.658922 -121.003568) (xy 321.65109 -120.949394)
			(xy 321.651087 -120.894657) (xy 321.658911 -120.840482) (xy 321.674401 -120.787982) (xy 321.69724 -120.738237)
			(xy 321.726957 -120.692269) (xy 321.744594 -120.671336) (xy 321.744848 -120.671082) (xy 321.750454 -120.664009)
			(xy 321.756688 -120.647082) (xy 321.75704 -120.638062) (xy 321.75704 -120.571006) (xy 321.756693 -120.561988)
			(xy 321.75044 -120.54507) (xy 321.744848 -120.537986) (xy 321.744594 -120.537986) (xy 321.744594 -120.537732)
			(xy 321.726956 -120.516799) (xy 321.697244 -120.470827) (xy 321.674408 -120.421079) (xy 321.658917 -120.368579)
			(xy 321.651088 -120.314403) (xy 321.650614 -120.287034) (xy 321.6511 -120.259783) (xy 321.658856 -120.205835)
			(xy 321.674211 -120.15354) (xy 321.696853 -120.103963) (xy 321.726319 -120.058113) (xy 321.76201 -120.016922)
			(xy 321.803201 -119.981231) (xy 321.849051 -119.951765) (xy 321.898628 -119.929123) (xy 321.950923 -119.913768)
			(xy 322.004871 -119.906012) (xy 322.059373 -119.906012) (xy 322.113321 -119.913768) (xy 322.165616 -119.929123)
			(xy 322.215193 -119.951765) (xy 322.261043 -119.981231) (xy 322.302234 -120.016922) (xy 322.337925 -120.058113)
			(xy 322.367391 -120.103963) (xy 322.390033 -120.15354) (xy 322.405388 -120.205835) (xy 322.413144 -120.259783)
			(xy 322.41363 -120.287034) (xy 322.413201 -120.314406) (xy 322.405377 -120.368587) (xy 322.38988 -120.421091)
			(xy 322.36703 -120.470838) (xy 322.337296 -120.516802) (xy 322.31965 -120.537732) (xy 322.319396 -120.537986)
			(xy 322.313809 -120.545072) (xy 322.307563 -120.561989) (xy 322.307204 -120.571006) (xy 322.307204 -120.638062)
			(xy 322.307579 -120.647077) (xy 322.313814 -120.663994) (xy 322.319396 -120.671082) (xy 322.31965 -120.671082)
			(xy 322.31965 -120.671336) (xy 322.337325 -120.692241) (xy 322.36705 -120.738213) (xy 322.389895 -120.787964)
			(xy 322.40539 -120.84047) (xy 322.413215 -120.894653) (xy 322.413212 -120.949398) (xy 322.405379 -121.00358)
			(xy 322.389877 -121.056084) (xy 322.367025 -121.105832) (xy 322.337294 -121.1518) (xy 322.31965 -121.172732)
			(xy 322.319396 -121.172986) (xy 322.313809 -121.180072) (xy 322.307563 -121.196989) (xy 322.307493 -121.198756)
			(xy 322.685317 -121.198756) (xy 322.685317 -121.144244) (xy 322.693075 -121.090287) (xy 322.708433 -121.037983)
			(xy 322.731079 -120.988397) (xy 322.76055 -120.942539) (xy 322.796249 -120.901342) (xy 322.837447 -120.865644)
			(xy 322.883306 -120.836174) (xy 322.932892 -120.81353) (xy 322.985196 -120.798173) (xy 323.039154 -120.790416)
			(xy 323.06641 -120.789954) (xy 323.093781 -120.790401) (xy 323.147962 -120.798221) (xy 323.200465 -120.813714)
			(xy 323.250212 -120.836561) (xy 323.296177 -120.86629) (xy 323.317108 -120.883934) (xy 323.317362 -120.884188)
			(xy 323.324456 -120.889763) (xy 323.341367 -120.896017) (xy 323.350382 -120.89638) (xy 323.417438 -120.89638)
			(xy 323.426457 -120.896045) (xy 323.443374 -120.889783) (xy 323.450458 -120.884188) (xy 323.450458 -120.883934)
			(xy 323.450712 -120.883934) (xy 323.471671 -120.866328) (xy 323.517636 -120.83661) (xy 323.567376 -120.813767)
			(xy 323.619871 -120.798268) (xy 323.674043 -120.790432) (xy 323.70141 -120.789954) (xy 323.728658 -120.790517)
			(xy 323.782599 -120.798274) (xy 323.834888 -120.813628) (xy 323.884458 -120.836268) (xy 323.930303 -120.865731)
			(xy 323.971488 -120.901419) (xy 324.007175 -120.942605) (xy 324.036637 -120.98845) (xy 324.059275 -121.038022)
			(xy 324.074628 -121.090311) (xy 324.082384 -121.144252) (xy 324.082384 -121.198748) (xy 324.074628 -121.252689)
			(xy 324.059275 -121.304978) (xy 324.036637 -121.35455) (xy 324.007175 -121.400395) (xy 323.971488 -121.441581)
			(xy 323.930303 -121.477269) (xy 323.884458 -121.506732) (xy 323.834888 -121.529372) (xy 323.782599 -121.544726)
			(xy 323.728658 -121.552483) (xy 323.70141 -121.55297) (xy 323.67404 -121.552505) (xy 323.61986 -121.544688)
			(xy 323.567357 -121.529199) (xy 323.51761 -121.506357) (xy 323.471643 -121.476632) (xy 323.450712 -121.45899)
			(xy 323.450458 -121.458736) (xy 323.443364 -121.45316) (xy 323.426453 -121.446909) (xy 323.417438 -121.446544)
			(xy 323.350382 -121.446544) (xy 323.341363 -121.446883) (xy 323.324446 -121.453142) (xy 323.317362 -121.458736)
			(xy 323.317362 -121.45899) (xy 323.317108 -121.45899) (xy 323.296182 -121.476637) (xy 323.250208 -121.506348)
			(xy 323.200459 -121.529183) (xy 323.147957 -121.544672) (xy 323.09378 -121.552497) (xy 323.06641 -121.55297)
			(xy 323.039154 -121.552584) (xy 322.985197 -121.544827) (xy 322.932892 -121.52947) (xy 322.883306 -121.506826)
			(xy 322.837447 -121.477356) (xy 322.796249 -121.441658) (xy 322.76055 -121.400461) (xy 322.731079 -121.354603)
			(xy 322.708433 -121.305017) (xy 322.693075 -121.252713) (xy 322.685317 -121.198756) (xy 322.307493 -121.198756)
			(xy 322.307204 -121.206006) (xy 322.307204 -121.273062) (xy 322.307579 -121.282077) (xy 322.313814 -121.298994)
			(xy 322.319396 -121.306082) (xy 322.31965 -121.306082) (xy 322.31965 -121.306336) (xy 322.337325 -121.327241)
			(xy 322.36705 -121.373213) (xy 322.389895 -121.422964) (xy 322.40539 -121.47547) (xy 322.413215 -121.529653)
			(xy 322.413212 -121.584398) (xy 322.405379 -121.63858) (xy 322.389877 -121.691084) (xy 322.367025 -121.740832)
			(xy 322.337294 -121.7868) (xy 322.31965 -121.807732) (xy 322.319396 -121.807986) (xy 322.313809 -121.815072)
			(xy 322.307563 -121.831989) (xy 322.307204 -121.841006) (xy 322.307204 -121.908062) (xy 322.307579 -121.917077)
			(xy 322.313814 -121.933994) (xy 322.319396 -121.941082) (xy 322.31965 -121.941082) (xy 322.31965 -121.941336)
			(xy 322.337265 -121.962288) (xy 322.366982 -122.008254) (xy 322.389823 -122.057997) (xy 322.40532 -122.110493)
			(xy 322.413153 -122.164666) (xy 322.41363 -122.192034) (xy 322.413144 -122.219285) (xy 322.405388 -122.273233)
			(xy 322.390033 -122.325528) (xy 322.367391 -122.375105) (xy 322.337925 -122.420955) (xy 322.302234 -122.462146)
			(xy 322.261043 -122.497837) (xy 322.215193 -122.527303) (xy 322.165616 -122.549945) (xy 322.113321 -122.5653)
			(xy 322.059373 -122.573056) (xy 322.004871 -122.573056) (xy 321.950923 -122.5653) (xy 321.898628 -122.549945)
			(xy 321.849051 -122.527303) (xy 321.803201 -122.497837) (xy 321.76201 -122.462146) (xy 321.726319 -122.420955)
			(xy 321.696853 -122.375105) (xy 321.674211 -122.325528) (xy 321.658856 -122.273233) (xy 321.6511 -122.219285)
			(xy 321.650614 -122.192034) (xy 321.465448 -122.192034) (xy 321.465448 -124.215144) (xy 326.806558 -124.215144)
			(xy 326.810629 -124.159522) (xy 326.822755 -124.105085) (xy 326.842678 -124.052994) (xy 326.869974 -124.004359)
			(xy 326.90406 -123.960216) (xy 326.944209 -123.921507) (xy 326.989567 -123.889056) (xy 327.039167 -123.863555)
			(xy 327.091951 -123.845548) (xy 327.146794 -123.835418) (xy 327.202528 -123.833381) (xy 327.257965 -123.839481)
			(xy 327.311922 -123.853587) (xy 327.363251 -123.875399) (xy 327.410857 -123.904453) (xy 327.453725 -123.940128)
			(xy 327.490942 -123.981665) (xy 327.521715 -124.028178) (xy 327.545387 -124.078675) (xy 327.561455 -124.132082)
			(xy 327.569575 -124.187258) (xy 327.570084 -124.215144) (xy 327.569575 -124.24303) (xy 327.561455 -124.298206)
			(xy 327.545387 -124.351613) (xy 327.521715 -124.40211) (xy 327.490942 -124.448623) (xy 327.453725 -124.49016)
			(xy 327.410857 -124.525835) (xy 327.363251 -124.554889) (xy 327.311922 -124.576701) (xy 327.257965 -124.590807)
			(xy 327.202528 -124.596907) (xy 327.146794 -124.59487) (xy 327.091951 -124.58474) (xy 327.039167 -124.566733)
			(xy 326.989567 -124.541232) (xy 326.944209 -124.508781) (xy 326.90406 -124.470072) (xy 326.869974 -124.425929)
			(xy 326.842678 -124.377294) (xy 326.822755 -124.325203) (xy 326.810629 -124.270766) (xy 326.806558 -124.215144)
			(xy 321.465448 -124.215144) (xy 321.465448 -125.006608) (xy 321.466464 -125.016006) (xy 321.466464 -125.016514)
			(xy 321.468171 -125.023672) (xy 321.475006 -125.036696) (xy 321.479926 -125.042168) (xy 322.329368 -125.891544)
			(xy 327.375012 -125.891544) (xy 327.375438 -125.865229) (xy 327.382681 -125.813098) (xy 327.397008 -125.762454)
			(xy 327.418148 -125.714256) (xy 327.445702 -125.669413) (xy 327.479147 -125.628775) (xy 327.498202 -125.61062)
			(xy 327.505597 -125.603093) (xy 327.514125 -125.583817) (xy 327.514712 -125.573282) (xy 327.514712 -125.498606)
			(xy 327.51419 -125.488056) (xy 327.505649 -125.46876) (xy 327.498202 -125.461268) (xy 327.479138 -125.443121)
			(xy 327.445682 -125.402489) (xy 327.418124 -125.357647) (xy 327.396987 -125.309445) (xy 327.382671 -125.258796)
			(xy 327.375449 -125.206661) (xy 327.375012 -125.180344) (xy 327.375498 -125.153093) (xy 327.383254 -125.099145)
			(xy 327.398609 -125.04685) (xy 327.421251 -124.997273) (xy 327.450717 -124.951423) (xy 327.486408 -124.910232)
			(xy 327.527599 -124.874541) (xy 327.573449 -124.845075) (xy 327.623026 -124.822433) (xy 327.675321 -124.807078)
			(xy 327.729269 -124.799322) (xy 327.783771 -124.799322) (xy 327.837719 -124.807078) (xy 327.890014 -124.822433)
			(xy 327.939591 -124.845075) (xy 327.985441 -124.874541) (xy 328.026632 -124.910232) (xy 328.062323 -124.951423)
			(xy 328.091789 -124.997273) (xy 328.114431 -125.04685) (xy 328.129786 -125.099145) (xy 328.137542 -125.153093)
			(xy 328.138028 -125.180344) (xy 328.137581 -125.206659) (xy 328.130341 -125.258788) (xy 328.116017 -125.30943)
			(xy 328.094881 -125.357629) (xy 328.067331 -125.402472) (xy 328.03389 -125.443111) (xy 328.014838 -125.461268)
			(xy 328.007454 -125.468805) (xy 327.998919 -125.488073) (xy 327.998328 -125.498606) (xy 327.998328 -125.573282)
			(xy 327.998845 -125.583833) (xy 328.007388 -125.603129) (xy 328.014838 -125.61062) (xy 328.033903 -125.628765)
			(xy 328.067358 -125.669398) (xy 328.094915 -125.714241) (xy 328.116052 -125.762443) (xy 328.130367 -125.813092)
			(xy 328.13759 -125.865227) (xy 328.138028 -125.891544) (xy 328.137542 -125.918795) (xy 328.129786 -125.972743)
			(xy 328.114431 -126.025038) (xy 328.091789 -126.074615) (xy 328.062323 -126.120465) (xy 328.026632 -126.161656)
			(xy 327.985441 -126.197347) (xy 327.939591 -126.226813) (xy 327.890014 -126.249455) (xy 327.837719 -126.26481)
			(xy 327.783771 -126.272566) (xy 327.729269 -126.272566) (xy 327.675321 -126.26481) (xy 327.623026 -126.249455)
			(xy 327.573449 -126.226813) (xy 327.527599 -126.197347) (xy 327.486408 -126.161656) (xy 327.450717 -126.120465)
			(xy 327.421251 -126.074615) (xy 327.398609 -126.025038) (xy 327.383254 -125.972743) (xy 327.375498 -125.918795)
			(xy 327.375012 -125.891544) (xy 322.329368 -125.891544) (xy 324.724522 -128.28651) (xy 324.742076 -128.304726)
			(xy 324.771813 -128.345649) (xy 324.794778 -128.390723) (xy 324.810404 -128.438835) (xy 324.818307 -128.488801)
			(xy 324.818756 -128.514094) (xy 324.818756 -128.570482) (xy 324.820026 -128.576324) (xy 324.82536 -128.603248)
			(xy 324.82536 -128.603756) (xy 324.827014 -128.615689) (xy 324.828793 -128.639716) (xy 324.828916 -128.651762)
			(xy 324.828916 -132.277866) (xy 324.829932 -132.288534) (xy 324.831653 -132.295516) (xy 324.838501 -132.308155)
			(xy 324.843394 -132.313426) (xy 325.38667 -132.856732) (xy 334.376522 -132.856732) (xy 334.37699 -132.829866)
			(xy 334.384514 -132.776664) (xy 334.399431 -132.725045) (xy 334.421446 -132.67603) (xy 334.450122 -132.630591)
			(xy 334.484893 -132.589627) (xy 334.52507 -132.553949) (xy 334.54721 -132.538724) (xy 334.557116 -132.53212)
			(xy 334.569054 -132.512054) (xy 334.575658 -132.419852) (xy 334.575959 -132.408145) (xy 334.567209 -132.386445)
			(xy 334.558894 -132.378196) (xy 334.55864 -132.378196) (xy 334.538953 -132.360013) (xy 334.504355 -132.319088)
			(xy 334.475824 -132.273724) (xy 334.45392 -132.224814) (xy 334.439076 -132.173321) (xy 334.431583 -132.120257)
			(xy 334.431132 -132.093462) (xy 334.43152 -132.066206) (xy 334.439283 -132.012251) (xy 334.454646 -131.959949)
			(xy 334.477296 -131.910366) (xy 334.506771 -131.864511) (xy 334.542473 -131.823318) (xy 334.583673 -131.787625)
			(xy 334.629534 -131.758158) (xy 334.679122 -131.735518) (xy 334.731427 -131.720166) (xy 334.785384 -131.712414)
			(xy 334.81264 -131.711954) (xy 334.83921 -131.712399) (xy 334.891838 -131.719755) (xy 334.942935 -131.734347)
			(xy 334.991512 -131.755891) (xy 335.036627 -131.783971) (xy 335.077406 -131.818043) (xy 335.11306 -131.857446)
			(xy 335.142897 -131.901419) (xy 335.155032 -131.92506) (xy 335.159221 -131.932932) (xy 335.172043 -131.945312)
			(xy 335.188329 -131.952554) (xy 335.197196 -131.953508) (xy 335.29905 -131.960112) (xy 335.32318 -131.948174)
			(xy 335.3308 -131.936744) (xy 335.346033 -131.914676) (xy 335.381682 -131.87462) (xy 335.422592 -131.839955)
			(xy 335.467957 -131.811365) (xy 335.51688 -131.789413) (xy 335.568396 -131.774534) (xy 335.621489 -131.76702)
			(xy 335.6483 -131.766564) (xy 335.67555 -131.767078) (xy 335.729495 -131.774833) (xy 335.781788 -131.790187)
			(xy 335.831363 -131.812826) (xy 335.877212 -131.84229) (xy 335.918402 -131.877978) (xy 335.954093 -131.919165)
			(xy 335.98356 -131.965012) (xy 336.006203 -132.014586) (xy 336.021561 -132.066877) (xy 336.02932 -132.120822)
			(xy 336.029808 -132.148072) (xy 336.02942 -132.174168) (xy 336.022308 -132.225873) (xy 336.008212 -132.276126)
			(xy 335.987397 -132.323988) (xy 335.960251 -132.368565) (xy 335.92728 -132.409024) (xy 335.889101 -132.44461)
			(xy 335.86801 -132.459984) (xy 335.858866 -132.466334) (xy 335.84769 -132.485384) (xy 335.839054 -132.57276)
			(xy 335.838439 -132.583664) (xy 335.845421 -132.604335) (xy 335.852516 -132.612638) (xy 335.85277 -132.612892)
			(xy 335.872282 -132.634241) (xy 335.905237 -132.68177) (xy 335.930637 -132.733729) (xy 335.9479 -132.788929)
			(xy 335.95663 -132.846102) (xy 335.957164 -132.87502) (xy 335.956764 -132.902275) (xy 335.949003 -132.956231)
			(xy 335.933642 -133.008533) (xy 335.910994 -133.058116) (xy 335.88152 -133.103971) (xy 335.845819 -133.145165)
			(xy 335.80462 -133.180858) (xy 335.75876 -133.210325) (xy 335.709173 -133.232964) (xy 335.656868 -133.248316)
			(xy 335.602911 -133.256068) (xy 335.575656 -133.256528) (xy 335.547526 -133.256047) (xy 335.491876 -133.247779)
			(xy 335.438044 -133.231429) (xy 335.387197 -133.207351) (xy 335.340436 -133.176068) (xy 335.298776 -133.138257)
			(xy 335.26312 -133.094738) (xy 335.24825 -133.070854) (xy 335.243565 -133.06368) (xy 335.230426 -133.052701)
			(xy 335.214385 -133.046713) (xy 335.205832 -133.046216) (xy 335.119726 -133.044184) (xy 335.111156 -133.044304)
			(xy 335.094879 -133.049653) (xy 335.081274 -133.060067) (xy 335.076292 -133.067044) (xy 335.061094 -133.08925)
			(xy 335.025422 -133.129536) (xy 334.984442 -133.164408) (xy 334.938966 -133.193173) (xy 334.889897 -133.215259)
			(xy 334.838212 -133.230228) (xy 334.784935 -133.237783) (xy 334.75803 -133.23824) (xy 334.730781 -133.237694)
			(xy 334.676837 -133.229942) (xy 334.624545 -133.214593) (xy 334.574971 -133.191957) (xy 334.529122 -133.162497)
			(xy 334.487932 -133.126812) (xy 334.45224 -133.085628) (xy 334.422772 -133.039784) (xy 334.400129 -132.990213)
			(xy 334.384771 -132.937924) (xy 334.37701 -132.883981) (xy 334.376522 -132.856732) (xy 325.38667 -132.856732)
			(xy 329.369166 -136.839452) (xy 329.373521 -136.843617) (xy 329.3838 -136.849902) (xy 329.389486 -136.851898)
			(xy 329.393267 -136.85298) (xy 329.401048 -136.854123) (xy 329.40498 -136.854184) (xy 336.82686 -136.854184)
			(xy 336.852883 -136.854712) (xy 336.904285 -136.862881) (xy 336.95378 -136.878978) (xy 337.000154 -136.902607)
			(xy 337.042269 -136.933189) (xy 337.061048 -136.951212) (xy 337.225132 -137.115296) (xy 337.230631 -137.120283)
			(xy 337.243798 -137.127126) (xy 337.25104 -137.128758) (xy 337.260692 -137.129774) (xy 343.14003 -137.129774)
			(xy 343.148158 -137.129012) (xy 343.148666 -137.129012) (xy 343.156182 -137.127407) (xy 343.169865 -137.120425)
			(xy 343.17559 -137.115296) (xy 344.688922 -135.60171) (xy 344.720418 -135.570214) (xy 344.724657 -135.565622)
			(xy 344.730946 -135.554826) (xy 344.732864 -135.548878) (xy 344.733817 -135.545399) (xy 344.734844 -135.53826)
			(xy 344.734896 -135.534654) (xy 344.734896 -126.70028) (xy 344.735389 -126.674438) (xy 344.743396 -126.623379)
			(xy 344.759214 -126.574175) (xy 344.782462 -126.528015) (xy 344.797126 -126.506732) (xy 344.79865 -126.5047)
			(xy 344.80373 -126.497334) (xy 344.805254 -126.490984) (xy 344.805762 -126.488698) (xy 344.806016 -126.486412)
			(xy 344.81008 -126.472442) (xy 344.810334 -126.47168) (xy 344.810842 -126.469902) (xy 344.811858 -126.466854)
			(xy 344.813382 -126.46279) (xy 344.814398 -126.459742) (xy 344.81516 -126.457202) (xy 344.815668 -126.456186)
			(xy 344.823542 -126.43612) (xy 344.824558 -126.433834) (xy 344.825828 -126.43104) (xy 344.826082 -126.430786)
			(xy 344.829892 -126.423166) (xy 344.841915 -126.400029) (xy 344.872298 -126.357659) (xy 344.890344 -126.338838)
			(xy 348.684342 -122.54484) (xy 348.689168 -122.539252) (xy 348.69383 -122.53251) (xy 348.699001 -122.516964)
			(xy 348.699328 -122.508772) (xy 348.699328 -114.922808) (xy 348.699858 -114.896785) (xy 348.708031 -114.845385)
			(xy 348.724129 -114.795891) (xy 348.747758 -114.749518) (xy 348.778338 -114.707404) (xy 348.796356 -114.68862)
			(xy 351.250504 -112.234472) (xy 351.255491 -112.228973) (xy 351.262334 -112.215806) (xy 351.263966 -112.208564)
			(xy 351.264982 -112.198912) (xy 351.264982 -108.40212) (xy 351.264921 -108.398514) (xy 351.263905 -108.391374)
			(xy 351.26295 -108.387896) (xy 351.261426 -108.383324) (xy 351.257616 -108.37418) (xy 351.126552 -108.243116)
			(xy 351.123699 -108.240413) (xy 351.117317 -108.235827) (xy 351.113852 -108.233972) (xy 351.108425 -108.231391)
			(xy 351.096745 -108.22857) (xy 351.090738 -108.228384) (xy 349.45828 -108.228384) (xy 349.448628 -108.232702)
			(xy 349.424216 -108.243082) (xy 349.373238 -108.257751) (xy 349.320718 -108.265214) (xy 349.294196 -108.265722)
			(xy 349.28429 -108.265722) (xy 349.25789 -108.264637) (xy 349.20575 -108.256092) (xy 349.155285 -108.24044)
			(xy 349.10746 -108.217979) (xy 349.063189 -108.189139) (xy 349.023318 -108.15447) (xy 348.988607 -108.114635)
			(xy 348.959719 -108.070395) (xy 348.937208 -108.022594) (xy 348.928944 -107.997498) (xy 348.927166 -107.991656)
			(xy 348.920816 -107.980988) (xy 348.493334 -107.553506) (xy 348.475217 -107.534727) (xy 348.444523 -107.492533)
			(xy 348.420813 -107.446052) (xy 348.404674 -107.396433) (xy 348.396503 -107.344899) (xy 348.396052 -107.31881)
			(xy 348.396052 -106.373422) (xy 348.396536 -106.347334) (xy 348.4047 -106.295801) (xy 348.42083 -106.246181)
			(xy 348.444529 -106.199698) (xy 348.475211 -106.157497) (xy 348.493334 -106.138726) (xy 350.037654 -104.594406)
			(xy 350.038162 -104.58704) (xy 350.038162 -101.469952) (xy 350.038096 -101.466347) (xy 350.037071 -101.459209)
			(xy 350.03613 -101.455728) (xy 350.034606 -101.451156) (xy 350.030796 -101.442012) (xy 350.022414 -101.43363)
			(xy 350.016318 -101.42855) (xy 349.979488 -101.403404) (xy 349.946722 -101.381052) (xy 349.943674 -101.37902)
			(xy 349.939102 -101.376734) (xy 349.92972 -101.372994) (xy 349.909545 -101.372459) (xy 349.899986 -101.375718)
			(xy 349.891604 -101.378766) (xy 349.860839 -101.388922) (xy 349.796994 -101.3999) (xy 349.764604 -101.40061)
			(xy 349.764096 -101.40061) (xy 349.736845 -101.400124) (xy 349.682897 -101.392367) (xy 349.630603 -101.377011)
			(xy 349.581026 -101.35437) (xy 349.535176 -101.324903) (xy 349.493986 -101.289212) (xy 349.458294 -101.248021)
			(xy 349.428828 -101.202171) (xy 349.406187 -101.152594) (xy 349.390832 -101.100299) (xy 349.383076 -101.046351)
			(xy 349.383076 -100.991849) (xy 349.390832 -100.937901) (xy 349.406187 -100.885606) (xy 349.428828 -100.836029)
			(xy 349.458294 -100.790179) (xy 349.493986 -100.748988) (xy 349.535176 -100.713297) (xy 349.581026 -100.68383)
			(xy 349.630603 -100.661189) (xy 349.682897 -100.645833) (xy 349.736845 -100.638076) (xy 349.764096 -100.637594)
			(xy 349.764604 -100.637594) (xy 349.797199 -100.63828) (xy 349.861435 -100.649388) (xy 349.892366 -100.659692)
			(xy 349.900748 -100.66274) (xy 349.923608 -100.66274) (xy 349.926148 -100.66274) (xy 349.932527 -100.662184)
			(xy 349.944732 -100.658323) (xy 349.950278 -100.65512) (xy 349.976186 -100.637086) (xy 350.018096 -100.60813)
			(xy 350.021906 -100.604828) (xy 350.022414 -100.60432) (xy 350.030034 -100.595176) (xy 350.032574 -100.590604)
			(xy 350.034809 -100.585993) (xy 350.037619 -100.576141) (xy 350.038162 -100.571046) (xy 350.038162 -95.495364)
			(xy 350.038593 -95.485298) (xy 350.046324 -95.466709) (xy 350.053148 -95.459296) (xy 350.942656 -94.569788)
			(xy 350.950053 -94.562941) (xy 350.968653 -94.555213) (xy 350.978724 -94.554802) (xy 351.37217 -94.554802)
			(xy 351.379282 -94.554294) (xy 352.338894 -93.594682) (xy 352.339402 -93.584522) (xy 352.335592 -93.55074)
			(xy 352.335592 -93.550232) (xy 352.330766 -93.510354) (xy 352.327718 -93.500194) (xy 352.325178 -93.495114)
			(xy 352.315272 -93.477588) (xy 352.312986 -93.47454) (xy 352.306128 -93.466666) (xy 352.30054 -93.46311)
			(xy 352.27842 -93.447797) (xy 352.238292 -93.411961) (xy 352.203571 -93.370864) (xy 352.174939 -93.325316)
			(xy 352.152961 -93.27621) (xy 352.138066 -93.224512) (xy 352.13055 -93.17124) (xy 352.130106 -93.14434)
			(xy 352.130106 -93.142308) (xy 352.13077 -93.112167) (xy 352.14041 -93.052655) (xy 352.159251 -92.995388)
			(xy 352.172524 -92.968318) (xy 352.175064 -92.963238) (xy 352.179636 -92.945966) (xy 352.18116 -92.933266)
			(xy 352.18116 -92.408756) (xy 352.181649 -92.38267) (xy 352.189823 -92.331143) (xy 352.20596 -92.28153)
			(xy 352.229665 -92.235054) (xy 352.260352 -92.192862) (xy 352.278442 -92.17406) (xy 352.491802 -91.9607)
			(xy 352.496792 -91.955202) (xy 352.503643 -91.942037) (xy 352.505264 -91.934792) (xy 352.50628 -91.92514)
			(xy 352.50628 -83.235292) (xy 352.505859 -83.225273) (xy 352.498186 -83.206763) (xy 352.484014 -83.192598)
			(xy 352.465499 -83.184936) (xy 352.45548 -83.184492) (xy 351.830132 -83.184492) (xy 351.826322 -83.186016)
			(xy 351.790818 -83.199982) (xy 351.717102 -83.219647) (xy 351.641457 -83.229578) (xy 351.60331 -83.230212)
			(xy 351.577257 -83.229884) (xy 351.525364 -83.225181) (xy 351.499678 -83.220814) (xy 351.49536 -83.220052)
			(xy 350.313752 -83.220052) (xy 350.271461 -83.219254) (xy 350.187805 -83.20676) (xy 350.147128 -83.19516)
			(xy 350.143572 -83.194144) (xy 349.231712 -83.194144) (xy 349.228106 -83.194206) (xy 349.220966 -83.195223)
			(xy 349.217488 -83.196176) (xy 349.212916 -83.1977) (xy 349.203772 -83.20151) (xy 348.883478 -83.521804)
			(xy 348.878652 -83.527392) (xy 348.878652 -83.787234) (xy 351.221292 -83.787234) (xy 351.225363 -83.731612)
			(xy 351.237489 -83.677175) (xy 351.257412 -83.625084) (xy 351.284708 -83.576449) (xy 351.318794 -83.532306)
			(xy 351.358943 -83.493597) (xy 351.404301 -83.461146) (xy 351.453901 -83.435645) (xy 351.506685 -83.417638)
			(xy 351.561528 -83.407508) (xy 351.617262 -83.405471) (xy 351.672699 -83.411571) (xy 351.726656 -83.425677)
			(xy 351.777985 -83.447489) (xy 351.825591 -83.476543) (xy 351.868459 -83.512218) (xy 351.905676 -83.553755)
			(xy 351.936449 -83.600268) (xy 351.960121 -83.650765) (xy 351.976189 -83.704172) (xy 351.984309 -83.759348)
			(xy 351.984818 -83.787234) (xy 351.984309 -83.81512) (xy 351.976189 -83.870296) (xy 351.960121 -83.923703)
			(xy 351.936449 -83.9742) (xy 351.905676 -84.020713) (xy 351.868459 -84.06225) (xy 351.825591 -84.097925)
			(xy 351.777985 -84.126979) (xy 351.726656 -84.148791) (xy 351.672699 -84.162897) (xy 351.617262 -84.168997)
			(xy 351.561528 -84.16696) (xy 351.506685 -84.15683) (xy 351.453901 -84.138823) (xy 351.404301 -84.113322)
			(xy 351.358943 -84.080871) (xy 351.318794 -84.042162) (xy 351.284708 -83.998019) (xy 351.257412 -83.949384)
			(xy 351.237489 -83.897293) (xy 351.225363 -83.842856) (xy 351.221292 -83.787234) (xy 348.878652 -83.787234)
			(xy 348.878652 -84.930234) (xy 351.221292 -84.930234) (xy 351.225363 -84.874612) (xy 351.237489 -84.820175)
			(xy 351.257412 -84.768084) (xy 351.284708 -84.719449) (xy 351.318794 -84.675306) (xy 351.358943 -84.636597)
			(xy 351.404301 -84.604146) (xy 351.453901 -84.578645) (xy 351.506685 -84.560638) (xy 351.561528 -84.550508)
			(xy 351.617262 -84.548471) (xy 351.672699 -84.554571) (xy 351.726656 -84.568677) (xy 351.777985 -84.590489)
			(xy 351.825591 -84.619543) (xy 351.868459 -84.655218) (xy 351.905676 -84.696755) (xy 351.936449 -84.743268)
			(xy 351.960121 -84.793765) (xy 351.976189 -84.847172) (xy 351.984309 -84.902348) (xy 351.984818 -84.930234)
			(xy 351.984309 -84.95812) (xy 351.976189 -85.013296) (xy 351.960121 -85.066703) (xy 351.936449 -85.1172)
			(xy 351.905676 -85.163713) (xy 351.868459 -85.20525) (xy 351.825591 -85.240925) (xy 351.777985 -85.269979)
			(xy 351.726656 -85.291791) (xy 351.672699 -85.305897) (xy 351.617262 -85.311997) (xy 351.561528 -85.30996)
			(xy 351.506685 -85.29983) (xy 351.453901 -85.281823) (xy 351.404301 -85.256322) (xy 351.358943 -85.223871)
			(xy 351.318794 -85.185162) (xy 351.284708 -85.141019) (xy 351.257412 -85.092384) (xy 351.237489 -85.040293)
			(xy 351.225363 -84.985856) (xy 351.221292 -84.930234) (xy 348.878652 -84.930234) (xy 348.878652 -85.803232)
			(xy 351.039936 -85.803232) (xy 351.044007 -85.74761) (xy 351.056133 -85.693173) (xy 351.076056 -85.641082)
			(xy 351.103352 -85.592447) (xy 351.137438 -85.548304) (xy 351.177587 -85.509595) (xy 351.222945 -85.477144)
			(xy 351.272545 -85.451643) (xy 351.325329 -85.433636) (xy 351.380172 -85.423506) (xy 351.435906 -85.421469)
			(xy 351.491343 -85.427569) (xy 351.5453 -85.441675) (xy 351.596629 -85.463487) (xy 351.644235 -85.492541)
			(xy 351.687103 -85.528216) (xy 351.72432 -85.569753) (xy 351.755093 -85.616266) (xy 351.778765 -85.666763)
			(xy 351.794833 -85.72017) (xy 351.802953 -85.775346) (xy 351.803462 -85.803232) (xy 351.802953 -85.831118)
			(xy 351.794833 -85.886294) (xy 351.778765 -85.939701) (xy 351.755093 -85.990198) (xy 351.72432 -86.036711)
			(xy 351.687103 -86.078248) (xy 351.644235 -86.113923) (xy 351.596629 -86.142977) (xy 351.5453 -86.164789)
			(xy 351.491343 -86.178895) (xy 351.435906 -86.184995) (xy 351.380172 -86.182958) (xy 351.325329 -86.172828)
			(xy 351.272545 -86.154821) (xy 351.222945 -86.12932) (xy 351.177587 -86.096869) (xy 351.137438 -86.05816)
			(xy 351.103352 -86.014017) (xy 351.076056 -85.965382) (xy 351.056133 -85.913291) (xy 351.044007 -85.858854)
			(xy 351.039936 -85.803232) (xy 348.878652 -85.803232) (xy 348.878652 -87.062564) (xy 351.061018 -87.062564)
			(xy 351.065089 -87.006942) (xy 351.077215 -86.952505) (xy 351.097138 -86.900414) (xy 351.124434 -86.851779)
			(xy 351.15852 -86.807636) (xy 351.198669 -86.768927) (xy 351.244027 -86.736476) (xy 351.293627 -86.710975)
			(xy 351.346411 -86.692968) (xy 351.401254 -86.682838) (xy 351.456988 -86.680801) (xy 351.512425 -86.686901)
			(xy 351.566382 -86.701007) (xy 351.617711 -86.722819) (xy 351.665317 -86.751873) (xy 351.708185 -86.787548)
			(xy 351.745402 -86.829085) (xy 351.776175 -86.875598) (xy 351.799847 -86.926095) (xy 351.815915 -86.979502)
			(xy 351.824035 -87.034678) (xy 351.824544 -87.062564) (xy 351.824035 -87.09045) (xy 351.815915 -87.145626)
			(xy 351.799847 -87.199033) (xy 351.776175 -87.24953) (xy 351.745402 -87.296043) (xy 351.708185 -87.33758)
			(xy 351.665317 -87.373255) (xy 351.617711 -87.402309) (xy 351.566382 -87.424121) (xy 351.512425 -87.438227)
			(xy 351.456988 -87.444327) (xy 351.401254 -87.44229) (xy 351.346411 -87.43216) (xy 351.293627 -87.414153)
			(xy 351.244027 -87.388652) (xy 351.198669 -87.356201) (xy 351.15852 -87.317492) (xy 351.124434 -87.273349)
			(xy 351.097138 -87.224714) (xy 351.077215 -87.172623) (xy 351.065089 -87.118186) (xy 351.061018 -87.062564)
			(xy 348.878652 -87.062564) (xy 348.878652 -88.756998) (xy 351.028762 -88.756998) (xy 351.029248 -88.729747)
			(xy 351.037004 -88.675799) (xy 351.052359 -88.623504) (xy 351.075001 -88.573927) (xy 351.104467 -88.528077)
			(xy 351.140158 -88.486886) (xy 351.181349 -88.451195) (xy 351.227199 -88.421729) (xy 351.276776 -88.399087)
			(xy 351.329071 -88.383732) (xy 351.383019 -88.375976) (xy 351.437521 -88.375976) (xy 351.491469 -88.383732)
			(xy 351.543764 -88.399087) (xy 351.593341 -88.421729) (xy 351.639191 -88.451195) (xy 351.680382 -88.486886)
			(xy 351.716073 -88.528077) (xy 351.745539 -88.573927) (xy 351.768181 -88.623504) (xy 351.783536 -88.675799)
			(xy 351.791292 -88.729747) (xy 351.791778 -88.756998) (xy 351.791327 -88.782508) (xy 351.784543 -88.833076)
			(xy 351.771081 -88.882289) (xy 351.751182 -88.929269) (xy 351.725202 -88.97318) (xy 351.709736 -88.993472)
			(xy 351.701773 -89.004257) (xy 351.691233 -89.028898) (xy 351.687465 -89.055432) (xy 351.690729 -89.082033)
			(xy 351.7008 -89.106869) (xy 351.716985 -89.12823) (xy 351.73817 -89.144646) (xy 351.750376 -89.15019)
			(xy 351.776044 -89.161469) (xy 351.824052 -89.190426) (xy 351.867306 -89.226095) (xy 351.904876 -89.267709)
			(xy 351.935953 -89.314373) (xy 351.959868 -89.365081) (xy 351.976106 -89.418742) (xy 351.984319 -89.474202)
			(xy 351.984818 -89.502234) (xy 351.984332 -89.529485) (xy 351.976576 -89.583433) (xy 351.961221 -89.635728)
			(xy 351.938579 -89.685305) (xy 351.909113 -89.731155) (xy 351.873422 -89.772346) (xy 351.832231 -89.808037)
			(xy 351.786381 -89.837503) (xy 351.736804 -89.860145) (xy 351.684509 -89.8755) (xy 351.630561 -89.883256)
			(xy 351.576059 -89.883256) (xy 351.522111 -89.8755) (xy 351.469816 -89.860145) (xy 351.420239 -89.837503)
			(xy 351.374389 -89.808037) (xy 351.333198 -89.772346) (xy 351.297507 -89.731155) (xy 351.268041 -89.685305)
			(xy 351.245399 -89.635728) (xy 351.230044 -89.583433) (xy 351.222288 -89.529485) (xy 351.221802 -89.502234)
			(xy 351.22222 -89.476722) (xy 351.229013 -89.426154) (xy 351.242482 -89.37694) (xy 351.262388 -89.329961)
			(xy 351.288375 -89.286051) (xy 351.303844 -89.26576) (xy 351.311777 -89.254953) (xy 351.322323 -89.230319)
			(xy 351.326097 -89.203789) (xy 351.322838 -89.177192) (xy 351.312772 -89.152358) (xy 351.29659 -89.130998)
			(xy 351.275409 -89.114585) (xy 351.263204 -89.109042) (xy 351.237528 -89.097778) (xy 351.189516 -89.068824)
			(xy 351.146258 -89.033155) (xy 351.108686 -88.991539) (xy 351.077609 -88.944873) (xy 351.053696 -88.894161)
			(xy 351.037462 -88.840495) (xy 351.029257 -88.785032) (xy 351.028762 -88.756998) (xy 348.878652 -88.756998)
			(xy 348.878652 -90.295222) (xy 348.888558 -90.305128) (xy 348.895416 -90.310208) (xy 348.930468 -90.327226)
			(xy 348.978982 -90.350848) (xy 348.985792 -90.353906) (xy 349.000507 -90.356371) (xy 349.007938 -90.355674)
			(xy 349.015304 -90.354658) (xy 349.028766 -90.348562) (xy 349.034354 -90.343736) (xy 349.036894 -90.341704)
			(xy 349.038164 -90.340942) (xy 349.062931 -90.322924) (xy 349.117016 -90.294192) (xy 349.174997 -90.274472)
			(xy 349.235385 -90.264273) (xy 349.266002 -90.263472) (xy 349.268796 -90.263472) (xy 349.280734 -90.263726)
			(xy 349.28302 -90.26398) (xy 349.284798 -90.26398) (xy 349.311272 -90.265562) (xy 349.363435 -90.275132)
			(xy 349.41377 -90.291836) (xy 349.461306 -90.315351) (xy 349.505126 -90.345224) (xy 349.544386 -90.380879)
			(xy 349.578328 -90.42163) (xy 349.606297 -90.466688) (xy 349.627756 -90.515187) (xy 349.642289 -90.566191)
			(xy 349.649617 -90.618717) (xy 349.65005 -90.645234) (xy 349.649562 -90.672485) (xy 349.641802 -90.726431)
			(xy 349.626444 -90.778724) (xy 349.603802 -90.8283) (xy 349.574335 -90.874149) (xy 349.538644 -90.915338)
			(xy 349.497455 -90.95103) (xy 349.451607 -90.980498) (xy 349.402032 -91.003141) (xy 349.349739 -91.0185)
			(xy 349.295793 -91.026261) (xy 349.268542 -91.026742) (xy 349.243158 -91.026328) (xy 349.192837 -91.019602)
			(xy 349.143852 -91.006264) (xy 349.097067 -90.986549) (xy 349.05331 -90.960806) (xy 349.033084 -90.945462)
			(xy 349.032322 -90.9447) (xy 349.032068 -90.9447) (xy 349.029782 -90.943176) (xy 349.018886 -90.936703)
			(xy 348.993691 -90.93429) (xy 348.981776 -90.938604) (xy 348.90456 -90.975688) (xy 348.904052 -90.976196)
			(xy 348.897194 -90.979498) (xy 348.891813 -90.982299) (xy 348.882446 -90.990004) (xy 348.878652 -90.994738)
			(xy 348.878652 -91.438222) (xy 348.888558 -91.448128) (xy 348.895416 -91.453208) (xy 348.930468 -91.470226)
			(xy 348.978982 -91.493848) (xy 348.985792 -91.496906) (xy 349.000507 -91.499371) (xy 349.007938 -91.498674)
			(xy 349.015304 -91.497658) (xy 349.028766 -91.491562) (xy 349.034354 -91.486736) (xy 349.036894 -91.484704)
			(xy 349.038164 -91.483942) (xy 349.062931 -91.465924) (xy 349.117016 -91.437192) (xy 349.174997 -91.417472)
			(xy 349.235385 -91.407273) (xy 349.266002 -91.406472) (xy 349.268796 -91.406472) (xy 349.280734 -91.406726)
			(xy 349.28302 -91.40698) (xy 349.284798 -91.40698) (xy 349.311272 -91.408562) (xy 349.363435 -91.418132)
			(xy 349.41377 -91.434836) (xy 349.461306 -91.458351) (xy 349.505126 -91.488224) (xy 349.544386 -91.523879)
			(xy 349.578328 -91.56463) (xy 349.606297 -91.609688) (xy 349.627756 -91.658187) (xy 349.642289 -91.709191)
			(xy 349.649617 -91.761717) (xy 349.65005 -91.788234) (xy 349.649562 -91.815485) (xy 349.641802 -91.869431)
			(xy 349.626444 -91.921724) (xy 349.603802 -91.9713) (xy 349.574335 -92.017149) (xy 349.538644 -92.058338)
			(xy 349.497455 -92.09403) (xy 349.451607 -92.123498) (xy 349.402032 -92.146141) (xy 349.349739 -92.1615)
			(xy 349.295793 -92.169261) (xy 349.268542 -92.169742) (xy 349.241715 -92.16929) (xy 349.18859 -92.161783)
			(xy 349.137039 -92.146912) (xy 349.088079 -92.124968) (xy 349.042673 -92.096386) (xy 349.001717 -92.061727)
			(xy 348.983554 -92.04198) (xy 348.976696 -92.034106) (xy 348.946724 -92.019628) (xy 348.93504 -92.01658)
			(xy 348.872302 -92.014548) (xy 348.86138 -92.014548) (xy 348.856695 -92.014703) (xy 348.847492 -92.016487)
			(xy 348.843092 -92.018104) (xy 348.833948 -92.021914) (xy 348.825312 -92.03055) (xy 348.824296 -92.031566)
			(xy 348.806216 -92.050108) (xy 348.765913 -92.082629) (xy 348.721577 -92.109394) (xy 348.674026 -92.129908)
			(xy 348.624134 -92.143795) (xy 348.572822 -92.150797) (xy 348.546928 -92.1512) (xy 348.519674 -92.150739)
			(xy 348.465721 -92.142985) (xy 348.41342 -92.127631) (xy 348.363837 -92.10499) (xy 348.317981 -92.075523)
			(xy 348.276785 -92.039829) (xy 348.241089 -91.998635) (xy 348.21162 -91.952781) (xy 348.188976 -91.903199)
			(xy 348.173619 -91.850899) (xy 348.165863 -91.796946) (xy 348.16542 -91.769692) (xy 348.16542 -91.769438)
			(xy 348.165817 -91.745191) (xy 348.171991 -91.697091) (xy 348.184194 -91.650157) (xy 348.20223 -91.605141)
			(xy 348.21368 -91.583764) (xy 348.215204 -91.58097) (xy 348.215204 -83.12404) (xy 348.215115 -83.11963)
			(xy 348.213578 -83.110944) (xy 348.212156 -83.106768) (xy 348.21013 -83.101625) (xy 348.204234 -83.092276)
			(xy 348.200472 -83.088226) (xy 341.177372 -76.06538) (xy 341.15934 -76.046609) (xy 341.12876 -76.004493)
			(xy 341.105135 -75.958116) (xy 341.089045 -75.908619) (xy 341.080885 -75.857215) (xy 341.080344 -75.831192)
			(xy 341.080344 -74.815954) (xy 341.080177 -74.809944) (xy 341.077357 -74.79826) (xy 341.074756 -74.79284)
			(xy 341.072918 -74.789365) (xy 341.068327 -74.782983) (xy 341.065612 -74.78014) (xy 337.887818 -71.602346)
			(xy 337.870264 -71.58413) (xy 337.84053 -71.543207) (xy 337.817568 -71.498133) (xy 337.801946 -71.45002)
			(xy 337.794049 -71.400055) (xy 337.793584 -71.374762) (xy 337.793584 -67.969384) (xy 337.79352 -67.965778)
			(xy 337.7925 -67.958639) (xy 337.791552 -67.95516) (xy 337.790028 -67.950588) (xy 337.786218 -67.941444)
			(xy 337.778598 -67.933824) (xy 336.942684 -67.097656) (xy 336.106516 -66.261488) (xy 336.103664 -66.258783)
			(xy 336.097285 -66.254192) (xy 336.093816 -66.252344) (xy 336.088389 -66.249763) (xy 336.076709 -66.246946)
			(xy 336.070702 -66.246756) (xy 331.53858 -66.246756) (xy 331.511126 -66.246331) (xy 331.456978 -66.237264)
			(xy 331.430884 -66.228722) (xy 331.43063 -66.228468) (xy 331.429868 -66.228214) (xy 331.42809 -66.227452)
			(xy 331.427328 -66.227198) (xy 331.425042 -66.226182) (xy 331.407008 -66.218816) (xy 331.311504 -66.152268)
			(xy 331.304646 -66.146426) (xy 331.087222 -65.929002) (xy 331.082142 -65.925954) (xy 331.06621 -65.915712)
			(xy 331.036542 -65.892165) (xy 331.02296 -65.878964) (xy 330.617576 -65.47358) (xy 330.606908 -65.46723)
			(xy 330.601066 -65.465452) (xy 330.573632 -65.456331) (xy 330.521672 -65.430985) (xy 330.474125 -65.398098)
			(xy 330.432076 -65.358423) (xy 330.396486 -65.312865) (xy 330.368167 -65.262464) (xy 330.347766 -65.208371)
			(xy 330.341224 -65.18021) (xy 330.335559 -65.150847) (xy 330.332362 -65.091136) (xy 330.334874 -65.061338)
			(xy 330.33589 -65.05067) (xy 330.332842 -65.040764) (xy 330.331407 -65.036605) (xy 330.327321 -65.028814)
			(xy 330.324714 -65.02527) (xy 330.278486 -64.9732) (xy 330.270866 -64.964564) (xy 330.266588 -64.960348)
			(xy 330.25644 -64.95393) (xy 330.2508 -64.951864) (xy 330.240132 -64.948816) (xy 329.715114 -64.948816)
			(xy 329.711508 -64.948878) (xy 329.704368 -64.949894) (xy 329.70089 -64.950848) (xy 329.696318 -64.952372)
			(xy 329.687174 -64.956182) (xy 328.660252 -65.983104) (xy 328.643381 -65.999378) (xy 328.605784 -66.027371)
			(xy 328.564532 -66.049629) (xy 328.54265 -66.058034) (xy 328.531982 -66.06159) (xy 328.524362 -66.064384)
			(xy 328.51725 -66.066416) (xy 328.515472 -66.06667) (xy 328.512424 -66.067432) (xy 328.511154 -66.067686)
			(xy 328.497315 -66.070999) (xy 328.469206 -66.075454) (xy 328.45502 -66.076576) (xy 328.448162 -66.077592)
			(xy 328.42835 -66.082169) (xy 328.387976 -66.087013) (xy 328.367644 -66.087244) (xy 325.117714 -66.087244)
			(xy 325.113396 -66.08953) (xy 325.08497 -66.104445) (xy 325.024369 -66.125602) (xy 324.961086 -66.136348)
			(xy 324.928992 -66.137028) (xy 324.928484 -66.137028) (xy 324.901232 -66.136541) (xy 324.847283 -66.128782)
			(xy 324.794988 -66.113425) (xy 324.74541 -66.090782) (xy 324.699559 -66.061313) (xy 324.658369 -66.02562)
			(xy 324.622677 -65.984428) (xy 324.593211 -65.938576) (xy 324.570569 -65.888997) (xy 324.555214 -65.836701)
			(xy 324.547458 -65.782752) (xy 324.547458 -65.728248) (xy 324.555214 -65.674299) (xy 324.570569 -65.622003)
			(xy 324.593211 -65.572424) (xy 324.622677 -65.526572) (xy 324.658369 -65.48538) (xy 324.699559 -65.449687)
			(xy 324.74541 -65.420218) (xy 324.794988 -65.397575) (xy 324.847283 -65.382218) (xy 324.901232 -65.374459)
			(xy 324.928484 -65.374012) (xy 324.928738 -65.374012) (xy 324.952985 -65.374408) (xy 325.001086 -65.380579)
			(xy 325.048022 -65.392779) (xy 325.09304 -65.410812) (xy 325.114412 -65.422272) (xy 325.117206 -65.423796)
			(xy 328.209148 -65.423796) (xy 328.218292 -65.423034) (xy 328.225784 -65.421405) (xy 328.23936 -65.414298)
			(xy 328.244962 -65.409064) (xy 329.284838 -64.368934) (xy 329.301191 -64.353107) (xy 329.337465 -64.325627)
			(xy 329.377159 -64.303369) (xy 329.419525 -64.286752) (xy 329.441556 -64.28105) (xy 329.448668 -64.279272)
			(xy 329.454256 -64.276224) (xy 329.457371 -64.274428) (xy 329.46311 -64.270096) (xy 329.465686 -64.267588)
			(xy 329.996546 -63.736474) (xy 329.997308 -63.735458) (xy 330.017469 -63.715282) (xy 330.063544 -63.68167)
			(xy 330.114818 -63.656697) (xy 330.142088 -63.648336) (xy 330.144882 -63.647828) (xy 330.147676 -63.647066)
			(xy 330.167754 -63.642052) (xy 330.208774 -63.636573) (xy 330.229464 -63.636144) (xy 332.368144 -63.636144)
			(xy 332.375296 -63.635764) (xy 332.388968 -63.631514) (xy 332.395068 -63.627762) (xy 332.401926 -63.622936)
			(xy 332.406498 -63.618872) (xy 332.411015 -63.614055) (xy 332.417573 -63.602597) (xy 332.419452 -63.596266)
			(xy 332.423008 -63.583312) (xy 332.427326 -63.572898) (xy 332.431898 -63.56096) (xy 332.433661 -63.556817)
			(xy 332.438386 -63.549155) (xy 332.441296 -63.54572) (xy 332.442312 -63.54445) (xy 332.446618 -63.538999)
			(xy 332.452403 -63.526375) (xy 332.453742 -63.519558) (xy 332.454758 -63.5127) (xy 332.453996 -63.505842)
			(xy 332.453447 -63.502169) (xy 332.451401 -63.495029) (xy 332.449932 -63.491618) (xy 332.441296 -63.472314)
			(xy 332.441296 -63.471806) (xy 332.436724 -63.461392) (xy 332.43012 -63.454534) (xy 332.429866 -63.45428)
			(xy 332.429358 -63.453772) (xy 332.409125 -63.432376) (xy 332.374825 -63.38451) (xy 332.348286 -63.331944)
			(xy 332.330138 -63.275925) (xy 332.320811 -63.217782) (xy 332.320138 -63.188342) (xy 332.320138 -63.180214)
			(xy 332.321138 -63.151261) (xy 332.330809 -63.094144) (xy 332.349003 -63.039145) (xy 332.375304 -62.987529)
			(xy 332.409106 -62.940482) (xy 332.449632 -62.899087) (xy 332.495951 -62.864295) (xy 332.546997 -62.836905)
			(xy 332.601597 -62.817547) (xy 332.658497 -62.806667) (xy 332.687422 -62.805056) (xy 332.687676 -62.805056)
			(xy 332.701646 -62.804802) (xy 332.702154 -62.804802) (xy 332.727781 -62.805229) (xy 332.778569 -62.812123)
			(xy 332.827975 -62.825765) (xy 332.875104 -62.84591) (xy 332.919107 -62.872192) (xy 332.93939 -62.88786)
			(xy 332.945994 -62.89294) (xy 332.95717 -62.89675) (xy 332.970632 -62.898782) (xy 332.992476 -62.898782)
			(xy 332.997917 -62.898919) (xy 333.008554 -62.901215) (xy 333.013558 -62.903354) (xy 333.027274 -62.909704)
			(xy 333.031978 -62.911769) (xy 333.041959 -62.914202) (xy 333.047086 -62.91453) (xy 333.055722 -62.914022)
			(xy 333.063005 -62.912734) (xy 333.076423 -62.906527) (xy 333.082138 -62.90183) (xy 333.082392 -62.901576)
			(xy 333.102279 -62.884469) (xy 333.145867 -62.855281) (xy 333.16926 -62.84341) (xy 333.183992 -62.836552)
			(xy 333.188564 -62.83452) (xy 333.2119 -62.825167) (xy 333.260414 -62.811973) (xy 333.310239 -62.805257)
			(xy 333.335376 -62.804802) (xy 333.34198 -62.804802) (xy 333.371744 -62.805789) (xy 333.430433 -62.815867)
			(xy 333.45882 -62.824868) (xy 333.489807 -62.836091) (xy 333.547669 -62.86763) (xy 333.573882 -62.887606)
			(xy 333.574136 -62.88786) (xy 333.577184 -62.8904) (xy 333.583294 -62.894131) (xy 333.596959 -62.898382)
			(xy 333.604108 -62.898782) (xy 333.627476 -62.898782) (xy 333.632917 -62.898919) (xy 333.643554 -62.901215)
			(xy 333.648558 -62.903354) (xy 333.662274 -62.909704) (xy 333.666978 -62.911769) (xy 333.676959 -62.914202)
			(xy 333.682086 -62.91453) (xy 333.690722 -62.914022) (xy 333.698005 -62.912734) (xy 333.711423 -62.906527)
			(xy 333.717138 -62.90183) (xy 333.717392 -62.901576) (xy 333.738462 -62.883469) (xy 333.784856 -62.852908)
			(xy 333.835189 -62.829395) (xy 333.888399 -62.813425) (xy 333.943361 -62.805335) (xy 333.971138 -62.804802)
			(xy 333.971646 -62.804802) (xy 333.998895 -62.805291) (xy 334.052837 -62.813053) (xy 334.105126 -62.828412)
			(xy 334.154696 -62.851056) (xy 334.20054 -62.880524) (xy 334.241724 -62.916216) (xy 334.27741 -62.957405)
			(xy 334.306871 -63.003253) (xy 334.329507 -63.052827) (xy 334.344859 -63.105118) (xy 334.352613 -63.159061)
			(xy 334.353154 -63.18631) (xy 334.352584 -63.216036) (xy 334.343356 -63.274769) (xy 334.325126 -63.331358)
			(xy 334.298334 -63.384432) (xy 334.263631 -63.432705) (xy 334.243172 -63.45428) (xy 334.242918 -63.454534)
			(xy 334.236822 -63.460884) (xy 334.228186 -63.479426) (xy 334.227424 -63.48222) (xy 334.223614 -63.499238)
			(xy 334.222928 -63.505124) (xy 334.223957 -63.516926) (xy 334.225646 -63.522606) (xy 334.244696 -63.569342)
			(xy 334.244696 -63.56985) (xy 334.26019 -63.606934) (xy 334.267048 -63.617856) (xy 334.274652 -63.626112)
			(xy 334.294954 -63.635619) (xy 334.306164 -63.636144) (xy 335.50098 -63.636144) (xy 335.509057 -63.634859)
			(xy 335.523833 -63.627872) (xy 335.529936 -63.622428) (xy 335.607152 -63.545212) (xy 335.611724 -63.539878)
			(xy 335.611724 -58.181494) (xy 335.611562 -58.175483) (xy 335.608748 -58.163795) (xy 335.606136 -58.15838)
			(xy 335.604297 -58.154905) (xy 335.599706 -58.148524) (xy 335.596992 -58.14568) (xy 335.27492 -57.823608)
			(xy 335.259465 -57.807641) (xy 335.232645 -57.77221) (xy 335.210951 -57.733428) (xy 335.20253 -57.712864)
			(xy 335.196688 -57.701942) (xy 335.195672 -57.700418) (xy 335.180034 -57.678708) (xy 335.155173 -57.631334)
			(xy 335.138231 -57.580586) (xy 335.129647 -57.527778) (xy 335.129124 -57.501028) (xy 335.129124 -56.577992)
			(xy 335.125052 -56.572851) (xy 335.114761 -56.56473) (xy 335.108804 -56.56199) (xy 335.016348 -56.528208)
			(xy 335.008974 -56.525735) (xy 334.993449 -56.524948) (xy 334.985868 -56.526684) (xy 334.978502 -56.528716)
			(xy 334.965294 -56.537098) (xy 334.960214 -56.543194) (xy 334.941958 -56.564011) (xy 334.900472 -56.600677)
			(xy 334.854131 -56.630975) (xy 334.803903 -56.654269) (xy 334.75084 -56.670074) (xy 334.696051 -56.678057)
			(xy 334.668368 -56.678576) (xy 334.641121 -56.678088) (xy 334.587181 -56.670328) (xy 334.534894 -56.654971)
			(xy 334.485325 -56.63233) (xy 334.439483 -56.602866) (xy 334.3983 -56.567177) (xy 334.362615 -56.525991)
			(xy 334.333154 -56.480146) (xy 334.310517 -56.430576) (xy 334.295165 -56.378288) (xy 334.28741 -56.324347)
			(xy 334.28741 -56.269853) (xy 334.295165 -56.215912) (xy 334.310517 -56.163624) (xy 334.333154 -56.114054)
			(xy 334.362615 -56.068209) (xy 334.3983 -56.027023) (xy 334.439483 -55.991334) (xy 334.485325 -55.96187)
			(xy 334.534894 -55.939229) (xy 334.587181 -55.923872) (xy 334.641121 -55.916112) (xy 334.668368 -55.91556)
			(xy 334.695346 -55.916022) (xy 334.748766 -55.923609) (xy 334.800586 -55.938637) (xy 334.849777 -55.960806)
			(xy 334.89536 -55.989676) (xy 334.936427 -56.024673) (xy 334.954626 -56.044592) (xy 334.960468 -56.051196)
			(xy 334.976216 -56.06161) (xy 334.985458 -56.066291) (xy 335.006025 -56.068628) (xy 335.016094 -56.066182)
			(xy 335.072736 -56.045608) (xy 335.10601 -56.033416) (xy 335.112814 -56.030669) (xy 335.124564 -56.021892)
			(xy 335.129124 -56.016144) (xy 335.129124 -55.113428) (xy 335.129608 -55.08734) (xy 335.13777 -55.035806)
			(xy 335.153899 -54.986184) (xy 335.177595 -54.939699) (xy 335.208276 -54.897496) (xy 335.226406 -54.878732)
			(xy 337.150456 -52.954682) (xy 337.156806 -52.944014) (xy 337.158584 -52.938172) (xy 337.167031 -52.912603)
			(xy 337.190108 -52.863952) (xy 337.219793 -52.819025) (xy 337.255495 -52.778715) (xy 337.296507 -52.743822)
			(xy 337.342016 -52.715038) (xy 337.391117 -52.692933) (xy 337.442837 -52.677948) (xy 337.49615 -52.670378)
			(xy 337.523074 -52.669948) (xy 337.550328 -52.670432) (xy 337.60428 -52.678185) (xy 337.656581 -52.693538)
			(xy 337.706164 -52.716177) (xy 337.752021 -52.745642) (xy 337.793218 -52.781332) (xy 337.828916 -52.822523)
			(xy 337.85839 -52.868374) (xy 337.881038 -52.917953) (xy 337.8964 -52.970251) (xy 337.904163 -53.024202)
			(xy 337.904582 -53.051456) (xy 337.904836 -53.051456) (xy 337.904376 -53.07839) (xy 337.896805 -53.131723)
			(xy 337.881809 -53.183461) (xy 337.859684 -53.232575) (xy 337.83087 -53.278089) (xy 337.795942 -53.319097)
			(xy 337.755593 -53.354786) (xy 337.710625 -53.384444) (xy 337.661932 -53.407482) (xy 337.636358 -53.415946)
			(xy 337.636104 -53.415946) (xy 337.630271 -53.417959) (xy 337.61974 -53.424385) (xy 337.615276 -53.428646)
			(xy 335.824576 -55.219346) (xy 335.824068 -55.226458) (xy 335.824068 -55.722266) (xy 336.03387 -55.722266)
			(xy 336.037941 -55.666644) (xy 336.050067 -55.612207) (xy 336.06999 -55.560116) (xy 336.097286 -55.511481)
			(xy 336.131372 -55.467338) (xy 336.171521 -55.428629) (xy 336.216879 -55.396178) (xy 336.266479 -55.370677)
			(xy 336.319263 -55.35267) (xy 336.374106 -55.34254) (xy 336.42984 -55.340503) (xy 336.485277 -55.346603)
			(xy 336.539234 -55.360709) (xy 336.590563 -55.382521) (xy 336.638169 -55.411575) (xy 336.681037 -55.44725)
			(xy 336.718254 -55.488787) (xy 336.749027 -55.5353) (xy 336.772699 -55.585797) (xy 336.788767 -55.639204)
			(xy 336.796887 -55.69438) (xy 336.797396 -55.722266) (xy 336.796887 -55.750152) (xy 336.788767 -55.805328)
			(xy 336.772699 -55.858735) (xy 336.749027 -55.909232) (xy 336.718254 -55.955745) (xy 336.681037 -55.997282)
			(xy 336.638169 -56.032957) (xy 336.590563 -56.062011) (xy 336.539234 -56.083823) (xy 336.485277 -56.097929)
			(xy 336.42984 -56.104029) (xy 336.374106 -56.101992) (xy 336.319263 -56.091862) (xy 336.266479 -56.073855)
			(xy 336.216879 -56.048354) (xy 336.171521 -56.015903) (xy 336.131372 -55.977194) (xy 336.097286 -55.933051)
			(xy 336.06999 -55.884416) (xy 336.050067 -55.832325) (xy 336.037941 -55.777888) (xy 336.03387 -55.722266)
			(xy 335.824068 -55.722266) (xy 335.824068 -56.585612) (xy 335.824707 -56.594905) (xy 335.831788 -56.612117)
			(xy 335.844565 -56.62565) (xy 335.85277 -56.630062) (xy 335.858358 -56.632348) (xy 335.87817 -56.638952)
			(xy 335.881963 -56.640295) (xy 335.889105 -56.644) (xy 335.892394 -56.646318) (xy 335.9023 -56.653684)
			(xy 335.909666 -56.659272) (xy 335.918002 -56.6649) (xy 335.93751 -56.669733) (xy 335.947512 -56.66867)
			(xy 335.95564 -56.6674) (xy 335.958942 -56.666384) (xy 335.98545 -56.659023) (xy 336.039893 -56.651112)
			(xy 336.0674 -56.650636) (xy 336.067654 -56.650636) (xy 336.071464 -56.650636) (xy 336.07375 -56.650636)
			(xy 336.083656 -56.65089) (xy 336.088482 -56.651144) (xy 336.088736 -56.651144) (xy 336.115445 -56.653067)
			(xy 336.167975 -56.663461) (xy 336.218533 -56.681103) (xy 336.266125 -56.705647) (xy 336.309815 -56.736609)
			(xy 336.348741 -56.77338) (xy 336.382139 -56.815237) (xy 336.409352 -56.861355) (xy 336.429842 -56.910828)
			(xy 336.43697 -56.93664) (xy 336.438748 -56.943498) (xy 336.44205 -56.949086) (xy 336.449924 -56.9595)
			(xy 337.391502 -57.900824) (xy 337.409057 -57.919039) (xy 337.438793 -57.959963) (xy 337.461757 -58.005037)
			(xy 337.477383 -58.053149) (xy 337.485284 -58.103115) (xy 337.485736 -58.128408) (xy 337.485736 -58.51271)
			(xy 337.486752 -58.516012) (xy 337.501546 -58.534052) (xy 337.526454 -58.573502) (xy 337.545582 -58.616055)
			(xy 337.558554 -58.66087) (xy 337.565113 -58.707061) (xy 337.565492 -58.730388) (xy 337.565492 -64.774064)
			(xy 337.565661 -64.780073) (xy 337.568487 -64.791754) (xy 337.57108 -64.797178) (xy 337.572917 -64.800654)
			(xy 337.577505 -64.807038) (xy 337.580224 -64.809878) (xy 338.520786 -65.75044) (xy 338.52104 -65.750694)
			(xy 338.52792 -65.756919) (xy 338.544884 -65.764395) (xy 338.563399 -65.765338) (xy 338.572348 -65.762886)
			(xy 338.603844 -65.749678) (xy 338.6074 -65.744344) (xy 338.6074 -41.67505) (xy 338.607233 -41.66904)
			(xy 338.604409 -41.657358) (xy 338.601812 -41.651936) (xy 338.599976 -41.648459) (xy 338.595388 -41.642075)
			(xy 338.592668 -41.639236) (xy 333.32293 -36.369498) (xy 333.304813 -36.350719) (xy 333.274121 -36.308524)
			(xy 333.250413 -36.262044) (xy 333.234275 -36.212425) (xy 333.226105 -36.160891) (xy 333.225648 -36.134802)
			(xy 333.225648 -29.774388) (xy 333.226135 -29.748301) (xy 333.234304 -29.696771) (xy 333.250437 -29.647154)
			(xy 333.274138 -29.600674) (xy 333.304823 -29.558478) (xy 333.32293 -29.539692) (xy 333.975202 -28.88742)
			(xy 333.981316 -28.880734) (xy 333.988792 -28.864245) (xy 333.990056 -28.846184) (xy 333.987902 -28.837382)
			(xy 333.985616 -28.832048) (xy 333.98253 -28.825231) (xy 333.97311 -28.813611) (xy 333.967074 -28.809188)
			(xy 333.961486 -28.805378) (xy 333.947008 -28.80106) (xy 331.481684 -28.80106) (xy 331.455597 -28.800573)
			(xy 331.404067 -28.792404) (xy 331.354451 -28.77627) (xy 331.307971 -28.752569) (xy 331.265774 -28.721885)
			(xy 331.246988 -28.703778) (xy 330.650596 -28.107386) (xy 330.643484 -28.10002) (xy 330.642976 -28.099512)
			(xy 330.223876 -27.680158) (xy 330.217436 -27.674183) (xy 330.201588 -27.666637) (xy 330.192888 -27.665426)
			(xy 330.187808 -27.665172) (xy 328.933302 -27.665172) (xy 328.90728 -27.664641) (xy 328.85588 -27.656468)
			(xy 328.806387 -27.640369) (xy 328.760014 -27.61674) (xy 328.7179 -27.586159) (xy 328.699114 -27.568144)
			(xy 327.746868 -26.615644) (xy 327.740261 -26.6097) (xy 327.724097 -26.602344) (xy 327.706393 -26.600954)
			(xy 327.689279 -26.605698) (xy 327.681844 -26.610564) (xy 327.669035 -26.620386) (xy 327.649883 -26.646347)
			(xy 327.639774 -26.676984) (xy 327.639172 -26.693114) (xy 327.639172 -27.342846) (xy 327.638682 -27.37283)
			(xy 327.630854 -27.432286) (xy 327.615333 -27.490211) (xy 327.592384 -27.545615) (xy 327.5624 -27.597549)
			(xy 327.525894 -27.645125) (xy 327.483489 -27.68753) (xy 327.435913 -27.724036) (xy 327.383979 -27.75402)
			(xy 327.328575 -27.776969) (xy 327.27065 -27.79249) (xy 327.211194 -27.800318) (xy 327.151226 -27.800318)
			(xy 327.09177 -27.79249) (xy 327.033845 -27.776969) (xy 326.978441 -27.75402) (xy 326.926507 -27.724036)
			(xy 326.878931 -27.68753) (xy 326.836526 -27.645125) (xy 326.80002 -27.597549) (xy 326.770036 -27.545615)
			(xy 326.747087 -27.490211) (xy 326.731566 -27.432286) (xy 326.723738 -27.37283) (xy 326.723248 -27.342846)
			(xy 326.723248 -26.479246) (xy 326.723779 -26.448026) (xy 326.732263 -26.386166) (xy 326.749066 -26.32603)
			(xy 326.773876 -26.268731) (xy 326.806236 -26.215331) (xy 326.845545 -26.166818) (xy 326.891076 -26.124091)
			(xy 326.941986 -26.08794) (xy 326.997332 -26.059035) (xy 327.026524 -26.047954) (xy 327.036938 -26.044144)
			(xy 327.052178 -26.029412) (xy 327.05548 -26.025602) (xy 327.05856 -26.021652) (xy 327.063303 -26.012831)
			(xy 327.064878 -26.008076) (xy 327.067672 -25.99563) (xy 327.067672 -25.995122) (xy 327.083928 -25.923494)
			(xy 327.085014 -25.915003) (xy 327.082163 -25.898133) (xy 327.07834 -25.890474) (xy 327.07326 -25.8826)
			(xy 326.678036 -25.487376) (xy 326.672956 -25.483058) (xy 326.630538 -25.453086) (xy 326.52081 -25.37587)
			(xy 326.514283 -25.371567) (xy 326.499411 -25.366774) (xy 326.4916 -25.366472) (xy 324.904862 -25.366472)
			(xy 324.90156 -25.366472) (xy 324.892538 -25.367416) (xy 324.875998 -25.374831) (xy 324.869302 -25.38095)
			(xy 324.795388 -25.455118) (xy 324.763638 -25.486868) (xy 324.757288 -25.497536) (xy 324.75551 -25.503378)
			(xy 324.74706 -25.528944) (xy 324.723979 -25.57759) (xy 324.694292 -25.62251) (xy 324.658588 -25.662814)
			(xy 324.617576 -25.697702) (xy 324.572068 -25.726481) (xy 324.522969 -25.748582) (xy 324.471251 -25.763564)
			(xy 324.417942 -25.771132) (xy 324.39102 -25.771602) (xy 324.363766 -25.77114) (xy 324.309814 -25.763385)
			(xy 324.257514 -25.748031) (xy 324.207931 -25.72539) (xy 324.162076 -25.695922) (xy 324.120882 -25.660228)
			(xy 324.085186 -25.619035) (xy 324.055717 -25.573181) (xy 324.033074 -25.523599) (xy 324.017718 -25.4713)
			(xy 324.009961 -25.417348) (xy 324.009512 -25.390094) (xy 324.009258 -25.390094) (xy 324.009715 -25.363158)
			(xy 324.017279 -25.30982) (xy 324.032271 -25.258077) (xy 324.054393 -25.208956) (xy 324.083204 -25.163436)
			(xy 324.118131 -25.122421) (xy 324.158481 -25.086727) (xy 324.20345 -25.057064) (xy 324.252145 -25.034021)
			(xy 324.277736 -25.025604) (xy 324.27799 -25.025604) (xy 324.283825 -25.023593) (xy 324.294361 -25.017172)
			(xy 324.298818 -25.012904) (xy 324.341236 -24.970486) (xy 324.341679 -24.96688) (xy 324.341685 -24.959613)
			(xy 324.341236 -24.956008) (xy 323.989446 -24.604218) (xy 323.964298 -24.578277) (xy 323.919879 -24.521292)
			(xy 323.882796 -24.459283) (xy 323.85361 -24.393189) (xy 323.832762 -24.324011) (xy 323.826124 -24.288496)
			(xy 323.82206 -24.263858) (xy 323.818006 -24.260147) (xy 323.808655 -24.254379) (xy 323.803518 -24.252428)
			(xy 323.736462 -24.231092) (xy 323.735954 -24.231092) (xy 323.723762 -24.227282) (xy 323.715126 -24.225504)
			(xy 323.708522 -24.224996) (xy 323.702934 -24.224996) (xy 323.69379 -24.228806) (xy 323.689223 -24.230809)
			(xy 323.680901 -24.2363) (xy 323.67728 -24.239728) (xy 323.492368 -24.42464) (xy 323.473597 -24.442671)
			(xy 323.43148 -24.473248) (xy 323.385103 -24.49687) (xy 323.335606 -24.512958) (xy 323.284203 -24.521116)
			(xy 323.25818 -24.521668) (xy 322.069968 -24.521668) (xy 322.06565 -24.523954) (xy 322.037225 -24.538872)
			(xy 321.976624 -24.560037) (xy 321.913341 -24.570791) (xy 321.881246 -24.571452) (xy 321.880738 -24.571452)
			(xy 321.85348 -24.570992) (xy 321.799519 -24.563238) (xy 321.74721 -24.547884) (xy 321.69762 -24.525241)
			(xy 321.651756 -24.49577) (xy 321.610554 -24.460072) (xy 321.574853 -24.418874) (xy 321.545378 -24.373014)
			(xy 321.52273 -24.323425) (xy 321.50737 -24.271118) (xy 321.499611 -24.217158) (xy 321.499611 -24.162642)
			(xy 321.50737 -24.108682) (xy 321.52273 -24.056375) (xy 321.545378 -24.006786) (xy 321.574853 -23.960926)
			(xy 321.610554 -23.919728) (xy 321.651756 -23.88403) (xy 321.69762 -23.854559) (xy 321.74721 -23.831916)
			(xy 321.799519 -23.816562) (xy 321.85348 -23.808808) (xy 321.880738 -23.808436) (xy 321.880992 -23.808436)
			(xy 321.90524 -23.808829) (xy 321.953343 -23.814995) (xy 322.000281 -23.827191) (xy 322.045302 -23.845221)
			(xy 322.066666 -23.856696) (xy 322.06946 -23.85822) (xy 323.099176 -23.85822) (xy 323.102478 -23.85822)
			(xy 323.111497 -23.857269) (xy 323.128027 -23.849845) (xy 323.134736 -23.843742) (xy 323.214746 -23.763478)
			(xy 323.253862 -23.724362) (xy 323.254116 -23.710646) (xy 323.252084 -23.701756) (xy 323.242686 -23.673562)
			(xy 323.242686 -23.673054) (xy 323.22135 -23.603712) (xy 323.213984 -23.597108) (xy 323.189346 -23.59279)
			(xy 323.1565 -23.586392) (xy 323.092429 -23.567072) (xy 323.030977 -23.540573) (xy 322.972947 -23.507243)
			(xy 322.919095 -23.467515) (xy 322.870123 -23.421907) (xy 322.826668 -23.371014) (xy 322.789299 -23.315499)
			(xy 322.758501 -23.256086) (xy 322.746116 -23.224998) (xy 322.737734 -23.203154) (xy 322.733699 -23.200575)
			(xy 322.724873 -23.196866) (xy 322.720208 -23.195788) (xy 322.670932 -23.185374) (xy 322.670424 -23.185374)
			(xy 322.63461 -23.177754) (xy 322.620386 -23.178008) (xy 322.358766 -23.439628) (xy 322.33518 -23.462565)
			(xy 322.283742 -23.503589) (xy 322.228035 -23.538596) (xy 322.168758 -23.567146) (xy 322.106658 -23.58888)
			(xy 322.042514 -23.603524) (xy 321.977135 -23.610895) (xy 321.944238 -23.611332) (xy 321.908807 -23.610821)
			(xy 321.838461 -23.602283) (xy 321.769658 -23.585329) (xy 321.7034 -23.560204) (xy 321.640653 -23.527276)
			(xy 321.582333 -23.487024) (xy 321.529291 -23.440036) (xy 321.482299 -23.386997) (xy 321.442044 -23.328679)
			(xy 321.409111 -23.265935) (xy 321.383982 -23.199679) (xy 321.367023 -23.130876) (xy 321.358482 -23.060531)
			(xy 321.358006 -23.0251) (xy 321.35845 -22.992203) (xy 321.365817 -22.926823) (xy 321.380458 -22.862679)
			(xy 321.40219 -22.800578) (xy 321.430738 -22.7413) (xy 321.465745 -22.685592) (xy 321.506769 -22.634154)
			(xy 321.52971 -22.610572) (xy 322.03644 -22.103842) (xy 322.060014 -22.080919) (xy 322.111421 -22.039916)
			(xy 322.167094 -22.004924) (xy 322.226333 -21.976381) (xy 322.288393 -21.954645) (xy 322.352496 -21.939991)
			(xy 322.417836 -21.932601) (xy 322.450714 -21.932138) (xy 322.451222 -21.932138) (xy 322.465192 -21.932392)
			(xy 326.217788 -21.932392) (xy 326.229635 -21.931775) (xy 326.250829 -21.921181) (xy 326.258428 -21.912072)
			(xy 326.27316 -21.892514) (xy 326.282558 -21.880068) (xy 326.285595 -21.875428) (xy 326.289827 -21.86518)
			(xy 326.29094 -21.859748) (xy 326.293226 -21.848318) (xy 326.28967 -21.83638) (xy 326.28967 -21.835872)
			(xy 326.282227 -21.809246) (xy 326.274193 -21.754548) (xy 326.273668 -21.726906) (xy 326.274189 -21.698167)
			(xy 326.282812 -21.64134) (xy 326.299864 -21.58645) (xy 326.324959 -21.53474) (xy 326.357528 -21.487381)
			(xy 326.376792 -21.466048) (xy 326.383904 -21.458428) (xy 326.387206 -21.449792) (xy 326.387968 -21.448014)
			(xy 326.3892 -21.444066) (xy 326.390476 -21.435894) (xy 326.390508 -21.431758) (xy 326.390508 -21.361654)
			(xy 326.390443 -21.357521) (xy 326.389172 -21.349353) (xy 326.387968 -21.345398) (xy 326.387206 -21.34362)
			(xy 326.383904 -21.334984) (xy 326.376792 -21.327364) (xy 326.357522 -21.306036) (xy 326.324959 -21.258673)
			(xy 326.299868 -21.206961) (xy 326.282819 -21.15207) (xy 326.274197 -21.095243) (xy 326.274196 -21.037766)
			(xy 326.282817 -20.980938) (xy 326.299865 -20.926047) (xy 326.324954 -20.874334) (xy 326.357517 -20.82697)
			(xy 326.376792 -20.805648) (xy 326.383904 -20.798028) (xy 326.387206 -20.789392) (xy 326.387968 -20.787614)
			(xy 326.3892 -20.783666) (xy 326.390476 -20.775494) (xy 326.390508 -20.771358) (xy 326.390508 -20.701254)
			(xy 326.390443 -20.697121) (xy 326.389172 -20.688953) (xy 326.387968 -20.684998) (xy 326.387206 -20.68322)
			(xy 326.383904 -20.674584) (xy 326.376792 -20.666964) (xy 326.357522 -20.645636) (xy 326.324959 -20.598273)
			(xy 326.299868 -20.546561) (xy 326.282819 -20.49167) (xy 326.274197 -20.434843) (xy 326.274196 -20.377366)
			(xy 326.282817 -20.320538) (xy 326.299865 -20.265647) (xy 326.324954 -20.213934) (xy 326.357517 -20.16657)
			(xy 326.376792 -20.145248) (xy 326.383904 -20.137628) (xy 326.387206 -20.128992) (xy 326.387968 -20.127214)
			(xy 326.3892 -20.123266) (xy 326.390476 -20.115094) (xy 326.390508 -20.110958) (xy 326.390508 -20.040854)
			(xy 326.390443 -20.036721) (xy 326.389172 -20.028553) (xy 326.387968 -20.024598) (xy 326.387206 -20.02282)
			(xy 326.383904 -20.014184) (xy 326.376792 -20.006564) (xy 326.357522 -19.985236) (xy 326.324959 -19.937873)
			(xy 326.299868 -19.886161) (xy 326.282819 -19.83127) (xy 326.274197 -19.774443) (xy 326.274196 -19.716966)
			(xy 326.282817 -19.660138) (xy 326.299865 -19.605247) (xy 326.324954 -19.553534) (xy 326.357517 -19.50617)
			(xy 326.376792 -19.484848) (xy 326.383904 -19.477228) (xy 326.387206 -19.468592) (xy 326.387968 -19.466814)
			(xy 326.3892 -19.462866) (xy 326.390476 -19.454694) (xy 326.390508 -19.450558) (xy 326.390508 -19.380454)
			(xy 326.390443 -19.376321) (xy 326.389172 -19.368153) (xy 326.387968 -19.364198) (xy 326.387206 -19.36242)
			(xy 326.383904 -19.353784) (xy 326.376792 -19.346164) (xy 326.357522 -19.324837) (xy 326.324959 -19.277474)
			(xy 326.299869 -19.225762) (xy 326.282819 -19.170871) (xy 326.274197 -19.114045) (xy 326.273668 -19.085306)
			(xy 326.274154 -19.058055) (xy 326.28191 -19.004107) (xy 326.297265 -18.951812) (xy 326.319907 -18.902235)
			(xy 326.349373 -18.856385) (xy 326.385064 -18.815194) (xy 326.426255 -18.779503) (xy 326.472105 -18.750037)
			(xy 326.521682 -18.727395) (xy 326.573977 -18.71204) (xy 326.627925 -18.704284) (xy 326.682427 -18.704284)
			(xy 326.736375 -18.71204) (xy 326.78867 -18.727395) (xy 326.838247 -18.750037) (xy 326.884097 -18.779503)
			(xy 326.925288 -18.815194) (xy 326.960979 -18.856385) (xy 326.990445 -18.902235) (xy 327.013087 -18.951812)
			(xy 327.028442 -19.004107) (xy 327.036198 -19.058055) (xy 327.036684 -19.085306) (xy 327.036163 -19.114045)
			(xy 327.027539 -19.170872) (xy 327.010487 -19.225762) (xy 326.985394 -19.277473) (xy 326.952828 -19.324834)
			(xy 326.93356 -19.346164) (xy 326.926448 -19.353784) (xy 326.923146 -19.36242) (xy 326.922384 -19.364198)
			(xy 326.921154 -19.368147) (xy 326.919882 -19.376318) (xy 326.919844 -19.380454) (xy 326.919844 -19.450558)
			(xy 326.91991 -19.454691) (xy 326.921182 -19.462859) (xy 326.922384 -19.466814) (xy 326.923146 -19.468592)
			(xy 326.926448 -19.477228) (xy 326.93356 -19.484848) (xy 326.952831 -19.506174) (xy 326.985397 -19.553536)
			(xy 327.010489 -19.605248) (xy 327.027539 -19.660138) (xy 327.036161 -19.716966) (xy 327.03616 -19.774443)
			(xy 327.027537 -19.83127) (xy 327.010485 -19.88616) (xy 326.985392 -19.937871) (xy 326.952826 -19.985232)
			(xy 326.93356 -20.006564) (xy 326.926448 -20.014184) (xy 326.923146 -20.02282) (xy 326.922384 -20.024598)
			(xy 326.921154 -20.028547) (xy 326.919882 -20.036718) (xy 326.919844 -20.040854) (xy 326.919844 -20.110958)
			(xy 326.91991 -20.115091) (xy 326.921182 -20.123259) (xy 326.922384 -20.127214) (xy 326.923146 -20.128992)
			(xy 326.926448 -20.137628) (xy 326.93356 -20.145248) (xy 326.952831 -20.166574) (xy 326.985397 -20.213936)
			(xy 327.010489 -20.265648) (xy 327.027539 -20.320538) (xy 327.036161 -20.377366) (xy 327.03616 -20.434843)
			(xy 327.027537 -20.49167) (xy 327.010485 -20.54656) (xy 326.985392 -20.598271) (xy 326.952826 -20.645632)
			(xy 326.93356 -20.666964) (xy 326.926448 -20.674584) (xy 326.923146 -20.68322) (xy 326.922384 -20.684998)
			(xy 326.921154 -20.688947) (xy 326.919882 -20.697118) (xy 326.919844 -20.701254) (xy 326.919844 -20.771358)
			(xy 326.91991 -20.775491) (xy 326.921182 -20.783659) (xy 326.922384 -20.787614) (xy 326.923146 -20.789392)
			(xy 326.926448 -20.798028) (xy 326.93356 -20.805648) (xy 326.952831 -20.826974) (xy 326.985397 -20.874336)
			(xy 327.010489 -20.926048) (xy 327.027539 -20.980938) (xy 327.036161 -21.037766) (xy 327.03616 -21.095243)
			(xy 327.027537 -21.15207) (xy 327.010485 -21.20696) (xy 326.985392 -21.258671) (xy 326.952826 -21.306032)
			(xy 326.93356 -21.327364) (xy 326.926448 -21.334984) (xy 326.923146 -21.34362) (xy 326.922384 -21.345398)
			(xy 326.921154 -21.349347) (xy 326.919882 -21.357518) (xy 326.919844 -21.361654) (xy 326.919844 -21.431758)
			(xy 326.91991 -21.435891) (xy 326.921182 -21.444059) (xy 326.922384 -21.448014) (xy 326.923146 -21.449792)
			(xy 326.926448 -21.458428) (xy 326.93356 -21.466048) (xy 326.952827 -21.487377) (xy 326.985384 -21.534741)
			(xy 327.010469 -21.586454) (xy 327.027515 -21.641343) (xy 327.036134 -21.698168) (xy 327.036684 -21.726906)
			(xy 327.036189 -21.754613) (xy 327.028153 -21.809441) (xy 327.020682 -21.836126) (xy 327.020682 -21.83638)
			(xy 327.019142 -21.842157) (xy 327.018509 -21.854092) (xy 327.019412 -21.860002) (xy 327.021444 -21.871432)
			(xy 327.037192 -21.892514) (xy 327.051924 -21.912072) (xy 327.059524 -21.921185) (xy 327.080715 -21.931797)
			(xy 327.092564 -21.932392) (xy 331.466444 -21.932392) (xy 331.476096 -21.931376) (xy 331.483337 -21.929743)
			(xy 331.496499 -21.922894) (xy 331.502004 -21.917914) (xy 331.828648 -21.59127) (xy 331.829156 -21.583904)
			(xy 331.829156 -21.567902) (xy 331.826108 -21.556218) (xy 331.82179 -21.547836) (xy 331.808256 -21.520574)
			(xy 331.789061 -21.46282) (xy 331.779273 -21.402751) (xy 331.77861 -21.372322) (xy 331.77861 -21.36394)
			(xy 331.779605 -21.337044) (xy 331.788225 -21.283918) (xy 331.804226 -21.232532) (xy 331.827291 -21.183904)
			(xy 331.856963 -21.139001) (xy 331.892651 -21.098715) (xy 331.933648 -21.063845) (xy 331.979139 -21.035083)
			(xy 332.028221 -21.013001) (xy 332.079919 -20.998037) (xy 332.133208 -20.990489) (xy 332.160118 -20.990052)
			(xy 332.160372 -20.990052) (xy 332.176374 -20.990306) (xy 332.187042 -20.990814) (xy 332.196186 -20.987512)
			(xy 332.201036 -20.98553) (xy 332.20987 -20.979898) (xy 332.213712 -20.976336) (xy 332.266544 -20.925536)
			(xy 332.272132 -20.919186) (xy 332.272132 -11.259312) (xy 332.272613 -11.226436) (xy 332.280011 -11.1611)
			(xy 332.294671 -11.097002) (xy 332.316408 -11.034946) (xy 332.34495 -10.97571) (xy 332.379938 -10.920039)
			(xy 332.420934 -10.86863) (xy 332.443836 -10.845038) (xy 332.958694 -10.33018) (xy 332.982248 -10.307234)
			(xy 333.033647 -10.266213) (xy 333.089318 -10.231209) (xy 333.14856 -10.202664) (xy 333.210628 -10.180936)
			(xy 333.27474 -10.166299) (xy 333.340087 -10.158939) (xy 333.372968 -10.158476) (xy 334.191102 -10.158476)
			(xy 334.22398 -10.158953) (xy 334.28932 -10.166342) (xy 334.353423 -10.180995) (xy 334.415484 -10.202726)
			(xy 334.474725 -10.231264) (xy 334.530402 -10.26625) (xy 334.581815 -10.307244) (xy 334.605376 -10.33018)
			(xy 335.40446 -11.129264) (xy 335.427406 -11.152818) (xy 335.468428 -11.204217) (xy 335.503432 -11.259888)
			(xy 335.531978 -11.31913) (xy 335.553708 -11.381198) (xy 335.568346 -11.445309) (xy 335.57571 -11.510657)
			(xy 335.576164 -11.543538) (xy 335.576164 -11.558016) (xy 335.57591 -11.563858) (xy 335.57422 -11.598461)
			(xy 335.563706 -11.66694) (xy 335.545186 -11.7337) (xy 335.518918 -11.797808) (xy 335.48527 -11.85837)
			(xy 335.444711 -11.914538) (xy 335.397809 -11.965529) (xy 335.345218 -12.010629) (xy 335.287672 -12.049209)
			(xy 335.225977 -12.080731) (xy 335.160994 -12.104753) (xy 335.09363 -12.120939) (xy 335.024827 -12.129065)
			(xy 334.990186 -12.129516) (xy 334.957312 -12.129087) (xy 334.891976 -12.121754) (xy 334.827872 -12.107148)
			(xy 334.765808 -12.085453) (xy 334.706564 -12.056942) (xy 334.650887 -12.021974) (xy 334.599478 -11.98099)
			(xy 334.575912 -11.958066) (xy 334.52816 -11.910314) (xy 334.52562 -11.909806) (xy 334.442308 -11.912092)
			(xy 334.43672 -11.912854) (xy 334.42275 -11.928856) (xy 334.395572 -11.958066) (xy 334.024732 -12.328906)
			(xy 334.02143 -12.33297) (xy 334.017296 -12.339481) (xy 334.012771 -12.354217) (xy 334.01254 -12.361926)
			(xy 334.01254 -13.644118) (xy 334.01254 -13.644372) (xy 334.01275 -13.650109) (xy 334.015451 -13.661265)
			(xy 334.017874 -13.66647) (xy 334.022954 -13.674852) (xy 334.030533 -13.68428) (xy 334.049272 -13.699564)
			(xy 334.060038 -13.705078) (xy 334.06207 -13.706094) (xy 334.06715 -13.708126) (xy 334.067658 -13.708126)
			(xy 334.076908 -13.711175) (xy 334.096364 -13.710813) (xy 334.114288 -13.703236) (xy 334.121506 -13.696696)
			(xy 336.197702 -11.6205) (xy 336.202692 -11.615002) (xy 336.209543 -11.601837) (xy 336.211164 -11.594592)
			(xy 336.21218 -11.58494) (xy 336.21218 -9.95299) (xy 336.212017 -9.946979) (xy 336.209201 -9.935293)
			(xy 336.206592 -9.929876) (xy 336.201004 -9.918954) (xy 336.200242 -9.918446) (xy 336.175604 -9.90092)
			(xy 336.167611 -9.895826) (xy 336.149235 -9.891257) (xy 336.13979 -9.89203) (xy 336.136996 -9.892538)
			(xy 336.130392 -9.894824) (xy 336.100029 -9.904676) (xy 336.037085 -9.91528) (xy 336.00517 -9.915906)
			(xy 336.004662 -9.915906) (xy 335.977284 -9.915415) (xy 335.923086 -9.907618) (xy 335.87055 -9.892187)
			(xy 335.820744 -9.869437) (xy 335.774682 -9.839831) (xy 335.733302 -9.803971) (xy 335.697447 -9.762588)
			(xy 335.667845 -9.716523) (xy 335.6451 -9.666715) (xy 335.629674 -9.614177) (xy 335.621882 -9.559978)
			(xy 335.621882 -9.505222) (xy 335.629674 -9.451023) (xy 335.6451 -9.398485) (xy 335.667845 -9.348677)
			(xy 335.697447 -9.302612) (xy 335.733302 -9.261229) (xy 335.774682 -9.225369) (xy 335.820744 -9.195763)
			(xy 335.87055 -9.173013) (xy 335.923086 -9.157582) (xy 335.977284 -9.149785) (xy 336.004662 -9.149334)
			(xy 336.005424 -9.149334) (xy 336.037273 -9.150009) (xy 336.100084 -9.160607) (xy 336.130392 -9.170416)
			(xy 336.140044 -9.173718) (xy 336.141822 -9.173972) (xy 336.150016 -9.17431) (xy 336.165938 -9.170414)
			(xy 336.173064 -9.166352) (xy 336.19059 -9.153906) (xy 336.194702 -9.150864) (xy 336.201734 -9.143438)
			(xy 336.20456 -9.139174) (xy 336.208094 -9.133011) (xy 336.211973 -9.11935) (xy 336.21218 -9.11225)
			(xy 336.21218 -7.536942) (xy 336.21266 -7.504065) (xy 336.220055 -7.438729) (xy 336.234713 -7.374629)
			(xy 336.256449 -7.312572) (xy 336.28499 -7.253335) (xy 336.319979 -7.197664) (xy 336.360976 -7.146255)
			(xy 336.383884 -7.122668) (xy 336.978244 -6.528308) (xy 337.001819 -6.505358) (xy 337.053257 -6.464331)
			(xy 337.108966 -6.429321) (xy 337.168244 -6.40077) (xy 337.230347 -6.379035) (xy 337.294492 -6.36439)
			(xy 337.359874 -6.35702) (xy 337.392772 -6.356604) (xy 337.428181 -6.357116) (xy 337.498483 -6.365652)
			(xy 337.567242 -6.382602) (xy 337.633456 -6.407719) (xy 337.696159 -6.440637) (xy 337.754434 -6.480875)
			(xy 337.807433 -6.527847) (xy 337.854381 -6.580866) (xy 337.894594 -6.639159) (xy 337.927485 -6.701876)
			(xy 337.94179 -6.739636) (xy 339.101936 -6.739636) (xy 339.106007 -6.684014) (xy 339.118133 -6.629577)
			(xy 339.138056 -6.577486) (xy 339.165352 -6.528851) (xy 339.199438 -6.484708) (xy 339.239587 -6.445999)
			(xy 339.284945 -6.413548) (xy 339.334545 -6.388047) (xy 339.387329 -6.37004) (xy 339.442172 -6.35991)
			(xy 339.497906 -6.357873) (xy 339.553343 -6.363973) (xy 339.6073 -6.378079) (xy 339.658629 -6.399891)
			(xy 339.706235 -6.428945) (xy 339.749103 -6.46462) (xy 339.78632 -6.506157) (xy 339.817093 -6.55267)
			(xy 339.840765 -6.603167) (xy 339.856833 -6.656574) (xy 339.864953 -6.71175) (xy 339.865462 -6.739636)
			(xy 339.864953 -6.767522) (xy 339.856833 -6.822698) (xy 339.840765 -6.876105) (xy 339.817093 -6.926602)
			(xy 339.78632 -6.973115) (xy 339.749103 -7.014652) (xy 339.706235 -7.050327) (xy 339.658629 -7.079381)
			(xy 339.6073 -7.101193) (xy 339.553343 -7.115299) (xy 339.497906 -7.121399) (xy 339.442172 -7.119362)
			(xy 339.387329 -7.109232) (xy 339.334545 -7.091225) (xy 339.284945 -7.065724) (xy 339.239587 -7.033273)
			(xy 339.199438 -6.994564) (xy 339.165352 -6.950421) (xy 339.138056 -6.901786) (xy 339.118133 -6.849695)
			(xy 339.106007 -6.795258) (xy 339.101936 -6.739636) (xy 337.94179 -6.739636) (xy 337.952574 -6.768101)
			(xy 337.969494 -6.836867) (xy 337.977999 -6.907173) (xy 337.978496 -6.942582) (xy 337.978069 -6.975456)
			(xy 337.970739 -7.040794) (xy 337.956136 -7.1049) (xy 337.934443 -7.166966) (xy 337.905933 -7.226211)
			(xy 337.870966 -7.28189) (xy 337.829982 -7.333301) (xy 337.807046 -7.356856) (xy 337.563714 -7.600188)
			(xy 337.563206 -7.610348) (xy 337.57108 -7.670038) (xy 337.57108 -7.670546) (xy 337.573874 -7.690866)
			(xy 337.574626 -7.695454) (xy 337.577559 -7.704274) (xy 337.579716 -7.708392) (xy 337.598258 -7.718806)
			(xy 337.625871 -7.7347) (xy 337.637103 -7.742682) (xy 339.120224 -7.742682) (xy 339.124295 -7.68706)
			(xy 339.136421 -7.632623) (xy 339.156344 -7.580532) (xy 339.18364 -7.531897) (xy 339.217726 -7.487754)
			(xy 339.257875 -7.449045) (xy 339.303233 -7.416594) (xy 339.352833 -7.391093) (xy 339.405617 -7.373086)
			(xy 339.46046 -7.362956) (xy 339.516194 -7.360919) (xy 339.571631 -7.367019) (xy 339.625588 -7.381125)
			(xy 339.676917 -7.402937) (xy 339.724523 -7.431991) (xy 339.767391 -7.467666) (xy 339.804608 -7.509203)
			(xy 339.835381 -7.555716) (xy 339.859053 -7.606213) (xy 339.875121 -7.65962) (xy 339.883241 -7.714796)
			(xy 339.88375 -7.742682) (xy 339.883241 -7.770568) (xy 339.875121 -7.825744) (xy 339.859053 -7.879151)
			(xy 339.835381 -7.929648) (xy 339.804608 -7.976161) (xy 339.767391 -8.017698) (xy 339.724523 -8.053373)
			(xy 339.676917 -8.082427) (xy 339.625588 -8.104239) (xy 339.571631 -8.118345) (xy 339.516194 -8.124445)
			(xy 339.46046 -8.122408) (xy 339.405617 -8.112278) (xy 339.352833 -8.094271) (xy 339.303233 -8.06877)
			(xy 339.257875 -8.036319) (xy 339.217726 -7.99761) (xy 339.18364 -7.953467) (xy 339.156344 -7.904832)
			(xy 339.136421 -7.852741) (xy 339.124295 -7.798304) (xy 339.120224 -7.742682) (xy 337.637103 -7.742682)
			(xy 337.677807 -7.771608) (xy 337.725433 -7.813932) (xy 337.768185 -7.861175) (xy 337.805559 -7.912777)
			(xy 337.837113 -7.96813) (xy 337.862474 -8.02658) (xy 337.872324 -8.05688) (xy 337.872324 -8.057134)
			(xy 337.875372 -8.06704) (xy 337.878674 -8.076946) (xy 337.884516 -8.080248) (xy 337.946238 -8.11276)
			(xy 337.953521 -8.116263) (xy 337.969445 -8.118969) (xy 337.97748 -8.118094) (xy 337.985354 -8.117078)
			(xy 337.988402 -8.116316) (xy 338.013851 -8.109633) (xy 338.06598 -8.102491) (xy 338.092288 -8.102092)
			(xy 338.094066 -8.102092) (xy 338.107274 -8.102346) (xy 338.113624 -8.102346) (xy 338.115402 -8.1026)
			(xy 338.128864 -8.10387) (xy 338.156844 -8.107055) (xy 338.211502 -8.120602) (xy 338.263576 -8.142035)
			(xy 338.311934 -8.17089) (xy 338.355526 -8.206538) (xy 338.393406 -8.248206) (xy 338.42475 -8.294989)
			(xy 338.448877 -8.34587) (xy 338.465264 -8.399745) (xy 338.473556 -8.455444) (xy 338.47405 -8.4836)
			(xy 338.473568 -8.510795) (xy 338.465845 -8.564633) (xy 338.450554 -8.616829) (xy 338.428006 -8.666324)
			(xy 338.398659 -8.712116) (xy 338.363105 -8.753276) (xy 338.322068 -8.788971) (xy 338.276377 -8.818476)
			(xy 338.226959 -8.841194) (xy 338.174816 -8.856664) (xy 338.121005 -8.864573) (xy 338.093812 -8.865108)
			(xy 338.092034 -8.865108) (xy 338.071747 -8.864822) (xy 338.031404 -8.86049) (xy 338.011516 -8.856472)
			(xy 338.000594 -8.854186) (xy 337.989418 -8.856726) (xy 337.983741 -8.858163) (xy 337.973222 -8.863302)
			(xy 337.96859 -8.866886) (xy 337.930744 -8.89762) (xy 337.90763 -8.916162) (xy 337.89874 -8.925306)
			(xy 337.89874 -11.984482) (xy 337.898259 -12.017358) (xy 337.890861 -12.082694) (xy 337.876202 -12.146792)
			(xy 337.854465 -12.208848) (xy 337.825922 -12.268083) (xy 337.790933 -12.323754) (xy 337.749936 -12.375161)
			(xy 337.727036 -12.398756) (xy 335.517236 -14.608302) (xy 335.51453 -14.611153) (xy 335.509937 -14.617531)
			(xy 335.508092 -14.621002) (xy 335.505505 -14.626428) (xy 335.502672 -14.638108) (xy 335.502504 -14.644116)
			(xy 335.502504 -16.969994) (xy 362.048305 -16.969994) (xy 362.05231 -16.882086) (xy 362.064293 -16.794906)
			(xy 362.084153 -16.709177) (xy 362.111728 -16.625609) (xy 362.146787 -16.544895) (xy 362.18904 -16.467703)
			(xy 362.238138 -16.394674) (xy 362.293674 -16.326412) (xy 362.355186 -16.263482) (xy 362.422167 -16.206408)
			(xy 362.49406 -16.15566) (xy 362.570269 -16.11166) (xy 362.650164 -16.074773) (xy 362.733083 -16.045304)
			(xy 362.818338 -16.023497) (xy 362.905222 -16.009533) (xy 362.993016 -16.003527) (xy 363.080993 -16.005531)
			(xy 363.168423 -16.015526) (xy 363.254582 -16.03343) (xy 363.338756 -16.059094) (xy 363.420247 -16.092307)
			(xy 363.498381 -16.132793) (xy 363.572509 -16.180215) (xy 363.642017 -16.234182) (xy 363.706331 -16.294247)
			(xy 363.764915 -16.359911) (xy 363.817286 -16.43063) (xy 363.863009 -16.505818) (xy 363.901706 -16.584853)
			(xy 363.933055 -16.667079) (xy 363.956797 -16.751815) (xy 363.972735 -16.838359) (xy 363.980737 -16.925994)
			(xy 363.981238 -16.969994) (xy 363.980737 -17.013994) (xy 363.972735 -17.101629) (xy 363.956797 -17.188173)
			(xy 363.933055 -17.272909) (xy 363.901706 -17.355135) (xy 363.863009 -17.43417) (xy 363.817286 -17.509358)
			(xy 363.764915 -17.580077) (xy 363.706331 -17.645741) (xy 363.642017 -17.705806) (xy 363.572509 -17.759773)
			(xy 363.498381 -17.807195) (xy 363.420247 -17.847681) (xy 363.338756 -17.880894) (xy 363.254582 -17.906558)
			(xy 363.168423 -17.924462) (xy 363.080993 -17.934457) (xy 362.993016 -17.936461) (xy 362.905222 -17.930455)
			(xy 362.818338 -17.916491) (xy 362.733083 -17.894684) (xy 362.650164 -17.865215) (xy 362.570269 -17.828328)
			(xy 362.49406 -17.784328) (xy 362.422167 -17.73358) (xy 362.355186 -17.676506) (xy 362.293674 -17.613576)
			(xy 362.238138 -17.545314) (xy 362.18904 -17.472285) (xy 362.146787 -17.395093) (xy 362.111728 -17.314379)
			(xy 362.084153 -17.230811) (xy 362.064293 -17.145082) (xy 362.05231 -17.057902) (xy 362.048305 -16.969994)
			(xy 335.502504 -16.969994) (xy 335.502504 -20.72513) (xy 353.480636 -20.72513) (xy 353.484606 -20.594996)
			(xy 353.496502 -20.465346) (xy 353.516281 -20.336663) (xy 353.543867 -20.209424) (xy 353.57916 -20.084105)
			(xy 353.622026 -19.961169) (xy 353.672308 -19.841076) (xy 353.729817 -19.724272) (xy 353.794341 -19.61119)
			(xy 353.865638 -19.502253) (xy 353.943443 -19.397865) (xy 354.027468 -19.298414) (xy 354.1174 -19.204271)
			(xy 354.212904 -19.115786) (xy 354.313624 -19.033287) (xy 354.419186 -18.957082) (xy 354.529198 -18.887455)
			(xy 354.64325 -18.824664) (xy 354.760918 -18.768942) (xy 354.881764 -18.720498) (xy 355.005339 -18.679511)
			(xy 355.131182 -18.646134) (xy 355.258827 -18.620491) (xy 355.387797 -18.602677) (xy 355.517613 -18.592759)
			(xy 355.647792 -18.590774) (xy 355.777851 -18.596728) (xy 355.907304 -18.610601) (xy 356.035671 -18.632339)
			(xy 356.162474 -18.661863) (xy 356.287241 -18.699062) (xy 356.409508 -18.743798) (xy 356.528821 -18.795906)
			(xy 356.644734 -18.855189) (xy 356.756819 -18.92143) (xy 356.864656 -18.99438) (xy 356.967845 -19.073768)
			(xy 357.066003 -19.1593) (xy 357.158764 -19.250657) (xy 357.245783 -19.347499) (xy 357.326736 -19.449466)
			(xy 357.401322 -19.556178) (xy 357.469263 -19.667239) (xy 357.530308 -19.782235) (xy 357.584229 -19.900739)
			(xy 357.630824 -20.02231) (xy 357.669922 -20.146495) (xy 357.701376 -20.272833) (xy 357.72507 -20.400854)
			(xy 357.740914 -20.53008) (xy 357.748852 -20.660033) (xy 357.749348 -20.72513) (xy 357.748852 -20.790227)
			(xy 357.740914 -20.92018) (xy 357.72507 -21.049406) (xy 357.701376 -21.177427) (xy 357.669922 -21.303765)
			(xy 357.630824 -21.42795) (xy 357.584229 -21.549521) (xy 357.530308 -21.668025) (xy 357.469263 -21.783021)
			(xy 357.401322 -21.894082) (xy 357.326736 -22.000794) (xy 357.245783 -22.102761) (xy 357.158764 -22.199603)
			(xy 357.066003 -22.29096) (xy 356.967845 -22.376492) (xy 356.864656 -22.45588) (xy 356.756819 -22.52883)
			(xy 356.644734 -22.595071) (xy 356.528821 -22.654354) (xy 356.409508 -22.706462) (xy 356.287241 -22.751198)
			(xy 356.162474 -22.788397) (xy 356.035671 -22.817921) (xy 355.907304 -22.839659) (xy 355.777851 -22.853532)
			(xy 355.647792 -22.859486) (xy 355.517613 -22.857501) (xy 355.387797 -22.847583) (xy 355.258827 -22.829769)
			(xy 355.131182 -22.804126) (xy 355.005339 -22.770749) (xy 354.881764 -22.729762) (xy 354.760918 -22.681318)
			(xy 354.64325 -22.625596) (xy 354.529198 -22.562805) (xy 354.419186 -22.493178) (xy 354.313624 -22.416973)
			(xy 354.212904 -22.334474) (xy 354.1174 -22.245989) (xy 354.027468 -22.151846) (xy 353.943443 -22.052395)
			(xy 353.865638 -21.948007) (xy 353.794341 -21.83907) (xy 353.729817 -21.725988) (xy 353.672308 -21.609184)
			(xy 353.622026 -21.489091) (xy 353.57916 -21.366155) (xy 353.543867 -21.240836) (xy 353.516281 -21.113597)
			(xy 353.496502 -20.984914) (xy 353.484606 -20.855264) (xy 353.480636 -20.72513) (xy 335.502504 -20.72513)
			(xy 335.502504 -24.807418) (xy 354.671374 -24.807418) (xy 354.675445 -24.751796) (xy 354.687571 -24.697359)
			(xy 354.707494 -24.645268) (xy 354.73479 -24.596633) (xy 354.768876 -24.55249) (xy 354.809025 -24.513781)
			(xy 354.854383 -24.48133) (xy 354.903983 -24.455829) (xy 354.956767 -24.437822) (xy 355.01161 -24.427692)
			(xy 355.067344 -24.425655) (xy 355.122781 -24.431755) (xy 355.176738 -24.445861) (xy 355.228067 -24.467673)
			(xy 355.275673 -24.496727) (xy 355.318541 -24.532402) (xy 355.355758 -24.573939) (xy 355.386531 -24.620452)
			(xy 355.410203 -24.670949) (xy 355.426271 -24.724356) (xy 355.434391 -24.779532) (xy 355.4349 -24.807418)
			(xy 355.434391 -24.835304) (xy 355.426271 -24.89048) (xy 355.410203 -24.943887) (xy 355.386531 -24.994384)
			(xy 355.355758 -25.040897) (xy 355.318541 -25.082434) (xy 355.275673 -25.118109) (xy 355.228067 -25.147163)
			(xy 355.176738 -25.168975) (xy 355.122781 -25.183081) (xy 355.067344 -25.189181) (xy 355.01161 -25.187144)
			(xy 354.956767 -25.177014) (xy 354.903983 -25.159007) (xy 354.854383 -25.133506) (xy 354.809025 -25.101055)
			(xy 354.768876 -25.062346) (xy 354.73479 -25.018203) (xy 354.707494 -24.969568) (xy 354.687571 -24.917477)
			(xy 354.675445 -24.86304) (xy 354.671374 -24.807418) (xy 335.502504 -24.807418) (xy 335.502504 -25.912572)
			(xy 335.502582 -25.916782) (xy 335.503982 -25.925083) (xy 335.505298 -25.929082) (xy 335.507838 -25.936448)
			(xy 335.51241 -25.942544) (xy 335.538318 -25.950418) (xy 335.561885 -25.958146) (xy 335.60697 -25.978815)
			(xy 335.649039 -26.005084) (xy 335.683994 -26.03373) (xy 353.567998 -26.03373) (xy 353.572069 -25.978108)
			(xy 353.584195 -25.923671) (xy 353.604118 -25.87158) (xy 353.631414 -25.822945) (xy 353.6655 -25.778802)
			(xy 353.705649 -25.740093) (xy 353.751007 -25.707642) (xy 353.800607 -25.682141) (xy 353.853391 -25.664134)
			(xy 353.908234 -25.654004) (xy 353.963968 -25.651967) (xy 354.019405 -25.658067) (xy 354.073362 -25.672173)
			(xy 354.124691 -25.693985) (xy 354.172297 -25.723039) (xy 354.215165 -25.758714) (xy 354.252382 -25.800251)
			(xy 354.283155 -25.846764) (xy 354.306827 -25.897261) (xy 354.322895 -25.950668) (xy 354.331015 -26.005844)
			(xy 354.331524 -26.03373) (xy 354.331015 -26.061616) (xy 354.322895 -26.116792) (xy 354.306827 -26.170199)
			(xy 354.283155 -26.220696) (xy 354.252382 -26.267209) (xy 354.215165 -26.308746) (xy 354.172297 -26.344421)
			(xy 354.124691 -26.373475) (xy 354.073362 -26.395287) (xy 354.019405 -26.409393) (xy 353.963968 -26.415493)
			(xy 353.908234 -26.413456) (xy 353.853391 -26.403326) (xy 353.800607 -26.385319) (xy 353.751007 -26.359818)
			(xy 353.705649 -26.327367) (xy 353.6655 -26.288658) (xy 353.631414 -26.244515) (xy 353.604118 -26.19588)
			(xy 353.584195 -26.143789) (xy 353.572069 -26.089352) (xy 353.567998 -26.03373) (xy 335.683994 -26.03373)
			(xy 335.6874 -26.036521) (xy 335.704688 -26.054304) (xy 335.725908 -26.077636) (xy 335.761247 -26.129868)
			(xy 335.787642 -26.187143) (xy 335.796636 -26.217372) (xy 335.798922 -26.2255) (xy 336.741008 -27.167586)
			(xy 336.759038 -27.186358) (xy 336.789615 -27.228475) (xy 336.813239 -27.274852) (xy 336.82933 -27.324349)
			(xy 336.837494 -27.375751) (xy 336.838036 -27.401774) (xy 336.838036 -28.139136) (xy 350.698052 -28.139136)
			(xy 350.702123 -28.083514) (xy 350.714249 -28.029077) (xy 350.734172 -27.976986) (xy 350.761468 -27.928351)
			(xy 350.795554 -27.884208) (xy 350.835703 -27.845499) (xy 350.881061 -27.813048) (xy 350.930661 -27.787547)
			(xy 350.983445 -27.76954) (xy 351.038288 -27.75941) (xy 351.094022 -27.757373) (xy 351.149459 -27.763473)
			(xy 351.203416 -27.777579) (xy 351.254745 -27.799391) (xy 351.302351 -27.828445) (xy 351.345219 -27.86412)
			(xy 351.382436 -27.905657) (xy 351.413209 -27.95217) (xy 351.436881 -28.002667) (xy 351.452949 -28.056074)
			(xy 351.461069 -28.11125) (xy 351.461578 -28.139136) (xy 351.968052 -28.139136) (xy 351.972123 -28.083514)
			(xy 351.984249 -28.029077) (xy 352.004172 -27.976986) (xy 352.031468 -27.928351) (xy 352.065554 -27.884208)
			(xy 352.105703 -27.845499) (xy 352.151061 -27.813048) (xy 352.200661 -27.787547) (xy 352.253445 -27.76954)
			(xy 352.308288 -27.75941) (xy 352.364022 -27.757373) (xy 352.419459 -27.763473) (xy 352.473416 -27.777579)
			(xy 352.524745 -27.799391) (xy 352.572351 -27.828445) (xy 352.615219 -27.86412) (xy 352.652436 -27.905657)
			(xy 352.683209 -27.95217) (xy 352.706881 -28.002667) (xy 352.722949 -28.056074) (xy 352.731069 -28.11125)
			(xy 352.731578 -28.139136) (xy 352.731069 -28.167022) (xy 352.722949 -28.222198) (xy 352.706881 -28.275605)
			(xy 352.683209 -28.326102) (xy 352.652436 -28.372615) (xy 352.615219 -28.414152) (xy 352.572351 -28.449827)
			(xy 352.524745 -28.478881) (xy 352.473416 -28.500693) (xy 352.419459 -28.514799) (xy 352.364022 -28.520899)
			(xy 352.308288 -28.518862) (xy 352.253445 -28.508732) (xy 352.200661 -28.490725) (xy 352.151061 -28.465224)
			(xy 352.105703 -28.432773) (xy 352.065554 -28.394064) (xy 352.031468 -28.349921) (xy 352.004172 -28.301286)
			(xy 351.984249 -28.249195) (xy 351.972123 -28.194758) (xy 351.968052 -28.139136) (xy 351.461578 -28.139136)
			(xy 351.461069 -28.167022) (xy 351.452949 -28.222198) (xy 351.436881 -28.275605) (xy 351.413209 -28.326102)
			(xy 351.382436 -28.372615) (xy 351.345219 -28.414152) (xy 351.302351 -28.449827) (xy 351.254745 -28.478881)
			(xy 351.203416 -28.500693) (xy 351.149459 -28.514799) (xy 351.094022 -28.520899) (xy 351.038288 -28.518862)
			(xy 350.983445 -28.508732) (xy 350.930661 -28.490725) (xy 350.881061 -28.465224) (xy 350.835703 -28.432773)
			(xy 350.795554 -28.394064) (xy 350.761468 -28.349921) (xy 350.734172 -28.301286) (xy 350.714249 -28.249195)
			(xy 350.702123 -28.194758) (xy 350.698052 -28.139136) (xy 336.838036 -28.139136) (xy 336.838036 -30.175454)
			(xy 336.837508 -30.201477) (xy 336.829341 -30.25288) (xy 336.813246 -30.302377) (xy 336.789618 -30.348752)
			(xy 336.769198 -30.376876) (xy 349.18904 -30.376876) (xy 349.189598 -30.34796) (xy 349.198317 -30.29079)
			(xy 349.215566 -30.235592) (xy 349.24095 -30.18363) (xy 349.273887 -30.136095) (xy 349.313623 -30.094077)
			(xy 349.336106 -30.075886) (xy 349.344911 -30.068276) (xy 349.355095 -30.047378) (xy 349.355664 -30.035754)
			(xy 349.355664 -29.955998) (xy 349.355124 -29.944366) (xy 349.344937 -29.923456) (xy 349.336106 -29.915866)
			(xy 349.313607 -29.897693) (xy 349.273873 -29.855669) (xy 349.240936 -29.808131) (xy 349.21555 -29.756166)
			(xy 349.198297 -29.700965) (xy 349.189572 -29.643793) (xy 349.18904 -29.614876) (xy 349.189526 -29.587625)
			(xy 349.197282 -29.533677) (xy 349.212637 -29.481382) (xy 349.235279 -29.431805) (xy 349.264745 -29.385955)
			(xy 349.300436 -29.344764) (xy 349.341627 -29.309073) (xy 349.387477 -29.279607) (xy 349.437054 -29.256965)
			(xy 349.489349 -29.24161) (xy 349.543297 -29.233854) (xy 349.597799 -29.233854) (xy 349.651747 -29.24161)
			(xy 349.704042 -29.256965) (xy 349.753619 -29.279607) (xy 349.799469 -29.309073) (xy 349.84066 -29.344764)
			(xy 349.876351 -29.385955) (xy 349.905817 -29.431805) (xy 349.928459 -29.481382) (xy 349.943814 -29.533677)
			(xy 349.95157 -29.587625) (xy 349.952056 -29.614876) (xy 349.951537 -29.643793) (xy 349.942811 -29.700965)
			(xy 349.925554 -29.756165) (xy 349.900162 -29.808127) (xy 349.867218 -29.85566) (xy 349.827476 -29.897677)
			(xy 349.80499 -29.915866) (xy 349.796207 -29.923496) (xy 349.78601 -29.944379) (xy 349.785432 -29.955998)
			(xy 349.785432 -30.035754) (xy 349.785943 -30.04739) (xy 349.796151 -30.068299) (xy 349.80499 -30.075886)
			(xy 349.827465 -30.094087) (xy 349.867201 -30.136105) (xy 349.900141 -30.183637) (xy 349.925531 -30.235597)
			(xy 349.942789 -30.290792) (xy 349.95152 -30.347961) (xy 349.952056 -30.376876) (xy 349.95157 -30.404127)
			(xy 349.943814 -30.458075) (xy 349.928459 -30.51037) (xy 349.905817 -30.559947) (xy 349.876351 -30.605797)
			(xy 349.84066 -30.646988) (xy 349.799469 -30.682679) (xy 349.753619 -30.712145) (xy 349.704042 -30.734787)
			(xy 349.651747 -30.750142) (xy 349.597799 -30.757898) (xy 349.543297 -30.757898) (xy 349.489349 -30.750142)
			(xy 349.437054 -30.734787) (xy 349.387477 -30.712145) (xy 349.341627 -30.682679) (xy 349.300436 -30.646988)
			(xy 349.264745 -30.605797) (xy 349.235279 -30.559947) (xy 349.212637 -30.51037) (xy 349.197282 -30.458075)
			(xy 349.189526 -30.404127) (xy 349.18904 -30.376876) (xy 336.769198 -30.376876) (xy 336.759038 -30.390869)
			(xy 336.741008 -30.409642) (xy 335.76006 -31.39059) (xy 335.757353 -31.39344) (xy 335.752756 -31.399817)
			(xy 335.750916 -31.40329) (xy 335.748337 -31.408718) (xy 335.745523 -31.420397) (xy 335.745328 -31.426404)
			(xy 335.745328 -31.567882) (xy 349.298766 -31.567882) (xy 349.302837 -31.51226) (xy 349.314963 -31.457823)
			(xy 349.334886 -31.405732) (xy 349.362182 -31.357097) (xy 349.396268 -31.312954) (xy 349.436417 -31.274245)
			(xy 349.481775 -31.241794) (xy 349.531375 -31.216293) (xy 349.584159 -31.198286) (xy 349.639002 -31.188156)
			(xy 349.694736 -31.186119) (xy 349.750173 -31.192219) (xy 349.80413 -31.206325) (xy 349.855459 -31.228137)
			(xy 349.903065 -31.257191) (xy 349.945933 -31.292866) (xy 349.98315 -31.334403) (xy 350.013923 -31.380916)
			(xy 350.037595 -31.431413) (xy 350.053663 -31.48482) (xy 350.061783 -31.539996) (xy 350.062292 -31.567882)
			(xy 350.061783 -31.595768) (xy 350.053663 -31.650944) (xy 350.037595 -31.704351) (xy 350.030603 -31.719266)
			(xy 350.58553 -31.719266) (xy 350.589601 -31.663644) (xy 350.601727 -31.609207) (xy 350.62165 -31.557116)
			(xy 350.648946 -31.508481) (xy 350.683032 -31.464338) (xy 350.723181 -31.425629) (xy 350.768539 -31.393178)
			(xy 350.818139 -31.367677) (xy 350.870923 -31.34967) (xy 350.925766 -31.33954) (xy 350.9815 -31.337503)
			(xy 351.036937 -31.343603) (xy 351.090894 -31.357709) (xy 351.142223 -31.379521) (xy 351.189829 -31.408575)
			(xy 351.232697 -31.44425) (xy 351.269914 -31.485787) (xy 351.300687 -31.5323) (xy 351.324359 -31.582797)
			(xy 351.340427 -31.636204) (xy 351.344577 -31.664402) (xy 351.861118 -31.664402) (xy 351.865189 -31.60878)
			(xy 351.877315 -31.554343) (xy 351.897238 -31.502252) (xy 351.924534 -31.453617) (xy 351.95862 -31.409474)
			(xy 351.998769 -31.370765) (xy 352.044127 -31.338314) (xy 352.093727 -31.312813) (xy 352.146511 -31.294806)
			(xy 352.201354 -31.284676) (xy 352.257088 -31.282639) (xy 352.312525 -31.288739) (xy 352.366482 -31.302845)
			(xy 352.417811 -31.324657) (xy 352.465417 -31.353711) (xy 352.508285 -31.389386) (xy 352.545502 -31.430923)
			(xy 352.576275 -31.477436) (xy 352.599947 -31.527933) (xy 352.616015 -31.58134) (xy 352.624135 -31.636516)
			(xy 352.624644 -31.664402) (xy 352.624135 -31.692288) (xy 352.616015 -31.747464) (xy 352.599947 -31.800871)
			(xy 352.576275 -31.851368) (xy 352.545502 -31.897881) (xy 352.508285 -31.939418) (xy 352.465417 -31.975093)
			(xy 352.417811 -32.004147) (xy 352.366482 -32.025959) (xy 352.312525 -32.040065) (xy 352.257088 -32.046165)
			(xy 352.201354 -32.044128) (xy 352.146511 -32.033998) (xy 352.093727 -32.015991) (xy 352.044127 -31.99049)
			(xy 351.998769 -31.958039) (xy 351.95862 -31.91933) (xy 351.924534 -31.875187) (xy 351.897238 -31.826552)
			(xy 351.877315 -31.774461) (xy 351.865189 -31.720024) (xy 351.861118 -31.664402) (xy 351.344577 -31.664402)
			(xy 351.348547 -31.69138) (xy 351.349056 -31.719266) (xy 351.348547 -31.747152) (xy 351.340427 -31.802328)
			(xy 351.324359 -31.855735) (xy 351.300687 -31.906232) (xy 351.269914 -31.952745) (xy 351.232697 -31.994282)
			(xy 351.189829 -32.029957) (xy 351.142223 -32.059011) (xy 351.090894 -32.080823) (xy 351.036937 -32.094929)
			(xy 350.9815 -32.101029) (xy 350.925766 -32.098992) (xy 350.870923 -32.088862) (xy 350.818139 -32.070855)
			(xy 350.768539 -32.045354) (xy 350.723181 -32.012903) (xy 350.683032 -31.974194) (xy 350.648946 -31.930051)
			(xy 350.62165 -31.881416) (xy 350.601727 -31.829325) (xy 350.589601 -31.774888) (xy 350.58553 -31.719266)
			(xy 350.030603 -31.719266) (xy 350.013923 -31.754848) (xy 349.98315 -31.801361) (xy 349.945933 -31.842898)
			(xy 349.903065 -31.878573) (xy 349.855459 -31.907627) (xy 349.80413 -31.929439) (xy 349.750173 -31.943545)
			(xy 349.694736 -31.949645) (xy 349.639002 -31.947608) (xy 349.584159 -31.937478) (xy 349.531375 -31.919471)
			(xy 349.481775 -31.89397) (xy 349.436417 -31.861519) (xy 349.396268 -31.82281) (xy 349.362182 -31.778667)
			(xy 349.334886 -31.730032) (xy 349.314963 -31.677941) (xy 349.302837 -31.623504) (xy 349.298766 -31.567882)
			(xy 335.745328 -31.567882) (xy 335.745328 -35.23107) (xy 335.746344 -35.240722) (xy 335.747968 -35.247968)
			(xy 335.754805 -35.261141) (xy 335.758186 -35.264852) (xy 352.202494 -35.264852) (xy 352.206565 -35.20923)
			(xy 352.218691 -35.154793) (xy 352.238614 -35.102702) (xy 352.26591 -35.054067) (xy 352.299996 -35.009924)
			(xy 352.340145 -34.971215) (xy 352.385503 -34.938764) (xy 352.435103 -34.913263) (xy 352.487887 -34.895256)
			(xy 352.54273 -34.885126) (xy 352.598464 -34.883089) (xy 352.653901 -34.889189) (xy 352.707858 -34.903295)
			(xy 352.759187 -34.925107) (xy 352.806793 -34.954161) (xy 352.849661 -34.989836) (xy 352.886878 -35.031373)
			(xy 352.917651 -35.077886) (xy 352.941323 -35.128383) (xy 352.957391 -35.18179) (xy 352.965511 -35.236966)
			(xy 352.96602 -35.264852) (xy 352.965511 -35.292738) (xy 352.957391 -35.347914) (xy 352.941323 -35.401321)
			(xy 352.917651 -35.451818) (xy 352.886878 -35.498331) (xy 352.849661 -35.539868) (xy 352.806793 -35.575543)
			(xy 352.759187 -35.604597) (xy 352.707858 -35.626409) (xy 352.653901 -35.640515) (xy 352.598464 -35.646615)
			(xy 352.54273 -35.644578) (xy 352.487887 -35.634448) (xy 352.435103 -35.616441) (xy 352.385503 -35.59094)
			(xy 352.340145 -35.558489) (xy 352.299996 -35.51978) (xy 352.26591 -35.475637) (xy 352.238614 -35.427002)
			(xy 352.218691 -35.374911) (xy 352.206565 -35.320474) (xy 352.202494 -35.264852) (xy 335.758186 -35.264852)
			(xy 335.759806 -35.26663) (xy 336.369914 -35.876738) (xy 341.01735 -35.876738) (xy 341.021421 -35.821116)
			(xy 341.033547 -35.766679) (xy 341.05347 -35.714588) (xy 341.080766 -35.665953) (xy 341.114852 -35.62181)
			(xy 341.155001 -35.583101) (xy 341.200359 -35.55065) (xy 341.249959 -35.525149) (xy 341.302743 -35.507142)
			(xy 341.357586 -35.497012) (xy 341.41332 -35.494975) (xy 341.468757 -35.501075) (xy 341.522714 -35.515181)
			(xy 341.574043 -35.536993) (xy 341.621649 -35.566047) (xy 341.664517 -35.601722) (xy 341.701734 -35.643259)
			(xy 341.732507 -35.689772) (xy 341.756179 -35.740269) (xy 341.772247 -35.793676) (xy 341.780367 -35.848852)
			(xy 341.780876 -35.876738) (xy 341.780367 -35.904624) (xy 341.772247 -35.9598) (xy 341.756179 -36.013207)
			(xy 341.732507 -36.063704) (xy 341.701734 -36.110217) (xy 341.664517 -36.151754) (xy 341.621649 -36.187429)
			(xy 341.574043 -36.216483) (xy 341.522714 -36.238295) (xy 341.468757 -36.252401) (xy 341.41332 -36.258501)
			(xy 341.357586 -36.256464) (xy 341.302743 -36.246334) (xy 341.249959 -36.228327) (xy 341.200359 -36.202826)
			(xy 341.155001 -36.170375) (xy 341.114852 -36.131666) (xy 341.080766 -36.087523) (xy 341.05347 -36.038888)
			(xy 341.033547 -35.986797) (xy 341.021421 -35.93236) (xy 341.01735 -35.876738) (xy 336.369914 -35.876738)
			(xy 337.003136 -36.50996) (xy 342.913968 -36.50996) (xy 342.918039 -36.454338) (xy 342.930165 -36.399901)
			(xy 342.950088 -36.34781) (xy 342.977384 -36.299175) (xy 343.01147 -36.255032) (xy 343.051619 -36.216323)
			(xy 343.096977 -36.183872) (xy 343.146577 -36.158371) (xy 343.199361 -36.140364) (xy 343.254204 -36.130234)
			(xy 343.309938 -36.128197) (xy 343.365375 -36.134297) (xy 343.419332 -36.148403) (xy 343.470661 -36.170215)
			(xy 343.518267 -36.199269) (xy 343.561135 -36.234944) (xy 343.598352 -36.276481) (xy 343.629125 -36.322994)
			(xy 343.652797 -36.373491) (xy 343.668865 -36.426898) (xy 343.676985 -36.482074) (xy 343.677494 -36.50996)
			(xy 343.676985 -36.537846) (xy 343.668865 -36.593022) (xy 343.652797 -36.646429) (xy 343.629125 -36.696926)
			(xy 343.598352 -36.743439) (xy 343.561135 -36.784976) (xy 343.518267 -36.820651) (xy 343.470661 -36.849705)
			(xy 343.419332 -36.871517) (xy 343.365375 -36.885623) (xy 343.309938 -36.891723) (xy 343.254204 -36.889686)
			(xy 343.199361 -36.879556) (xy 343.146577 -36.861549) (xy 343.096977 -36.836048) (xy 343.051619 -36.803597)
			(xy 343.01147 -36.764888) (xy 342.977384 -36.720745) (xy 342.950088 -36.67211) (xy 342.930165 -36.620019)
			(xy 342.918039 -36.565582) (xy 342.913968 -36.50996) (xy 337.003136 -36.50996) (xy 337.968336 -37.47516)
			(xy 340.059262 -37.47516) (xy 340.063333 -37.419538) (xy 340.075459 -37.365101) (xy 340.095382 -37.31301)
			(xy 340.122678 -37.264375) (xy 340.156764 -37.220232) (xy 340.196913 -37.181523) (xy 340.242271 -37.149072)
			(xy 340.291871 -37.123571) (xy 340.344655 -37.105564) (xy 340.399498 -37.095434) (xy 340.455232 -37.093397)
			(xy 340.510669 -37.099497) (xy 340.564626 -37.113603) (xy 340.615955 -37.135415) (xy 340.663561 -37.164469)
			(xy 340.706429 -37.200144) (xy 340.743646 -37.241681) (xy 340.774419 -37.288194) (xy 340.798091 -37.338691)
			(xy 340.814159 -37.392098) (xy 340.822279 -37.447274) (xy 340.822788 -37.47516) (xy 340.822279 -37.503046)
			(xy 340.814159 -37.558222) (xy 340.798091 -37.611629) (xy 340.774419 -37.662126) (xy 340.774266 -37.662358)
			(xy 342.248488 -37.662358) (xy 342.252559 -37.606736) (xy 342.264685 -37.552299) (xy 342.284608 -37.500208)
			(xy 342.311904 -37.451573) (xy 342.34599 -37.40743) (xy 342.386139 -37.368721) (xy 342.431497 -37.33627)
			(xy 342.481097 -37.310769) (xy 342.533881 -37.292762) (xy 342.588724 -37.282632) (xy 342.644458 -37.280595)
			(xy 342.699895 -37.286695) (xy 342.753852 -37.300801) (xy 342.805181 -37.322613) (xy 342.852787 -37.351667)
			(xy 342.895655 -37.387342) (xy 342.932872 -37.428879) (xy 342.963645 -37.475392) (xy 342.987317 -37.525889)
			(xy 343.003385 -37.579296) (xy 343.011505 -37.634472) (xy 343.012014 -37.662358) (xy 343.011505 -37.690244)
			(xy 343.003385 -37.74542) (xy 342.987317 -37.798827) (xy 342.963645 -37.849324) (xy 342.932872 -37.895837)
			(xy 342.895655 -37.937374) (xy 342.852787 -37.973049) (xy 342.805181 -38.002103) (xy 342.753852 -38.023915)
			(xy 342.699895 -38.038021) (xy 342.644458 -38.044121) (xy 342.588724 -38.042084) (xy 342.533881 -38.031954)
			(xy 342.481097 -38.013947) (xy 342.431497 -37.988446) (xy 342.386139 -37.955995) (xy 342.34599 -37.917286)
			(xy 342.311904 -37.873143) (xy 342.284608 -37.824508) (xy 342.264685 -37.772417) (xy 342.252559 -37.71798)
			(xy 342.248488 -37.662358) (xy 340.774266 -37.662358) (xy 340.743646 -37.708639) (xy 340.706429 -37.750176)
			(xy 340.663561 -37.785851) (xy 340.615955 -37.814905) (xy 340.564626 -37.836717) (xy 340.510669 -37.850823)
			(xy 340.455232 -37.856923) (xy 340.399498 -37.854886) (xy 340.344655 -37.844756) (xy 340.291871 -37.826749)
			(xy 340.242271 -37.801248) (xy 340.196913 -37.768797) (xy 340.156764 -37.730088) (xy 340.122678 -37.685945)
			(xy 340.095382 -37.63731) (xy 340.075459 -37.585219) (xy 340.063333 -37.530782) (xy 340.059262 -37.47516)
			(xy 337.968336 -37.47516) (xy 339.223124 -38.729948) (xy 346.00112 -38.729948) (xy 346.00112 -38.675452)
			(xy 346.008875 -38.621512) (xy 346.024228 -38.569224) (xy 346.046866 -38.519653) (xy 346.076327 -38.473809)
			(xy 346.112013 -38.432623) (xy 346.153197 -38.396936) (xy 346.199041 -38.367472) (xy 346.248611 -38.344833)
			(xy 346.300898 -38.329478) (xy 346.354838 -38.321721) (xy 346.382086 -38.321234) (xy 346.410391 -38.321719)
			(xy 346.46638 -38.33007) (xy 346.52052 -38.346605) (xy 346.571621 -38.37096) (xy 346.618561 -38.402602)
			(xy 346.660308 -38.440835) (xy 346.695945 -38.484818) (xy 346.710762 -38.50894) (xy 346.718313 -38.521007)
			(xy 346.738941 -38.540611) (xy 346.764183 -38.553753) (xy 346.792074 -38.559408) (xy 346.820441 -38.557138)
			(xy 346.847077 -38.547118) (xy 346.869907 -38.530129) (xy 346.87891 -38.5191) (xy 346.897096 -38.496223)
			(xy 346.939259 -38.455759) (xy 346.987095 -38.422192) (xy 347.039487 -38.396305) (xy 347.095211 -38.378703)
			(xy 347.152967 -38.369797) (xy 347.182186 -38.36924) (xy 347.209443 -38.369606) (xy 347.263402 -38.377362)
			(xy 347.315708 -38.392719) (xy 347.365297 -38.415364) (xy 347.411157 -38.444835) (xy 347.452357 -38.480533)
			(xy 347.488057 -38.521731) (xy 347.51753 -38.567591) (xy 347.540176 -38.617178) (xy 347.555535 -38.669484)
			(xy 347.563293 -38.723443) (xy 347.563293 -38.777957) (xy 347.555535 -38.831916) (xy 347.540176 -38.884222)
			(xy 347.51753 -38.933809) (xy 347.488057 -38.979669) (xy 347.452357 -39.020867) (xy 347.411157 -39.056565)
			(xy 347.365297 -39.086036) (xy 347.315708 -39.108681) (xy 347.263402 -39.124038) (xy 347.209443 -39.131794)
			(xy 347.182186 -39.132256) (xy 347.153883 -39.131719) (xy 347.097896 -39.123379) (xy 347.043757 -39.106853)
			(xy 346.992656 -39.082506) (xy 346.945715 -39.050872) (xy 346.903966 -39.012647) (xy 346.868327 -38.968669)
			(xy 346.85351 -38.94455) (xy 346.845866 -38.932548) (xy 346.825256 -38.91295) (xy 346.800034 -38.899808)
			(xy 346.772163 -38.894145) (xy 346.743812 -38.896403) (xy 346.717189 -38.906404) (xy 346.694364 -38.923372)
			(xy 346.685362 -38.93439) (xy 346.66719 -38.957278) (xy 346.625024 -38.997742) (xy 346.577186 -39.031308)
			(xy 346.524791 -39.057193) (xy 346.469064 -39.074793) (xy 346.411306 -39.083695) (xy 346.382086 -39.08425)
			(xy 346.354838 -39.083679) (xy 346.300898 -39.075922) (xy 346.248611 -39.060567) (xy 346.199041 -39.037928)
			(xy 346.153197 -39.008464) (xy 346.112013 -38.972777) (xy 346.076327 -38.931591) (xy 346.046866 -38.885747)
			(xy 346.024228 -38.836176) (xy 346.008875 -38.783888) (xy 346.00112 -38.729948) (xy 339.223124 -38.729948)
			(xy 341.130636 -40.63746) (xy 341.148671 -40.656229) (xy 341.179258 -40.698344) (xy 341.202891 -40.74472)
			(xy 341.21899 -40.794218) (xy 341.227159 -40.845623) (xy 341.227664 -40.871648) (xy 341.227664 -40.971724)
			(xy 348.894144 -40.971724) (xy 348.898215 -40.916102) (xy 348.910341 -40.861665) (xy 348.930264 -40.809574)
			(xy 348.95756 -40.760939) (xy 348.991646 -40.716796) (xy 349.031795 -40.678087) (xy 349.077153 -40.645636)
			(xy 349.126753 -40.620135) (xy 349.179537 -40.602128) (xy 349.23438 -40.591998) (xy 349.290114 -40.589961)
			(xy 349.345551 -40.596061) (xy 349.399508 -40.610167) (xy 349.450837 -40.631979) (xy 349.498443 -40.661033)
			(xy 349.541311 -40.696708) (xy 349.578528 -40.738245) (xy 349.609301 -40.784758) (xy 349.632973 -40.835255)
			(xy 349.649041 -40.888662) (xy 349.657161 -40.943838) (xy 349.65767 -40.971724) (xy 349.657161 -40.99961)
			(xy 349.649041 -41.054786) (xy 349.632973 -41.108193) (xy 349.609301 -41.15869) (xy 349.578528 -41.205203)
			(xy 349.541311 -41.24674) (xy 349.498443 -41.282415) (xy 349.450837 -41.311469) (xy 349.399508 -41.333281)
			(xy 349.345551 -41.347387) (xy 349.290114 -41.353487) (xy 349.23438 -41.35145) (xy 349.179537 -41.34132)
			(xy 349.126753 -41.323313) (xy 349.077153 -41.297812) (xy 349.031795 -41.265361) (xy 348.991646 -41.226652)
			(xy 348.95756 -41.182509) (xy 348.930264 -41.133874) (xy 348.910341 -41.081783) (xy 348.898215 -41.027346)
			(xy 348.894144 -40.971724) (xy 341.227664 -40.971724) (xy 341.227664 -49.601949) (xy 354.413082 -49.601949)
			(xy 354.413082 -49.547451) (xy 354.420837 -49.493507) (xy 354.43619 -49.441217) (xy 354.458828 -49.391643)
			(xy 354.48829 -49.345795) (xy 354.523976 -49.304606) (xy 354.565161 -49.268915) (xy 354.611006 -49.239448)
			(xy 354.660577 -49.216805) (xy 354.712866 -49.201446) (xy 354.766809 -49.193685) (xy 354.794058 -49.193196)
			(xy 354.821427 -49.193688) (xy 354.875605 -49.201499) (xy 354.928108 -49.216983) (xy 354.977855 -49.239819)
			(xy 355.023823 -49.269537) (xy 355.044756 -49.287176) (xy 355.04501 -49.28743) (xy 355.052087 -49.29303)
			(xy 355.069011 -49.299268) (xy 355.07803 -49.299622) (xy 355.145086 -49.299622) (xy 355.154102 -49.299253)
			(xy 355.171018 -49.293013) (xy 355.178106 -49.28743) (xy 355.178106 -49.287176) (xy 355.17836 -49.287176)
			(xy 355.199293 -49.269535) (xy 355.245261 -49.239811) (xy 355.295007 -49.216965) (xy 355.347509 -49.201469)
			(xy 355.401687 -49.19364) (xy 355.456429 -49.19364) (xy 355.510607 -49.201469) (xy 355.563109 -49.216965)
			(xy 355.612855 -49.239811) (xy 355.658823 -49.269535) (xy 355.679756 -49.287176) (xy 355.68001 -49.28743)
			(xy 355.687087 -49.29303) (xy 355.704011 -49.299268) (xy 355.71303 -49.299622) (xy 355.780086 -49.299622)
			(xy 355.789102 -49.299253) (xy 355.806018 -49.293013) (xy 355.813106 -49.28743) (xy 355.813106 -49.287176)
			(xy 355.81336 -49.287176) (xy 355.834293 -49.269535) (xy 355.880261 -49.239811) (xy 355.930007 -49.216965)
			(xy 355.982509 -49.201469) (xy 356.036687 -49.19364) (xy 356.091429 -49.19364) (xy 356.145607 -49.201469)
			(xy 356.198109 -49.216965) (xy 356.247855 -49.239811) (xy 356.293823 -49.269535) (xy 356.314756 -49.287176)
			(xy 356.31501 -49.28743) (xy 356.322087 -49.29303) (xy 356.339011 -49.299268) (xy 356.34803 -49.299622)
			(xy 356.415086 -49.299622) (xy 356.424102 -49.299253) (xy 356.441018 -49.293013) (xy 356.448106 -49.28743)
			(xy 356.448106 -49.287176) (xy 356.44836 -49.287176) (xy 356.469293 -49.269538) (xy 356.515266 -49.239827)
			(xy 356.565013 -49.216991) (xy 356.617514 -49.2015) (xy 356.671689 -49.193671) (xy 356.699058 -49.193196)
			(xy 356.726313 -49.193648) (xy 356.780269 -49.201401) (xy 356.832573 -49.216753) (xy 356.882158 -49.239394)
			(xy 356.928017 -49.268861) (xy 356.969215 -49.304555) (xy 357.004914 -49.345749) (xy 357.034386 -49.391605)
			(xy 357.057032 -49.441188) (xy 357.07239 -49.49349) (xy 357.080149 -49.547445) (xy 357.080149 -49.601955)
			(xy 357.07239 -49.65591) (xy 357.057032 -49.708212) (xy 357.034386 -49.757795) (xy 357.004914 -49.803651)
			(xy 356.969215 -49.844845) (xy 356.928017 -49.880539) (xy 356.882158 -49.910006) (xy 356.832573 -49.932647)
			(xy 356.780269 -49.947999) (xy 356.726313 -49.955752) (xy 356.699058 -49.956212) (xy 356.671689 -49.955709)
			(xy 356.617512 -49.9479) (xy 356.565009 -49.932419) (xy 356.515262 -49.909586) (xy 356.469293 -49.879869)
			(xy 356.44836 -49.862232) (xy 356.448106 -49.861978) (xy 356.441024 -49.856385) (xy 356.424104 -49.850143)
			(xy 356.415086 -49.849786) (xy 356.34803 -49.849786) (xy 356.339015 -49.85016) (xy 356.322098 -49.856396)
			(xy 356.31501 -49.861978) (xy 356.314756 -49.862232) (xy 356.293823 -49.879873) (xy 356.247855 -49.909597)
			(xy 356.198109 -49.932443) (xy 356.145607 -49.947939) (xy 356.091429 -49.955768) (xy 356.036687 -49.955768)
			(xy 355.982509 -49.947939) (xy 355.930007 -49.932443) (xy 355.880261 -49.909597) (xy 355.834293 -49.879873)
			(xy 355.81336 -49.862232) (xy 355.813106 -49.861978) (xy 355.806024 -49.856385) (xy 355.789104 -49.850143)
			(xy 355.780086 -49.849786) (xy 355.71303 -49.849786) (xy 355.704015 -49.85016) (xy 355.687098 -49.856396)
			(xy 355.68001 -49.861978) (xy 355.68001 -49.862232) (xy 355.679756 -49.862232) (xy 355.658823 -49.879873)
			(xy 355.612855 -49.909597) (xy 355.563109 -49.932443) (xy 355.510607 -49.947939) (xy 355.456429 -49.955768)
			(xy 355.401687 -49.955768) (xy 355.347509 -49.947939) (xy 355.295007 -49.932443) (xy 355.245261 -49.909597)
			(xy 355.199293 -49.879873) (xy 355.17836 -49.862232) (xy 355.178106 -49.861978) (xy 355.171024 -49.856385)
			(xy 355.154104 -49.850143) (xy 355.145086 -49.849786) (xy 355.07803 -49.849786) (xy 355.069015 -49.85016)
			(xy 355.052098 -49.856396) (xy 355.04501 -49.861978) (xy 355.04501 -49.862232) (xy 355.044756 -49.862232)
			(xy 355.023818 -49.879863) (xy 354.977846 -49.909575) (xy 354.9281 -49.932412) (xy 354.875601 -49.947905)
			(xy 354.821427 -49.955736) (xy 354.794058 -49.956212) (xy 354.766809 -49.955715) (xy 354.712866 -49.947954)
			(xy 354.660577 -49.932595) (xy 354.611006 -49.909952) (xy 354.565161 -49.880485) (xy 354.523976 -49.844794)
			(xy 354.48829 -49.803605) (xy 354.458828 -49.757757) (xy 354.43619 -49.708183) (xy 354.420837 -49.655893)
			(xy 354.413082 -49.601949) (xy 341.227664 -49.601949) (xy 341.227664 -51.243992) (xy 355.433122 -51.243992)
			(xy 355.433578 -51.216621) (xy 355.441397 -51.162442) (xy 355.456889 -51.109938) (xy 355.479733 -51.060191)
			(xy 355.50946 -51.014225) (xy 355.527102 -50.993294) (xy 355.527356 -50.99304) (xy 355.532939 -50.985951)
			(xy 355.539186 -50.969036) (xy 355.539548 -50.96002) (xy 355.539548 -50.892964) (xy 355.53922 -50.883944)
			(xy 355.532954 -50.867027) (xy 355.527356 -50.859944) (xy 355.527102 -50.859944) (xy 355.527102 -50.85969)
			(xy 355.509445 -50.838772) (xy 355.479736 -50.792796) (xy 355.456903 -50.743044) (xy 355.441416 -50.690541)
			(xy 355.433593 -50.636362) (xy 355.433122 -50.608992) (xy 355.433548 -50.581738) (xy 355.441307 -50.527784)
			(xy 355.456665 -50.475483) (xy 355.479311 -50.425901) (xy 355.508783 -50.380047) (xy 355.54448 -50.338853)
			(xy 355.585677 -50.30316) (xy 355.631535 -50.273693) (xy 355.681119 -50.251052) (xy 355.733421 -50.235699)
			(xy 355.787376 -50.227945) (xy 355.81463 -50.227484) (xy 355.843547 -50.228021) (xy 355.900718 -50.236742)
			(xy 355.955918 -50.253994) (xy 356.007881 -50.279382) (xy 356.055415 -50.312324) (xy 356.097431 -50.352065)
			(xy 356.11562 -50.37455) (xy 356.123219 -50.383365) (xy 356.144126 -50.393542) (xy 356.155752 -50.394108)
			(xy 356.235508 -50.394108) (xy 356.247138 -50.393556) (xy 356.268048 -50.383376) (xy 356.27564 -50.37455)
			(xy 356.293796 -50.352037) (xy 356.335824 -50.312306) (xy 356.383367 -50.279372) (xy 356.435335 -50.253989)
			(xy 356.490538 -50.236739) (xy 356.547712 -50.228016) (xy 356.57663 -50.227484) (xy 356.603882 -50.22795)
			(xy 356.65783 -50.23571) (xy 356.710124 -50.251069) (xy 356.759701 -50.273713) (xy 356.805551 -50.303182)
			(xy 356.846741 -50.338875) (xy 356.882432 -50.380067) (xy 356.911898 -50.425918) (xy 356.934539 -50.475496)
			(xy 356.949894 -50.527792) (xy 356.957652 -50.58174) (xy 356.958138 -50.608992) (xy 356.957685 -50.635307)
			(xy 356.95045 -50.687437) (xy 356.936129 -50.73808) (xy 356.914994 -50.78628) (xy 356.887445 -50.831123)
			(xy 356.854002 -50.871761) (xy 356.834948 -50.889916) (xy 356.827545 -50.897436) (xy 356.81902 -50.916717)
			(xy 356.818438 -50.927254) (xy 356.818438 -51.00193) (xy 356.81898 -51.012478) (xy 356.827505 -51.031775)
			(xy 356.834948 -51.039268) (xy 356.854039 -51.057388) (xy 356.887491 -51.098026) (xy 356.915044 -51.142875)
			(xy 356.936176 -51.191082) (xy 356.950486 -51.241735) (xy 356.957703 -51.293874) (xy 356.958138 -51.320192)
			(xy 356.957615 -51.347442) (xy 356.94986 -51.401387) (xy 356.934508 -51.453679) (xy 356.91187 -51.503254)
			(xy 356.882407 -51.549103) (xy 356.846719 -51.590293) (xy 356.805533 -51.625984) (xy 356.759687 -51.655451)
			(xy 356.710114 -51.678094) (xy 356.657824 -51.693452) (xy 356.60388 -51.701212) (xy 356.57663 -51.7017)
			(xy 356.548966 -51.701164) (xy 356.494218 -51.693169) (xy 356.441197 -51.677357) (xy 356.391013 -51.654057)
			(xy 356.344717 -51.62376) (xy 356.303278 -51.587098) (xy 356.267564 -51.544839) (xy 356.252526 -51.521614)
			(xy 356.245887 -51.51194) (xy 356.226027 -51.499496) (xy 356.214426 -51.497738) (xy 356.134416 -51.489864)
			(xy 356.122778 -51.489246) (xy 356.100941 -51.497316) (xy 356.092506 -51.505358) (xy 356.092252 -51.505612)
			(xy 356.074179 -51.524201) (xy 356.033845 -51.556778) (xy 355.989469 -51.58359) (xy 355.941869 -51.604141)
			(xy 355.891923 -51.618053) (xy 355.840554 -51.625069) (xy 355.81463 -51.6255) (xy 355.787378 -51.625017)
			(xy 355.733427 -51.617264) (xy 355.681129 -51.601911) (xy 355.631548 -51.579271) (xy 355.585695 -51.549806)
			(xy 355.544501 -51.514114) (xy 355.508807 -51.472923) (xy 355.479339 -51.427071) (xy 355.456697 -51.377492)
			(xy 355.441341 -51.325195) (xy 355.433585 -51.271244) (xy 355.433122 -51.243992) (xy 341.227664 -51.243992)
			(xy 341.227664 -52.555948) (xy 354.884002 -52.555948) (xy 354.884002 -52.501452) (xy 354.891757 -52.44751)
			(xy 354.90711 -52.39522) (xy 354.929748 -52.345648) (xy 354.95921 -52.299802) (xy 354.994897 -52.258615)
			(xy 355.036081 -52.222926) (xy 355.081925 -52.193461) (xy 355.131496 -52.170819) (xy 355.183784 -52.155463)
			(xy 355.237726 -52.147704) (xy 355.264974 -52.147216) (xy 355.292344 -52.147693) (xy 355.346523 -52.155508)
			(xy 355.399026 -52.170994) (xy 355.448773 -52.193833) (xy 355.49474 -52.223556) (xy 355.515672 -52.241196)
			(xy 355.515926 -52.24145) (xy 355.523025 -52.247018) (xy 355.539932 -52.253275) (xy 355.548946 -52.253642)
			(xy 355.616002 -52.253642) (xy 355.62502 -52.253298) (xy 355.641938 -52.247043) (xy 355.649022 -52.24145)
			(xy 355.649022 -52.241196) (xy 355.649276 -52.241196) (xy 355.670206 -52.223554) (xy 355.716179 -52.193843)
			(xy 355.765927 -52.171007) (xy 355.818429 -52.155517) (xy 355.872605 -52.14769) (xy 355.899974 -52.147216)
			(xy 355.92723 -52.147629) (xy 355.981187 -52.155384) (xy 356.033491 -52.170738) (xy 356.083078 -52.193381)
			(xy 356.128937 -52.22285) (xy 356.170136 -52.258546) (xy 356.205834 -52.299742) (xy 356.235307 -52.345599)
			(xy 356.257953 -52.395184) (xy 356.273311 -52.447488) (xy 356.281069 -52.501444) (xy 356.281069 -52.555956)
			(xy 356.273311 -52.609912) (xy 356.257953 -52.662216) (xy 356.235307 -52.711801) (xy 356.205834 -52.757658)
			(xy 356.170136 -52.798854) (xy 356.128937 -52.83455) (xy 356.083078 -52.864019) (xy 356.033491 -52.886662)
			(xy 355.981187 -52.902016) (xy 355.92723 -52.909771) (xy 355.899974 -52.910232) (xy 355.872602 -52.909798)
			(xy 355.818421 -52.901975) (xy 355.765917 -52.886479) (xy 355.716171 -52.86363) (xy 355.670206 -52.833897)
			(xy 355.649276 -52.816252) (xy 355.649022 -52.815998) (xy 355.641933 -52.810414) (xy 355.625018 -52.804166)
			(xy 355.616002 -52.803806) (xy 355.548946 -52.803806) (xy 355.539931 -52.804184) (xy 355.523014 -52.810417)
			(xy 355.515926 -52.815998) (xy 355.515926 -52.816252) (xy 355.515672 -52.816252) (xy 355.494717 -52.833863)
			(xy 355.448752 -52.863581) (xy 355.39901 -52.886423) (xy 355.346514 -52.90192) (xy 355.292342 -52.909755)
			(xy 355.264974 -52.910232) (xy 355.237726 -52.909696) (xy 355.183784 -52.901937) (xy 355.131496 -52.886581)
			(xy 355.081925 -52.863939) (xy 355.036081 -52.834474) (xy 354.994897 -52.798785) (xy 354.95921 -52.757598)
			(xy 354.929748 -52.711752) (xy 354.90711 -52.66218) (xy 354.891757 -52.60989) (xy 354.884002 -52.555948)
			(xy 341.227664 -52.555948) (xy 341.227664 -53.496555) (xy 354.433541 -53.496555) (xy 354.433541 -53.442045)
			(xy 354.441299 -53.388089) (xy 354.456657 -53.335787) (xy 354.479303 -53.286202) (xy 354.508775 -53.240346)
			(xy 354.544474 -53.199151) (xy 354.585672 -53.163456) (xy 354.63153 -53.133988) (xy 354.681117 -53.111346)
			(xy 354.73342 -53.095992) (xy 354.787377 -53.088239) (xy 354.814632 -53.087778) (xy 354.842004 -53.088206)
			(xy 354.896185 -53.09603) (xy 354.94869 -53.111527) (xy 354.998436 -53.134378) (xy 355.0444 -53.164112)
			(xy 355.06533 -53.181758) (xy 355.065584 -53.182012) (xy 355.07267 -53.187599) (xy 355.089587 -53.193845)
			(xy 355.098604 -53.194204) (xy 355.16566 -53.194204) (xy 355.174675 -53.193827) (xy 355.191592 -53.187593)
			(xy 355.19868 -53.182012) (xy 355.19868 -53.181758) (xy 355.198934 -53.181758) (xy 355.219874 -53.164129)
			(xy 355.265846 -53.134417) (xy 355.315591 -53.11158) (xy 355.36809 -53.096086) (xy 355.422264 -53.088254)
			(xy 355.449632 -53.087778) (xy 355.476881 -53.088294) (xy 355.530823 -53.096054) (xy 355.583112 -53.111412)
			(xy 355.632683 -53.134054) (xy 355.678528 -53.16352) (xy 355.719713 -53.19921) (xy 355.755399 -53.240398)
			(xy 355.784862 -53.286245) (xy 355.8075 -53.335818) (xy 355.822852 -53.388108) (xy 355.830608 -53.442051)
			(xy 355.830608 -53.496549) (xy 355.822852 -53.550492) (xy 355.8075 -53.602782) (xy 355.784862 -53.652355)
			(xy 355.755399 -53.698202) (xy 355.719713 -53.73939) (xy 355.678528 -53.77508) (xy 355.632683 -53.804546)
			(xy 355.583112 -53.827188) (xy 355.530823 -53.842546) (xy 355.476881 -53.850306) (xy 355.449632 -53.850794)
			(xy 355.422262 -53.850311) (xy 355.368084 -53.842497) (xy 355.315581 -53.827012) (xy 355.265834 -53.804174)
			(xy 355.219866 -53.774453) (xy 355.198934 -53.756814) (xy 355.19868 -53.75656) (xy 355.191607 -53.750954)
			(xy 355.17468 -53.74472) (xy 355.16566 -53.744368) (xy 355.098604 -53.744368) (xy 355.089588 -53.744734)
			(xy 355.072672 -53.750976) (xy 355.065584 -53.75656) (xy 355.065584 -53.756814) (xy 355.06533 -53.756814)
			(xy 355.044399 -53.774455) (xy 354.998426 -53.804166) (xy 354.948678 -53.827001) (xy 354.896177 -53.842492)
			(xy 354.842001 -53.85032) (xy 354.814632 -53.850794) (xy 354.787377 -53.850361) (xy 354.73342 -53.842608)
			(xy 354.681117 -53.827254) (xy 354.63153 -53.804612) (xy 354.585672 -53.775144) (xy 354.544474 -53.739449)
			(xy 354.508775 -53.698254) (xy 354.479303 -53.652398) (xy 354.456657 -53.602813) (xy 354.441299 -53.550511)
			(xy 354.433541 -53.496555) (xy 341.227664 -53.496555) (xy 341.227664 -54.989055) (xy 352.201145 -54.989055)
			(xy 352.201145 -54.934545) (xy 352.208903 -54.880591) (xy 352.224261 -54.828289) (xy 352.246906 -54.778706)
			(xy 352.276377 -54.73285) (xy 352.312074 -54.691656) (xy 352.353271 -54.655961) (xy 352.399129 -54.626493)
			(xy 352.448714 -54.603851) (xy 352.501016 -54.588497) (xy 352.554971 -54.580743) (xy 352.582226 -54.580282)
			(xy 352.610318 -54.580756) (xy 352.665896 -54.588987) (xy 352.719666 -54.605282) (xy 352.770463 -54.629288)
			(xy 352.81719 -54.660486) (xy 352.858835 -54.698201) (xy 352.894496 -54.741616) (xy 352.909378 -54.765448)
			(xy 352.914712 -54.774338) (xy 352.93173 -54.78653) (xy 353.024948 -54.80685) (xy 353.045522 -54.802532)
			(xy 353.054158 -54.79669) (xy 353.078231 -54.780705) (xy 353.130159 -54.755359) (xy 353.185314 -54.738129)
			(xy 353.242436 -54.729409) (xy 353.271328 -54.728872) (xy 353.298579 -54.729352) (xy 353.352526 -54.737112)
			(xy 353.40482 -54.752469) (xy 353.454396 -54.775112) (xy 353.500245 -54.804579) (xy 353.541434 -54.840271)
			(xy 353.577125 -54.881462) (xy 353.606592 -54.927311) (xy 353.629234 -54.976888) (xy 353.64459 -55.029182)
			(xy 353.652349 -55.083129) (xy 353.652836 -55.11038) (xy 353.652374 -55.137751) (xy 353.644557 -55.19193)
			(xy 353.629068 -55.244434) (xy 353.606225 -55.294181) (xy 353.576499 -55.340147) (xy 353.558856 -55.361078)
			(xy 353.558602 -55.361332) (xy 353.553038 -55.368434) (xy 353.546778 -55.385339) (xy 353.54641 -55.394352)
			(xy 353.54641 -55.461408) (xy 353.546761 -55.470426) (xy 353.553012 -55.487343) (xy 353.558602 -55.494428)
			(xy 353.558856 -55.494428) (xy 353.558856 -55.494682) (xy 353.576478 -55.51563) (xy 353.606205 -55.561595)
			(xy 353.629052 -55.611339) (xy 353.644551 -55.663838) (xy 353.652382 -55.718015) (xy 353.652384 -55.772755)
			(xy 353.644557 -55.826932) (xy 353.629063 -55.879433) (xy 353.606219 -55.929179) (xy 353.576496 -55.975146)
			(xy 353.558856 -55.996078) (xy 353.558602 -55.996332) (xy 353.553038 -56.003434) (xy 353.546778 -56.020339)
			(xy 353.54641 -56.029352) (xy 353.54641 -56.096408) (xy 353.546761 -56.105426) (xy 353.553012 -56.122343)
			(xy 353.558602 -56.129428) (xy 353.558856 -56.129428) (xy 353.558856 -56.129682) (xy 353.576493 -56.150616)
			(xy 353.606207 -56.196587) (xy 353.629044 -56.246334) (xy 353.644535 -56.298835) (xy 353.652363 -56.353011)
			(xy 353.652836 -56.38038) (xy 353.65235 -56.407631) (xy 353.644594 -56.461579) (xy 353.629239 -56.513874)
			(xy 353.606597 -56.563451) (xy 353.577131 -56.609301) (xy 353.54144 -56.650492) (xy 353.500249 -56.686183)
			(xy 353.454399 -56.715649) (xy 353.404822 -56.738291) (xy 353.352527 -56.753646) (xy 353.298579 -56.761402)
			(xy 353.244077 -56.761402) (xy 353.190129 -56.753646) (xy 353.137834 -56.738291) (xy 353.088257 -56.715649)
			(xy 353.042407 -56.686183) (xy 353.001216 -56.650492) (xy 352.965525 -56.609301) (xy 352.936059 -56.563451)
			(xy 352.913417 -56.513874) (xy 352.898062 -56.461579) (xy 352.890306 -56.407631) (xy 352.88982 -56.38038)
			(xy 352.890269 -56.353009) (xy 352.898091 -56.298829) (xy 352.913583 -56.246326) (xy 352.936429 -56.196579)
			(xy 352.966157 -56.150613) (xy 352.9838 -56.129682) (xy 352.984054 -56.129428) (xy 352.989641 -56.122342)
			(xy 352.995886 -56.105425) (xy 352.996246 -56.096408) (xy 352.996246 -56.029352) (xy 352.995876 -56.020336)
			(xy 352.989639 -56.003418) (xy 352.984054 -55.996332) (xy 352.9838 -55.996332) (xy 352.9838 -55.996078)
			(xy 352.966141 -55.975161) (xy 352.936419 -55.929189) (xy 352.913576 -55.879441) (xy 352.898083 -55.826936)
			(xy 352.890257 -55.772756) (xy 352.890259 -55.718014) (xy 352.898089 -55.663834) (xy 352.913587 -55.611331)
			(xy 352.936433 -55.561584) (xy 352.966159 -55.515615) (xy 352.9838 -55.494682) (xy 352.984054 -55.494428)
			(xy 352.989641 -55.487342) (xy 352.995886 -55.470425) (xy 352.996246 -55.461408) (xy 352.996246 -55.394352)
			(xy 352.995876 -55.385336) (xy 352.989639 -55.368418) (xy 352.984054 -55.361332) (xy 352.9838 -55.360824)
			(xy 352.972856 -55.348089) (xy 352.953015 -55.320998) (xy 352.944176 -55.306722) (xy 352.938842 -55.297832)
			(xy 352.921824 -55.28564) (xy 352.828606 -55.26532) (xy 352.808032 -55.269638) (xy 352.799396 -55.27548)
			(xy 352.775333 -55.291482) (xy 352.723402 -55.316825) (xy 352.668243 -55.33405) (xy 352.611119 -55.342764)
			(xy 352.582226 -55.343298) (xy 352.554971 -55.342857) (xy 352.501016 -55.335103) (xy 352.448714 -55.319749)
			(xy 352.399129 -55.297107) (xy 352.353271 -55.267639) (xy 352.312074 -55.231944) (xy 352.276377 -55.19075)
			(xy 352.246906 -55.144894) (xy 352.224261 -55.095311) (xy 352.208903 -55.043009) (xy 352.201145 -54.989055)
			(xy 341.227664 -54.989055) (xy 341.227664 -55.420855) (xy 350.524745 -55.420855) (xy 350.524745 -55.366345)
			(xy 350.532503 -55.312391) (xy 350.547861 -55.260089) (xy 350.570506 -55.210506) (xy 350.599977 -55.16465)
			(xy 350.635674 -55.123456) (xy 350.676871 -55.087761) (xy 350.722729 -55.058293) (xy 350.772314 -55.035651)
			(xy 350.824616 -55.020297) (xy 350.878571 -55.012543) (xy 350.905826 -55.012082) (xy 350.93214 -55.012538)
			(xy 350.984269 -55.019776) (xy 351.034912 -55.034098) (xy 351.083111 -55.055232) (xy 351.127954 -55.08278)
			(xy 351.168593 -55.11622) (xy 351.18675 -55.135272) (xy 351.194255 -55.142694) (xy 351.213547 -55.151208)
			(xy 351.224088 -55.151782) (xy 351.298764 -55.151782) (xy 351.309314 -55.151252) (xy 351.32861 -55.142718)
			(xy 351.336102 -55.135272) (xy 351.354258 -55.116217) (xy 351.394888 -55.082761) (xy 351.439729 -55.055203)
			(xy 351.487929 -55.034064) (xy 351.538576 -55.019747) (xy 351.59071 -55.012521) (xy 351.617026 -55.012082)
			(xy 351.644275 -55.01259) (xy 351.698219 -55.020349) (xy 351.750509 -55.035706) (xy 351.800082 -55.058348)
			(xy 351.845927 -55.087814) (xy 351.887113 -55.123505) (xy 351.922801 -55.164693) (xy 351.952264 -55.210541)
			(xy 351.974903 -55.260115) (xy 351.990256 -55.312407) (xy 351.998012 -55.366351) (xy 351.998012 -55.420849)
			(xy 351.990256 -55.474793) (xy 351.974903 -55.527085) (xy 351.952264 -55.576659) (xy 351.922801 -55.622507)
			(xy 351.887113 -55.663695) (xy 351.845927 -55.699386) (xy 351.800082 -55.728852) (xy 351.750509 -55.751494)
			(xy 351.698219 -55.766851) (xy 351.644275 -55.77461) (xy 351.617026 -55.775098) (xy 351.590713 -55.774614)
			(xy 351.538585 -55.767383) (xy 351.487942 -55.753067) (xy 351.439743 -55.731937) (xy 351.394899 -55.704394)
			(xy 351.354259 -55.670958) (xy 351.336102 -55.651908) (xy 351.32858 -55.644507) (xy 351.3093 -55.635982)
			(xy 351.298764 -55.635398) (xy 351.224088 -55.635398) (xy 351.213536 -55.635908) (xy 351.194241 -55.644457)
			(xy 351.18675 -55.651908) (xy 351.168613 -55.670982) (xy 351.127979 -55.704437) (xy 351.083135 -55.731994)
			(xy 351.034931 -55.753129) (xy 350.98428 -55.767442) (xy 350.932143 -55.774662) (xy 350.905826 -55.775098)
			(xy 350.878571 -55.774657) (xy 350.824616 -55.766903) (xy 350.772314 -55.751549) (xy 350.722729 -55.728907)
			(xy 350.676871 -55.699439) (xy 350.635674 -55.663744) (xy 350.599977 -55.62255) (xy 350.570506 -55.576694)
			(xy 350.547861 -55.527111) (xy 350.532503 -55.474809) (xy 350.524745 -55.420855) (xy 341.227664 -55.420855)
			(xy 341.227664 -57.48528) (xy 352.906074 -57.48528) (xy 352.910145 -57.429658) (xy 352.922271 -57.375221)
			(xy 352.942194 -57.32313) (xy 352.96949 -57.274495) (xy 353.003576 -57.230352) (xy 353.043725 -57.191643)
			(xy 353.089083 -57.159192) (xy 353.138683 -57.133691) (xy 353.191467 -57.115684) (xy 353.24631 -57.105554)
			(xy 353.302044 -57.103517) (xy 353.357481 -57.109617) (xy 353.411438 -57.123723) (xy 353.462767 -57.145535)
			(xy 353.510373 -57.174589) (xy 353.553241 -57.210264) (xy 353.590458 -57.251801) (xy 353.621231 -57.298314)
			(xy 353.644903 -57.348811) (xy 353.660971 -57.402218) (xy 353.669091 -57.457394) (xy 353.6696 -57.48528)
			(xy 353.669091 -57.513166) (xy 353.660971 -57.568342) (xy 353.644903 -57.621749) (xy 353.621231 -57.672246)
			(xy 353.590458 -57.718759) (xy 353.553241 -57.760296) (xy 353.510373 -57.795971) (xy 353.462767 -57.825025)
			(xy 353.411438 -57.846837) (xy 353.357481 -57.860943) (xy 353.302044 -57.867043) (xy 353.24631 -57.865006)
			(xy 353.191467 -57.854876) (xy 353.138683 -57.836869) (xy 353.089083 -57.811368) (xy 353.043725 -57.778917)
			(xy 353.003576 -57.740208) (xy 352.96949 -57.696065) (xy 352.942194 -57.64743) (xy 352.922271 -57.595339)
			(xy 352.910145 -57.540902) (xy 352.906074 -57.48528) (xy 341.227664 -57.48528) (xy 341.227664 -58.561224)
			(xy 354.862382 -58.561224) (xy 354.866453 -58.505602) (xy 354.878579 -58.451165) (xy 354.898502 -58.399074)
			(xy 354.925798 -58.350439) (xy 354.959884 -58.306296) (xy 355.000033 -58.267587) (xy 355.045391 -58.235136)
			(xy 355.094991 -58.209635) (xy 355.147775 -58.191628) (xy 355.202618 -58.181498) (xy 355.258352 -58.179461)
			(xy 355.313789 -58.185561) (xy 355.367746 -58.199667) (xy 355.419075 -58.221479) (xy 355.466681 -58.250533)
			(xy 355.509549 -58.286208) (xy 355.546766 -58.327745) (xy 355.577539 -58.374258) (xy 355.601211 -58.424755)
			(xy 355.617279 -58.478162) (xy 355.625399 -58.533338) (xy 355.625908 -58.561224) (xy 355.625399 -58.58911)
			(xy 355.617279 -58.644286) (xy 355.601211 -58.697693) (xy 355.577539 -58.74819) (xy 355.546766 -58.794703)
			(xy 355.509549 -58.83624) (xy 355.466681 -58.871915) (xy 355.419075 -58.900969) (xy 355.367746 -58.922781)
			(xy 355.313789 -58.936887) (xy 355.258352 -58.942987) (xy 355.202618 -58.94095) (xy 355.147775 -58.93082)
			(xy 355.094991 -58.912813) (xy 355.045391 -58.887312) (xy 355.000033 -58.854861) (xy 354.959884 -58.816152)
			(xy 354.925798 -58.772009) (xy 354.898502 -58.723374) (xy 354.878579 -58.671283) (xy 354.866453 -58.616846)
			(xy 354.862382 -58.561224) (xy 341.227664 -58.561224) (xy 341.227664 -59.174634) (xy 353.393246 -59.174634)
			(xy 353.397317 -59.119012) (xy 353.409443 -59.064575) (xy 353.429366 -59.012484) (xy 353.456662 -58.963849)
			(xy 353.490748 -58.919706) (xy 353.530897 -58.880997) (xy 353.576255 -58.848546) (xy 353.625855 -58.823045)
			(xy 353.678639 -58.805038) (xy 353.733482 -58.794908) (xy 353.789216 -58.792871) (xy 353.844653 -58.798971)
			(xy 353.89861 -58.813077) (xy 353.949939 -58.834889) (xy 353.997545 -58.863943) (xy 354.040413 -58.899618)
			(xy 354.07763 -58.941155) (xy 354.108403 -58.987668) (xy 354.132075 -59.038165) (xy 354.148143 -59.091572)
			(xy 354.156263 -59.146748) (xy 354.156772 -59.174634) (xy 354.156263 -59.20252) (xy 354.148143 -59.257696)
			(xy 354.132075 -59.311103) (xy 354.108403 -59.3616) (xy 354.07763 -59.408113) (xy 354.040413 -59.44965)
			(xy 353.997545 -59.485325) (xy 353.949939 -59.514379) (xy 353.89861 -59.536191) (xy 353.844653 -59.550297)
			(xy 353.789216 -59.556397) (xy 353.733482 -59.55436) (xy 353.678639 -59.54423) (xy 353.625855 -59.526223)
			(xy 353.576255 -59.500722) (xy 353.530897 -59.468271) (xy 353.490748 -59.429562) (xy 353.456662 -59.385419)
			(xy 353.429366 -59.336784) (xy 353.409443 -59.284693) (xy 353.397317 -59.230256) (xy 353.393246 -59.174634)
			(xy 341.227664 -59.174634) (xy 341.227664 -60.633356) (xy 356.097076 -60.633356) (xy 356.101147 -60.577734)
			(xy 356.113273 -60.523297) (xy 356.133196 -60.471206) (xy 356.160492 -60.422571) (xy 356.194578 -60.378428)
			(xy 356.234727 -60.339719) (xy 356.280085 -60.307268) (xy 356.329685 -60.281767) (xy 356.382469 -60.26376)
			(xy 356.437312 -60.25363) (xy 356.493046 -60.251593) (xy 356.548483 -60.257693) (xy 356.60244 -60.271799)
			(xy 356.653769 -60.293611) (xy 356.701375 -60.322665) (xy 356.744243 -60.35834) (xy 356.78146 -60.399877)
			(xy 356.812233 -60.44639) (xy 356.835905 -60.496887) (xy 356.851973 -60.550294) (xy 356.860093 -60.60547)
			(xy 356.860602 -60.633356) (xy 356.860093 -60.661242) (xy 356.851973 -60.716418) (xy 356.835905 -60.769825)
			(xy 356.812233 -60.820322) (xy 356.78146 -60.866835) (xy 356.744243 -60.908372) (xy 356.701375 -60.944047)
			(xy 356.653769 -60.973101) (xy 356.60244 -60.994913) (xy 356.548483 -61.009019) (xy 356.493046 -61.015119)
			(xy 356.437312 -61.013082) (xy 356.382469 -61.002952) (xy 356.329685 -60.984945) (xy 356.280085 -60.959444)
			(xy 356.234727 -60.926993) (xy 356.194578 -60.888284) (xy 356.160492 -60.844141) (xy 356.133196 -60.795506)
			(xy 356.113273 -60.743415) (xy 356.101147 -60.688978) (xy 356.097076 -60.633356) (xy 341.227664 -60.633356)
			(xy 341.227664 -62.121034) (xy 352.542346 -62.121034) (xy 352.546417 -62.065412) (xy 352.558543 -62.010975)
			(xy 352.578466 -61.958884) (xy 352.605762 -61.910249) (xy 352.639848 -61.866106) (xy 352.679997 -61.827397)
			(xy 352.725355 -61.794946) (xy 352.774955 -61.769445) (xy 352.827739 -61.751438) (xy 352.882582 -61.741308)
			(xy 352.938316 -61.739271) (xy 352.993753 -61.745371) (xy 353.04771 -61.759477) (xy 353.099039 -61.781289)
			(xy 353.146645 -61.810343) (xy 353.189513 -61.846018) (xy 353.22673 -61.887555) (xy 353.257503 -61.934068)
			(xy 353.281175 -61.984565) (xy 353.297243 -62.037972) (xy 353.305363 -62.093148) (xy 353.305872 -62.121034)
			(xy 353.305363 -62.14892) (xy 353.297243 -62.204096) (xy 353.281175 -62.257503) (xy 353.257503 -62.308)
			(xy 353.22673 -62.354513) (xy 353.189513 -62.39605) (xy 353.146645 -62.431725) (xy 353.099039 -62.460779)
			(xy 353.04771 -62.482591) (xy 352.993753 -62.496697) (xy 352.938316 -62.502797) (xy 352.882582 -62.50076)
			(xy 352.827739 -62.49063) (xy 352.774955 -62.472623) (xy 352.725355 -62.447122) (xy 352.679997 -62.414671)
			(xy 352.639848 -62.375962) (xy 352.605762 -62.331819) (xy 352.578466 -62.283184) (xy 352.558543 -62.231093)
			(xy 352.546417 -62.176656) (xy 352.542346 -62.121034) (xy 341.227664 -62.121034) (xy 341.227664 -63.086234)
			(xy 349.68764 -63.086234) (xy 349.691711 -63.030612) (xy 349.703837 -62.976175) (xy 349.72376 -62.924084)
			(xy 349.751056 -62.875449) (xy 349.785142 -62.831306) (xy 349.825291 -62.792597) (xy 349.870649 -62.760146)
			(xy 349.920249 -62.734645) (xy 349.973033 -62.716638) (xy 350.027876 -62.706508) (xy 350.08361 -62.704471)
			(xy 350.139047 -62.710571) (xy 350.193004 -62.724677) (xy 350.244333 -62.746489) (xy 350.291939 -62.775543)
			(xy 350.334807 -62.811218) (xy 350.372024 -62.852755) (xy 350.402797 -62.899268) (xy 350.426469 -62.949765)
			(xy 350.442537 -63.003172) (xy 350.450657 -63.058348) (xy 350.451166 -63.086234) (xy 350.450657 -63.11412)
			(xy 350.442537 -63.169296) (xy 350.426469 -63.222703) (xy 350.402797 -63.2732) (xy 350.402644 -63.273432)
			(xy 351.876866 -63.273432) (xy 351.880937 -63.21781) (xy 351.893063 -63.163373) (xy 351.912986 -63.111282)
			(xy 351.940282 -63.062647) (xy 351.974368 -63.018504) (xy 352.014517 -62.979795) (xy 352.059875 -62.947344)
			(xy 352.109475 -62.921843) (xy 352.162259 -62.903836) (xy 352.217102 -62.893706) (xy 352.272836 -62.891669)
			(xy 352.328273 -62.897769) (xy 352.38223 -62.911875) (xy 352.433559 -62.933687) (xy 352.481165 -62.962741)
			(xy 352.524033 -62.998416) (xy 352.56125 -63.039953) (xy 352.592023 -63.086466) (xy 352.615695 -63.136963)
			(xy 352.631763 -63.19037) (xy 352.639883 -63.245546) (xy 352.640392 -63.273432) (xy 352.639883 -63.301318)
			(xy 352.631763 -63.356494) (xy 352.615695 -63.409901) (xy 352.592023 -63.460398) (xy 352.56125 -63.506911)
			(xy 352.524033 -63.548448) (xy 352.481165 -63.584123) (xy 352.433559 -63.613177) (xy 352.38223 -63.634989)
			(xy 352.328273 -63.649095) (xy 352.272836 -63.655195) (xy 352.217102 -63.653158) (xy 352.162259 -63.643028)
			(xy 352.109475 -63.625021) (xy 352.059875 -63.59952) (xy 352.014517 -63.567069) (xy 351.974368 -63.52836)
			(xy 351.940282 -63.484217) (xy 351.912986 -63.435582) (xy 351.893063 -63.383491) (xy 351.880937 -63.329054)
			(xy 351.876866 -63.273432) (xy 350.402644 -63.273432) (xy 350.372024 -63.319713) (xy 350.334807 -63.36125)
			(xy 350.291939 -63.396925) (xy 350.244333 -63.425979) (xy 350.193004 -63.447791) (xy 350.139047 -63.461897)
			(xy 350.08361 -63.467997) (xy 350.027876 -63.46596) (xy 349.973033 -63.45583) (xy 349.920249 -63.437823)
			(xy 349.870649 -63.412322) (xy 349.825291 -63.379871) (xy 349.785142 -63.341162) (xy 349.751056 -63.297019)
			(xy 349.72376 -63.248384) (xy 349.703837 -63.196293) (xy 349.691711 -63.141856) (xy 349.68764 -63.086234)
			(xy 341.227664 -63.086234) (xy 341.227664 -67.01663) (xy 341.228172 -67.024758) (xy 341.229741 -67.032439)
			(xy 341.236852 -67.046403) (xy 341.242142 -67.05219) (xy 341.556402 -67.366388) (xy 342.116918 -67.366388)
			(xy 342.117394 -67.339478) (xy 342.124973 -67.286193) (xy 342.139964 -67.234502) (xy 342.162069 -67.185431)
			(xy 342.190851 -67.139953) (xy 342.225738 -67.09897) (xy 342.266037 -67.063296) (xy 342.310949 -67.033639)
			(xy 342.359584 -67.010587) (xy 342.385142 -67.002152) (xy 342.385396 -67.002152) (xy 342.391084 -67.000159)
			(xy 342.401362 -66.993873) (xy 342.405716 -66.989706) (xy 344.632026 -64.763396) (xy 344.650814 -64.745382)
			(xy 344.692926 -64.7148) (xy 344.739298 -64.691169) (xy 344.788791 -64.67507) (xy 344.840192 -64.666898)
			(xy 344.866214 -64.666368) (xy 351.60966 -64.666368) (xy 351.619728 -64.66593) (xy 351.638326 -64.658219)
			(xy 351.645728 -64.651382) (xy 354.480114 -61.816742) (xy 354.501474 -61.796301) (xy 354.550027 -61.762577)
			(xy 354.576634 -61.749686) (xy 354.585099 -61.745345) (xy 354.598277 -61.731642) (xy 354.602288 -61.723016)
			(xy 354.628704 -61.658754) (xy 354.631998 -61.649871) (xy 354.632379 -61.63094) (xy 354.629466 -61.621924)
			(xy 354.629466 -61.621416) (xy 354.618148 -61.589178) (xy 354.605883 -61.52197) (xy 354.605082 -61.487812)
			(xy 354.605568 -61.460561) (xy 354.613324 -61.406613) (xy 354.628679 -61.354318) (xy 354.651321 -61.304741)
			(xy 354.680787 -61.258891) (xy 354.716478 -61.2177) (xy 354.757669 -61.182009) (xy 354.803519 -61.152543)
			(xy 354.853096 -61.129901) (xy 354.905391 -61.114546) (xy 354.959339 -61.10679) (xy 355.013841 -61.10679)
			(xy 355.067789 -61.114546) (xy 355.120084 -61.129901) (xy 355.169661 -61.152543) (xy 355.215511 -61.182009)
			(xy 355.256702 -61.2177) (xy 355.292393 -61.258891) (xy 355.321859 -61.304741) (xy 355.344501 -61.354318)
			(xy 355.359856 -61.406613) (xy 355.367612 -61.460561) (xy 355.368098 -61.487812) (xy 355.367631 -61.513864)
			(xy 355.36049 -61.565479) (xy 355.353874 -61.590682) (xy 355.350572 -61.602366) (xy 355.355144 -61.625226)
			(xy 355.411278 -61.699394) (xy 355.41885 -61.708407) (xy 355.439907 -61.718867) (xy 355.451664 -61.71946)
			(xy 356.716584 -61.71946) (xy 356.72776 -61.71692) (xy 356.733094 -61.714126) (xy 356.73411 -61.713618)
			(xy 356.761582 -61.699889) (xy 356.819831 -61.680438) (xy 356.880443 -61.670564) (xy 356.911148 -61.66993)
			(xy 356.941952 -61.670524) (xy 357.002753 -61.680455) (xy 357.061166 -61.700036) (xy 357.088694 -61.713872)
			(xy 357.089202 -61.714126) (xy 357.094529 -61.716588) (xy 357.105943 -61.719291) (xy 357.111808 -61.71946)
			(xy 357.247444 -61.71946) (xy 357.257517 -61.719068) (xy 357.276115 -61.711325) (xy 357.283512 -61.704474)
			(xy 357.810054 -61.177932) (xy 357.816866 -61.17051) (xy 357.824604 -61.151928) (xy 357.82504 -61.141864)
			(xy 357.82504 -58.873136) (xy 357.82469 -58.864344) (xy 357.818726 -58.847802) (xy 357.807523 -58.834249)
			(xy 357.800148 -58.829448) (xy 357.724964 -58.784998) (xy 357.717182 -58.780897) (xy 357.699918 -58.777617)
			(xy 357.682559 -58.780346) (xy 357.674672 -58.784236) (xy 357.646424 -58.798992) (xy 357.586234 -58.819928)
			(xy 357.523401 -58.830564) (xy 357.491538 -58.831226) (xy 357.49103 -58.831226) (xy 357.463777 -58.830729)
			(xy 357.409825 -58.822976) (xy 357.357526 -58.807623) (xy 357.307945 -58.784983) (xy 357.26209 -58.755517)
			(xy 357.220896 -58.719825) (xy 357.185201 -58.678634) (xy 357.155731 -58.632782) (xy 357.133088 -58.583202)
			(xy 357.117731 -58.530904) (xy 357.109973 -58.476953) (xy 357.109973 -58.422447) (xy 357.117731 -58.368496)
			(xy 357.133088 -58.316198) (xy 357.155731 -58.266618) (xy 357.185201 -58.220766) (xy 357.220896 -58.179575)
			(xy 357.26209 -58.143883) (xy 357.307945 -58.114417) (xy 357.357526 -58.091777) (xy 357.409825 -58.076424)
			(xy 357.463777 -58.068671) (xy 357.49103 -58.06821) (xy 357.491538 -58.06821) (xy 357.5234 -58.068892)
			(xy 357.58623 -58.079528) (xy 357.646423 -58.100449) (xy 357.674672 -58.1152) (xy 357.682564 -58.119106)
			(xy 357.699931 -58.121902) (xy 357.717211 -58.118608) (xy 357.724964 -58.114438) (xy 357.800148 -58.069988)
			(xy 357.807513 -58.065176) (xy 357.818717 -58.051629) (xy 357.82467 -58.035089) (xy 357.82504 -58.0263)
			(xy 357.82504 -54.867302) (xy 357.808022 -54.841902) (xy 357.793798 -54.83606) (xy 357.784374 -54.832593)
			(xy 357.764304 -54.832657) (xy 357.745791 -54.840407) (xy 357.738426 -54.847236) (xy 354.718366 -57.867296)
			(xy 355.943152 -57.867296) (xy 355.947223 -57.811674) (xy 355.959349 -57.757237) (xy 355.979272 -57.705146)
			(xy 356.006568 -57.656511) (xy 356.040654 -57.612368) (xy 356.080803 -57.573659) (xy 356.126161 -57.541208)
			(xy 356.175761 -57.515707) (xy 356.228545 -57.4977) (xy 356.283388 -57.48757) (xy 356.339122 -57.485533)
			(xy 356.394559 -57.491633) (xy 356.448516 -57.505739) (xy 356.499845 -57.527551) (xy 356.547451 -57.556605)
			(xy 356.590319 -57.59228) (xy 356.627536 -57.633817) (xy 356.658309 -57.68033) (xy 356.681981 -57.730827)
			(xy 356.698049 -57.784234) (xy 356.706169 -57.83941) (xy 356.706678 -57.867296) (xy 356.706169 -57.895182)
			(xy 356.698049 -57.950358) (xy 356.681981 -58.003765) (xy 356.658309 -58.054262) (xy 356.627536 -58.100775)
			(xy 356.590319 -58.142312) (xy 356.547451 -58.177987) (xy 356.499845 -58.207041) (xy 356.448516 -58.228853)
			(xy 356.394559 -58.242959) (xy 356.339122 -58.249059) (xy 356.283388 -58.247022) (xy 356.228545 -58.236892)
			(xy 356.175761 -58.218885) (xy 356.126161 -58.193384) (xy 356.080803 -58.160933) (xy 356.040654 -58.122224)
			(xy 356.006568 -58.078081) (xy 355.979272 -58.029446) (xy 355.959349 -57.977355) (xy 355.947223 -57.922918)
			(xy 355.943152 -57.867296) (xy 354.718366 -57.867296) (xy 354.416868 -58.168794) (xy 354.412757 -58.173192)
			(xy 354.406469 -58.183453) (xy 354.404422 -58.189114) (xy 354.404422 -58.189622) (xy 354.395966 -58.215163)
			(xy 354.372899 -58.263769) (xy 354.343231 -58.308651) (xy 354.307552 -58.34892) (xy 354.266569 -58.383777)
			(xy 354.221095 -58.41253) (xy 354.172033 -58.434608) (xy 354.120355 -58.449574) (xy 354.067087 -58.457132)
			(xy 354.040186 -58.457592) (xy 354.012932 -58.457158) (xy 353.958979 -58.449399) (xy 353.90668 -58.43404)
			(xy 353.857098 -58.411395) (xy 353.811245 -58.381924) (xy 353.770052 -58.346227) (xy 353.734358 -58.305031)
			(xy 353.704891 -58.259175) (xy 353.682249 -58.209592) (xy 353.666895 -58.157291) (xy 353.65914 -58.103338)
			(xy 353.658678 -58.076084) (xy 353.659179 -58.049175) (xy 353.666757 -57.995893) (xy 353.681746 -57.944204)
			(xy 353.70385 -57.895134) (xy 353.732628 -57.849657) (xy 353.767512 -57.808674) (xy 353.807807 -57.772999)
			(xy 353.852715 -57.74334) (xy 353.901346 -57.720285) (xy 353.926902 -57.711848) (xy 353.927156 -57.711848)
			(xy 353.932851 -57.709873) (xy 353.943125 -57.703574) (xy 353.947476 -57.699402) (xy 357.451914 -54.194964)
			(xy 357.458764 -54.187572) (xy 357.466477 -54.168967) (xy 357.4669 -54.158896) (xy 357.4669 -47.177706)
			(xy 357.466498 -47.167634) (xy 357.458764 -47.149034) (xy 357.451914 -47.141638) (xy 350.62922 -40.31869)
			(xy 350.621808 -40.311865) (xy 350.603218 -40.304137) (xy 350.593152 -40.303704) (xy 348.779084 -40.303704)
			(xy 348.772933 -40.303884) (xy 348.760992 -40.306846) (xy 348.755462 -40.309546) (xy 348.727925 -40.32336)
			(xy 348.669513 -40.342933) (xy 348.608717 -40.352874) (xy 348.577916 -40.353488) (xy 348.550661 -40.353066)
			(xy 348.496705 -40.345311) (xy 348.444403 -40.329955) (xy 348.394818 -40.307312) (xy 348.34896 -40.277843)
			(xy 348.307764 -40.242148) (xy 348.272066 -40.200952) (xy 348.242595 -40.155096) (xy 348.21995 -40.105512)
			(xy 348.204593 -40.05321) (xy 348.196835 -39.999255) (xy 348.196835 -39.944745) (xy 348.204593 -39.89079)
			(xy 348.21995 -39.838488) (xy 348.242595 -39.788904) (xy 348.272066 -39.743048) (xy 348.307764 -39.701852)
			(xy 348.34896 -39.666157) (xy 348.394818 -39.636688) (xy 348.444403 -39.614045) (xy 348.496705 -39.598689)
			(xy 348.550661 -39.590934) (xy 348.577916 -39.590472) (xy 348.608719 -39.591084) (xy 348.66952 -39.601009)
			(xy 348.727933 -39.620581) (xy 348.755462 -39.634414) (xy 348.760992 -39.637117) (xy 348.772932 -39.640081)
			(xy 348.779084 -39.640256) (xy 350.752156 -39.640256) (xy 350.778181 -39.640753) (xy 350.829587 -39.648923)
			(xy 350.879085 -39.665024) (xy 350.925461 -39.688658) (xy 350.967575 -39.719247) (xy 350.986344 -39.737284)
			(xy 351.82175 -40.57269) (xy 351.851722 -40.578532) (xy 351.865946 -40.57269) (xy 351.874967 -40.568356)
			(xy 351.889054 -40.554171) (xy 351.896691 -40.535695) (xy 351.897188 -40.5257) (xy 351.897188 -40.101774)
			(xy 351.896779 -40.091703) (xy 351.889047 -40.073105) (xy 351.882202 -40.065706) (xy 348.040198 -36.223702)
			(xy 348.032792 -36.216869) (xy 348.014197 -36.209145) (xy 348.00413 -36.208716) (xy 347.07195 -36.208716)
			(xy 347.060003 -36.209313) (xy 347.038665 -36.220058) (xy 347.031056 -36.22929) (xy 346.975176 -36.304982)
			(xy 346.971366 -36.328858) (xy 346.974922 -36.340288) (xy 346.982971 -36.367916) (xy 346.991648 -36.424801)
			(xy 346.992194 -36.453572) (xy 346.991708 -36.480823) (xy 346.983952 -36.534771) (xy 346.968597 -36.587066)
			(xy 346.945955 -36.636643) (xy 346.916489 -36.682493) (xy 346.880798 -36.723684) (xy 346.839607 -36.759375)
			(xy 346.793757 -36.788841) (xy 346.74418 -36.811483) (xy 346.691885 -36.826838) (xy 346.637937 -36.834594)
			(xy 346.583435 -36.834594) (xy 346.529487 -36.826838) (xy 346.477192 -36.811483) (xy 346.427615 -36.788841)
			(xy 346.381765 -36.759375) (xy 346.340574 -36.723684) (xy 346.304883 -36.682493) (xy 346.275417 -36.636643)
			(xy 346.252775 -36.587066) (xy 346.23742 -36.534771) (xy 346.229664 -36.480823) (xy 346.229178 -36.453572)
			(xy 346.229711 -36.4248) (xy 346.238386 -36.367912) (xy 346.24645 -36.340288) (xy 346.250006 -36.328858)
			(xy 346.246196 -36.304982) (xy 346.190316 -36.22929) (xy 346.182709 -36.220066) (xy 346.161364 -36.209351)
			(xy 346.149422 -36.208716) (xy 345.665552 -36.208716) (xy 345.654376 -36.211256) (xy 345.649042 -36.21405)
			(xy 345.648026 -36.214558) (xy 345.620548 -36.228273) (xy 345.562302 -36.24773) (xy 345.501692 -36.257609)
			(xy 345.470988 -36.258246) (xy 345.44374 -36.257683) (xy 345.389799 -36.249926) (xy 345.337511 -36.234571)
			(xy 345.28794 -36.211932) (xy 345.242096 -36.182468) (xy 345.200911 -36.14678) (xy 345.165225 -36.105594)
			(xy 345.135763 -36.059749) (xy 345.113125 -36.010178) (xy 345.097772 -35.957889) (xy 345.090016 -35.903948)
			(xy 345.090016 -35.849452) (xy 345.097772 -35.795511) (xy 345.113125 -35.743222) (xy 345.135763 -35.693651)
			(xy 345.165225 -35.647806) (xy 345.200911 -35.60662) (xy 345.242096 -35.570932) (xy 345.28794 -35.541468)
			(xy 345.337511 -35.518829) (xy 345.389799 -35.503474) (xy 345.44374 -35.495717) (xy 345.470988 -35.49523)
			(xy 345.50179 -35.495847) (xy 345.562592 -35.505769) (xy 345.621005 -35.52534) (xy 345.648534 -35.539172)
			(xy 345.649042 -35.539426) (xy 345.654363 -35.541901) (xy 345.665782 -35.544595) (xy 345.671648 -35.54476)
			(xy 348.162626 -35.54476) (xy 348.188713 -35.545262) (xy 348.240245 -35.55342) (xy 348.289864 -35.569547)
			(xy 348.336345 -35.593245) (xy 348.378542 -35.623929) (xy 348.397322 -35.642042) (xy 349.042228 -36.286948)
			(xy 353.500434 -36.286948) (xy 353.504505 -36.231326) (xy 353.516631 -36.176889) (xy 353.536554 -36.124798)
			(xy 353.56385 -36.076163) (xy 353.597936 -36.03202) (xy 353.638085 -35.993311) (xy 353.683443 -35.96086)
			(xy 353.733043 -35.935359) (xy 353.785827 -35.917352) (xy 353.84067 -35.907222) (xy 353.896404 -35.905185)
			(xy 353.951841 -35.911285) (xy 354.005798 -35.925391) (xy 354.057127 -35.947203) (xy 354.104733 -35.976257)
			(xy 354.147601 -36.011932) (xy 354.184818 -36.053469) (xy 354.215591 -36.099982) (xy 354.239263 -36.150479)
			(xy 354.255331 -36.203886) (xy 354.263451 -36.259062) (xy 354.26396 -36.286948) (xy 354.263451 -36.314834)
			(xy 354.255331 -36.37001) (xy 354.239263 -36.423417) (xy 354.215591 -36.473914) (xy 354.184818 -36.520427)
			(xy 354.147601 -36.561964) (xy 354.104733 -36.597639) (xy 354.057127 -36.626693) (xy 354.005798 -36.648505)
			(xy 353.951841 -36.662611) (xy 353.896404 -36.668711) (xy 353.84067 -36.666674) (xy 353.785827 -36.656544)
			(xy 353.733043 -36.638537) (xy 353.683443 -36.613036) (xy 353.638085 -36.580585) (xy 353.597936 -36.541876)
			(xy 353.56385 -36.497733) (xy 353.536554 -36.449098) (xy 353.516631 -36.397007) (xy 353.504505 -36.34257)
			(xy 353.500434 -36.286948) (xy 349.042228 -36.286948) (xy 350.529398 -37.774118) (xy 353.764848 -37.774118)
			(xy 353.768919 -37.718496) (xy 353.781045 -37.664059) (xy 353.800968 -37.611968) (xy 353.828264 -37.563333)
			(xy 353.86235 -37.51919) (xy 353.902499 -37.480481) (xy 353.947857 -37.44803) (xy 353.997457 -37.422529)
			(xy 354.050241 -37.404522) (xy 354.105084 -37.394392) (xy 354.160818 -37.392355) (xy 354.216255 -37.398455)
			(xy 354.270212 -37.412561) (xy 354.321541 -37.434373) (xy 354.369147 -37.463427) (xy 354.412015 -37.499102)
			(xy 354.449232 -37.540639) (xy 354.480005 -37.587152) (xy 354.503677 -37.637649) (xy 354.519745 -37.691056)
			(xy 354.527865 -37.746232) (xy 354.528374 -37.774118) (xy 354.527865 -37.802004) (xy 354.519745 -37.85718)
			(xy 354.503677 -37.910587) (xy 354.480005 -37.961084) (xy 354.449232 -38.007597) (xy 354.412015 -38.049134)
			(xy 354.369147 -38.084809) (xy 354.321541 -38.113863) (xy 354.270212 -38.135675) (xy 354.216255 -38.149781)
			(xy 354.160818 -38.155881) (xy 354.105084 -38.153844) (xy 354.050241 -38.143714) (xy 353.997457 -38.125707)
			(xy 353.947857 -38.100206) (xy 353.902499 -38.067755) (xy 353.86235 -38.029046) (xy 353.828264 -37.984903)
			(xy 353.800968 -37.936268) (xy 353.781045 -37.884177) (xy 353.768919 -37.82974) (xy 353.764848 -37.774118)
			(xy 350.529398 -37.774118) (xy 352.463862 -39.708582) (xy 352.481963 -39.727373) (xy 352.512648 -39.769569)
			(xy 352.536351 -39.816047) (xy 352.552486 -39.865662) (xy 352.560656 -39.917191) (xy 352.561144 -39.943278)
			(xy 352.561144 -40.559482) (xy 352.561567 -40.569552) (xy 352.569288 -40.58815) (xy 352.57613 -40.59555)
			(xy 358.391714 -46.411134) (xy 358.409849 -46.429894) (xy 358.440528 -46.472099) (xy 358.464223 -46.518585)
			(xy 358.48035 -46.568207) (xy 358.488512 -46.619741) (xy 358.488996 -46.64583) (xy 358.488996 -61.30036)
			(xy 358.488499 -61.326447) (xy 358.480337 -61.377978) (xy 358.464208 -61.427597) (xy 358.44051 -61.474078)
			(xy 358.409826 -61.516275) (xy 358.391714 -61.535056) (xy 357.640636 -62.286134) (xy 357.621832 -62.304221)
			(xy 357.579641 -62.33491) (xy 357.533166 -62.358615) (xy 357.483553 -62.374754) (xy 357.432026 -62.382927)
			(xy 357.40594 -62.383416) (xy 357.105712 -62.383416) (xy 357.094536 -62.385956) (xy 357.089202 -62.38875)
			(xy 357.088186 -62.389258) (xy 357.060714 -62.402987) (xy 357.002465 -62.422439) (xy 356.941853 -62.432312)
			(xy 356.911148 -62.432946) (xy 356.880344 -62.432356) (xy 356.819542 -62.422424) (xy 356.761129 -62.402841)
			(xy 356.733602 -62.389004) (xy 356.733094 -62.38875) (xy 356.727769 -62.386285) (xy 356.716353 -62.383584)
			(xy 356.710488 -62.383416) (xy 356.68331 -62.383416) (xy 356.673287 -62.383828) (xy 356.654768 -62.391498)
			(xy 356.640594 -62.405673) (xy 356.632927 -62.424193) (xy 356.63251 -62.434216) (xy 356.63251 -62.442852)
			(xy 356.638352 -62.459108) (xy 356.64394 -62.465966) (xy 356.659907 -62.486416) (xy 356.686771 -62.530802)
			(xy 356.707365 -62.578423) (xy 356.721307 -62.628397) (xy 356.728341 -62.679801) (xy 356.728776 -62.705742)
			(xy 356.728776 -62.705996) (xy 356.72829 -62.733247) (xy 356.720534 -62.787195) (xy 356.705179 -62.83949)
			(xy 356.682537 -62.889067) (xy 356.653071 -62.934917) (xy 356.61738 -62.976108) (xy 356.576189 -63.011799)
			(xy 356.530339 -63.041265) (xy 356.480762 -63.063907) (xy 356.428467 -63.079262) (xy 356.374519 -63.087018)
			(xy 356.320017 -63.087018) (xy 356.266069 -63.079262) (xy 356.213774 -63.063907) (xy 356.164197 -63.041265)
			(xy 356.118347 -63.011799) (xy 356.077156 -62.976108) (xy 356.041465 -62.934917) (xy 356.011999 -62.889067)
			(xy 355.989357 -62.83949) (xy 355.974002 -62.787195) (xy 355.966246 -62.733247) (xy 355.96576 -62.705996)
			(xy 355.966367 -62.675766) (xy 355.975966 -62.616073) (xy 355.994845 -62.558635) (xy 356.008178 -62.531498)
			(xy 356.011821 -62.523638) (xy 356.01415 -62.506485) (xy 356.010606 -62.489541) (xy 356.0064 -62.481968)
			(xy 355.960934 -62.4078) (xy 355.956164 -62.400565) (xy 355.942722 -62.389639) (xy 355.926413 -62.383801)
			(xy 355.917754 -62.383416) (xy 354.873306 -62.383416) (xy 354.863237 -62.38384) (xy 354.844639 -62.391561)
			(xy 354.837238 -62.398402) (xy 352.111564 -65.124076) (xy 354.407468 -65.124076) (xy 354.411539 -65.068454)
			(xy 354.423665 -65.014017) (xy 354.443588 -64.961926) (xy 354.470884 -64.913291) (xy 354.50497 -64.869148)
			(xy 354.545119 -64.830439) (xy 354.590477 -64.797988) (xy 354.640077 -64.772487) (xy 354.692861 -64.75448)
			(xy 354.747704 -64.74435) (xy 354.803438 -64.742313) (xy 354.858875 -64.748413) (xy 354.912832 -64.762519)
			(xy 354.964161 -64.784331) (xy 355.011767 -64.813385) (xy 355.054635 -64.84906) (xy 355.091852 -64.890597)
			(xy 355.122625 -64.93711) (xy 355.146297 -64.987607) (xy 355.162365 -65.041014) (xy 355.170485 -65.09619)
			(xy 355.170994 -65.124076) (xy 355.170485 -65.151962) (xy 355.162365 -65.207138) (xy 355.146297 -65.260545)
			(xy 355.122625 -65.311042) (xy 355.091852 -65.357555) (xy 355.054635 -65.399092) (xy 355.011767 -65.434767)
			(xy 354.964161 -65.463821) (xy 354.912832 -65.485633) (xy 354.858875 -65.499739) (xy 354.803438 -65.505839)
			(xy 354.747704 -65.503802) (xy 354.692861 -65.493672) (xy 354.640077 -65.475665) (xy 354.590477 -65.450164)
			(xy 354.545119 -65.417713) (xy 354.50497 -65.379004) (xy 354.470884 -65.334861) (xy 354.443588 -65.286226)
			(xy 354.423665 -65.234135) (xy 354.411539 -65.179698) (xy 354.407468 -65.124076) (xy 352.111564 -65.124076)
			(xy 352.002852 -65.232788) (xy 351.984071 -65.250809) (xy 351.941957 -65.281392) (xy 351.895584 -65.305021)
			(xy 351.846089 -65.321118) (xy 351.794687 -65.329288) (xy 351.768664 -65.329816) (xy 345.025218 -65.329816)
			(xy 345.015149 -65.330247) (xy 344.996551 -65.337963) (xy 344.98915 -65.344802) (xy 342.875108 -67.459098)
			(xy 342.871001 -67.463499) (xy 342.86471 -67.473758) (xy 342.862662 -67.479418) (xy 342.862662 -67.479926)
			(xy 342.854173 -67.505456) (xy 342.831109 -67.554059) (xy 342.801445 -67.59894) (xy 342.765769 -67.639209)
			(xy 342.724791 -67.674066) (xy 342.679321 -67.70282) (xy 342.630263 -67.724901) (xy 342.57859 -67.739871)
			(xy 342.525325 -67.747433) (xy 342.498426 -67.747896) (xy 342.471173 -67.74742) (xy 342.417222 -67.739667)
			(xy 342.364924 -67.724313) (xy 342.315343 -67.701673) (xy 342.269489 -67.672207) (xy 342.228296 -67.636514)
			(xy 342.192602 -67.595322) (xy 342.163134 -67.549469) (xy 342.140492 -67.499889) (xy 342.125136 -67.447592)
			(xy 342.117381 -67.393641) (xy 342.116918 -67.366388) (xy 341.556402 -67.366388) (xy 342.531192 -68.340986)
			(xy 343.165176 -68.97497) (xy 343.166192 -68.975986) (xy 343.17932 -68.989514) (xy 343.202747 -69.019049)
			(xy 343.212928 -69.034914) (xy 343.215976 -69.039994) (xy 343.291414 -69.115432) (xy 343.298265 -69.122828)
			(xy 343.306001 -69.141427) (xy 343.3064 -69.1515) (xy 343.3064 -74.781918) (xy 343.306827 -74.791987)
			(xy 343.314546 -74.810586) (xy 343.321386 -74.817986) (xy 348.671642 -80.168242) (xy 348.67904 -80.175088)
			(xy 348.697639 -80.182816) (xy 348.70771 -80.183228) (xy 353.391724 -80.183228) (xy 353.401376 -80.184244)
			(xy 354.19411 -80.184244) (xy 354.201984 -80.183482) (xy 360.339386 -74.04608) (xy 360.344375 -74.040582)
			(xy 360.351223 -74.027416) (xy 360.352848 -74.020172) (xy 360.353864 -74.01052) (xy 360.353864 -44.203112)
			(xy 360.353692 -44.197104) (xy 360.350859 -44.185426) (xy 360.348276 -44.179998) (xy 360.346437 -44.176524)
			(xy 360.341843 -44.170145) (xy 360.339132 -44.167298) (xy 355.471476 -39.299642) (xy 355.45344 -39.280873)
			(xy 355.422852 -39.238758) (xy 355.399218 -39.192383) (xy 355.383118 -39.142884) (xy 355.374948 -39.091479)
			(xy 355.374448 -39.065454) (xy 355.374448 -36.741354) (xy 355.372416 -36.727384) (xy 355.367336 -36.709096)
			(xy 355.365304 -36.705286) (xy 355.354636 -36.685982) (xy 355.354636 -36.685474) (xy 355.347856 -36.671677)
			(xy 355.336289 -36.643193) (xy 355.331522 -36.628578) (xy 355.329744 -36.622736) (xy 355.323394 -36.612068)
			(xy 353.828858 -35.117532) (xy 353.810749 -35.09875) (xy 353.780071 -35.056551) (xy 353.756378 -35.01007)
			(xy 353.740253 -34.960452) (xy 353.732096 -34.908922) (xy 353.731576 -34.882836) (xy 353.731576 -32.410654)
			(xy 353.727258 -32.405574) (xy 353.67468 -32.362394) (xy 353.663504 -32.35325) (xy 353.660645 -32.350961)
			(xy 353.654394 -32.347142) (xy 353.651058 -32.34563) (xy 353.629976 -32.350202) (xy 353.599918 -32.356215)
			(xy 353.53896 -32.362707) (xy 353.50831 -32.363156) (xy 353.472896 -32.362643) (xy 353.402584 -32.354107)
			(xy 353.333814 -32.337157) (xy 353.267589 -32.312041) (xy 353.204874 -32.279126) (xy 353.146584 -32.238891)
			(xy 353.093569 -32.191923) (xy 353.046602 -32.138907) (xy 353.006368 -32.080616) (xy 352.973454 -32.0179)
			(xy 352.94834 -31.951674) (xy 352.931391 -31.882904) (xy 352.922856 -31.812592) (xy 352.922332 -31.777178)
			(xy 352.922332 -30.776164) (xy 352.919914 -30.773073) (xy 352.9143 -30.76759) (xy 352.911156 -30.765242)
			(xy 352.876358 -30.743906) (xy 352.838766 -30.720792) (xy 352.828352 -30.715966) (xy 352.826066 -30.715204)
			(xy 352.816815 -30.712952) (xy 352.797877 -30.714766) (xy 352.789236 -30.71876) (xy 352.788982 -30.71876)
			(xy 352.778314 -30.724094) (xy 352.752084 -30.736183) (xy 352.696908 -30.753249) (xy 352.639805 -30.761895)
			(xy 352.610928 -30.762448) (xy 352.610674 -30.762448) (xy 352.583134 -30.761955) (xy 352.528616 -30.754113)
			(xy 352.475769 -30.738592) (xy 352.425668 -30.715707) (xy 352.379334 -30.685926) (xy 352.33771 -30.649854)
			(xy 352.301644 -30.608226) (xy 352.271869 -30.561888) (xy 352.248991 -30.511784) (xy 352.233477 -30.458935)
			(xy 352.225641 -30.404416) (xy 352.225102 -30.376876) (xy 352.225626 -30.347907) (xy 352.234302 -30.290621)
			(xy 352.251456 -30.23528) (xy 352.2767 -30.18313) (xy 352.309467 -30.135347) (xy 352.349017 -30.093007)
			(xy 352.371406 -30.074616) (xy 352.375774 -30.07096) (xy 352.382954 -30.062119) (xy 352.38563 -30.05709)
			(xy 352.390202 -30.047692) (xy 352.390456 -30.047184) (xy 352.392921 -30.041859) (xy 352.395622 -30.030443)
			(xy 352.39579 -30.024578) (xy 352.39579 -29.967682) (xy 352.395648 -29.962242) (xy 352.393343 -29.951609)
			(xy 352.391218 -29.9466) (xy 352.387916 -29.939742) (xy 352.387916 -29.939234) (xy 352.381058 -29.925518)
			(xy 352.372676 -29.914088) (xy 352.36785 -29.909262) (xy 352.366072 -29.907738) (xy 352.345044 -29.8895)
			(xy 352.307979 -29.847975) (xy 352.277335 -29.801509) (xy 352.253763 -29.751087) (xy 352.237761 -29.697776)
			(xy 352.229668 -29.642706) (xy 352.229166 -29.614876) (xy 352.229653 -29.587625) (xy 352.237413 -29.533679)
			(xy 352.252769 -29.481385) (xy 352.275412 -29.431809) (xy 352.304878 -29.38596) (xy 352.340569 -29.344771)
			(xy 352.381759 -29.309079) (xy 352.427608 -29.279613) (xy 352.477183 -29.25697) (xy 352.529477 -29.241613)
			(xy 352.583423 -29.233854) (xy 352.610674 -29.233368) (xy 352.636103 -29.233787) (xy 352.686511 -29.24054)
			(xy 352.735575 -29.25393) (xy 352.782425 -29.273721) (xy 352.82623 -29.29956) (xy 352.866214 -29.330989)
			(xy 352.884232 -29.348938) (xy 352.89109 -29.35605) (xy 352.92665 -29.371798) (xy 352.939096 -29.37129)
			(xy 352.93935 -29.37129) (xy 352.951034 -29.363416) (xy 352.956824 -29.35915) (xy 352.965978 -29.348066)
			(xy 352.969068 -29.341572) (xy 352.976434 -29.324808) (xy 352.977704 -29.322268) (xy 352.984816 -29.308044)
			(xy 352.999191 -29.280328) (xy 353.033006 -29.227839) (xy 353.072224 -29.179253) (xy 353.094036 -29.156914)
			(xy 355.534976 -26.715974) (xy 355.538278 -26.71191) (xy 355.542409 -26.705398) (xy 355.546927 -26.690662)
			(xy 355.547168 -26.682954) (xy 355.547168 -24.158194) (xy 355.547663 -24.124108) (xy 355.555578 -24.056398)
			(xy 355.571299 -23.990064) (xy 355.594615 -23.926004) (xy 355.62521 -23.865084) (xy 355.662671 -23.808127)
			(xy 355.706491 -23.755905) (xy 355.756077 -23.709123) (xy 355.810759 -23.668414) (xy 355.869797 -23.634328)
			(xy 355.932393 -23.607327) (xy 355.9977 -23.587775) (xy 356.064836 -23.575937) (xy 356.132892 -23.571974)
			(xy 356.200948 -23.575937) (xy 356.268084 -23.587775) (xy 356.333391 -23.607327) (xy 356.395987 -23.634328)
			(xy 356.455025 -23.668414) (xy 356.509707 -23.709123) (xy 356.559293 -23.755905) (xy 356.603113 -23.808127)
			(xy 356.640574 -23.865084) (xy 356.671169 -23.926004) (xy 356.694485 -23.990064) (xy 356.710206 -24.056398)
			(xy 356.718121 -24.124108) (xy 356.718616 -24.158194) (xy 356.718616 -24.807418) (xy 356.92029 -24.807418)
			(xy 356.924361 -24.751796) (xy 356.936487 -24.697359) (xy 356.95641 -24.645268) (xy 356.983706 -24.596633)
			(xy 357.017792 -24.55249) (xy 357.057941 -24.513781) (xy 357.103299 -24.48133) (xy 357.152899 -24.455829)
			(xy 357.205683 -24.437822) (xy 357.260526 -24.427692) (xy 357.31626 -24.425655) (xy 357.371697 -24.431755)
			(xy 357.425654 -24.445861) (xy 357.476983 -24.467673) (xy 357.524589 -24.496727) (xy 357.567457 -24.532402)
			(xy 357.604674 -24.573939) (xy 357.635447 -24.620452) (xy 357.659119 -24.670949) (xy 357.675187 -24.724356)
			(xy 357.683307 -24.779532) (xy 357.683816 -24.807418) (xy 357.683307 -24.835304) (xy 357.675187 -24.89048)
			(xy 357.659119 -24.943887) (xy 357.635447 -24.994384) (xy 357.604674 -25.040897) (xy 357.567457 -25.082434)
			(xy 357.524589 -25.118109) (xy 357.476983 -25.147163) (xy 357.425654 -25.168975) (xy 357.371697 -25.183081)
			(xy 357.31626 -25.189181) (xy 357.260526 -25.187144) (xy 357.205683 -25.177014) (xy 357.152899 -25.159007)
			(xy 357.103299 -25.133506) (xy 357.057941 -25.101055) (xy 357.017792 -25.062346) (xy 356.983706 -25.018203)
			(xy 356.95641 -24.969568) (xy 356.936487 -24.917477) (xy 356.924361 -24.86304) (xy 356.92029 -24.807418)
			(xy 356.718616 -24.807418) (xy 356.718616 -26.724356) (xy 356.723442 -26.729944) (xy 356.72903 -26.734516)
			(xy 357.038148 -26.734516) (xy 357.043936 -26.734384) (xy 357.05522 -26.73181) (xy 357.0605 -26.729436)
			(xy 357.064818 -26.72715) (xy 357.06558 -26.726642) (xy 357.080058 -26.708608) (xy 357.086662 -26.697686)
			(xy 357.088948 -26.69286) (xy 357.082852 -26.665682) (xy 357.082344 -26.663396) (xy 357.080846 -26.657705)
			(xy 357.075585 -26.647181) (xy 357.07193 -26.642568) (xy 357.05415 -26.620724) (xy 357.04653 -26.614628)
			(xy 357.040434 -26.611834) (xy 357.016166 -26.599948) (xy 356.970955 -26.570349) (xy 356.930372 -26.534669)
			(xy 356.895229 -26.49362) (xy 356.866229 -26.448023) (xy 356.843953 -26.398791) (xy 356.828845 -26.346908)
			(xy 356.821207 -26.293413) (xy 356.820724 -26.266394) (xy 356.82121 -26.239143) (xy 356.828966 -26.185195)
			(xy 356.844321 -26.1329) (xy 356.866963 -26.083323) (xy 356.896429 -26.037473) (xy 356.93212 -25.996282)
			(xy 356.973311 -25.960591) (xy 357.019161 -25.931125) (xy 357.068738 -25.908483) (xy 357.121033 -25.893128)
			(xy 357.174981 -25.885372) (xy 357.229483 -25.885372) (xy 357.283431 -25.893128) (xy 357.335726 -25.908483)
			(xy 357.385303 -25.931125) (xy 357.431153 -25.960591) (xy 357.472344 -25.996282) (xy 357.508035 -26.037473)
			(xy 357.537501 -26.083323) (xy 357.560143 -26.1329) (xy 357.575498 -26.185195) (xy 357.583254 -26.239143)
			(xy 357.58374 -26.266394) (xy 357.583206 -26.29531) (xy 357.574479 -26.352481) (xy 357.557224 -26.407679)
			(xy 357.531835 -26.459641) (xy 357.498896 -26.507176) (xy 357.45916 -26.549195) (xy 357.436674 -26.567384)
			(xy 357.432102 -26.57094) (xy 357.422704 -26.582624) (xy 357.417371 -26.589604) (xy 357.411389 -26.606106)
			(xy 357.41102 -26.614882) (xy 357.41102 -26.617422) (xy 357.412544 -26.648156) (xy 357.412544 -26.648664)
			(xy 357.415084 -26.688034) (xy 357.415338 -26.690828) (xy 357.416082 -26.695979) (xy 357.419409 -26.705839)
			(xy 357.421942 -26.710386) (xy 357.426006 -26.717244) (xy 357.431086 -26.725372) (xy 357.438452 -26.73477)
			(xy 357.44404 -26.740358) (xy 357.448612 -26.743152) (xy 357.471531 -26.758336) (xy 357.513181 -26.794221)
			(xy 357.549281 -26.835686) (xy 357.57909 -26.88188) (xy 357.601999 -26.931856) (xy 357.617538 -26.984592)
			(xy 357.625388 -27.039005) (xy 357.625904 -27.066494) (xy 357.625416 -27.093873) (xy 357.617624 -27.148074)
			(xy 357.602198 -27.200614) (xy 357.579452 -27.250424) (xy 357.549849 -27.29649) (xy 357.513991 -27.337874)
			(xy 357.472609 -27.373735) (xy 357.426545 -27.403341) (xy 357.376736 -27.42609) (xy 357.324197 -27.441519)
			(xy 357.269997 -27.449314) (xy 357.242618 -27.44978) (xy 357.242364 -27.44978) (xy 357.211483 -27.449137)
			(xy 357.150525 -27.439202) (xy 357.09194 -27.419643) (xy 357.06431 -27.405838) (xy 357.06177 -27.404568)
			(xy 357.04399 -27.399996) (xy 357.031544 -27.398472) (xy 356.878382 -27.398472) (xy 356.873556 -27.403552)
			(xy 356.871778 -27.405076) (xy 356.870508 -27.406092) (xy 355.15423 -29.12237) (xy 356.907084 -29.12237)
			(xy 356.907084 -28.25877) (xy 356.907574 -28.228802) (xy 356.915397 -28.16938) (xy 356.93091 -28.111487)
			(xy 356.953846 -28.056114) (xy 356.983813 -28.004208) (xy 357.0203 -27.956658) (xy 357.06268 -27.914278)
			(xy 357.11023 -27.877791) (xy 357.162136 -27.847824) (xy 357.217509 -27.824888) (xy 357.275402 -27.809375)
			(xy 357.334824 -27.801552) (xy 357.39476 -27.801552) (xy 357.454182 -27.809375) (xy 357.512075 -27.824888)
			(xy 357.567448 -27.847824) (xy 357.619354 -27.877791) (xy 357.666904 -27.914278) (xy 357.709284 -27.956658)
			(xy 357.745771 -28.004208) (xy 357.775738 -28.056114) (xy 357.798674 -28.111487) (xy 357.814187 -28.16938)
			(xy 357.82201 -28.228802) (xy 357.8225 -28.25877) (xy 357.8225 -29.114242) (xy 367.147348 -29.114242)
			(xy 367.147348 -28.250642) (xy 367.147838 -28.220658) (xy 367.155666 -28.161202) (xy 367.171187 -28.103277)
			(xy 367.194136 -28.047873) (xy 367.22412 -27.995939) (xy 367.260626 -27.948363) (xy 367.303031 -27.905958)
			(xy 367.350607 -27.869452) (xy 367.402541 -27.839468) (xy 367.457945 -27.816519) (xy 367.51587 -27.800998)
			(xy 367.575326 -27.79317) (xy 367.635294 -27.79317) (xy 367.69475 -27.800998) (xy 367.752675 -27.816519)
			(xy 367.808079 -27.839468) (xy 367.860013 -27.869452) (xy 367.907589 -27.905958) (xy 367.949994 -27.948363)
			(xy 367.9865 -27.995939) (xy 368.016484 -28.047873) (xy 368.039433 -28.103277) (xy 368.054954 -28.161202)
			(xy 368.062782 -28.220658) (xy 368.063272 -28.250642) (xy 368.063272 -29.114242) (xy 368.062782 -29.144226)
			(xy 368.054954 -29.203682) (xy 368.039433 -29.261607) (xy 368.016484 -29.317011) (xy 367.9865 -29.368945)
			(xy 367.949994 -29.416521) (xy 367.907589 -29.458926) (xy 367.860013 -29.495432) (xy 367.808079 -29.525416)
			(xy 367.752675 -29.548365) (xy 367.69475 -29.563886) (xy 367.635294 -29.571714) (xy 367.575326 -29.571714)
			(xy 367.51587 -29.563886) (xy 367.457945 -29.548365) (xy 367.402541 -29.525416) (xy 367.350607 -29.495432)
			(xy 367.303031 -29.458926) (xy 367.260626 -29.416521) (xy 367.22412 -29.368945) (xy 367.194136 -29.317011)
			(xy 367.171187 -29.261607) (xy 367.155666 -29.203682) (xy 367.147838 -29.144226) (xy 367.147348 -29.114242)
			(xy 357.8225 -29.114242) (xy 357.8225 -29.12237) (xy 357.82201 -29.152338) (xy 357.814187 -29.21176)
			(xy 357.798674 -29.269653) (xy 357.775738 -29.325026) (xy 357.745771 -29.376932) (xy 357.709284 -29.424482)
			(xy 357.666904 -29.466862) (xy 357.619354 -29.503349) (xy 357.567448 -29.533316) (xy 357.512075 -29.556252)
			(xy 357.454182 -29.571765) (xy 357.39476 -29.579588) (xy 357.334824 -29.579588) (xy 357.275402 -29.571765)
			(xy 357.217509 -29.556252) (xy 357.162136 -29.533316) (xy 357.11023 -29.503349) (xy 357.06268 -29.466862)
			(xy 357.0203 -29.424482) (xy 356.983813 -29.376932) (xy 356.953846 -29.325026) (xy 356.93091 -29.269653)
			(xy 356.915397 -29.21176) (xy 356.907574 -29.152338) (xy 356.907084 -29.12237) (xy 355.15423 -29.12237)
			(xy 354.39731 -29.87929) (xy 354.395532 -29.881576) (xy 354.395532 -30.922468) (xy 355.052884 -30.922468)
			(xy 355.052884 -30.058868) (xy 355.053374 -30.0289) (xy 355.061197 -29.969478) (xy 355.07671 -29.911585)
			(xy 355.099646 -29.856212) (xy 355.129613 -29.804306) (xy 355.1661 -29.756756) (xy 355.20848 -29.714376)
			(xy 355.25603 -29.677889) (xy 355.307936 -29.647922) (xy 355.363309 -29.624986) (xy 355.421202 -29.609473)
			(xy 355.480624 -29.60165) (xy 355.54056 -29.60165) (xy 355.599982 -29.609473) (xy 355.657875 -29.624986)
			(xy 355.713248 -29.647922) (xy 355.765154 -29.677889) (xy 355.812704 -29.714376) (xy 355.855084 -29.756756)
			(xy 355.891571 -29.804306) (xy 355.921538 -29.856212) (xy 355.944474 -29.911585) (xy 355.959987 -29.969478)
			(xy 355.96781 -30.0289) (xy 355.9683 -30.058868) (xy 355.9683 -30.92069) (xy 369.789456 -30.92069)
			(xy 369.789456 -30.05709) (xy 369.789946 -30.027106) (xy 369.797774 -29.96765) (xy 369.813295 -29.909725)
			(xy 369.836244 -29.854321) (xy 369.866228 -29.802387) (xy 369.902734 -29.754811) (xy 369.945139 -29.712406)
			(xy 369.992715 -29.6759) (xy 370.044649 -29.645916) (xy 370.100053 -29.622967) (xy 370.157978 -29.607446)
			(xy 370.217434 -29.599618) (xy 370.277402 -29.599618) (xy 370.336858 -29.607446) (xy 370.394783 -29.622967)
			(xy 370.450187 -29.645916) (xy 370.502121 -29.6759) (xy 370.549697 -29.712406) (xy 370.592102 -29.754811)
			(xy 370.628608 -29.802387) (xy 370.658592 -29.854321) (xy 370.681541 -29.909725) (xy 370.697062 -29.96765)
			(xy 370.70489 -30.027106) (xy 370.70538 -30.05709) (xy 370.70538 -30.92069) (xy 370.70489 -30.950674)
			(xy 370.697062 -31.01013) (xy 370.681541 -31.068055) (xy 370.658592 -31.123459) (xy 370.628608 -31.175393)
			(xy 370.592102 -31.222969) (xy 370.549697 -31.265374) (xy 370.502121 -31.30188) (xy 370.450187 -31.331864)
			(xy 370.394783 -31.354813) (xy 370.336858 -31.370334) (xy 370.277402 -31.378162) (xy 370.217434 -31.378162)
			(xy 370.157978 -31.370334) (xy 370.100053 -31.354813) (xy 370.044649 -31.331864) (xy 369.992715 -31.30188)
			(xy 369.945139 -31.265374) (xy 369.902734 -31.222969) (xy 369.866228 -31.175393) (xy 369.836244 -31.123459)
			(xy 369.813295 -31.068055) (xy 369.797774 -31.01013) (xy 369.789946 -30.950674) (xy 369.789456 -30.92069)
			(xy 355.9683 -30.92069) (xy 355.9683 -30.922468) (xy 355.96781 -30.952436) (xy 355.959987 -31.011858)
			(xy 355.944474 -31.069751) (xy 355.921538 -31.125124) (xy 355.891571 -31.17703) (xy 355.855084 -31.22458)
			(xy 355.812704 -31.26696) (xy 355.765154 -31.303447) (xy 355.713248 -31.333414) (xy 355.657875 -31.35635)
			(xy 355.599982 -31.371863) (xy 355.54056 -31.379686) (xy 355.480624 -31.379686) (xy 355.421202 -31.371863)
			(xy 355.363309 -31.35635) (xy 355.307936 -31.333414) (xy 355.25603 -31.303447) (xy 355.20848 -31.26696)
			(xy 355.1661 -31.22458) (xy 355.129613 -31.17703) (xy 355.099646 -31.125124) (xy 355.07671 -31.069751)
			(xy 355.061197 -31.011858) (xy 355.053374 -30.952436) (xy 355.052884 -30.922468) (xy 354.395532 -30.922468)
			(xy 354.395532 -32.722312) (xy 356.907084 -32.722312) (xy 356.907084 -31.858712) (xy 356.907574 -31.828744)
			(xy 356.915397 -31.769322) (xy 356.93091 -31.711429) (xy 356.953846 -31.656056) (xy 356.983813 -31.60415)
			(xy 357.0203 -31.5566) (xy 357.06268 -31.51422) (xy 357.11023 -31.477733) (xy 357.162136 -31.447766)
			(xy 357.217509 -31.42483) (xy 357.275402 -31.409317) (xy 357.334824 -31.401494) (xy 357.39476 -31.401494)
			(xy 357.454182 -31.409317) (xy 357.512075 -31.42483) (xy 357.567448 -31.447766) (xy 357.619354 -31.477733)
			(xy 357.666904 -31.51422) (xy 357.709284 -31.5566) (xy 357.745771 -31.60415) (xy 357.775738 -31.656056)
			(xy 357.798674 -31.711429) (xy 357.814187 -31.769322) (xy 357.82201 -31.828744) (xy 357.8225 -31.858712)
			(xy 357.8225 -32.714184) (xy 367.147348 -32.714184) (xy 367.147348 -31.850584) (xy 367.147838 -31.8206)
			(xy 367.155666 -31.761144) (xy 367.171187 -31.703219) (xy 367.194136 -31.647815) (xy 367.22412 -31.595881)
			(xy 367.260626 -31.548305) (xy 367.303031 -31.5059) (xy 367.350607 -31.469394) (xy 367.402541 -31.43941)
			(xy 367.457945 -31.416461) (xy 367.51587 -31.40094) (xy 367.575326 -31.393112) (xy 367.635294 -31.393112)
			(xy 367.69475 -31.40094) (xy 367.752675 -31.416461) (xy 367.808079 -31.43941) (xy 367.860013 -31.469394)
			(xy 367.907589 -31.5059) (xy 367.949994 -31.548305) (xy 367.9865 -31.595881) (xy 368.016484 -31.647815)
			(xy 368.039433 -31.703219) (xy 368.054954 -31.761144) (xy 368.062782 -31.8206) (xy 368.063272 -31.850584)
			(xy 368.063272 -32.714184) (xy 368.062782 -32.744168) (xy 368.054954 -32.803624) (xy 368.039433 -32.861549)
			(xy 368.016484 -32.916953) (xy 367.9865 -32.968887) (xy 367.949994 -33.016463) (xy 367.907589 -33.058868)
			(xy 367.860013 -33.095374) (xy 367.808079 -33.125358) (xy 367.752675 -33.148307) (xy 367.69475 -33.163828)
			(xy 367.635294 -33.171656) (xy 367.575326 -33.171656) (xy 367.51587 -33.163828) (xy 367.457945 -33.148307)
			(xy 367.402541 -33.125358) (xy 367.350607 -33.095374) (xy 367.303031 -33.058868) (xy 367.260626 -33.016463)
			(xy 367.22412 -32.968887) (xy 367.194136 -32.916953) (xy 367.171187 -32.861549) (xy 367.155666 -32.803624)
			(xy 367.147838 -32.744168) (xy 367.147348 -32.714184) (xy 357.8225 -32.714184) (xy 357.8225 -32.722312)
			(xy 357.82201 -32.75228) (xy 357.814187 -32.811702) (xy 357.798674 -32.869595) (xy 357.775738 -32.924968)
			(xy 357.745771 -32.976874) (xy 357.709284 -33.024424) (xy 357.666904 -33.066804) (xy 357.619354 -33.103291)
			(xy 357.567448 -33.133258) (xy 357.512075 -33.156194) (xy 357.454182 -33.171707) (xy 357.39476 -33.17953)
			(xy 357.334824 -33.17953) (xy 357.275402 -33.171707) (xy 357.217509 -33.156194) (xy 357.162136 -33.133258)
			(xy 357.11023 -33.103291) (xy 357.06268 -33.066804) (xy 357.0203 -33.024424) (xy 356.983813 -32.976874)
			(xy 356.953846 -32.924968) (xy 356.93091 -32.869595) (xy 356.915397 -32.811702) (xy 356.907574 -32.75228)
			(xy 356.907084 -32.722312) (xy 354.395532 -32.722312) (xy 354.395532 -34.52241) (xy 355.052884 -34.52241)
			(xy 355.052884 -33.65881) (xy 355.053374 -33.628842) (xy 355.061197 -33.56942) (xy 355.07671 -33.511527)
			(xy 355.099646 -33.456154) (xy 355.129613 -33.404248) (xy 355.1661 -33.356698) (xy 355.20848 -33.314318)
			(xy 355.25603 -33.277831) (xy 355.307936 -33.247864) (xy 355.363309 -33.224928) (xy 355.421202 -33.209415)
			(xy 355.480624 -33.201592) (xy 355.54056 -33.201592) (xy 355.599982 -33.209415) (xy 355.657875 -33.224928)
			(xy 355.713248 -33.247864) (xy 355.765154 -33.277831) (xy 355.812704 -33.314318) (xy 355.855084 -33.356698)
			(xy 355.891571 -33.404248) (xy 355.921538 -33.456154) (xy 355.944474 -33.511527) (xy 355.959987 -33.56942)
			(xy 355.96781 -33.628842) (xy 355.9683 -33.65881) (xy 355.9683 -34.520886) (xy 369.789456 -34.520886)
			(xy 369.789456 -33.657286) (xy 369.789946 -33.627302) (xy 369.797774 -33.567846) (xy 369.813295 -33.509921)
			(xy 369.836244 -33.454517) (xy 369.866228 -33.402583) (xy 369.902734 -33.355007) (xy 369.945139 -33.312602)
			(xy 369.992715 -33.276096) (xy 370.044649 -33.246112) (xy 370.100053 -33.223163) (xy 370.157978 -33.207642)
			(xy 370.217434 -33.199814) (xy 370.277402 -33.199814) (xy 370.336858 -33.207642) (xy 370.394783 -33.223163)
			(xy 370.450187 -33.246112) (xy 370.502121 -33.276096) (xy 370.549697 -33.312602) (xy 370.592102 -33.355007)
			(xy 370.628608 -33.402583) (xy 370.658592 -33.454517) (xy 370.681541 -33.509921) (xy 370.697062 -33.567846)
			(xy 370.70489 -33.627302) (xy 370.70538 -33.657286) (xy 370.70538 -34.520886) (xy 370.70489 -34.55087)
			(xy 370.697062 -34.610326) (xy 370.681541 -34.668251) (xy 370.658592 -34.723655) (xy 370.628608 -34.775589)
			(xy 370.592102 -34.823165) (xy 370.549697 -34.86557) (xy 370.502121 -34.902076) (xy 370.450187 -34.93206)
			(xy 370.394783 -34.955009) (xy 370.336858 -34.97053) (xy 370.277402 -34.978358) (xy 370.217434 -34.978358)
			(xy 370.157978 -34.97053) (xy 370.100053 -34.955009) (xy 370.044649 -34.93206) (xy 369.992715 -34.902076)
			(xy 369.945139 -34.86557) (xy 369.902734 -34.823165) (xy 369.866228 -34.775589) (xy 369.836244 -34.723655)
			(xy 369.813295 -34.668251) (xy 369.797774 -34.610326) (xy 369.789946 -34.55087) (xy 369.789456 -34.520886)
			(xy 355.9683 -34.520886) (xy 355.9683 -34.52241) (xy 355.96781 -34.552378) (xy 355.959987 -34.6118)
			(xy 355.944474 -34.669693) (xy 355.921538 -34.725066) (xy 355.891571 -34.776972) (xy 355.855084 -34.824522)
			(xy 355.812704 -34.866902) (xy 355.765154 -34.903389) (xy 355.713248 -34.933356) (xy 355.657875 -34.956292)
			(xy 355.599982 -34.971805) (xy 355.54056 -34.979628) (xy 355.480624 -34.979628) (xy 355.421202 -34.971805)
			(xy 355.363309 -34.956292) (xy 355.307936 -34.933356) (xy 355.25603 -34.903389) (xy 355.20848 -34.866902)
			(xy 355.1661 -34.824522) (xy 355.129613 -34.776972) (xy 355.099646 -34.725066) (xy 355.07671 -34.669693)
			(xy 355.061197 -34.6118) (xy 355.053374 -34.552378) (xy 355.052884 -34.52241) (xy 354.395532 -34.52241)
			(xy 354.395532 -34.72434) (xy 354.396548 -34.733992) (xy 354.398181 -34.741233) (xy 354.405032 -34.754393)
			(xy 354.41001 -34.7599) (xy 355.797612 -36.147502) (xy 355.804216 -36.149534) (xy 355.830029 -36.157633)
			(xy 355.87924 -36.180104) (xy 355.924782 -36.209303) (xy 355.965742 -36.244644) (xy 356.001297 -36.285417)
			(xy 356.030734 -36.330806) (xy 356.053462 -36.379899) (xy 356.069026 -36.43171) (xy 356.077112 -36.485201)
			(xy 356.077774 -36.512246) (xy 356.077774 -36.519104) (xy 356.077196 -36.543004) (xy 356.070832 -36.590388)
			(xy 356.068415 -36.60013) (xy 360.298245 -36.60013) (xy 360.30225 -36.512222) (xy 360.314233 -36.425042)
			(xy 360.334093 -36.339313) (xy 360.361668 -36.255745) (xy 360.396727 -36.175031) (xy 360.43898 -36.097839)
			(xy 360.488078 -36.02481) (xy 360.543614 -35.956548) (xy 360.605126 -35.893618) (xy 360.672107 -35.836544)
			(xy 360.744 -35.785796) (xy 360.820209 -35.741796) (xy 360.900104 -35.704909) (xy 360.983023 -35.67544)
			(xy 361.068278 -35.653633) (xy 361.155162 -35.639669) (xy 361.242956 -35.633663) (xy 361.330933 -35.635667)
			(xy 361.418363 -35.645662) (xy 361.504522 -35.663566) (xy 361.588696 -35.68923) (xy 361.670187 -35.722443)
			(xy 361.748321 -35.762929) (xy 361.822449 -35.810351) (xy 361.891957 -35.864318) (xy 361.905256 -35.876738)
			(xy 367.017298 -35.876738) (xy 367.021369 -35.821116) (xy 367.033495 -35.766679) (xy 367.053418 -35.714588)
			(xy 367.080714 -35.665953) (xy 367.1148 -35.62181) (xy 367.154949 -35.583101) (xy 367.200307 -35.55065)
			(xy 367.249907 -35.525149) (xy 367.302691 -35.507142) (xy 367.357534 -35.497012) (xy 367.413268 -35.494975)
			(xy 367.468705 -35.501075) (xy 367.522662 -35.515181) (xy 367.573991 -35.536993) (xy 367.621597 -35.566047)
			(xy 367.664465 -35.601722) (xy 367.701682 -35.643259) (xy 367.732455 -35.689772) (xy 367.756127 -35.740269)
			(xy 367.772195 -35.793676) (xy 367.780315 -35.848852) (xy 367.780824 -35.876738) (xy 367.780315 -35.904624)
			(xy 367.772195 -35.9598) (xy 367.756127 -36.013207) (xy 367.732455 -36.063704) (xy 367.701682 -36.110217)
			(xy 367.664465 -36.151754) (xy 367.621597 -36.187429) (xy 367.573991 -36.216483) (xy 367.522662 -36.238295)
			(xy 367.468705 -36.252401) (xy 367.413268 -36.258501) (xy 367.357534 -36.256464) (xy 367.302691 -36.246334)
			(xy 367.249907 -36.228327) (xy 367.200307 -36.202826) (xy 367.154949 -36.170375) (xy 367.1148 -36.131666)
			(xy 367.080714 -36.087523) (xy 367.053418 -36.038888) (xy 367.033495 -35.986797) (xy 367.021369 -35.93236)
			(xy 367.017298 -35.876738) (xy 361.905256 -35.876738) (xy 361.956271 -35.924383) (xy 362.014855 -35.990047)
			(xy 362.067226 -36.060766) (xy 362.112949 -36.135954) (xy 362.151646 -36.214989) (xy 362.182995 -36.297215)
			(xy 362.206737 -36.381951) (xy 362.222675 -36.468495) (xy 362.226461 -36.50996) (xy 368.913916 -36.50996)
			(xy 368.917987 -36.454338) (xy 368.930113 -36.399901) (xy 368.950036 -36.34781) (xy 368.977332 -36.299175)
			(xy 369.011418 -36.255032) (xy 369.051567 -36.216323) (xy 369.096925 -36.183872) (xy 369.146525 -36.158371)
			(xy 369.199309 -36.140364) (xy 369.254152 -36.130234) (xy 369.309886 -36.128197) (xy 369.365323 -36.134297)
			(xy 369.41928 -36.148403) (xy 369.470609 -36.170215) (xy 369.518215 -36.199269) (xy 369.561083 -36.234944)
			(xy 369.5983 -36.276481) (xy 369.629073 -36.322994) (xy 369.652745 -36.373491) (xy 369.668813 -36.426898)
			(xy 369.676933 -36.482074) (xy 369.677442 -36.50996) (xy 369.676933 -36.537846) (xy 369.668813 -36.593022)
			(xy 369.652745 -36.646429) (xy 369.629073 -36.696926) (xy 369.5983 -36.743439) (xy 369.561083 -36.784976)
			(xy 369.518215 -36.820651) (xy 369.470609 -36.849705) (xy 369.41928 -36.871517) (xy 369.365323 -36.885623)
			(xy 369.309886 -36.891723) (xy 369.254152 -36.889686) (xy 369.199309 -36.879556) (xy 369.146525 -36.861549)
			(xy 369.096925 -36.836048) (xy 369.051567 -36.803597) (xy 369.011418 -36.764888) (xy 368.977332 -36.720745)
			(xy 368.950036 -36.67211) (xy 368.930113 -36.620019) (xy 368.917987 -36.565582) (xy 368.913916 -36.50996)
			(xy 362.226461 -36.50996) (xy 362.230677 -36.55613) (xy 362.231178 -36.60013) (xy 362.230677 -36.64413)
			(xy 362.222675 -36.731765) (xy 362.206737 -36.818309) (xy 362.182995 -36.903045) (xy 362.151646 -36.985271)
			(xy 362.112949 -37.064306) (xy 362.067226 -37.139494) (xy 362.014855 -37.210213) (xy 361.956271 -37.275877)
			(xy 361.891957 -37.335942) (xy 361.822449 -37.389909) (xy 361.748321 -37.437331) (xy 361.675315 -37.47516)
			(xy 366.05921 -37.47516) (xy 366.063281 -37.419538) (xy 366.075407 -37.365101) (xy 366.09533 -37.31301)
			(xy 366.122626 -37.264375) (xy 366.156712 -37.220232) (xy 366.196861 -37.181523) (xy 366.242219 -37.149072)
			(xy 366.291819 -37.123571) (xy 366.344603 -37.105564) (xy 366.399446 -37.095434) (xy 366.45518 -37.093397)
			(xy 366.510617 -37.099497) (xy 366.564574 -37.113603) (xy 366.615903 -37.135415) (xy 366.663509 -37.164469)
			(xy 366.706377 -37.200144) (xy 366.743594 -37.241681) (xy 366.774367 -37.288194) (xy 366.798039 -37.338691)
			(xy 366.814107 -37.392098) (xy 366.822227 -37.447274) (xy 366.822736 -37.47516) (xy 366.822227 -37.503046)
			(xy 366.814107 -37.558222) (xy 366.798039 -37.611629) (xy 366.774367 -37.662126) (xy 366.774214 -37.662358)
			(xy 368.248436 -37.662358) (xy 368.252507 -37.606736) (xy 368.264633 -37.552299) (xy 368.284556 -37.500208)
			(xy 368.311852 -37.451573) (xy 368.345938 -37.40743) (xy 368.386087 -37.368721) (xy 368.431445 -37.33627)
			(xy 368.481045 -37.310769) (xy 368.533829 -37.292762) (xy 368.588672 -37.282632) (xy 368.644406 -37.280595)
			(xy 368.699843 -37.286695) (xy 368.7538 -37.300801) (xy 368.805129 -37.322613) (xy 368.852735 -37.351667)
			(xy 368.895603 -37.387342) (xy 368.93282 -37.428879) (xy 368.963593 -37.475392) (xy 368.987265 -37.525889)
			(xy 369.003333 -37.579296) (xy 369.011453 -37.634472) (xy 369.011962 -37.662358) (xy 369.011453 -37.690244)
			(xy 369.003333 -37.74542) (xy 368.987265 -37.798827) (xy 368.963593 -37.849324) (xy 368.93282 -37.895837)
			(xy 368.895603 -37.937374) (xy 368.852735 -37.973049) (xy 368.805129 -38.002103) (xy 368.7538 -38.023915)
			(xy 368.699843 -38.038021) (xy 368.644406 -38.044121) (xy 368.588672 -38.042084) (xy 368.533829 -38.031954)
			(xy 368.481045 -38.013947) (xy 368.431445 -37.988446) (xy 368.386087 -37.955995) (xy 368.345938 -37.917286)
			(xy 368.311852 -37.873143) (xy 368.284556 -37.824508) (xy 368.264633 -37.772417) (xy 368.252507 -37.71798)
			(xy 368.248436 -37.662358) (xy 366.774214 -37.662358) (xy 366.743594 -37.708639) (xy 366.706377 -37.750176)
			(xy 366.663509 -37.785851) (xy 366.615903 -37.814905) (xy 366.564574 -37.836717) (xy 366.510617 -37.850823)
			(xy 366.45518 -37.856923) (xy 366.399446 -37.854886) (xy 366.344603 -37.844756) (xy 366.291819 -37.826749)
			(xy 366.242219 -37.801248) (xy 366.196861 -37.768797) (xy 366.156712 -37.730088) (xy 366.122626 -37.685945)
			(xy 366.09533 -37.63731) (xy 366.075407 -37.585219) (xy 366.063281 -37.530782) (xy 366.05921 -37.47516)
			(xy 361.675315 -37.47516) (xy 361.670187 -37.477817) (xy 361.588696 -37.51103) (xy 361.504522 -37.536694)
			(xy 361.418363 -37.554598) (xy 361.330933 -37.564593) (xy 361.242956 -37.566597) (xy 361.155162 -37.560591)
			(xy 361.068278 -37.546627) (xy 360.983023 -37.52482) (xy 360.900104 -37.495351) (xy 360.820209 -37.458464)
			(xy 360.744 -37.414464) (xy 360.672107 -37.363716) (xy 360.605126 -37.306642) (xy 360.543614 -37.243712)
			(xy 360.488078 -37.17545) (xy 360.43898 -37.102421) (xy 360.396727 -37.025229) (xy 360.361668 -36.944515)
			(xy 360.334093 -36.860947) (xy 360.314233 -36.775218) (xy 360.30225 -36.688038) (xy 360.298245 -36.60013)
			(xy 356.068415 -36.60013) (xy 356.065074 -36.613592) (xy 356.053644 -36.64966) (xy 356.050596 -36.657788)
			(xy 356.045008 -36.67125) (xy 356.042976 -36.675822) (xy 356.04196 -36.678108) (xy 356.040182 -36.681664)
			(xy 356.037896 -36.691824) (xy 356.037896 -38.729951) (xy 372.000997 -38.729951) (xy 372.000997 -38.675449)
			(xy 372.008754 -38.621501) (xy 372.02411 -38.569206) (xy 372.046753 -38.519629) (xy 372.076221 -38.473779)
			(xy 372.111914 -38.43259) (xy 372.153106 -38.3969) (xy 372.198959 -38.367437) (xy 372.248538 -38.344798)
			(xy 372.300834 -38.329447) (xy 372.354783 -38.321695) (xy 372.382034 -38.321234) (xy 372.410337 -38.32176)
			(xy 372.466325 -38.330103) (xy 372.520464 -38.346631) (xy 372.571565 -38.37098) (xy 372.618505 -38.402615)
			(xy 372.660254 -38.440842) (xy 372.695892 -38.48482) (xy 372.71071 -38.50894) (xy 372.718328 -38.52096)
			(xy 372.738943 -38.540561) (xy 372.76417 -38.553704) (xy 372.792047 -38.559365) (xy 372.820403 -38.557104)
			(xy 372.84703 -38.547097) (xy 372.869856 -38.530122) (xy 372.878858 -38.5191) (xy 372.897073 -38.496248)
			(xy 372.93923 -38.455783) (xy 372.98706 -38.422212) (xy 373.039446 -38.396321) (xy 373.095165 -38.378714)
			(xy 373.152917 -38.369801) (xy 373.182134 -38.36924) (xy 373.209387 -38.369632) (xy 373.263338 -38.377394)
			(xy 373.315635 -38.392754) (xy 373.365214 -38.4154) (xy 373.411066 -38.44487) (xy 373.452258 -38.480566)
			(xy 373.48795 -38.521761) (xy 373.517417 -38.567616) (xy 373.540058 -38.617197) (xy 373.555414 -38.669495)
			(xy 373.56317 -38.723447) (xy 373.56317 -38.777953) (xy 373.555414 -38.831905) (xy 373.540058 -38.884203)
			(xy 373.517417 -38.933784) (xy 373.48795 -38.979639) (xy 373.452258 -39.020834) (xy 373.411066 -39.05653)
			(xy 373.365214 -39.086) (xy 373.315635 -39.108646) (xy 373.263338 -39.124006) (xy 373.209387 -39.131768)
			(xy 373.182134 -39.132256) (xy 373.15383 -39.13176) (xy 373.097841 -39.123412) (xy 373.043701 -39.10688)
			(xy 372.992599 -39.082526) (xy 372.945659 -39.050885) (xy 372.903912 -39.012654) (xy 372.868275 -38.968672)
			(xy 372.853458 -38.94455) (xy 372.845881 -38.932501) (xy 372.825258 -38.9129) (xy 372.800021 -38.899759)
			(xy 372.772137 -38.894102) (xy 372.743774 -38.896369) (xy 372.717142 -38.906383) (xy 372.694313 -38.923364)
			(xy 372.68531 -38.93439) (xy 372.66711 -38.957255) (xy 372.624951 -38.99772) (xy 372.577118 -39.031289)
			(xy 372.524728 -39.057178) (xy 372.469006 -39.074783) (xy 372.411252 -39.083692) (xy 372.382034 -39.08425)
			(xy 372.354783 -39.083705) (xy 372.300834 -39.075953) (xy 372.248538 -39.060602) (xy 372.198959 -39.037963)
			(xy 372.153106 -39.0085) (xy 372.111914 -38.97281) (xy 372.076221 -38.931621) (xy 372.046753 -38.885771)
			(xy 372.02411 -38.836194) (xy 372.008754 -38.783899) (xy 372.000997 -38.729951) (xy 356.037896 -38.729951)
			(xy 356.037896 -38.90645) (xy 356.037962 -38.910459) (xy 356.039232 -38.918374) (xy 356.040436 -38.922198)
			(xy 356.042447 -38.927776) (xy 356.048609 -38.937903) (xy 356.052628 -38.942264) (xy 358.379236 -41.268751)
			(xy 364.14405 -41.268751) (xy 364.14405 -41.214249) (xy 364.151806 -41.160301) (xy 364.167159 -41.108007)
			(xy 364.189799 -41.058429) (xy 364.219263 -41.012578) (xy 364.254952 -40.971386) (xy 364.296139 -40.935691)
			(xy 364.341987 -40.906222) (xy 364.391562 -40.883576) (xy 364.443855 -40.868216) (xy 364.497801 -40.860453)
			(xy 364.525052 -40.859964) (xy 364.553792 -40.860466) (xy 364.61062 -40.869095) (xy 364.66551 -40.886151)
			(xy 364.717221 -40.911247) (xy 364.764583 -40.943816) (xy 364.78591 -40.963088) (xy 364.792768 -40.969692)
			(xy 364.810802 -40.976804) (xy 364.899702 -40.976804) (xy 364.917736 -40.969692) (xy 364.924594 -40.963088)
			(xy 364.945907 -40.943801) (xy 364.993272 -40.911235) (xy 365.044987 -40.886145) (xy 365.099881 -40.869098)
			(xy 365.156712 -40.860481) (xy 365.185452 -40.859964) (xy 365.212705 -40.86048) (xy 365.266657 -40.868231)
			(xy 365.318957 -40.883582) (xy 365.36854 -40.90622) (xy 365.414395 -40.935684) (xy 365.455591 -40.971375)
			(xy 365.491287 -41.012566) (xy 365.520757 -41.058418) (xy 365.543402 -41.107998) (xy 365.558759 -41.160296)
			(xy 365.566517 -41.214247) (xy 365.566517 -41.268753) (xy 365.558759 -41.322704) (xy 365.543402 -41.375002)
			(xy 365.520757 -41.424582) (xy 365.491287 -41.470434) (xy 365.455591 -41.511625) (xy 365.414395 -41.547316)
			(xy 365.36854 -41.57678) (xy 365.318957 -41.599418) (xy 365.266657 -41.614769) (xy 365.212705 -41.62252)
			(xy 365.185452 -41.62298) (xy 365.156713 -41.622464) (xy 365.099886 -41.613836) (xy 365.044996 -41.596783)
			(xy 364.993285 -41.571691) (xy 364.945922 -41.539126) (xy 364.924594 -41.519856) (xy 364.917736 -41.513252)
			(xy 364.899702 -41.50614) (xy 364.810802 -41.50614) (xy 364.792768 -41.513252) (xy 364.78591 -41.519856)
			(xy 364.764602 -41.539149) (xy 364.717235 -41.571712) (xy 364.665518 -41.5968) (xy 364.610623 -41.613846)
			(xy 364.553792 -41.622463) (xy 364.525052 -41.62298) (xy 364.497801 -41.622547) (xy 364.443854 -41.614784)
			(xy 364.391562 -41.599424) (xy 364.341987 -41.576778) (xy 364.296139 -41.547309) (xy 364.254952 -41.511614)
			(xy 364.219263 -41.470422) (xy 364.189799 -41.424571) (xy 364.167159 -41.374993) (xy 364.151806 -41.322699)
			(xy 364.14405 -41.268751) (xy 358.379236 -41.268751) (xy 360.415814 -43.305222) (xy 366.607344 -43.305222)
			(xy 366.607812 -43.277852) (xy 366.615628 -43.223672) (xy 366.631116 -43.171169) (xy 366.653957 -43.121422)
			(xy 366.683682 -43.075455) (xy 366.701324 -43.054524) (xy 366.701578 -43.05427) (xy 366.707151 -43.047174)
			(xy 366.713404 -43.030264) (xy 366.71377 -43.02125) (xy 366.71377 -42.954194) (xy 366.713423 -42.945176)
			(xy 366.707169 -42.928259) (xy 366.701578 -42.921174) (xy 366.701324 -42.921174) (xy 366.701324 -42.92092)
			(xy 366.683685 -42.899988) (xy 366.653972 -42.854016) (xy 366.631136 -42.804268) (xy 366.615645 -42.751767)
			(xy 366.607817 -42.697591) (xy 366.607344 -42.670222) (xy 366.607896 -42.641484) (xy 366.616514 -42.584659)
			(xy 366.633558 -42.529769) (xy 366.658643 -42.478057) (xy 366.691201 -42.430692) (xy 366.710468 -42.409364)
			(xy 366.717072 -42.402506) (xy 366.724184 -42.384472) (xy 366.724184 -42.295572) (xy 366.717072 -42.277538)
			(xy 366.710468 -42.27068) (xy 366.691222 -42.249333) (xy 366.65866 -42.201972) (xy 366.633571 -42.150264)
			(xy 366.616522 -42.095376) (xy 366.607899 -42.038553) (xy 366.607896 -41.981079) (xy 366.616515 -41.924255)
			(xy 366.633559 -41.869366) (xy 366.658644 -41.817655) (xy 366.691201 -41.770292) (xy 366.710468 -41.748964)
			(xy 366.717072 -41.742106) (xy 366.724184 -41.724072) (xy 366.724184 -41.635172) (xy 366.717072 -41.617138)
			(xy 366.710468 -41.61028) (xy 366.691213 -41.58894) (xy 366.658643 -41.541582) (xy 366.633547 -41.489874)
			(xy 366.616493 -41.434986) (xy 366.607867 -41.37816) (xy 366.607344 -41.349422) (xy 366.60783 -41.322171)
			(xy 366.615586 -41.268223) (xy 366.630941 -41.215928) (xy 366.653583 -41.166351) (xy 366.683049 -41.120501)
			(xy 366.71874 -41.07931) (xy 366.759931 -41.043619) (xy 366.805781 -41.014153) (xy 366.855358 -40.991511)
			(xy 366.907653 -40.976156) (xy 366.961601 -40.9684) (xy 367.016103 -40.9684) (xy 367.039224 -40.971724)
			(xy 374.894092 -40.971724) (xy 374.898163 -40.916102) (xy 374.910289 -40.861665) (xy 374.930212 -40.809574)
			(xy 374.957508 -40.760939) (xy 374.991594 -40.716796) (xy 375.031743 -40.678087) (xy 375.077101 -40.645636)
			(xy 375.126701 -40.620135) (xy 375.179485 -40.602128) (xy 375.234328 -40.591998) (xy 375.290062 -40.589961)
			(xy 375.345499 -40.596061) (xy 375.399456 -40.610167) (xy 375.450785 -40.631979) (xy 375.498391 -40.661033)
			(xy 375.541259 -40.696708) (xy 375.578476 -40.738245) (xy 375.609249 -40.784758) (xy 375.632921 -40.835255)
			(xy 375.648989 -40.888662) (xy 375.657109 -40.943838) (xy 375.657618 -40.971724) (xy 375.657109 -40.99961)
			(xy 375.648989 -41.054786) (xy 375.632921 -41.108193) (xy 375.609249 -41.15869) (xy 375.578476 -41.205203)
			(xy 375.541259 -41.24674) (xy 375.498391 -41.282415) (xy 375.450785 -41.311469) (xy 375.399456 -41.333281)
			(xy 375.345499 -41.347387) (xy 375.290062 -41.353487) (xy 375.234328 -41.35145) (xy 375.179485 -41.34132)
			(xy 375.126701 -41.323313) (xy 375.077101 -41.297812) (xy 375.031743 -41.265361) (xy 374.991594 -41.226652)
			(xy 374.957508 -41.182509) (xy 374.930212 -41.133874) (xy 374.910289 -41.081783) (xy 374.898163 -41.027346)
			(xy 374.894092 -40.971724) (xy 367.039224 -40.971724) (xy 367.070051 -40.976156) (xy 367.122346 -40.991511)
			(xy 367.171923 -41.014153) (xy 367.217773 -41.043619) (xy 367.258964 -41.07931) (xy 367.294655 -41.120501)
			(xy 367.324121 -41.166351) (xy 367.346763 -41.215928) (xy 367.362118 -41.268223) (xy 367.369874 -41.322171)
			(xy 367.37036 -41.349422) (xy 367.369834 -41.378161) (xy 367.361209 -41.434987) (xy 367.344159 -41.489877)
			(xy 367.319068 -41.541589) (xy 367.286505 -41.588952) (xy 367.267236 -41.61028) (xy 367.260632 -41.617138)
			(xy 367.25352 -41.635172) (xy 367.25352 -41.724072) (xy 367.260632 -41.742106) (xy 367.267236 -41.748964)
			(xy 367.28653 -41.770271) (xy 367.319098 -41.817636) (xy 367.344191 -41.86935) (xy 367.361242 -41.924245)
			(xy 367.369863 -41.981075) (xy 367.369861 -42.038557) (xy 367.361234 -42.095387) (xy 367.34418 -42.150279)
			(xy 367.319082 -42.201992) (xy 367.28651 -42.249354) (xy 367.267236 -42.27068) (xy 367.260632 -42.277538)
			(xy 367.25352 -42.295572) (xy 367.25352 -42.384472) (xy 367.260632 -42.402506) (xy 367.267236 -42.409364)
			(xy 367.286513 -42.430686) (xy 367.319079 -42.478049) (xy 367.344171 -42.529762) (xy 367.36122 -42.584654)
			(xy 367.369841 -42.641483) (xy 367.37036 -42.670222) (xy 367.369917 -42.697593) (xy 367.362095 -42.751774)
			(xy 367.346601 -42.804277) (xy 367.326044 -42.849038) (xy 369.192046 -42.849038) (xy 369.196117 -42.793416)
			(xy 369.208243 -42.738979) (xy 369.228166 -42.686888) (xy 369.255462 -42.638253) (xy 369.289548 -42.59411)
			(xy 369.329697 -42.555401) (xy 369.375055 -42.52295) (xy 369.424655 -42.497449) (xy 369.477439 -42.479442)
			(xy 369.532282 -42.469312) (xy 369.588016 -42.467275) (xy 369.643453 -42.473375) (xy 369.69741 -42.487481)
			(xy 369.748739 -42.509293) (xy 369.796345 -42.538347) (xy 369.839213 -42.574022) (xy 369.87643 -42.615559)
			(xy 369.907203 -42.662072) (xy 369.930875 -42.712569) (xy 369.946943 -42.765976) (xy 369.955063 -42.821152)
			(xy 369.955424 -42.84091) (xy 375.233182 -42.84091) (xy 375.237253 -42.785288) (xy 375.249379 -42.730851)
			(xy 375.269302 -42.67876) (xy 375.296598 -42.630125) (xy 375.330684 -42.585982) (xy 375.370833 -42.547273)
			(xy 375.416191 -42.514822) (xy 375.465791 -42.489321) (xy 375.518575 -42.471314) (xy 375.573418 -42.461184)
			(xy 375.629152 -42.459147) (xy 375.684589 -42.465247) (xy 375.738546 -42.479353) (xy 375.789875 -42.501165)
			(xy 375.837481 -42.530219) (xy 375.880349 -42.565894) (xy 375.917566 -42.607431) (xy 375.948339 -42.653944)
			(xy 375.972011 -42.704441) (xy 375.988079 -42.757848) (xy 375.996199 -42.813024) (xy 375.996708 -42.84091)
			(xy 375.996199 -42.868796) (xy 375.988079 -42.923972) (xy 375.972011 -42.977379) (xy 375.948339 -43.027876)
			(xy 375.917566 -43.074389) (xy 375.880349 -43.115926) (xy 375.837481 -43.151601) (xy 375.789875 -43.180655)
			(xy 375.738546 -43.202467) (xy 375.684589 -43.216573) (xy 375.629152 -43.222673) (xy 375.573418 -43.220636)
			(xy 375.518575 -43.210506) (xy 375.465791 -43.192499) (xy 375.416191 -43.166998) (xy 375.370833 -43.134547)
			(xy 375.330684 -43.095838) (xy 375.296598 -43.051695) (xy 375.269302 -43.00306) (xy 375.249379 -42.950969)
			(xy 375.237253 -42.896532) (xy 375.233182 -42.84091) (xy 369.955424 -42.84091) (xy 369.955572 -42.849038)
			(xy 369.955063 -42.876924) (xy 369.946943 -42.9321) (xy 369.930875 -42.985507) (xy 369.907203 -43.036004)
			(xy 369.87643 -43.082517) (xy 369.839213 -43.124054) (xy 369.796345 -43.159729) (xy 369.748739 -43.188783)
			(xy 369.69741 -43.210595) (xy 369.643453 -43.224701) (xy 369.588016 -43.230801) (xy 369.532282 -43.228764)
			(xy 369.477439 -43.218634) (xy 369.424655 -43.200627) (xy 369.375055 -43.175126) (xy 369.329697 -43.142675)
			(xy 369.289548 -43.103966) (xy 369.255462 -43.059823) (xy 369.228166 -43.011188) (xy 369.208243 -42.959097)
			(xy 369.196117 -42.90466) (xy 369.192046 -42.849038) (xy 367.326044 -42.849038) (xy 367.323754 -42.854024)
			(xy 367.294024 -42.899989) (xy 367.27638 -42.92092) (xy 367.276126 -42.921174) (xy 367.270536 -42.928258)
			(xy 367.264293 -42.945177) (xy 367.263934 -42.954194) (xy 367.263934 -43.02125) (xy 367.264308 -43.030265)
			(xy 367.270543 -43.047183) (xy 367.276126 -43.05427) (xy 367.27638 -43.05427) (xy 367.27638 -43.054524)
			(xy 367.293994 -43.075476) (xy 367.32371 -43.121443) (xy 367.346551 -43.171186) (xy 367.362048 -43.223682)
			(xy 367.369883 -43.277854) (xy 367.37036 -43.305222) (xy 367.369874 -43.332473) (xy 367.362118 -43.386421)
			(xy 367.346763 -43.438716) (xy 367.324121 -43.488293) (xy 367.294655 -43.534143) (xy 367.258964 -43.575334)
			(xy 367.217773 -43.611025) (xy 367.171923 -43.640491) (xy 367.122346 -43.663133) (xy 367.070051 -43.678488)
			(xy 367.016103 -43.686244) (xy 366.961601 -43.686244) (xy 366.907653 -43.678488) (xy 366.855358 -43.663133)
			(xy 366.805781 -43.640491) (xy 366.759931 -43.611025) (xy 366.71874 -43.575334) (xy 366.683049 -43.534143)
			(xy 366.653583 -43.488293) (xy 366.630941 -43.438716) (xy 366.615586 -43.386421) (xy 366.60783 -43.332473)
			(xy 366.607344 -43.305222) (xy 360.415814 -43.305222) (xy 360.846874 -43.73626) (xy 368.513104 -43.73626)
			(xy 368.517175 -43.680638) (xy 368.529301 -43.626201) (xy 368.549224 -43.57411) (xy 368.57652 -43.525475)
			(xy 368.610606 -43.481332) (xy 368.650755 -43.442623) (xy 368.696113 -43.410172) (xy 368.745713 -43.384671)
			(xy 368.798497 -43.366664) (xy 368.85334 -43.356534) (xy 368.909074 -43.354497) (xy 368.964511 -43.360597)
			(xy 369.018468 -43.374703) (xy 369.069797 -43.396515) (xy 369.117403 -43.425569) (xy 369.160271 -43.461244)
			(xy 369.197488 -43.502781) (xy 369.228261 -43.549294) (xy 369.251933 -43.599791) (xy 369.268001 -43.653198)
			(xy 369.276121 -43.708374) (xy 369.27663 -43.73626) (xy 369.276121 -43.764146) (xy 369.268001 -43.819322)
			(xy 369.251933 -43.872729) (xy 369.228261 -43.923226) (xy 369.197488 -43.969739) (xy 369.160271 -44.011276)
			(xy 369.117403 -44.046951) (xy 369.069797 -44.076005) (xy 369.018468 -44.097817) (xy 368.964511 -44.111923)
			(xy 368.909074 -44.118023) (xy 368.85334 -44.115986) (xy 368.798497 -44.105856) (xy 368.745713 -44.087849)
			(xy 368.696113 -44.062348) (xy 368.650755 -44.029897) (xy 368.610606 -43.991188) (xy 368.57652 -43.947045)
			(xy 368.549224 -43.89841) (xy 368.529301 -43.846319) (xy 368.517175 -43.791882) (xy 368.513104 -43.73626)
			(xy 360.846874 -43.73626) (xy 360.920538 -43.80992) (xy 360.93865 -43.828701) (xy 360.969335 -43.870898)
			(xy 360.993035 -43.917379) (xy 361.009166 -43.966997) (xy 361.017332 -44.018529) (xy 361.01782 -44.044616)
			(xy 361.01782 -45.114464) (xy 368.36553 -45.114464) (xy 368.369601 -45.058842) (xy 368.381727 -45.004405)
			(xy 368.40165 -44.952314) (xy 368.428946 -44.903679) (xy 368.463032 -44.859536) (xy 368.503181 -44.820827)
			(xy 368.548539 -44.788376) (xy 368.598139 -44.762875) (xy 368.650923 -44.744868) (xy 368.705766 -44.734738)
			(xy 368.7615 -44.732701) (xy 368.816937 -44.738801) (xy 368.870894 -44.752907) (xy 368.922223 -44.774719)
			(xy 368.969829 -44.803773) (xy 369.012697 -44.839448) (xy 369.049914 -44.880985) (xy 369.080687 -44.927498)
			(xy 369.104359 -44.977995) (xy 369.120427 -45.031402) (xy 369.128547 -45.086578) (xy 369.129056 -45.114464)
			(xy 369.128547 -45.14235) (xy 369.120427 -45.197526) (xy 369.104359 -45.250933) (xy 369.080687 -45.30143)
			(xy 369.049914 -45.347943) (xy 369.012697 -45.38948) (xy 368.969829 -45.425155) (xy 368.922223 -45.454209)
			(xy 368.870894 -45.476021) (xy 368.816937 -45.490127) (xy 368.7615 -45.496227) (xy 368.705766 -45.49419)
			(xy 368.650923 -45.48406) (xy 368.598139 -45.466053) (xy 368.548539 -45.440552) (xy 368.503181 -45.408101)
			(xy 368.463032 -45.369392) (xy 368.428946 -45.325249) (xy 368.40165 -45.276614) (xy 368.381727 -45.224523)
			(xy 368.369601 -45.170086) (xy 368.36553 -45.114464) (xy 361.01782 -45.114464) (xy 361.01782 -46.082204)
			(xy 366.352582 -46.082204) (xy 366.353081 -46.054953) (xy 366.360837 -46.001007) (xy 366.376191 -45.948713)
			(xy 366.398831 -45.899136) (xy 366.428296 -45.853286) (xy 366.463986 -45.812096) (xy 366.505175 -45.776405)
			(xy 366.551024 -45.746938) (xy 366.6006 -45.724296) (xy 366.652893 -45.70894) (xy 366.706839 -45.701182)
			(xy 366.73409 -45.700696) (xy 366.760992 -45.701166) (xy 366.814262 -45.708736) (xy 366.86594 -45.723714)
			(xy 366.915002 -45.745803) (xy 366.960474 -45.774564) (xy 367.001456 -45.809428) (xy 367.037134 -45.849703)
			(xy 367.052352 -45.871892) (xy 367.059464 -45.882814) (xy 367.082324 -45.894752) (xy 367.194592 -45.89272)
			(xy 367.216944 -45.879766) (xy 367.223802 -45.86859) (xy 367.238736 -45.844997) (xy 367.274413 -45.802045)
			(xy 367.315969 -45.764751) (xy 367.362517 -45.733913) (xy 367.413062 -45.710188) (xy 367.466526 -45.694084)
			(xy 367.521766 -45.685944) (xy 367.549684 -45.685456) (xy 367.576677 -45.685926) (xy 367.630125 -45.69353)
			(xy 367.681968 -45.708588) (xy 367.731173 -45.7308) (xy 367.776757 -45.759723) (xy 367.797588 -45.776896)
			(xy 367.805716 -45.784008) (xy 367.82629 -45.790104) (xy 367.911634 -45.779182) (xy 367.922185 -45.777434)
			(xy 367.940465 -45.766361) (xy 367.94694 -45.757846) (xy 367.962275 -45.736602) (xy 367.997865 -45.698149)
			(xy 368.038385 -45.664932) (xy 368.083072 -45.637575) (xy 368.131083 -45.616593) (xy 368.181514 -45.602383)
			(xy 368.233416 -45.595211) (xy 368.259614 -45.594778) (xy 368.286864 -45.595293) (xy 368.340808 -45.603051)
			(xy 368.393099 -45.618407) (xy 368.442672 -45.641048) (xy 368.488519 -45.670513) (xy 368.529706 -45.706204)
			(xy 368.565395 -45.747392) (xy 368.594859 -45.79324) (xy 368.617498 -45.842814) (xy 368.632852 -45.895106)
			(xy 368.640608 -45.94905) (xy 368.640608 -46.00355) (xy 368.632852 -46.057494) (xy 368.617498 -46.109786)
			(xy 368.594859 -46.15936) (xy 368.565395 -46.205208) (xy 368.529706 -46.246396) (xy 368.488519 -46.282087)
			(xy 368.442672 -46.311552) (xy 368.393099 -46.334193) (xy 368.340808 -46.349549) (xy 368.286864 -46.357307)
			(xy 368.259614 -46.357794) (xy 368.232622 -46.357313) (xy 368.179175 -46.34971) (xy 368.127332 -46.334654)
			(xy 368.078127 -46.312445) (xy 368.032542 -46.283525) (xy 368.01171 -46.266354) (xy 368.003582 -46.259242)
			(xy 367.983008 -46.253146) (xy 367.897664 -46.264068) (xy 367.887117 -46.265832) (xy 367.868837 -46.276895)
			(xy 367.862358 -46.285404) (xy 367.844747 -46.309706) (xy 367.80315 -46.352965) (xy 367.779554 -46.37151)
			(xy 367.77168 -46.377352) (xy 367.761266 -46.394878) (xy 367.748058 -46.485302) (xy 367.752884 -46.504606)
			(xy 367.758726 -46.51248) (xy 367.758726 -46.512734) (xy 367.776223 -46.537482) (xy 367.804028 -46.591333)
			(xy 367.822967 -46.648904) (xy 367.83256 -46.708745) (xy 367.833148 -46.739048) (xy 367.832667 -46.766299)
			(xy 367.824905 -46.820244) (xy 367.809546 -46.872537) (xy 367.786902 -46.922112) (xy 367.757434 -46.96796)
			(xy 367.721743 -47.009148) (xy 367.680553 -47.044839) (xy 367.634705 -47.074306) (xy 367.585129 -47.096949)
			(xy 367.532837 -47.112307) (xy 367.478891 -47.120068) (xy 367.45164 -47.120556) (xy 367.425606 -47.120136)
			(xy 367.374022 -47.113041) (xy 367.32388 -47.099005) (xy 367.276109 -47.078289) (xy 367.231596 -47.051275)
			(xy 367.211102 -47.035212) (xy 367.203351 -47.02946) (xy 367.184936 -47.023726) (xy 367.175288 -47.024036)
			(xy 367.095532 -47.030386) (xy 367.077752 -47.039022) (xy 367.071402 -47.046388) (xy 367.053243 -47.066055)
			(xy 367.012331 -47.100575) (xy 366.966997 -47.129042) (xy 366.918131 -47.150895) (xy 366.866692 -47.165708)
			(xy 366.813687 -47.17319) (xy 366.786922 -47.173642) (xy 366.759673 -47.173101) (xy 366.705729 -47.165349)
			(xy 366.653437 -47.149998) (xy 366.603863 -47.127362) (xy 366.558014 -47.097901) (xy 366.516824 -47.062216)
			(xy 366.481132 -47.021031) (xy 366.451665 -46.975187) (xy 366.429021 -46.925615) (xy 366.413663 -46.873326)
			(xy 366.405903 -46.819383) (xy 366.405414 -46.792134) (xy 366.405935 -46.76336) (xy 366.414586 -46.706465)
			(xy 366.431683 -46.651515) (xy 366.456838 -46.599755) (xy 366.489479 -46.552359) (xy 366.508792 -46.531022)
			(xy 366.516158 -46.523148) (xy 366.52327 -46.503336) (xy 366.515904 -46.40707) (xy 366.505998 -46.388274)
			(xy 366.497616 -46.38167) (xy 366.47543 -46.363446) (xy 366.436221 -46.321511) (xy 366.403735 -46.274175)
			(xy 366.378707 -46.222507) (xy 366.361701 -46.167672) (xy 366.3531 -46.110909) (xy 366.352582 -46.082204)
			(xy 361.01782 -46.082204) (xy 361.01782 -48.753014) (xy 369.468398 -48.753014) (xy 369.472469 -48.697392)
			(xy 369.484595 -48.642955) (xy 369.504518 -48.590864) (xy 369.531814 -48.542229) (xy 369.5659 -48.498086)
			(xy 369.606049 -48.459377) (xy 369.651407 -48.426926) (xy 369.701007 -48.401425) (xy 369.753791 -48.383418)
			(xy 369.808634 -48.373288) (xy 369.864368 -48.371251) (xy 369.919805 -48.377351) (xy 369.973762 -48.391457)
			(xy 370.025091 -48.413269) (xy 370.072697 -48.442323) (xy 370.115565 -48.477998) (xy 370.152782 -48.519535)
			(xy 370.183555 -48.566048) (xy 370.207227 -48.616545) (xy 370.223295 -48.669952) (xy 370.231415 -48.725128)
			(xy 370.231924 -48.753014) (xy 370.231415 -48.7809) (xy 370.223295 -48.836076) (xy 370.207227 -48.889483)
			(xy 370.205831 -48.89246) (xy 371.310408 -48.89246) (xy 371.310408 -48.892206) (xy 371.310887 -48.859353)
			(xy 371.318249 -48.794061) (xy 371.33287 -48.730002) (xy 371.354567 -48.667982) (xy 371.383066 -48.608778)
			(xy 371.418011 -48.553135) (xy 371.458962 -48.501751) (xy 371.481858 -48.478186) (xy 372.08841 -47.871634)
			(xy 372.095229 -47.864217) (xy 372.102961 -47.845631) (xy 372.103396 -47.835566) (xy 372.103396 -44.504356)
			(xy 372.103021 -44.494281) (xy 372.095268 -44.475682) (xy 372.08841 -44.468288) (xy 371.601238 -43.981116)
			(xy 371.578353 -43.957539) (xy 371.537388 -43.906164) (xy 371.502431 -43.850527) (xy 371.473924 -43.791325)
			(xy 371.452224 -43.729305) (xy 371.437604 -43.665244) (xy 371.430248 -43.59995) (xy 371.429788 -43.567096)
			(xy 371.429788 -43.566842) (xy 371.430395 -43.531441) (xy 371.438922 -43.461155) (xy 371.455857 -43.392408)
			(xy 371.480952 -43.326203) (xy 371.513843 -43.263505) (xy 371.554049 -43.205227) (xy 371.600985 -43.152219)
			(xy 371.653967 -43.105253) (xy 371.712222 -43.065014) (xy 371.774902 -43.032088) (xy 371.841093 -43.006955)
			(xy 371.90983 -42.989982) (xy 371.980111 -42.981415) (xy 372.015512 -42.980864) (xy 372.048394 -42.981277)
			(xy 372.113744 -42.988647) (xy 372.177856 -43.003292) (xy 372.239924 -43.025027) (xy 372.299166 -43.05358)
			(xy 372.354836 -43.088591) (xy 372.406233 -43.129618) (xy 372.429786 -43.152568) (xy 372.932198 -43.65498)
			(xy 372.940529 -43.662368) (xy 372.961459 -43.669886) (xy 372.972584 -43.669458) (xy 373.061738 -43.66133)
			(xy 373.081296 -43.6499) (xy 373.087646 -43.640502) (xy 373.10302 -43.619061) (xy 373.138643 -43.580147)
			(xy 373.179288 -43.546513) (xy 373.22418 -43.5188) (xy 373.272462 -43.497536) (xy 373.323213 -43.483129)
			(xy 373.375466 -43.475852) (xy 373.401844 -43.475402) (xy 373.429094 -43.475871) (xy 373.483038 -43.483633)
			(xy 373.535329 -43.498992) (xy 373.584902 -43.521636) (xy 373.630748 -43.551104) (xy 373.671934 -43.586797)
			(xy 373.707622 -43.627987) (xy 373.737085 -43.673837) (xy 373.759723 -43.723412) (xy 373.775077 -43.775705)
			(xy 373.782832 -43.82965) (xy 373.782832 -43.88415) (xy 373.775077 -43.938095) (xy 373.759723 -43.990388)
			(xy 373.737085 -44.039963) (xy 373.707622 -44.085813) (xy 373.671934 -44.127003) (xy 373.630748 -44.162696)
			(xy 373.584902 -44.192164) (xy 373.535329 -44.214808) (xy 373.483038 -44.230167) (xy 373.429094 -44.237929)
			(xy 373.401844 -44.238418) (xy 373.40159 -44.238418) (xy 373.382032 -44.23791) (xy 373.381778 -44.23791)
			(xy 373.371481 -44.237919) (xy 373.352214 -44.245128) (xy 373.34444 -44.25188) (xy 373.2911 -44.30268)
			(xy 373.283983 -44.310186) (xy 373.275845 -44.329179) (xy 373.275352 -44.33951) (xy 373.275352 -44.871132)
			(xy 373.275424 -44.87291) (xy 375.233182 -44.87291) (xy 375.237253 -44.817288) (xy 375.249379 -44.762851)
			(xy 375.269302 -44.71076) (xy 375.296598 -44.662125) (xy 375.330684 -44.617982) (xy 375.370833 -44.579273)
			(xy 375.416191 -44.546822) (xy 375.465791 -44.521321) (xy 375.518575 -44.503314) (xy 375.573418 -44.493184)
			(xy 375.629152 -44.491147) (xy 375.684589 -44.497247) (xy 375.738546 -44.511353) (xy 375.789875 -44.533165)
			(xy 375.837481 -44.562219) (xy 375.880349 -44.597894) (xy 375.917566 -44.639431) (xy 375.948339 -44.685944)
			(xy 375.972011 -44.736441) (xy 375.988079 -44.789848) (xy 375.996199 -44.845024) (xy 375.996708 -44.87291)
			(xy 375.996199 -44.900796) (xy 375.988079 -44.955972) (xy 375.972011 -45.009379) (xy 375.948339 -45.059876)
			(xy 375.917566 -45.106389) (xy 375.880349 -45.147926) (xy 375.837481 -45.183601) (xy 375.789875 -45.212655)
			(xy 375.738546 -45.234467) (xy 375.684589 -45.248573) (xy 375.629152 -45.254673) (xy 375.573418 -45.252636)
			(xy 375.518575 -45.242506) (xy 375.465791 -45.224499) (xy 375.416191 -45.198998) (xy 375.370833 -45.166547)
			(xy 375.330684 -45.127838) (xy 375.296598 -45.083695) (xy 375.269302 -45.03506) (xy 375.249379 -44.982969)
			(xy 375.237253 -44.928532) (xy 375.233182 -44.87291) (xy 373.275424 -44.87291) (xy 373.275762 -44.881295)
			(xy 373.283638 -44.900031) (xy 373.290592 -44.907454) (xy 373.34952 -44.965366) (xy 373.36857 -44.972986)
			(xy 373.37873 -44.972732) (xy 373.385842 -44.972732) (xy 373.413094 -44.973141) (xy 373.467043 -44.980903)
			(xy 373.519338 -44.996263) (xy 373.568915 -45.018909) (xy 373.614765 -45.04838) (xy 373.655955 -45.084075)
			(xy 373.691645 -45.125268) (xy 373.721111 -45.171122) (xy 373.743751 -45.220701) (xy 373.759106 -45.272998)
			(xy 373.766862 -45.326948) (xy 373.766862 -45.381452) (xy 373.759106 -45.435402) (xy 373.743751 -45.487699)
			(xy 373.721111 -45.537278) (xy 373.691645 -45.583132) (xy 373.655955 -45.624325) (xy 373.614765 -45.66002)
			(xy 373.568915 -45.689491) (xy 373.519338 -45.712137) (xy 373.467043 -45.727497) (xy 373.413094 -45.735259)
			(xy 373.385842 -45.735748) (xy 373.37873 -45.735748) (xy 373.36857 -45.735494) (xy 373.34952 -45.743114)
			(xy 373.290592 -45.801026) (xy 373.283658 -45.80846) (xy 373.275801 -45.827192) (xy 373.275352 -45.837348)
			(xy 373.275352 -46.211236) (xy 373.275793 -46.220965) (xy 373.283122 -46.238993) (xy 373.289576 -46.246288)
			(xy 373.33809 -46.297088) (xy 373.345231 -46.303806) (xy 373.363117 -46.311788) (xy 373.372888 -46.312582)
			(xy 373.399418 -46.314097) (xy 373.451709 -46.323545) (xy 373.502184 -46.340155) (xy 373.549866 -46.363608)
			(xy 373.593834 -46.39345) (xy 373.633235 -46.429103) (xy 373.66731 -46.469878) (xy 373.695397 -46.514986)
			(xy 373.716955 -46.563555) (xy 373.731565 -46.614644) (xy 373.738947 -46.667267) (xy 373.73941 -46.693836)
			(xy 373.738936 -46.720263) (xy 373.731627 -46.772611) (xy 373.717154 -46.823446) (xy 373.695795 -46.871793)
			(xy 373.68226 -46.894496) (xy 373.682006 -46.89475) (xy 373.676669 -46.904768) (xy 373.674414 -46.927318)
			(xy 373.677688 -46.938184) (xy 373.70385 -47.01286) (xy 373.708235 -47.023375) (xy 373.724323 -47.039463)
			(xy 373.734838 -47.043848) (xy 373.735092 -47.043848) (xy 373.759611 -47.052892) (xy 373.806062 -47.07684)
			(xy 373.848813 -47.1069) (xy 373.887063 -47.142511) (xy 373.920098 -47.183007) (xy 373.9473 -47.227631)
			(xy 373.968161 -47.275548) (xy 373.98229 -47.325863) (xy 373.989423 -47.377635) (xy 373.989854 -47.403766)
			(xy 373.98929 -47.431014) (xy 373.987767 -47.441612) (xy 375.261884 -47.441612) (xy 375.265955 -47.38599)
			(xy 375.278081 -47.331553) (xy 375.298004 -47.279462) (xy 375.3253 -47.230827) (xy 375.359386 -47.186684)
			(xy 375.399535 -47.147975) (xy 375.444893 -47.115524) (xy 375.494493 -47.090023) (xy 375.547277 -47.072016)
			(xy 375.60212 -47.061886) (xy 375.657854 -47.059849) (xy 375.713291 -47.065949) (xy 375.767248 -47.080055)
			(xy 375.818577 -47.101867) (xy 375.866183 -47.130921) (xy 375.909051 -47.166596) (xy 375.946268 -47.208133)
			(xy 375.977041 -47.254646) (xy 376.000713 -47.305143) (xy 376.016781 -47.35855) (xy 376.024901 -47.413726)
			(xy 376.02541 -47.441612) (xy 376.024901 -47.469498) (xy 376.016781 -47.524674) (xy 376.000713 -47.578081)
			(xy 375.977041 -47.628578) (xy 375.946268 -47.675091) (xy 375.909051 -47.716628) (xy 375.866183 -47.752303)
			(xy 375.818577 -47.781357) (xy 375.767248 -47.803169) (xy 375.713291 -47.817275) (xy 375.657854 -47.823375)
			(xy 375.60212 -47.821338) (xy 375.547277 -47.811208) (xy 375.494493 -47.793201) (xy 375.444893 -47.7677)
			(xy 375.399535 -47.735249) (xy 375.359386 -47.69654) (xy 375.3253 -47.652397) (xy 375.298004 -47.603762)
			(xy 375.278081 -47.551671) (xy 375.265955 -47.497234) (xy 375.261884 -47.441612) (xy 373.987767 -47.441612)
			(xy 373.98154 -47.484957) (xy 373.966191 -47.537247) (xy 373.943557 -47.586821) (xy 373.914099 -47.63267)
			(xy 373.878416 -47.673859) (xy 373.837234 -47.709551) (xy 373.791391 -47.739019) (xy 373.741822 -47.761663)
			(xy 373.689535 -47.777023) (xy 373.635594 -47.784785) (xy 373.608346 -47.785274) (xy 373.576536 -47.784634)
			(xy 373.513798 -47.774068) (xy 373.453684 -47.753238) (xy 373.425466 -47.738538) (xy 373.417582 -47.734741)
			(xy 373.4003 -47.732094) (xy 373.383135 -47.735414) (xy 373.375428 -47.739554) (xy 373.300244 -47.784004)
			(xy 373.292881 -47.788819) (xy 373.281678 -47.802364) (xy 373.275723 -47.818903) (xy 373.275352 -47.827692)
			(xy 373.275352 -47.902368) (xy 373.297704 -47.930054) (xy 373.315484 -47.933864) (xy 373.343594 -47.940412)
			(xy 373.397587 -47.960802) (xy 373.447893 -47.989093) (xy 373.493363 -48.024639) (xy 373.532959 -48.066629)
			(xy 373.565779 -48.114104) (xy 373.591073 -48.165981) (xy 373.608264 -48.221076) (xy 373.616959 -48.278133)
			(xy 373.61749 -48.30699) (xy 373.617035 -48.334243) (xy 373.609279 -48.388196) (xy 373.593924 -48.440495)
			(xy 373.571281 -48.490076) (xy 373.541812 -48.53593) (xy 373.506118 -48.577123) (xy 373.464924 -48.612817)
			(xy 373.419069 -48.642285) (xy 373.369487 -48.664926) (xy 373.317188 -48.680281) (xy 373.263235 -48.688036)
			(xy 373.235982 -48.688498) (xy 373.210009 -48.688039) (xy 373.158542 -48.681004) (xy 373.108504 -48.667055)
			(xy 373.06082 -48.646447) (xy 373.03837 -48.63338) (xy 373.02313 -48.624236) (xy 372.988586 -48.628554)
			(xy 372.982744 -48.634396) (xy 372.998817 -48.654882) (xy 373.025834 -48.699394) (xy 373.046547 -48.747167)
			(xy 373.060572 -48.797312) (xy 373.067648 -48.848899) (xy 373.068088 -48.874934) (xy 373.067654 -48.902187)
			(xy 373.062658 -48.93691) (xy 375.233182 -48.93691) (xy 375.237253 -48.881288) (xy 375.249379 -48.826851)
			(xy 375.269302 -48.77476) (xy 375.296598 -48.726125) (xy 375.330684 -48.681982) (xy 375.370833 -48.643273)
			(xy 375.416191 -48.610822) (xy 375.465791 -48.585321) (xy 375.518575 -48.567314) (xy 375.573418 -48.557184)
			(xy 375.629152 -48.555147) (xy 375.684589 -48.561247) (xy 375.738546 -48.575353) (xy 375.789875 -48.597165)
			(xy 375.837481 -48.626219) (xy 375.880349 -48.661894) (xy 375.917566 -48.703431) (xy 375.948339 -48.749944)
			(xy 375.972011 -48.800441) (xy 375.988079 -48.853848) (xy 375.996199 -48.909024) (xy 375.996708 -48.93691)
			(xy 375.996199 -48.964796) (xy 375.988079 -49.019972) (xy 375.972011 -49.073379) (xy 375.948339 -49.123876)
			(xy 375.917566 -49.170389) (xy 375.880349 -49.211926) (xy 375.837481 -49.247601) (xy 375.789875 -49.276655)
			(xy 375.738546 -49.298467) (xy 375.684589 -49.312573) (xy 375.629152 -49.318673) (xy 375.573418 -49.316636)
			(xy 375.518575 -49.306506) (xy 375.465791 -49.288499) (xy 375.416191 -49.262998) (xy 375.370833 -49.230547)
			(xy 375.330684 -49.191838) (xy 375.296598 -49.147695) (xy 375.269302 -49.09906) (xy 375.249379 -49.046969)
			(xy 375.237253 -48.992532) (xy 375.233182 -48.93691) (xy 373.062658 -48.93691) (xy 373.059892 -48.956138)
			(xy 373.044532 -49.008435) (xy 373.021885 -49.058013) (xy 372.992413 -49.103864) (xy 372.956717 -49.145055)
			(xy 372.915521 -49.180746) (xy 372.869666 -49.210211) (xy 372.820084 -49.232851) (xy 372.767785 -49.248204)
			(xy 372.713833 -49.255958) (xy 372.68658 -49.256442) (xy 372.659136 -49.255955) (xy 372.604814 -49.248086)
			(xy 372.552185 -49.232501) (xy 372.502339 -49.209521) (xy 372.479062 -49.194974) (xy 372.468982 -49.18914)
			(xy 372.445886 -49.18635) (xy 372.423909 -49.19398) (xy 372.415308 -49.201832) (xy 372.310406 -49.306734)
			(xy 372.286828 -49.329619) (xy 372.235455 -49.370585) (xy 372.179817 -49.405542) (xy 372.120616 -49.43405)
			(xy 372.058595 -49.45575) (xy 371.994534 -49.470369) (xy 371.92924 -49.477725) (xy 371.896386 -49.478184)
			(xy 371.896132 -49.478184) (xy 371.860732 -49.477681) (xy 371.790449 -49.46915) (xy 371.721707 -49.452209)
			(xy 371.655508 -49.427105) (xy 371.592818 -49.394204) (xy 371.534551 -49.353986) (xy 371.481557 -49.307037)
			(xy 371.434609 -49.254043) (xy 371.394392 -49.195776) (xy 371.361492 -49.133085) (xy 371.336389 -49.066886)
			(xy 371.319449 -48.998143) (xy 371.310919 -48.92786) (xy 371.310408 -48.89246) (xy 370.205831 -48.89246)
			(xy 370.183555 -48.93998) (xy 370.152782 -48.986493) (xy 370.115565 -49.02803) (xy 370.072697 -49.063705)
			(xy 370.025091 -49.092759) (xy 369.973762 -49.114571) (xy 369.919805 -49.128677) (xy 369.864368 -49.134777)
			(xy 369.808634 -49.13274) (xy 369.753791 -49.12261) (xy 369.701007 -49.104603) (xy 369.651407 -49.079102)
			(xy 369.606049 -49.046651) (xy 369.5659 -49.007942) (xy 369.531814 -48.963799) (xy 369.504518 -48.915164)
			(xy 369.484595 -48.863073) (xy 369.472469 -48.808636) (xy 369.468398 -48.753014) (xy 361.01782 -48.753014)
			(xy 361.01782 -49.95291) (xy 375.233182 -49.95291) (xy 375.237253 -49.897288) (xy 375.249379 -49.842851)
			(xy 375.269302 -49.79076) (xy 375.296598 -49.742125) (xy 375.330684 -49.697982) (xy 375.370833 -49.659273)
			(xy 375.416191 -49.626822) (xy 375.465791 -49.601321) (xy 375.518575 -49.583314) (xy 375.573418 -49.573184)
			(xy 375.629152 -49.571147) (xy 375.684589 -49.577247) (xy 375.738546 -49.591353) (xy 375.76349 -49.601953)
			(xy 380.412959 -49.601953) (xy 380.412959 -49.547447) (xy 380.420716 -49.493496) (xy 380.436073 -49.441199)
			(xy 380.458715 -49.391618) (xy 380.488184 -49.345766) (xy 380.523877 -49.304573) (xy 380.56507 -49.26888)
			(xy 380.610924 -49.239412) (xy 380.660504 -49.21677) (xy 380.712802 -49.201415) (xy 380.766753 -49.193659)
			(xy 380.794006 -49.193196) (xy 380.821376 -49.19366) (xy 380.875555 -49.201478) (xy 380.928059 -49.216968)
			(xy 380.977805 -49.23981) (xy 381.023772 -49.269535) (xy 381.044704 -49.287176) (xy 381.044958 -49.28743)
			(xy 381.05205 -49.293008) (xy 381.068963 -49.299259) (xy 381.077978 -49.299622) (xy 381.145034 -49.299622)
			(xy 381.154052 -49.299277) (xy 381.170969 -49.293021) (xy 381.178054 -49.28743) (xy 381.178054 -49.287176)
			(xy 381.178308 -49.287176) (xy 381.199241 -49.269535) (xy 381.245209 -49.239811) (xy 381.294955 -49.216965)
			(xy 381.347457 -49.201469) (xy 381.401635 -49.19364) (xy 381.456377 -49.19364) (xy 381.510555 -49.201469)
			(xy 381.563057 -49.216965) (xy 381.612803 -49.239811) (xy 381.658771 -49.269535) (xy 381.679704 -49.287176)
			(xy 381.679958 -49.28743) (xy 381.68705 -49.293008) (xy 381.703963 -49.299259) (xy 381.712978 -49.299622)
			(xy 381.780034 -49.299622) (xy 381.789052 -49.299277) (xy 381.805969 -49.293021) (xy 381.813054 -49.28743)
			(xy 381.813054 -49.287176) (xy 381.813308 -49.287176) (xy 381.834241 -49.269535) (xy 381.880209 -49.239811)
			(xy 381.929955 -49.216965) (xy 381.982457 -49.201469) (xy 382.036635 -49.19364) (xy 382.091377 -49.19364)
			(xy 382.145555 -49.201469) (xy 382.198057 -49.216965) (xy 382.247803 -49.239811) (xy 382.293771 -49.269535)
			(xy 382.314704 -49.287176) (xy 382.314958 -49.28743) (xy 382.32205 -49.293008) (xy 382.338963 -49.299259)
			(xy 382.347978 -49.299622) (xy 382.415034 -49.299622) (xy 382.424052 -49.299277) (xy 382.440969 -49.293021)
			(xy 382.448054 -49.28743) (xy 382.448054 -49.287176) (xy 382.448308 -49.287176) (xy 382.469223 -49.269516)
			(xy 382.515201 -49.239808) (xy 382.564953 -49.216977) (xy 382.617457 -49.20149) (xy 382.671636 -49.193667)
			(xy 382.699006 -49.193196) (xy 382.726257 -49.193674) (xy 382.780205 -49.201431) (xy 382.832499 -49.216787)
			(xy 382.882076 -49.239429) (xy 382.927927 -49.268896) (xy 382.969117 -49.304588) (xy 383.004808 -49.345778)
			(xy 383.034274 -49.391629) (xy 383.056915 -49.441206) (xy 383.07227 -49.493501) (xy 383.080026 -49.547449)
			(xy 383.080026 -49.601951) (xy 383.07227 -49.655899) (xy 383.056915 -49.708194) (xy 383.034274 -49.757771)
			(xy 383.004808 -49.803622) (xy 382.969117 -49.844812) (xy 382.927927 -49.880504) (xy 382.882076 -49.909971)
			(xy 382.832499 -49.932613) (xy 382.780205 -49.947969) (xy 382.726257 -49.955726) (xy 382.699006 -49.956212)
			(xy 382.671636 -49.955739) (xy 382.617457 -49.947923) (xy 382.564954 -49.932435) (xy 382.515207 -49.909595)
			(xy 382.46924 -49.879872) (xy 382.448308 -49.862232) (xy 382.448054 -49.861978) (xy 382.440958 -49.856405)
			(xy 382.424048 -49.850151) (xy 382.415034 -49.849786) (xy 382.347978 -49.849786) (xy 382.33896 -49.850136)
			(xy 382.322044 -49.856389) (xy 382.314958 -49.861978) (xy 382.314704 -49.862232) (xy 382.293771 -49.879873)
			(xy 382.247803 -49.909597) (xy 382.198057 -49.932443) (xy 382.145555 -49.947939) (xy 382.091377 -49.955768)
			(xy 382.036635 -49.955768) (xy 381.982457 -49.947939) (xy 381.929955 -49.932443) (xy 381.880209 -49.909597)
			(xy 381.834241 -49.879873) (xy 381.813308 -49.862232) (xy 381.813054 -49.861978) (xy 381.805958 -49.856405)
			(xy 381.789048 -49.850151) (xy 381.780034 -49.849786) (xy 381.712978 -49.849786) (xy 381.70396 -49.850136)
			(xy 381.687044 -49.856389) (xy 381.679958 -49.861978) (xy 381.679958 -49.862232) (xy 381.679704 -49.862232)
			(xy 381.658771 -49.879873) (xy 381.612803 -49.909597) (xy 381.563057 -49.932443) (xy 381.510555 -49.947939)
			(xy 381.456377 -49.955768) (xy 381.401635 -49.955768) (xy 381.347457 -49.947939) (xy 381.294955 -49.932443)
			(xy 381.245209 -49.909597) (xy 381.199241 -49.879873) (xy 381.178308 -49.862232) (xy 381.178054 -49.861978)
			(xy 381.170958 -49.856405) (xy 381.154048 -49.850151) (xy 381.145034 -49.849786) (xy 381.077978 -49.849786)
			(xy 381.06896 -49.850136) (xy 381.052044 -49.856389) (xy 381.044958 -49.861978) (xy 381.044958 -49.862232)
			(xy 381.044704 -49.862232) (xy 381.023785 -49.879888) (xy 380.977808 -49.909596) (xy 380.928057 -49.932428)
			(xy 380.875554 -49.947915) (xy 380.821376 -49.95574) (xy 380.794006 -49.956212) (xy 380.766753 -49.955741)
			(xy 380.712802 -49.947985) (xy 380.660504 -49.93263) (xy 380.610924 -49.909988) (xy 380.56507 -49.88052)
			(xy 380.523877 -49.844827) (xy 380.488184 -49.803634) (xy 380.458715 -49.757782) (xy 380.436073 -49.708201)
			(xy 380.420716 -49.655904) (xy 380.412959 -49.601953) (xy 375.76349 -49.601953) (xy 375.789875 -49.613165)
			(xy 375.837481 -49.642219) (xy 375.880349 -49.677894) (xy 375.917566 -49.719431) (xy 375.948339 -49.765944)
			(xy 375.972011 -49.816441) (xy 375.988079 -49.869848) (xy 375.996199 -49.925024) (xy 375.996708 -49.95291)
			(xy 375.996199 -49.980796) (xy 375.988079 -50.035972) (xy 375.972011 -50.089379) (xy 375.948339 -50.139876)
			(xy 375.917566 -50.186389) (xy 375.880349 -50.227926) (xy 375.837481 -50.263601) (xy 375.789875 -50.292655)
			(xy 375.738546 -50.314467) (xy 375.684589 -50.328573) (xy 375.629152 -50.334673) (xy 375.573418 -50.332636)
			(xy 375.518575 -50.322506) (xy 375.465791 -50.304499) (xy 375.416191 -50.278998) (xy 375.370833 -50.246547)
			(xy 375.330684 -50.207838) (xy 375.296598 -50.163695) (xy 375.269302 -50.11506) (xy 375.249379 -50.062969)
			(xy 375.237253 -50.008532) (xy 375.233182 -49.95291) (xy 361.01782 -49.95291) (xy 361.01782 -51.019456)
			(xy 373.049544 -51.019456) (xy 373.053615 -50.963834) (xy 373.065741 -50.909397) (xy 373.085664 -50.857306)
			(xy 373.11296 -50.808671) (xy 373.147046 -50.764528) (xy 373.187195 -50.725819) (xy 373.232553 -50.693368)
			(xy 373.282153 -50.667867) (xy 373.334937 -50.64986) (xy 373.38978 -50.63973) (xy 373.445514 -50.637693)
			(xy 373.500951 -50.643793) (xy 373.554908 -50.657899) (xy 373.606237 -50.679711) (xy 373.653843 -50.708765)
			(xy 373.696711 -50.74444) (xy 373.733928 -50.785977) (xy 373.764701 -50.83249) (xy 373.788373 -50.882987)
			(xy 373.804441 -50.936394) (xy 373.812561 -50.99157) (xy 373.81307 -51.019456) (xy 373.812561 -51.047342)
			(xy 373.804441 -51.102518) (xy 373.788373 -51.155925) (xy 373.764701 -51.206422) (xy 373.739845 -51.243992)
			(xy 381.43307 -51.243992) (xy 381.433514 -51.216621) (xy 381.441335 -51.16244) (xy 381.456828 -51.109936)
			(xy 381.479675 -51.060189) (xy 381.509406 -51.014224) (xy 381.52705 -50.993294) (xy 381.527304 -50.99304)
			(xy 381.53288 -50.985946) (xy 381.539133 -50.969035) (xy 381.539496 -50.96002) (xy 381.539496 -50.892964)
			(xy 381.539157 -50.883945) (xy 381.532897 -50.867028) (xy 381.527304 -50.859944) (xy 381.52705 -50.859944)
			(xy 381.52705 -50.85969) (xy 381.509401 -50.838766) (xy 381.479689 -50.792792) (xy 381.456854 -50.743042)
			(xy 381.441365 -50.69054) (xy 381.433541 -50.636362) (xy 381.43307 -50.608992) (xy 381.43357 -50.581742)
			(xy 381.441327 -50.527795) (xy 381.456682 -50.475502) (xy 381.479323 -50.425927) (xy 381.508788 -50.380077)
			(xy 381.544478 -50.338888) (xy 381.585666 -50.303196) (xy 381.631514 -50.27373) (xy 381.681089 -50.251087)
			(xy 381.733382 -50.23573) (xy 381.787328 -50.227971) (xy 381.814578 -50.227484) (xy 381.843496 -50.227986)
			(xy 381.900669 -50.236714) (xy 381.95587 -50.253973) (xy 382.007832 -50.279368) (xy 382.055365 -50.312316)
			(xy 382.09738 -50.352062) (xy 382.115568 -50.37455) (xy 382.12319 -50.383341) (xy 382.14408 -50.393532)
			(xy 382.1557 -50.394108) (xy 382.235456 -50.394108) (xy 382.24709 -50.393584) (xy 382.267999 -50.383384)
			(xy 382.275588 -50.37455) (xy 382.293773 -50.352062) (xy 382.335796 -50.312329) (xy 382.383332 -50.279392)
			(xy 382.435294 -50.254005) (xy 382.490492 -50.236749) (xy 382.547662 -50.22802) (xy 382.576578 -50.227484)
			(xy 382.60383 -50.227976) (xy 382.657779 -50.23573) (xy 382.710076 -50.251082) (xy 382.759656 -50.273722)
			(xy 382.805509 -50.303187) (xy 382.846701 -50.338877) (xy 382.882395 -50.380067) (xy 382.911864 -50.425918)
			(xy 382.934507 -50.475496) (xy 382.949864 -50.527791) (xy 382.957622 -50.58174) (xy 382.958086 -50.608992)
			(xy 382.957618 -50.635306) (xy 382.950384 -50.687435) (xy 382.936065 -50.738078) (xy 382.914933 -50.786277)
			(xy 382.887387 -50.83112) (xy 382.853948 -50.87176) (xy 382.834896 -50.889916) (xy 382.827485 -50.897429)
			(xy 382.818966 -50.916716) (xy 382.818386 -50.927254) (xy 382.818386 -51.00193) (xy 382.818943 -51.012476)
			(xy 382.827459 -51.031772) (xy 382.834896 -51.039268) (xy 382.853977 -51.057398) (xy 382.887432 -51.098033)
			(xy 382.914988 -51.142879) (xy 382.936122 -51.191085) (xy 382.950433 -51.241737) (xy 382.957651 -51.293874)
			(xy 382.958086 -51.320192) (xy 382.957637 -51.347446) (xy 382.949881 -51.401398) (xy 382.934525 -51.453698)
			(xy 382.911881 -51.503279) (xy 382.882412 -51.549133) (xy 382.846717 -51.590327) (xy 382.805522 -51.626021)
			(xy 382.759667 -51.655488) (xy 382.710085 -51.678129) (xy 382.657785 -51.693484) (xy 382.603832 -51.701238)
			(xy 382.576578 -51.7017) (xy 382.548912 -51.701205) (xy 382.494162 -51.693203) (xy 382.44114 -51.677383)
			(xy 382.390956 -51.654077) (xy 382.344661 -51.623773) (xy 382.303223 -51.587106) (xy 382.267511 -51.544842)
			(xy 382.252474 -51.521614) (xy 382.245859 -51.511919) (xy 382.225982 -51.499486) (xy 382.214374 -51.497738)
			(xy 382.134364 -51.489864) (xy 382.122725 -51.489214) (xy 382.100886 -51.497306) (xy 382.092454 -51.505358)
			(xy 382.0922 -51.505612) (xy 382.074104 -51.524178) (xy 382.033775 -51.556757) (xy 381.989404 -51.583572)
			(xy 381.941808 -51.604127) (xy 381.891867 -51.618044) (xy 381.8405 -51.625066) (xy 381.814578 -51.6255)
			(xy 381.787326 -51.625043) (xy 381.733377 -51.617283) (xy 381.681081 -51.601925) (xy 381.631503 -51.57928)
			(xy 381.585652 -51.549811) (xy 381.544462 -51.514117) (xy 381.508771 -51.472924) (xy 381.479305 -51.427071)
			(xy 381.456665 -51.377491) (xy 381.441311 -51.325194) (xy 381.433555 -51.271244) (xy 381.43307 -51.243992)
			(xy 373.739845 -51.243992) (xy 373.733928 -51.252935) (xy 373.696711 -51.294472) (xy 373.653843 -51.330147)
			(xy 373.606237 -51.359201) (xy 373.554908 -51.381013) (xy 373.500951 -51.395119) (xy 373.445514 -51.401219)
			(xy 373.38978 -51.399182) (xy 373.334937 -51.389052) (xy 373.282153 -51.371045) (xy 373.232553 -51.345544)
			(xy 373.187195 -51.313093) (xy 373.147046 -51.274384) (xy 373.11296 -51.230241) (xy 373.085664 -51.181606)
			(xy 373.065741 -51.129515) (xy 373.053615 -51.075078) (xy 373.049544 -51.019456) (xy 361.01782 -51.019456)
			(xy 361.01782 -52.035456) (xy 375.24131 -52.035456) (xy 375.245381 -51.979834) (xy 375.257507 -51.925397)
			(xy 375.27743 -51.873306) (xy 375.304726 -51.824671) (xy 375.338812 -51.780528) (xy 375.378961 -51.741819)
			(xy 375.424319 -51.709368) (xy 375.473919 -51.683867) (xy 375.526703 -51.66586) (xy 375.581546 -51.65573)
			(xy 375.63728 -51.653693) (xy 375.692717 -51.659793) (xy 375.746674 -51.673899) (xy 375.798003 -51.695711)
			(xy 375.845609 -51.724765) (xy 375.888477 -51.76044) (xy 375.925694 -51.801977) (xy 375.956467 -51.84849)
			(xy 375.980139 -51.898987) (xy 375.996207 -51.952394) (xy 376.004327 -52.00757) (xy 376.004836 -52.035456)
			(xy 376.004327 -52.063342) (xy 375.996207 -52.118518) (xy 375.980139 -52.171925) (xy 375.956467 -52.222422)
			(xy 375.925694 -52.268935) (xy 375.888477 -52.310472) (xy 375.845609 -52.346147) (xy 375.798003 -52.375201)
			(xy 375.746674 -52.397013) (xy 375.692717 -52.411119) (xy 375.63728 -52.417219) (xy 375.581546 -52.415182)
			(xy 375.526703 -52.405052) (xy 375.473919 -52.387045) (xy 375.424319 -52.361544) (xy 375.378961 -52.329093)
			(xy 375.338812 -52.290384) (xy 375.304726 -52.246241) (xy 375.27743 -52.197606) (xy 375.257507 -52.145515)
			(xy 375.245381 -52.091078) (xy 375.24131 -52.035456) (xy 361.01782 -52.035456) (xy 361.01782 -54.731412)
			(xy 361.820714 -54.731412) (xy 361.821184 -54.704042) (xy 361.829 -54.649863) (xy 361.844488 -54.59736)
			(xy 361.867329 -54.547613) (xy 361.897053 -54.501646) (xy 361.914694 -54.480714) (xy 361.914948 -54.48046)
			(xy 361.920521 -54.473365) (xy 361.926775 -54.456454) (xy 361.92714 -54.44744) (xy 361.92714 -54.380384)
			(xy 361.926803 -54.371365) (xy 361.920543 -54.354447) (xy 361.914948 -54.347364) (xy 361.914694 -54.347364)
			(xy 361.914694 -54.34711) (xy 361.897066 -54.326167) (xy 361.867344 -54.2802) (xy 361.8445 -54.230455)
			(xy 361.829004 -54.177955) (xy 361.821175 -54.123779) (xy 361.821174 -54.069039) (xy 361.829 -54.014862)
			(xy 361.844493 -53.962361) (xy 361.867335 -53.912616) (xy 361.897056 -53.866647) (xy 361.914694 -53.845714)
			(xy 361.914948 -53.84546) (xy 361.920521 -53.838365) (xy 361.926775 -53.821454) (xy 361.92714 -53.81244)
			(xy 361.92714 -53.745384) (xy 361.926803 -53.736365) (xy 361.920543 -53.719447) (xy 361.914948 -53.712364)
			(xy 361.914694 -53.712364) (xy 361.914694 -53.71211) (xy 361.897066 -53.691167) (xy 361.867344 -53.6452)
			(xy 361.8445 -53.595455) (xy 361.829004 -53.542955) (xy 361.821175 -53.488779) (xy 361.821174 -53.434039)
			(xy 361.829 -53.379862) (xy 361.844493 -53.327361) (xy 361.867335 -53.277616) (xy 361.897056 -53.231647)
			(xy 361.914694 -53.210714) (xy 361.914948 -53.21046) (xy 361.920521 -53.203365) (xy 361.926775 -53.186454)
			(xy 361.92714 -53.17744) (xy 361.92714 -53.110384) (xy 361.926803 -53.101365) (xy 361.920543 -53.084447)
			(xy 361.914948 -53.077364) (xy 361.914694 -53.077364) (xy 361.914694 -53.07711) (xy 361.897045 -53.056186)
			(xy 361.867335 -53.010211) (xy 361.844501 -52.960461) (xy 361.829012 -52.907959) (xy 361.821187 -52.853782)
			(xy 361.820714 -52.826412) (xy 361.8212 -52.799161) (xy 361.828956 -52.745213) (xy 361.844311 -52.692918)
			(xy 361.866953 -52.643341) (xy 361.896419 -52.597491) (xy 361.93211 -52.5563) (xy 361.973301 -52.520609)
			(xy 362.019151 -52.491143) (xy 362.068728 -52.468501) (xy 362.121023 -52.453146) (xy 362.174971 -52.44539)
			(xy 362.229473 -52.44539) (xy 362.283421 -52.453146) (xy 362.335716 -52.468501) (xy 362.385293 -52.491143)
			(xy 362.431143 -52.520609) (xy 362.472334 -52.5563) (xy 362.508025 -52.597491) (xy 362.537491 -52.643341)
			(xy 362.560133 -52.692918) (xy 362.575488 -52.745213) (xy 362.583244 -52.799161) (xy 362.58373 -52.826412)
			(xy 362.583288 -52.853783) (xy 362.575467 -52.907964) (xy 362.559973 -52.960468) (xy 362.537126 -53.010215)
			(xy 362.507395 -53.05618) (xy 362.48975 -53.07711) (xy 362.489496 -53.077364) (xy 362.483918 -53.084456)
			(xy 362.477666 -53.101369) (xy 362.477304 -53.110384) (xy 362.477304 -53.17744) (xy 362.477641 -53.186459)
			(xy 362.483903 -53.203376) (xy 362.489496 -53.21046) (xy 362.48975 -53.21046) (xy 362.48975 -53.210714)
			(xy 362.507403 -53.231637) (xy 362.537129 -53.277606) (xy 362.559976 -53.327353) (xy 362.575472 -53.379857)
			(xy 362.5833 -53.434038) (xy 362.583299 -53.48878) (xy 362.575468 -53.54296) (xy 362.559969 -53.595463)
			(xy 362.537121 -53.64521) (xy 362.507392 -53.691178) (xy 362.48975 -53.71211) (xy 362.489496 -53.712364)
			(xy 362.483918 -53.719456) (xy 362.477666 -53.736369) (xy 362.477304 -53.745384) (xy 362.477304 -53.81244)
			(xy 362.477641 -53.821459) (xy 362.483903 -53.838376) (xy 362.489496 -53.84546) (xy 362.48975 -53.84546)
			(xy 362.48975 -53.845714) (xy 362.507403 -53.866637) (xy 362.537129 -53.912606) (xy 362.559976 -53.962353)
			(xy 362.575472 -54.014857) (xy 362.5833 -54.069038) (xy 362.583299 -54.12378) (xy 362.575468 -54.17796)
			(xy 362.559969 -54.230463) (xy 362.537121 -54.28021) (xy 362.507392 -54.326178) (xy 362.48975 -54.34711)
			(xy 362.489496 -54.347364) (xy 362.483918 -54.354456) (xy 362.477666 -54.371369) (xy 362.477304 -54.380384)
			(xy 362.477304 -54.44744) (xy 362.477641 -54.456459) (xy 362.483903 -54.473376) (xy 362.489496 -54.48046)
			(xy 362.48975 -54.48046) (xy 362.48975 -54.480714) (xy 362.507354 -54.501674) (xy 362.537073 -54.547638)
			(xy 362.559917 -54.597379) (xy 362.575416 -54.649873) (xy 362.583252 -54.704045) (xy 362.58373 -54.731412)
			(xy 362.583244 -54.758663) (xy 362.57858 -54.791102) (xy 364.476538 -54.791102) (xy 364.476996 -54.763731)
			(xy 364.484814 -54.709552) (xy 364.500305 -54.657048) (xy 364.523149 -54.607301) (xy 364.552875 -54.561335)
			(xy 364.570518 -54.540404) (xy 364.570772 -54.54015) (xy 364.576352 -54.533059) (xy 364.582601 -54.516145)
			(xy 364.582964 -54.50713) (xy 364.582964 -54.440074) (xy 364.582627 -54.431055) (xy 364.576367 -54.414138)
			(xy 364.570772 -54.407054) (xy 364.570518 -54.407054) (xy 364.570518 -54.4068) (xy 364.55288 -54.385865)
			(xy 364.523155 -54.339898) (xy 364.500311 -54.290152) (xy 364.484814 -54.23765) (xy 364.476986 -54.183472)
			(xy 364.476986 -54.128731) (xy 364.484814 -54.074553) (xy 364.500309 -54.022051) (xy 364.523154 -53.972305)
			(xy 364.552878 -53.926337) (xy 364.570518 -53.905404) (xy 364.570772 -53.90515) (xy 364.576352 -53.898059)
			(xy 364.582601 -53.881145) (xy 364.582964 -53.87213) (xy 364.582964 -53.805074) (xy 364.582627 -53.796055)
			(xy 364.576367 -53.779138) (xy 364.570772 -53.772054) (xy 364.570518 -53.772054) (xy 364.570518 -53.7718)
			(xy 364.55288 -53.750865) (xy 364.523155 -53.704898) (xy 364.500311 -53.655152) (xy 364.484814 -53.60265)
			(xy 364.476986 -53.548472) (xy 364.476986 -53.493731) (xy 364.484814 -53.439553) (xy 364.500309 -53.387051)
			(xy 364.523154 -53.337305) (xy 364.552878 -53.291337) (xy 364.570518 -53.270404) (xy 364.570772 -53.27015)
			(xy 364.576352 -53.263059) (xy 364.582601 -53.246145) (xy 364.582964 -53.23713) (xy 364.582964 -53.170074)
			(xy 364.582627 -53.161055) (xy 364.576367 -53.144138) (xy 364.570772 -53.137054) (xy 364.570518 -53.137054)
			(xy 364.570518 -53.1368) (xy 364.552868 -53.115876) (xy 364.523157 -53.069902) (xy 364.500323 -53.020152)
			(xy 364.484835 -52.967649) (xy 364.47701 -52.913472) (xy 364.476538 -52.886102) (xy 364.477024 -52.858851)
			(xy 364.48478 -52.804903) (xy 364.500135 -52.752608) (xy 364.522777 -52.703031) (xy 364.552243 -52.657181)
			(xy 364.587934 -52.61599) (xy 364.629125 -52.580299) (xy 364.674975 -52.550833) (xy 364.724552 -52.528191)
			(xy 364.776847 -52.512836) (xy 364.830795 -52.50508) (xy 364.885297 -52.50508) (xy 364.939245 -52.512836)
			(xy 364.99154 -52.528191) (xy 365.030649 -52.546052) (xy 369.979673 -52.546052) (xy 369.979673 -52.491548)
			(xy 369.98743 -52.4376) (xy 370.002785 -52.385304) (xy 370.025427 -52.335726) (xy 370.054894 -52.289875)
			(xy 370.090586 -52.248685) (xy 370.131777 -52.212993) (xy 370.177628 -52.183526) (xy 370.227206 -52.160885)
			(xy 370.279502 -52.14553) (xy 370.33345 -52.137773) (xy 370.360702 -52.13731) (xy 370.388072 -52.137772)
			(xy 370.442252 -52.145591) (xy 370.494755 -52.161081) (xy 370.544502 -52.183923) (xy 370.590468 -52.213648)
			(xy 370.6114 -52.23129) (xy 370.611654 -52.231544) (xy 370.618746 -52.237123) (xy 370.635659 -52.243373)
			(xy 370.644674 -52.243736) (xy 370.71173 -52.243736) (xy 370.720747 -52.243386) (xy 370.737664 -52.237133)
			(xy 370.74475 -52.231544) (xy 370.74475 -52.23129) (xy 370.745004 -52.23129) (xy 370.765937 -52.213649)
			(xy 370.811905 -52.183925) (xy 370.861651 -52.161079) (xy 370.914153 -52.145583) (xy 370.968331 -52.137754)
			(xy 371.023073 -52.137754) (xy 371.077251 -52.145583) (xy 371.129753 -52.161079) (xy 371.179499 -52.183925)
			(xy 371.225467 -52.213649) (xy 371.2464 -52.23129) (xy 371.246654 -52.231544) (xy 371.253746 -52.237123)
			(xy 371.270659 -52.243373) (xy 371.279674 -52.243736) (xy 371.34673 -52.243736) (xy 371.355747 -52.243386)
			(xy 371.372664 -52.237133) (xy 371.37975 -52.231544) (xy 371.37975 -52.23129) (xy 371.380004 -52.23129)
			(xy 371.400922 -52.213634) (xy 371.446899 -52.183925) (xy 371.49665 -52.161093) (xy 371.549154 -52.145605)
			(xy 371.603332 -52.137782) (xy 371.630702 -52.13731) (xy 371.657954 -52.13776) (xy 371.711905 -52.145517)
			(xy 371.764201 -52.160873) (xy 371.813781 -52.183515) (xy 371.859633 -52.212983) (xy 371.900825 -52.248676)
			(xy 371.936518 -52.289868) (xy 371.965986 -52.335721) (xy 371.988628 -52.3853) (xy 372.003983 -52.437597)
			(xy 372.01174 -52.491548) (xy 372.01174 -52.546052) (xy 372.005795 -52.587398) (xy 373.055386 -52.587398)
			(xy 373.059457 -52.531776) (xy 373.071583 -52.477339) (xy 373.091506 -52.425248) (xy 373.118802 -52.376613)
			(xy 373.152888 -52.33247) (xy 373.193037 -52.293761) (xy 373.238395 -52.26131) (xy 373.287995 -52.235809)
			(xy 373.340779 -52.217802) (xy 373.395622 -52.207672) (xy 373.451356 -52.205635) (xy 373.506793 -52.211735)
			(xy 373.56075 -52.225841) (xy 373.612079 -52.247653) (xy 373.659685 -52.276707) (xy 373.702553 -52.312382)
			(xy 373.73977 -52.353919) (xy 373.770543 -52.400432) (xy 373.794215 -52.450929) (xy 373.810283 -52.504336)
			(xy 373.817879 -52.555952) (xy 380.883879 -52.555952) (xy 380.883879 -52.501448) (xy 380.891636 -52.447498)
			(xy 380.906993 -52.395202) (xy 380.929635 -52.345624) (xy 380.959103 -52.299772) (xy 380.994797 -52.258582)
			(xy 381.03599 -52.22289) (xy 381.081843 -52.193425) (xy 381.131423 -52.170785) (xy 381.18372 -52.155432)
			(xy 381.23767 -52.147678) (xy 381.264922 -52.147216) (xy 381.292293 -52.147665) (xy 381.346473 -52.155487)
			(xy 381.398976 -52.170979) (xy 381.448723 -52.193825) (xy 381.494689 -52.223553) (xy 381.51562 -52.241196)
			(xy 381.515874 -52.24145) (xy 381.522959 -52.247038) (xy 381.539877 -52.253283) (xy 381.548894 -52.253642)
			(xy 381.61595 -52.253642) (xy 381.624966 -52.253274) (xy 381.641884 -52.247035) (xy 381.64897 -52.24145)
			(xy 381.64897 -52.241196) (xy 381.649224 -52.241196) (xy 381.670173 -52.223578) (xy 381.716142 -52.193864)
			(xy 381.765885 -52.171023) (xy 381.818381 -52.155527) (xy 381.872554 -52.147693) (xy 381.899922 -52.147216)
			(xy 381.927174 -52.147655) (xy 381.981123 -52.155415) (xy 382.033418 -52.170773) (xy 382.082996 -52.193417)
			(xy 382.128846 -52.222885) (xy 382.170036 -52.258579) (xy 382.205728 -52.299771) (xy 382.235194 -52.345624)
			(xy 382.257835 -52.395203) (xy 382.27319 -52.447499) (xy 382.280946 -52.501448) (xy 382.280946 -52.555952)
			(xy 382.27319 -52.609901) (xy 382.257835 -52.662197) (xy 382.235194 -52.711776) (xy 382.205728 -52.757629)
			(xy 382.170036 -52.798821) (xy 382.128846 -52.834515) (xy 382.082996 -52.863983) (xy 382.033418 -52.886627)
			(xy 381.981123 -52.901985) (xy 381.927174 -52.909745) (xy 381.899922 -52.910232) (xy 381.872551 -52.90977)
			(xy 381.818372 -52.901953) (xy 381.765868 -52.886464) (xy 381.716121 -52.863621) (xy 381.670155 -52.833895)
			(xy 381.649224 -52.816252) (xy 381.64897 -52.815998) (xy 381.641868 -52.810434) (xy 381.624963 -52.804174)
			(xy 381.61595 -52.803806) (xy 381.548894 -52.803806) (xy 381.539877 -52.804159) (xy 381.52296 -52.810409)
			(xy 381.515874 -52.815998) (xy 381.515874 -52.816252) (xy 381.51562 -52.816252) (xy 381.494685 -52.833888)
			(xy 381.448714 -52.863602) (xy 381.398967 -52.886439) (xy 381.346467 -52.901931) (xy 381.292291 -52.909759)
			(xy 381.264922 -52.910232) (xy 381.23767 -52.909722) (xy 381.18372 -52.901968) (xy 381.131423 -52.886615)
			(xy 381.081843 -52.863975) (xy 381.03599 -52.83451) (xy 380.994797 -52.798818) (xy 380.959103 -52.757628)
			(xy 380.929635 -52.711776) (xy 380.906993 -52.662198) (xy 380.891636 -52.609902) (xy 380.883879 -52.555952)
			(xy 373.817879 -52.555952) (xy 373.818403 -52.559512) (xy 373.818912 -52.587398) (xy 373.818403 -52.615284)
			(xy 373.810283 -52.67046) (xy 373.794215 -52.723867) (xy 373.770543 -52.774364) (xy 373.73977 -52.820877)
			(xy 373.702553 -52.862414) (xy 373.659685 -52.898089) (xy 373.612079 -52.927143) (xy 373.56075 -52.948955)
			(xy 373.506793 -52.963061) (xy 373.451356 -52.969161) (xy 373.395622 -52.967124) (xy 373.340779 -52.956994)
			(xy 373.287995 -52.938987) (xy 373.238395 -52.913486) (xy 373.193037 -52.881035) (xy 373.152888 -52.842326)
			(xy 373.118802 -52.798183) (xy 373.091506 -52.749548) (xy 373.071583 -52.697457) (xy 373.059457 -52.64302)
			(xy 373.055386 -52.587398) (xy 372.005795 -52.587398) (xy 372.003983 -52.600003) (xy 371.988628 -52.6523)
			(xy 371.965986 -52.701879) (xy 371.936518 -52.747732) (xy 371.900825 -52.788924) (xy 371.859633 -52.824617)
			(xy 371.813781 -52.854085) (xy 371.764201 -52.876727) (xy 371.711905 -52.892083) (xy 371.657954 -52.89984)
			(xy 371.630702 -52.900326) (xy 371.603331 -52.899877) (xy 371.54915 -52.892058) (xy 371.496646 -52.876566)
			(xy 371.4469 -52.85372) (xy 371.400934 -52.82399) (xy 371.380004 -52.806346) (xy 371.37975 -52.806092)
			(xy 371.372654 -52.800519) (xy 371.355744 -52.794265) (xy 371.34673 -52.7939) (xy 371.279674 -52.7939)
			(xy 371.270656 -52.794245) (xy 371.253739 -52.800501) (xy 371.246654 -52.806092) (xy 371.2464 -52.806346)
			(xy 371.225467 -52.823987) (xy 371.179499 -52.853711) (xy 371.129753 -52.876557) (xy 371.077251 -52.892053)
			(xy 371.023073 -52.899882) (xy 370.968331 -52.899882) (xy 370.914153 -52.892053) (xy 370.861651 -52.876557)
			(xy 370.811905 -52.853711) (xy 370.765937 -52.823987) (xy 370.745004 -52.806346) (xy 370.74475 -52.806092)
			(xy 370.737654 -52.800519) (xy 370.720744 -52.794265) (xy 370.71173 -52.7939) (xy 370.644674 -52.7939)
			(xy 370.635656 -52.794245) (xy 370.618739 -52.800501) (xy 370.611654 -52.806092) (xy 370.611654 -52.806346)
			(xy 370.6114 -52.806346) (xy 370.590472 -52.82399) (xy 370.544499 -52.853703) (xy 370.49475 -52.876539)
			(xy 370.442249 -52.892029) (xy 370.388072 -52.899854) (xy 370.360702 -52.900326) (xy 370.33345 -52.899827)
			(xy 370.279502 -52.89207) (xy 370.227206 -52.876715) (xy 370.177628 -52.854074) (xy 370.131777 -52.824607)
			(xy 370.090586 -52.788915) (xy 370.054894 -52.747725) (xy 370.025427 -52.701874) (xy 370.002785 -52.652296)
			(xy 369.98743 -52.6) (xy 369.979673 -52.546052) (xy 365.030649 -52.546052) (xy 365.041117 -52.550833)
			(xy 365.086967 -52.580299) (xy 365.128158 -52.61599) (xy 365.163849 -52.657181) (xy 365.193315 -52.703031)
			(xy 365.215957 -52.752608) (xy 365.231312 -52.804903) (xy 365.239068 -52.858851) (xy 365.239554 -52.886102)
			(xy 365.2391 -52.913473) (xy 365.231281 -52.967653) (xy 365.21579 -53.020157) (xy 365.192945 -53.069903)
			(xy 365.163217 -53.115869) (xy 365.145574 -53.1368) (xy 365.14532 -53.137054) (xy 365.139737 -53.144143)
			(xy 365.13349 -53.161058) (xy 365.133128 -53.170074) (xy 365.133128 -53.23713) (xy 365.133465 -53.246149)
			(xy 365.139726 -53.263066) (xy 365.14532 -53.27015) (xy 365.145574 -53.27015) (xy 365.145574 -53.270404)
			(xy 365.163217 -53.291335) (xy 365.192941 -53.337303) (xy 365.215786 -53.38705) (xy 365.231283 -53.439552)
			(xy 365.239111 -53.493731) (xy 365.239111 -53.548472) (xy 365.231282 -53.602651) (xy 365.215785 -53.655153)
			(xy 365.19294 -53.704899) (xy 365.163215 -53.750867) (xy 365.146644 -53.77053) (xy 365.510826 -53.77053)
			(xy 365.511356 -53.741613) (xy 365.520081 -53.684442) (xy 365.537336 -53.629243) (xy 365.562726 -53.577281)
			(xy 365.595668 -53.529747) (xy 365.635407 -53.48773) (xy 365.657892 -53.46954) (xy 365.66667 -53.461904)
			(xy 365.67687 -53.441025) (xy 365.67745 -53.429408) (xy 365.67745 -53.349652) (xy 365.676942 -53.338016)
			(xy 365.666733 -53.317105) (xy 365.657892 -53.30952) (xy 365.635416 -53.29132) (xy 365.595681 -53.249302)
			(xy 365.562741 -53.201769) (xy 365.537352 -53.149809) (xy 365.520094 -53.094613) (xy 365.511362 -53.037445)
			(xy 365.510826 -53.00853) (xy 365.511283 -52.981276) (xy 365.519037 -52.927323) (xy 365.534391 -52.875023)
			(xy 365.557033 -52.825441) (xy 365.586501 -52.779586) (xy 365.622195 -52.738392) (xy 365.663389 -52.702698)
			(xy 365.709245 -52.673231) (xy 365.758827 -52.65059) (xy 365.811127 -52.635236) (xy 365.86508 -52.627483)
			(xy 365.892334 -52.627022) (xy 365.918649 -52.62746) (xy 365.970779 -52.6347) (xy 366.021423 -52.649024)
			(xy 366.069622 -52.670162) (xy 366.114464 -52.697714) (xy 366.155103 -52.731158) (xy 366.173258 -52.750212)
			(xy 366.180792 -52.757599) (xy 366.200063 -52.766131) (xy 366.210596 -52.766722) (xy 366.285272 -52.766722)
			(xy 366.295821 -52.766185) (xy 366.315115 -52.757654) (xy 366.32261 -52.750212) (xy 366.34077 -52.731161)
			(xy 366.381399 -52.697703) (xy 366.426238 -52.670143) (xy 366.474438 -52.649004) (xy 366.525085 -52.634686)
			(xy 366.577218 -52.627461) (xy 366.603534 -52.627022) (xy 366.630787 -52.627446) (xy 366.684739 -52.635208)
			(xy 366.737037 -52.650569) (xy 366.786616 -52.673216) (xy 366.832468 -52.702689) (xy 366.873658 -52.738387)
			(xy 366.909349 -52.779584) (xy 366.938814 -52.82544) (xy 366.961453 -52.875023) (xy 366.976805 -52.927324)
			(xy 366.984558 -52.981276) (xy 366.985042 -53.00853) (xy 366.98458 -53.036197) (xy 366.976575 -53.09095)
			(xy 366.960752 -53.143974) (xy 366.937441 -53.194159) (xy 366.907131 -53.240454) (xy 366.870457 -53.28189)
			(xy 366.828187 -53.317599) (xy 366.804956 -53.332634) (xy 366.795266 -53.339255) (xy 366.782828 -53.359128)
			(xy 366.78108 -53.370734) (xy 366.773206 -53.450744) (xy 366.772568 -53.462382) (xy 366.780654 -53.484219)
			(xy 366.7887 -53.492654) (xy 366.788954 -53.492908) (xy 366.807513 -53.511012) (xy 366.840095 -53.551337)
			(xy 366.866912 -53.595707) (xy 366.887469 -53.643301) (xy 366.901387 -53.693242) (xy 366.908408 -53.744608)
			(xy 366.908842 -53.77053) (xy 366.90835 -53.79778) (xy 366.90059 -53.851726) (xy 366.885233 -53.904019)
			(xy 366.862591 -53.953594) (xy 366.833125 -53.999442) (xy 366.797434 -54.040631) (xy 366.756246 -54.076322)
			(xy 366.710397 -54.105789) (xy 366.660822 -54.128432) (xy 366.60853 -54.14379) (xy 366.554584 -54.15155)
			(xy 366.527334 -54.152038) (xy 366.499964 -54.151567) (xy 366.445784 -54.143753) (xy 366.393281 -54.128266)
			(xy 366.343534 -54.105425) (xy 366.297567 -54.0757) (xy 366.276636 -54.058058) (xy 366.276382 -54.057804)
			(xy 366.269304 -54.052204) (xy 366.252381 -54.045965) (xy 366.243362 -54.045612) (xy 366.176306 -54.045612)
			(xy 366.167289 -54.045969) (xy 366.150372 -54.052216) (xy 366.143286 -54.057804) (xy 366.143286 -54.058058)
			(xy 366.143032 -54.058058) (xy 366.122093 -54.075689) (xy 366.076123 -54.105404) (xy 366.026377 -54.128242)
			(xy 365.973878 -54.143734) (xy 365.919703 -54.151564) (xy 365.892334 -54.152038) (xy 365.865083 -54.151513)
			(xy 365.811136 -54.143762) (xy 365.758841 -54.128411) (xy 365.709263 -54.105775) (xy 365.663411 -54.076313)
			(xy 365.622219 -54.040626) (xy 365.586525 -53.99944) (xy 365.557056 -53.953593) (xy 365.534411 -53.904019)
			(xy 365.519052 -53.851726) (xy 365.511291 -53.797781) (xy 365.510826 -53.77053) (xy 365.146644 -53.77053)
			(xy 365.145574 -53.7718) (xy 365.14532 -53.772054) (xy 365.139737 -53.779143) (xy 365.13349 -53.796058)
			(xy 365.133128 -53.805074) (xy 365.133128 -53.87213) (xy 365.133465 -53.881149) (xy 365.139726 -53.898066)
			(xy 365.14532 -53.90515) (xy 365.145574 -53.90515) (xy 365.145574 -53.905404) (xy 365.163217 -53.926335)
			(xy 365.192941 -53.972303) (xy 365.215786 -54.02205) (xy 365.231283 -54.074552) (xy 365.239111 -54.128731)
			(xy 365.239111 -54.183472) (xy 365.231282 -54.237651) (xy 365.215785 -54.290153) (xy 365.201993 -54.320186)
			(xy 367.430558 -54.320186) (xy 367.431002 -54.292815) (xy 367.438823 -54.238634) (xy 367.454316 -54.18613)
			(xy 367.477163 -54.136384) (xy 367.506894 -54.090418) (xy 367.524538 -54.069488) (xy 367.524792 -54.069234)
			(xy 367.53037 -54.062141) (xy 367.536622 -54.045229) (xy 367.536984 -54.036214) (xy 367.536984 -53.969158)
			(xy 367.536603 -53.960144) (xy 367.530372 -53.943226) (xy 367.524792 -53.936138) (xy 367.524538 -53.936138)
			(xy 367.524538 -53.935884) (xy 367.506931 -53.914926) (xy 367.477213 -53.868961) (xy 367.45437 -53.81922)
			(xy 367.438872 -53.766725) (xy 367.431036 -53.712554) (xy 367.430558 -53.685186) (xy 367.431044 -53.657935)
			(xy 367.4388 -53.603987) (xy 367.454155 -53.551692) (xy 367.476797 -53.502115) (xy 367.506263 -53.456265)
			(xy 367.541954 -53.415074) (xy 367.583145 -53.379383) (xy 367.628995 -53.349917) (xy 367.678572 -53.327275)
			(xy 367.730867 -53.31192) (xy 367.784815 -53.304164) (xy 367.839317 -53.304164) (xy 367.893265 -53.31192)
			(xy 367.94556 -53.327275) (xy 367.995137 -53.349917) (xy 368.040987 -53.379383) (xy 368.082178 -53.415074)
			(xy 368.117869 -53.456265) (xy 368.147335 -53.502115) (xy 368.169977 -53.551692) (xy 368.185332 -53.603987)
			(xy 368.193088 -53.657935) (xy 368.193574 -53.685186) (xy 368.193106 -53.712556) (xy 368.18529 -53.766735)
			(xy 368.169801 -53.819239) (xy 368.14696 -53.868986) (xy 368.117235 -53.914952) (xy 368.099594 -53.935884)
			(xy 368.09934 -53.936138) (xy 368.093766 -53.943233) (xy 368.087513 -53.960144) (xy 368.087148 -53.969158)
			(xy 368.087148 -54.036214) (xy 368.087488 -54.045233) (xy 368.093746 -54.06215) (xy 368.09934 -54.069234)
			(xy 368.099594 -54.069234) (xy 368.099594 -54.069488) (xy 368.11724 -54.090415) (xy 368.146951 -54.136389)
			(xy 368.169786 -54.186138) (xy 368.185275 -54.23864) (xy 368.193101 -54.292816) (xy 368.193574 -54.320186)
			(xy 368.193088 -54.347437) (xy 368.185332 -54.401385) (xy 368.169977 -54.45368) (xy 368.147335 -54.503257)
			(xy 368.117869 -54.549107) (xy 368.082178 -54.590298) (xy 368.040987 -54.625989) (xy 367.995137 -54.655455)
			(xy 367.94556 -54.678097) (xy 367.893265 -54.693452) (xy 367.839317 -54.701208) (xy 367.784815 -54.701208)
			(xy 367.730867 -54.693452) (xy 367.678572 -54.678097) (xy 367.628995 -54.655455) (xy 367.583145 -54.625989)
			(xy 367.541954 -54.590298) (xy 367.506263 -54.549107) (xy 367.476797 -54.503257) (xy 367.454155 -54.45368)
			(xy 367.4388 -54.401385) (xy 367.431044 -54.347437) (xy 367.430558 -54.320186) (xy 365.201993 -54.320186)
			(xy 365.19294 -54.339899) (xy 365.163215 -54.385867) (xy 365.145574 -54.4068) (xy 365.14532 -54.407054)
			(xy 365.139737 -54.414143) (xy 365.13349 -54.431058) (xy 365.133128 -54.440074) (xy 365.133128 -54.50713)
			(xy 365.133465 -54.516149) (xy 365.139726 -54.533066) (xy 365.14532 -54.54015) (xy 365.145574 -54.54015)
			(xy 365.145574 -54.540404) (xy 365.163224 -54.561327) (xy 365.192935 -54.607302) (xy 365.21577 -54.657052)
			(xy 365.231258 -54.709555) (xy 365.239082 -54.763732) (xy 365.239199 -54.770528) (xy 368.37112 -54.770528)
			(xy 368.371598 -54.743158) (xy 368.379412 -54.688979) (xy 368.394898 -54.636476) (xy 368.417737 -54.586729)
			(xy 368.44746 -54.540762) (xy 368.4651 -54.51983) (xy 368.465354 -54.519576) (xy 368.470963 -54.512505)
			(xy 368.477195 -54.495576) (xy 368.477546 -54.486556) (xy 368.477546 -54.4195) (xy 368.477201 -54.410482)
			(xy 368.470946 -54.393564) (xy 368.465354 -54.38648) (xy 368.4651 -54.38648) (xy 368.4651 -54.386226)
			(xy 368.44746 -54.365295) (xy 368.417748 -54.319322) (xy 368.394912 -54.269574) (xy 368.379422 -54.217073)
			(xy 368.371594 -54.162897) (xy 368.37112 -54.135528) (xy 368.371606 -54.108277) (xy 368.379362 -54.054329)
			(xy 368.394717 -54.002034) (xy 368.417359 -53.952457) (xy 368.446825 -53.906607) (xy 368.482516 -53.865416)
			(xy 368.523707 -53.829725) (xy 368.569557 -53.800259) (xy 368.619134 -53.777617) (xy 368.671429 -53.762262)
			(xy 368.725377 -53.754506) (xy 368.779879 -53.754506) (xy 368.833827 -53.762262) (xy 368.886122 -53.777617)
			(xy 368.935699 -53.800259) (xy 368.981549 -53.829725) (xy 369.02274 -53.865416) (xy 369.058431 -53.906607)
			(xy 369.087897 -53.952457) (xy 369.092972 -53.96357) (xy 373.07215 -53.96357) (xy 373.076221 -53.907948)
			(xy 373.088347 -53.853511) (xy 373.10827 -53.80142) (xy 373.135566 -53.752785) (xy 373.169652 -53.708642)
			(xy 373.209801 -53.669933) (xy 373.255159 -53.637482) (xy 373.304759 -53.611981) (xy 373.357543 -53.593974)
			(xy 373.412386 -53.583844) (xy 373.46812 -53.581807) (xy 373.523557 -53.587907) (xy 373.577514 -53.602013)
			(xy 373.628843 -53.623825) (xy 373.676449 -53.652879) (xy 373.719317 -53.688554) (xy 373.756534 -53.730091)
			(xy 373.787307 -53.776604) (xy 373.810979 -53.827101) (xy 373.827047 -53.880508) (xy 373.835167 -53.935684)
			(xy 373.835676 -53.96357) (xy 373.835167 -53.991456) (xy 373.827047 -54.046632) (xy 373.810979 -54.100039)
			(xy 373.787307 -54.150536) (xy 373.756534 -54.197049) (xy 373.719317 -54.238586) (xy 373.676449 -54.274261)
			(xy 373.628843 -54.303315) (xy 373.577514 -54.325127) (xy 373.523557 -54.339233) (xy 373.46812 -54.345333)
			(xy 373.412386 -54.343296) (xy 373.357543 -54.333166) (xy 373.304759 -54.315159) (xy 373.255159 -54.289658)
			(xy 373.209801 -54.257207) (xy 373.169652 -54.218498) (xy 373.135566 -54.174355) (xy 373.10827 -54.12572)
			(xy 373.088347 -54.073629) (xy 373.076221 -54.019192) (xy 373.07215 -53.96357) (xy 369.092972 -53.96357)
			(xy 369.110539 -54.002034) (xy 369.125894 -54.054329) (xy 369.13365 -54.108277) (xy 369.134136 -54.135528)
			(xy 369.133702 -54.1629) (xy 369.125879 -54.217081) (xy 369.110383 -54.269585) (xy 369.087534 -54.319331)
			(xy 369.057801 -54.365296) (xy 369.040156 -54.386226) (xy 369.039902 -54.38648) (xy 369.034318 -54.393568)
			(xy 369.02807 -54.410484) (xy 369.02771 -54.4195) (xy 369.02771 -54.486556) (xy 369.028086 -54.495571)
			(xy 369.03432 -54.512488) (xy 369.039902 -54.519576) (xy 369.040156 -54.519576) (xy 369.040156 -54.51983)
			(xy 369.057769 -54.540783) (xy 369.087486 -54.58675) (xy 369.110328 -54.636492) (xy 369.125825 -54.688988)
			(xy 369.133659 -54.74316) (xy 369.134136 -54.770528) (xy 369.13365 -54.797779) (xy 369.125894 -54.851727)
			(xy 369.110539 -54.904022) (xy 369.087897 -54.953599) (xy 369.058431 -54.999449) (xy 369.02274 -55.04064)
			(xy 368.981549 -55.076331) (xy 368.935699 -55.105797) (xy 368.886122 -55.128439) (xy 368.833827 -55.143794)
			(xy 368.779879 -55.15155) (xy 368.725377 -55.15155) (xy 368.671429 -55.143794) (xy 368.619134 -55.128439)
			(xy 368.569557 -55.105797) (xy 368.523707 -55.076331) (xy 368.482516 -55.04064) (xy 368.446825 -54.999449)
			(xy 368.417359 -54.953599) (xy 368.394717 -54.904022) (xy 368.379362 -54.851727) (xy 368.371606 -54.797779)
			(xy 368.37112 -54.770528) (xy 365.239199 -54.770528) (xy 365.239554 -54.791102) (xy 365.239068 -54.818353)
			(xy 365.231312 -54.872301) (xy 365.215957 -54.924596) (xy 365.193315 -54.974173) (xy 365.163849 -55.020023)
			(xy 365.128158 -55.061214) (xy 365.086967 -55.096905) (xy 365.041117 -55.126371) (xy 364.99154 -55.149013)
			(xy 364.939245 -55.164368) (xy 364.885297 -55.172124) (xy 364.830795 -55.172124) (xy 364.776847 -55.164368)
			(xy 364.724552 -55.149013) (xy 364.674975 -55.126371) (xy 364.629125 -55.096905) (xy 364.587934 -55.061214)
			(xy 364.552243 -55.020023) (xy 364.522777 -54.974173) (xy 364.500135 -54.924596) (xy 364.48478 -54.872301)
			(xy 364.477024 -54.818353) (xy 364.476538 -54.791102) (xy 362.57858 -54.791102) (xy 362.575488 -54.812611)
			(xy 362.560133 -54.864906) (xy 362.537491 -54.914483) (xy 362.508025 -54.960333) (xy 362.472334 -55.001524)
			(xy 362.431143 -55.037215) (xy 362.385293 -55.066681) (xy 362.335716 -55.089323) (xy 362.283421 -55.104678)
			(xy 362.229473 -55.112434) (xy 362.174971 -55.112434) (xy 362.121023 -55.104678) (xy 362.068728 -55.089323)
			(xy 362.019151 -55.066681) (xy 361.973301 -55.037215) (xy 361.93211 -55.001524) (xy 361.896419 -54.960333)
			(xy 361.866953 -54.914483) (xy 361.844311 -54.864906) (xy 361.828956 -54.812611) (xy 361.8212 -54.758663)
			(xy 361.820714 -54.731412) (xy 361.01782 -54.731412) (xy 361.01782 -57.002934) (xy 369.863624 -57.002934)
			(xy 369.864125 -56.974842) (xy 369.872349 -56.919265) (xy 369.888637 -56.865495) (xy 369.912638 -56.814697)
			(xy 369.943833 -56.76797) (xy 369.981545 -56.726325) (xy 370.024959 -56.690664) (xy 370.04879 -56.675782)
			(xy 370.05768 -56.670448) (xy 370.069872 -56.65343) (xy 370.090192 -56.560212) (xy 370.085874 -56.539638)
			(xy 370.080032 -56.531002) (xy 370.064034 -56.506937) (xy 370.03869 -56.455006) (xy 370.021464 -56.399848)
			(xy 370.012748 -56.342724) (xy 370.012214 -56.313832) (xy 370.012685 -56.286579) (xy 370.020438 -56.232627)
			(xy 370.035791 -56.180328) (xy 370.058432 -56.130747) (xy 370.087899 -56.084892) (xy 370.123592 -56.043699)
			(xy 370.164784 -56.008005) (xy 370.210638 -55.978537) (xy 370.260219 -55.955895) (xy 370.312517 -55.94054)
			(xy 370.366469 -55.932786) (xy 370.393722 -55.932324) (xy 370.421093 -55.932771) (xy 370.475273 -55.940593)
			(xy 370.527777 -55.956086) (xy 370.577523 -55.978932) (xy 370.623489 -56.008661) (xy 370.64442 -56.026304)
			(xy 370.644674 -56.026558) (xy 370.651759 -56.032147) (xy 370.668677 -56.038391) (xy 370.677694 -56.03875)
			(xy 370.74475 -56.03875) (xy 370.753766 -56.03838) (xy 370.770683 -56.032143) (xy 370.77777 -56.026558)
			(xy 370.77777 -56.026304) (xy 370.778024 -56.026304) (xy 370.798957 -56.008663) (xy 370.844925 -55.978939)
			(xy 370.894671 -55.956093) (xy 370.947173 -55.940597) (xy 371.001351 -55.932768) (xy 371.056093 -55.932768)
			(xy 371.110271 -55.940597) (xy 371.162773 -55.956093) (xy 371.212519 -55.978939) (xy 371.258487 -56.008663)
			(xy 371.27942 -56.026304) (xy 371.279674 -56.026558) (xy 371.286759 -56.032147) (xy 371.303677 -56.038391)
			(xy 371.312694 -56.03875) (xy 371.37975 -56.03875) (xy 371.388766 -56.03838) (xy 371.405683 -56.032143)
			(xy 371.41277 -56.026558) (xy 371.41277 -56.026304) (xy 371.413024 -56.026304) (xy 371.433974 -56.008688)
			(xy 371.479942 -55.978972) (xy 371.529685 -55.956132) (xy 371.582182 -55.940635) (xy 371.636354 -55.932801)
			(xy 371.663722 -55.932324) (xy 371.690975 -55.932747) (xy 371.744924 -55.940507) (xy 371.797221 -55.955865)
			(xy 371.846799 -55.97851) (xy 371.892651 -56.007979) (xy 371.933842 -56.043674) (xy 371.969534 -56.084867)
			(xy 371.999001 -56.13072) (xy 372.021642 -56.1803) (xy 372.036998 -56.232597) (xy 372.044754 -56.286547)
			(xy 372.044754 -56.341053) (xy 372.036998 -56.395003) (xy 372.021642 -56.4473) (xy 371.999001 -56.49688)
			(xy 371.969534 -56.542733) (xy 371.933842 -56.583926) (xy 371.892651 -56.619621) (xy 371.846799 -56.64909)
			(xy 371.797221 -56.671735) (xy 371.744924 -56.687093) (xy 371.690975 -56.694853) (xy 371.663722 -56.69534)
			(xy 371.636352 -56.694876) (xy 371.582172 -56.68706) (xy 371.529668 -56.671571) (xy 371.479921 -56.648728)
			(xy 371.433955 -56.619002) (xy 371.413024 -56.60136) (xy 371.41277 -56.601106) (xy 371.405667 -56.595543)
			(xy 371.388763 -56.589282) (xy 371.37975 -56.588914) (xy 371.312694 -56.588914) (xy 371.303676 -56.589265)
			(xy 371.286759 -56.595516) (xy 371.279674 -56.601106) (xy 371.279674 -56.60136) (xy 371.27942 -56.60136)
			(xy 371.258487 -56.619001) (xy 371.212519 -56.648725) (xy 371.162773 -56.671571) (xy 371.110271 -56.687067)
			(xy 371.056093 -56.694896) (xy 371.001351 -56.694896) (xy 370.947173 -56.687067) (xy 370.894671 -56.671571)
			(xy 370.844925 -56.648725) (xy 370.798957 -56.619001) (xy 370.778024 -56.60136) (xy 370.77777 -56.601106)
			(xy 370.770667 -56.595543) (xy 370.753763 -56.589282) (xy 370.74475 -56.588914) (xy 370.677694 -56.588914)
			(xy 370.668676 -56.589265) (xy 370.651759 -56.595516) (xy 370.644674 -56.601106) (xy 370.644166 -56.60136)
			(xy 370.631431 -56.612304) (xy 370.60434 -56.632145) (xy 370.590064 -56.640984) (xy 370.581174 -56.646318)
			(xy 370.568982 -56.663336) (xy 370.548662 -56.756554) (xy 370.55298 -56.777128) (xy 370.558822 -56.785764)
			(xy 370.574811 -56.809834) (xy 370.600156 -56.861764) (xy 370.617384 -56.91692) (xy 370.626103 -56.974042)
			(xy 370.62664 -57.002934) (xy 370.626154 -57.030185) (xy 370.618398 -57.084133) (xy 370.603043 -57.136428)
			(xy 370.580401 -57.186005) (xy 370.550935 -57.231855) (xy 370.515244 -57.273046) (xy 370.474053 -57.308737)
			(xy 370.428203 -57.338203) (xy 370.378626 -57.360845) (xy 370.326331 -57.3762) (xy 370.272383 -57.383956)
			(xy 370.217881 -57.383956) (xy 370.163933 -57.3762) (xy 370.111638 -57.360845) (xy 370.062061 -57.338203)
			(xy 370.016211 -57.308737) (xy 369.97502 -57.273046) (xy 369.939329 -57.231855) (xy 369.909863 -57.186005)
			(xy 369.887221 -57.136428) (xy 369.871866 -57.084133) (xy 369.86411 -57.030185) (xy 369.863624 -57.002934)
			(xy 361.01782 -57.002934) (xy 361.01782 -58.679334) (xy 370.295424 -58.679334) (xy 370.29584 -58.653018)
			(xy 370.303084 -58.600887) (xy 370.317413 -58.550243) (xy 370.338555 -58.502044) (xy 370.36611 -58.457202)
			(xy 370.399558 -58.416565) (xy 370.418614 -58.39841) (xy 370.426015 -58.390889) (xy 370.43454 -58.371608)
			(xy 370.435124 -58.361072) (xy 370.435124 -58.286396) (xy 370.434603 -58.275846) (xy 370.426061 -58.256551)
			(xy 370.418614 -58.249058) (xy 370.399548 -58.230913) (xy 370.366091 -58.190281) (xy 370.338533 -58.145439)
			(xy 370.317396 -58.097236) (xy 370.303082 -58.046587) (xy 370.29586 -57.994451) (xy 370.295424 -57.968134)
			(xy 370.29591 -57.940883) (xy 370.303666 -57.886935) (xy 370.319021 -57.83464) (xy 370.341663 -57.785063)
			(xy 370.371129 -57.739213) (xy 370.40682 -57.698022) (xy 370.448011 -57.662331) (xy 370.493861 -57.632865)
			(xy 370.543438 -57.610223) (xy 370.595733 -57.594868) (xy 370.649681 -57.587112) (xy 370.704183 -57.587112)
			(xy 370.758131 -57.594868) (xy 370.810426 -57.610223) (xy 370.860003 -57.632865) (xy 370.905853 -57.662331)
			(xy 370.947044 -57.698022) (xy 370.982735 -57.739213) (xy 371.012201 -57.785063) (xy 371.034843 -57.83464)
			(xy 371.050198 -57.886935) (xy 371.057954 -57.940883) (xy 371.05844 -57.968134) (xy 371.058014 -57.99445)
			(xy 371.050774 -58.046581) (xy 371.036448 -58.097225) (xy 371.015308 -58.145424) (xy 370.987753 -58.190267)
			(xy 370.954306 -58.230903) (xy 370.93525 -58.249058) (xy 370.927872 -58.2566) (xy 370.919333 -58.275864)
			(xy 370.91874 -58.286396) (xy 370.91874 -58.361072) (xy 370.919259 -58.371623) (xy 370.9278 -58.390919)
			(xy 370.93525 -58.39841) (xy 370.954313 -58.416558) (xy 370.987767 -58.45719) (xy 371.015324 -58.502033)
			(xy 371.036461 -58.550235) (xy 371.050777 -58.600883) (xy 371.058002 -58.653018) (xy 371.05844 -58.679334)
			(xy 371.057954 -58.706585) (xy 371.050198 -58.760533) (xy 371.034843 -58.812828) (xy 371.012201 -58.862405)
			(xy 370.982735 -58.908255) (xy 370.947044 -58.949446) (xy 370.905853 -58.985137) (xy 370.860003 -59.014603)
			(xy 370.810426 -59.037245) (xy 370.758131 -59.0526) (xy 370.704183 -59.060356) (xy 370.649681 -59.060356)
			(xy 370.595733 -59.0526) (xy 370.543438 -59.037245) (xy 370.493861 -59.014603) (xy 370.448011 -58.985137)
			(xy 370.40682 -58.949446) (xy 370.371129 -58.908255) (xy 370.341663 -58.862405) (xy 370.319021 -58.812828)
			(xy 370.303666 -58.760533) (xy 370.29591 -58.706585) (xy 370.295424 -58.679334) (xy 361.01782 -58.679334)
			(xy 361.01782 -60.01925) (xy 370.435884 -60.01925) (xy 370.435884 -59.96475) (xy 370.44364 -59.910804)
			(xy 370.458994 -59.858511) (xy 370.481634 -59.808936) (xy 370.511098 -59.763087) (xy 370.546788 -59.721898)
			(xy 370.587976 -59.686207) (xy 370.633824 -59.65674) (xy 370.683398 -59.634099) (xy 370.73569 -59.618743)
			(xy 370.789636 -59.610985) (xy 370.816886 -59.610498) (xy 370.844256 -59.610973) (xy 370.898435 -59.618789)
			(xy 370.950938 -59.634276) (xy 371.000685 -59.657115) (xy 371.046652 -59.686838) (xy 371.067584 -59.704478)
			(xy 371.067838 -59.704732) (xy 371.074936 -59.710302) (xy 371.091844 -59.716558) (xy 371.100858 -59.716924)
			(xy 371.167914 -59.716924) (xy 371.176931 -59.716568) (xy 371.193847 -59.710319) (xy 371.200934 -59.704732)
			(xy 371.200934 -59.704478) (xy 371.201188 -59.704478) (xy 371.222121 -59.686837) (xy 371.268089 -59.657113)
			(xy 371.317835 -59.634267) (xy 371.370337 -59.618771) (xy 371.424515 -59.610942) (xy 371.479257 -59.610942)
			(xy 371.533435 -59.618771) (xy 371.585937 -59.634267) (xy 371.635683 -59.657113) (xy 371.681651 -59.686837)
			(xy 371.702584 -59.704478) (xy 371.702838 -59.704732) (xy 371.709936 -59.710302) (xy 371.726844 -59.716558)
			(xy 371.735858 -59.716924) (xy 371.802914 -59.716924) (xy 371.811931 -59.716568) (xy 371.828847 -59.710319)
			(xy 371.835934 -59.704732) (xy 371.835934 -59.704478) (xy 371.836188 -59.704478) (xy 371.857111 -59.686828)
			(xy 371.903087 -59.657118) (xy 371.952836 -59.634285) (xy 372.005339 -59.618796) (xy 372.059516 -59.610971)
			(xy 372.086886 -59.610498) (xy 372.11414 -59.610948) (xy 372.168093 -59.618704) (xy 372.220394 -59.634059)
			(xy 372.269976 -59.656701) (xy 372.315832 -59.686169) (xy 372.357027 -59.721863) (xy 372.392723 -59.763057)
			(xy 372.422192 -59.808911) (xy 372.444836 -59.858493) (xy 372.460193 -59.910793) (xy 372.467951 -59.964746)
			(xy 372.467951 -60.019254) (xy 372.460193 -60.073207) (xy 372.444836 -60.125507) (xy 372.422192 -60.175089)
			(xy 372.392723 -60.220943) (xy 372.357027 -60.262137) (xy 372.315832 -60.297831) (xy 372.269976 -60.327299)
			(xy 372.220394 -60.349941) (xy 372.168093 -60.365296) (xy 372.11414 -60.373052) (xy 372.086886 -60.373514)
			(xy 372.059516 -60.373053) (xy 372.005336 -60.365233) (xy 371.952833 -60.349743) (xy 371.903087 -60.3269)
			(xy 371.85712 -60.297175) (xy 371.836188 -60.279534) (xy 371.835934 -60.27928) (xy 371.828844 -60.273699)
			(xy 371.81193 -60.26745) (xy 371.802914 -60.267088) (xy 371.735858 -60.267088) (xy 371.726844 -60.267476)
			(xy 371.709927 -60.273702) (xy 371.702838 -60.27928) (xy 371.702584 -60.279534) (xy 371.681651 -60.297175)
			(xy 371.635683 -60.326899) (xy 371.585937 -60.349745) (xy 371.533435 -60.365241) (xy 371.479257 -60.37307)
			(xy 371.424515 -60.37307) (xy 371.370337 -60.365241) (xy 371.317835 -60.349745) (xy 371.268089 -60.326899)
			(xy 371.222121 -60.297175) (xy 371.201188 -60.279534) (xy 371.200934 -60.27928) (xy 371.193844 -60.273699)
			(xy 371.17693 -60.26745) (xy 371.167914 -60.267088) (xy 371.100858 -60.267088) (xy 371.091844 -60.267476)
			(xy 371.074927 -60.273702) (xy 371.067838 -60.27928) (xy 371.067838 -60.279534) (xy 371.067584 -60.279534)
			(xy 371.046635 -60.297152) (xy 371.000667 -60.326866) (xy 370.950923 -60.349706) (xy 370.898426 -60.365202)
			(xy 370.844254 -60.373036) (xy 370.816886 -60.373514) (xy 370.789636 -60.373015) (xy 370.73569 -60.365257)
			(xy 370.683398 -60.349901) (xy 370.633824 -60.32726) (xy 370.587976 -60.297793) (xy 370.546788 -60.262102)
			(xy 370.511098 -60.220913) (xy 370.481634 -60.175064) (xy 370.458994 -60.125489) (xy 370.44364 -60.073196)
			(xy 370.435884 -60.01925) (xy 361.01782 -60.01925) (xy 361.01782 -66.348864) (xy 361.018241 -66.357957)
			(xy 361.024687 -66.374967) (xy 361.036671 -66.388651) (xy 361.04449 -66.393314) (xy 361.04957 -66.395346)
			(xy 361.056602 -66.398062) (xy 361.071592 -66.399603) (xy 361.079034 -66.398394) (xy 361.085638 -66.397124)
			(xy 361.098846 -66.390012) (xy 361.968034 -65.520824) (xy 361.986804 -65.502789) (xy 362.028919 -65.472203)
			(xy 362.075295 -65.448569) (xy 362.124792 -65.432469) (xy 362.176197 -65.424296) (xy 362.202222 -65.423796)
			(xy 362.840016 -65.423796) (xy 362.84281 -65.422272) (xy 362.867294 -65.409192) (xy 362.91918 -65.389468)
			(xy 362.973376 -65.377465) (xy 363.028738 -65.373436) (xy 363.0841 -65.377465) (xy 363.138296 -65.389468)
			(xy 363.190182 -65.409192) (xy 363.214666 -65.422272) (xy 363.21746 -65.423796) (xy 366.270794 -65.423796)
			(xy 366.281208 -65.42278) (xy 366.288335 -65.421039) (xy 366.301234 -65.414061) (xy 366.306608 -65.409064)
			(xy 367.703354 -64.012064) (xy 367.733072 -63.982346) (xy 367.753232 -63.963024) (xy 367.798785 -63.930733)
			(xy 367.849098 -63.906516) (xy 367.902753 -63.891057) (xy 367.93043 -63.88735) (xy 367.939066 -63.886334)
			(xy 367.946686 -63.882778) (xy 367.950448 -63.880798) (xy 367.957342 -63.875823) (xy 367.960402 -63.872872)
			(xy 368.102642 -63.730632) (xy 368.119553 -63.714348) (xy 368.157236 -63.68635) (xy 368.198579 -63.66411)
			(xy 368.220498 -63.655702) (xy 368.221768 -63.655702) (xy 368.238278 -63.649352) (xy 368.24031 -63.64859)
			(xy 368.243866 -63.647574) (xy 368.249962 -63.646304) (xy 368.250724 -63.646304) (xy 368.255296 -63.645542)
			(xy 368.256566 -63.645288) (xy 368.257328 -63.645034) (xy 368.257836 -63.645034) (xy 368.267141 -63.642892)
			(xy 368.28595 -63.639587) (xy 368.295428 -63.63843) (xy 368.295682 -63.63843) (xy 368.298222 -63.638176)
			(xy 368.330226 -63.636652) (xy 370.467128 -63.636652) (xy 370.473732 -63.636144) (xy 370.47424 -63.636144)
			(xy 370.484404 -63.634278) (xy 370.502115 -63.62367) (xy 370.50853 -63.61557) (xy 370.514118 -63.605156)
			(xy 370.525802 -63.576962) (xy 370.525802 -63.576454) (xy 370.532152 -63.56096) (xy 370.53388 -63.556958)
			(xy 370.538477 -63.549553) (xy 370.541296 -63.546228) (xy 370.543074 -63.544196) (xy 370.546469 -63.539828)
			(xy 370.551461 -63.529958) (xy 370.55298 -63.524638) (xy 370.555012 -63.512954) (xy 370.55425 -63.506858)
			(xy 370.553769 -63.50313) (xy 370.551857 -63.495862) (xy 370.55044 -63.49238) (xy 370.537232 -63.461392)
			(xy 370.530374 -63.454534) (xy 370.510461 -63.433627) (xy 370.476532 -63.386912) (xy 370.450034 -63.335616)
			(xy 370.431572 -63.280911) (xy 370.421568 -63.224049) (xy 370.420392 -63.1952) (xy 370.420392 -63.180468)
			(xy 370.421374 -63.151504) (xy 370.431015 -63.094359) (xy 370.449189 -63.03933) (xy 370.475478 -62.987684)
			(xy 370.509276 -62.940608) (xy 370.549807 -62.899186) (xy 370.596137 -62.864372) (xy 370.647199 -62.836967)
			(xy 370.70182 -62.817601) (xy 370.758742 -62.80672) (xy 370.787676 -62.805056) (xy 370.78793 -62.805056)
			(xy 370.8019 -62.804802) (xy 370.802408 -62.804802) (xy 370.828034 -62.805233) (xy 370.878819 -62.812133)
			(xy 370.92822 -62.825781) (xy 370.975345 -62.84593) (xy 371.019342 -62.872217) (xy 371.039644 -62.88786)
			(xy 371.046248 -62.89294) (xy 371.057424 -62.89675) (xy 371.070886 -62.898782) (xy 371.09273 -62.898782)
			(xy 371.09817 -62.898925) (xy 371.108802 -62.901231) (xy 371.113812 -62.903354) (xy 371.127528 -62.909704)
			(xy 371.132231 -62.911773) (xy 371.142212 -62.914215) (xy 371.14734 -62.91453) (xy 371.155976 -62.914022)
			(xy 371.163262 -62.91274) (xy 371.176689 -62.906543) (xy 371.182392 -62.90183) (xy 371.182646 -62.901576)
			(xy 371.202532 -62.884467) (xy 371.246117 -62.855274) (xy 371.269514 -62.84341) (xy 371.284246 -62.836552)
			(xy 371.288818 -62.83452) (xy 371.312155 -62.82517) (xy 371.360669 -62.811983) (xy 371.410494 -62.805275)
			(xy 371.43563 -62.804802) (xy 371.442234 -62.804802) (xy 371.471997 -62.805793) (xy 371.530684 -62.815879)
			(xy 371.559074 -62.824868) (xy 371.590059 -62.836095) (xy 371.647916 -62.86764) (xy 371.674136 -62.887606)
			(xy 371.67439 -62.88786) (xy 371.677438 -62.8904) (xy 371.683547 -62.894137) (xy 371.697212 -62.8984)
			(xy 371.704362 -62.898782) (xy 371.72773 -62.898782) (xy 371.73317 -62.898925) (xy 371.743802 -62.901231)
			(xy 371.748812 -62.903354) (xy 371.762528 -62.909704) (xy 371.767231 -62.911773) (xy 371.777212 -62.914215)
			(xy 371.78234 -62.91453) (xy 371.790976 -62.914022) (xy 371.798262 -62.91274) (xy 371.811689 -62.906543)
			(xy 371.817392 -62.90183) (xy 371.817646 -62.901576) (xy 371.838715 -62.883466) (xy 371.885108 -62.8529)
			(xy 371.935441 -62.829381) (xy 371.98865 -62.813404) (xy 372.043614 -62.805308) (xy 372.071392 -62.804802)
			(xy 372.0719 -62.804802) (xy 372.099153 -62.805265) (xy 372.153103 -62.813022) (xy 372.2054 -62.828379)
			(xy 372.25498 -62.851021) (xy 372.300832 -62.880489) (xy 372.342024 -62.916183) (xy 372.377717 -62.957376)
			(xy 372.407184 -63.003229) (xy 372.429825 -63.052809) (xy 372.44518 -63.105107) (xy 372.452935 -63.159057)
			(xy 372.453408 -63.18631) (xy 372.452838 -63.216037) (xy 372.443611 -63.27477) (xy 372.425383 -63.331361)
			(xy 372.398594 -63.384437) (xy 372.363894 -63.432714) (xy 372.343426 -63.45428) (xy 372.343172 -63.454534)
			(xy 372.336822 -63.461138) (xy 372.330726 -63.4746) (xy 372.328694 -63.479172) (xy 372.327424 -63.482982)
			(xy 372.323868 -63.500508) (xy 372.323374 -63.506029) (xy 372.324537 -63.51705) (xy 372.326154 -63.522352)
			(xy 372.347998 -63.576454) (xy 372.347998 -63.576962) (xy 372.359428 -63.604902) (xy 372.364438 -63.615633)
			(xy 372.382184 -63.63127) (xy 372.393464 -63.634874) (xy 372.401592 -63.63716) (xy 372.409974 -63.636652)
			(xy 373.09044 -63.636652) (xy 373.098568 -63.63589) (xy 373.099076 -63.63589) (xy 373.106598 -63.634296)
			(xy 373.120296 -63.627329) (xy 373.126 -63.622174) (xy 373.360696 -63.387478) (xy 373.36568 -63.382049)
			(xy 373.372533 -63.369011) (xy 373.374158 -63.361824) (xy 373.374158 -63.361316) (xy 373.375174 -63.351918)
			(xy 373.375174 -57.856628) (xy 373.374666 -57.84977) (xy 373.372634 -57.838594) (xy 373.36984 -57.829196)
			(xy 373.365776 -57.819036) (xy 373.363998 -57.814718) (xy 373.357394 -57.803796) (xy 373.355362 -57.80151)
			(xy 373.353076 -57.798462) (xy 373.352822 -57.798208) (xy 373.352314 -57.797446) (xy 373.338396 -57.779757)
			(xy 373.315069 -57.741263) (xy 373.305832 -57.720738) (xy 373.305832 -57.72023) (xy 373.30253 -57.712102)
			(xy 373.29999 -57.706768) (xy 373.295672 -57.69991) (xy 373.295672 -57.699656) (xy 373.280161 -57.678035)
			(xy 373.255505 -57.630885) (xy 373.238692 -57.580404) (xy 373.230154 -57.527885) (xy 373.229632 -57.501282)
			(xy 373.229632 -56.577992) (xy 373.225019 -56.572299) (xy 373.213283 -56.563536) (xy 373.206518 -56.56072)
			(xy 373.163084 -56.544718) (xy 373.116856 -56.5277) (xy 373.109236 -56.525668) (xy 373.103477 -56.524687)
			(xy 373.091803 -56.525069) (xy 373.086122 -56.52643) (xy 373.078756 -56.528462) (xy 373.065548 -56.536844)
			(xy 373.060468 -56.54294) (xy 373.042235 -56.563795) (xy 373.000779 -56.600534) (xy 372.954447 -56.630894)
			(xy 372.904213 -56.654238) (xy 372.851132 -56.670075) (xy 372.796319 -56.678071) (xy 372.768622 -56.678576)
			(xy 372.74137 -56.678114) (xy 372.687422 -56.67036) (xy 372.635126 -56.655008) (xy 372.585547 -56.632368)
			(xy 372.539695 -56.602903) (xy 372.498503 -56.567213) (xy 372.46281 -56.526023) (xy 372.433342 -56.480173)
			(xy 372.4107 -56.430595) (xy 372.395344 -56.3783) (xy 372.387587 -56.324352) (xy 372.387587 -56.269848)
			(xy 372.395344 -56.2159) (xy 372.4107 -56.163605) (xy 372.433342 -56.114027) (xy 372.46281 -56.068177)
			(xy 372.498503 -56.026987) (xy 372.539695 -55.991297) (xy 372.585547 -55.961832) (xy 372.635126 -55.939192)
			(xy 372.687422 -55.92384) (xy 372.74137 -55.916086) (xy 372.768622 -55.91556) (xy 372.795598 -55.916026)
			(xy 372.849014 -55.92362) (xy 372.90083 -55.938653) (xy 372.950016 -55.960827) (xy 372.995592 -55.9897)
			(xy 373.036653 -56.024699) (xy 373.05488 -56.044592) (xy 373.060722 -56.051196) (xy 373.07393 -56.060086)
			(xy 373.080534 -56.063388) (xy 373.081042 -56.063896) (xy 373.089969 -56.067465) (xy 373.109158 -56.068387)
			(xy 373.11838 -56.065674) (xy 373.119142 -56.06542) (xy 373.206518 -56.033416) (xy 373.213294 -56.030712)
			(xy 373.225032 -56.022061) (xy 373.229632 -56.016398) (xy 373.229632 -55.11292) (xy 373.230162 -55.086897)
			(xy 373.238332 -55.035496) (xy 373.254429 -54.986001) (xy 373.278057 -54.939627) (xy 373.308637 -54.897511)
			(xy 373.32666 -54.878732) (xy 375.25071 -52.954682) (xy 375.25706 -52.944014) (xy 375.258838 -52.938172)
			(xy 375.267286 -52.912605) (xy 375.290364 -52.863957) (xy 375.32005 -52.819035) (xy 375.355753 -52.778731)
			(xy 375.396766 -52.743843) (xy 375.442275 -52.715064) (xy 375.491376 -52.692967) (xy 375.543095 -52.677988)
			(xy 375.596406 -52.670425) (xy 375.623328 -52.669948) (xy 375.650579 -52.670436) (xy 375.704526 -52.678195)
			(xy 375.75682 -52.693552) (xy 375.806397 -52.716194) (xy 375.852247 -52.745661) (xy 375.893437 -52.781352)
			(xy 375.92913 -52.822541) (xy 375.958598 -52.868389) (xy 375.981242 -52.917965) (xy 375.996601 -52.970258)
			(xy 376.004363 -53.024205) (xy 376.004836 -53.051456) (xy 376.00509 -53.051456) (xy 376.00463 -53.078391)
			(xy 375.99706 -53.131726) (xy 375.982064 -53.183466) (xy 375.959941 -53.232583) (xy 375.931129 -53.2781)
			(xy 375.896203 -53.319113) (xy 375.855855 -53.354806) (xy 375.810889 -53.38447) (xy 375.762197 -53.407514)
			(xy 375.736612 -53.415946) (xy 375.736358 -53.415946) (xy 375.730522 -53.417954) (xy 375.719983 -53.424372)
			(xy 375.71553 -53.428646) (xy 375.647625 -53.496551) (xy 380.433564 -53.496551) (xy 380.433564 -53.442049)
			(xy 380.44132 -53.388101) (xy 380.456675 -53.335806) (xy 380.479315 -53.286228) (xy 380.508781 -53.240377)
			(xy 380.544471 -53.199186) (xy 380.585661 -53.163493) (xy 380.63151 -53.134025) (xy 380.681087 -53.111382)
			(xy 380.733381 -53.096024) (xy 380.787329 -53.088265) (xy 380.81458 -53.087778) (xy 380.841951 -53.088237)
			(xy 380.896131 -53.096053) (xy 380.948635 -53.111543) (xy 380.998382 -53.134387) (xy 381.044347 -53.164115)
			(xy 381.065278 -53.181758) (xy 381.065532 -53.182012) (xy 381.072633 -53.187578) (xy 381.089539 -53.193837)
			(xy 381.098552 -53.194204) (xy 381.165608 -53.194204) (xy 381.174625 -53.19385) (xy 381.191542 -53.1876)
			(xy 381.198628 -53.182012) (xy 381.198628 -53.181758) (xy 381.198882 -53.181758) (xy 381.219804 -53.164107)
			(xy 381.26578 -53.134398) (xy 381.315531 -53.111565) (xy 381.368033 -53.096077) (xy 381.42221 -53.088251)
			(xy 381.44958 -53.087778) (xy 381.476833 -53.088268) (xy 381.530784 -53.096022) (xy 381.583082 -53.111376)
			(xy 381.632663 -53.134017) (xy 381.678517 -53.163483) (xy 381.719711 -53.199175) (xy 381.755405 -53.240367)
			(xy 381.784874 -53.286219) (xy 381.807517 -53.335799) (xy 381.822873 -53.388097) (xy 381.830631 -53.442047)
			(xy 381.830631 -53.496553) (xy 381.822873 -53.550503) (xy 381.807517 -53.602801) (xy 381.784874 -53.652381)
			(xy 381.755405 -53.698233) (xy 381.719711 -53.739425) (xy 381.678517 -53.775117) (xy 381.632663 -53.804583)
			(xy 381.583082 -53.827224) (xy 381.530784 -53.842578) (xy 381.476833 -53.850332) (xy 381.44958 -53.850794)
			(xy 381.422209 -53.850341) (xy 381.36803 -53.84252) (xy 381.315526 -53.827028) (xy 381.26578 -53.804184)
			(xy 381.219813 -53.774456) (xy 381.198882 -53.756814) (xy 381.198628 -53.75656) (xy 381.191541 -53.750974)
			(xy 381.174624 -53.744728) (xy 381.165608 -53.744368) (xy 381.098552 -53.744368) (xy 381.089538 -53.744757)
			(xy 381.072622 -53.750983) (xy 381.065532 -53.75656) (xy 381.065532 -53.756814) (xy 381.065278 -53.756814)
			(xy 381.044329 -53.774432) (xy 380.998361 -53.804147) (xy 380.948617 -53.826986) (xy 380.896121 -53.842482)
			(xy 380.841948 -53.850317) (xy 380.81458 -53.850794) (xy 380.787329 -53.850335) (xy 380.733381 -53.842576)
			(xy 380.681087 -53.827218) (xy 380.63151 -53.804575) (xy 380.585661 -53.775107) (xy 380.544471 -53.739414)
			(xy 380.508781 -53.698223) (xy 380.479315 -53.652372) (xy 380.456675 -53.602794) (xy 380.44132 -53.550499)
			(xy 380.433564 -53.496551) (xy 375.647625 -53.496551) (xy 374.155125 -54.989051) (xy 378.201168 -54.989051)
			(xy 378.201168 -54.934549) (xy 378.208924 -54.880602) (xy 378.224278 -54.828308) (xy 378.246918 -54.778732)
			(xy 378.276382 -54.732881) (xy 378.312072 -54.691691) (xy 378.35326 -54.655998) (xy 378.399109 -54.62653)
			(xy 378.448684 -54.603887) (xy 378.500977 -54.588529) (xy 378.554923 -54.58077) (xy 378.582174 -54.580282)
			(xy 378.610265 -54.580797) (xy 378.665841 -54.589021) (xy 378.71961 -54.605308) (xy 378.770407 -54.629308)
			(xy 378.817134 -54.660499) (xy 378.85878 -54.698208) (xy 378.894443 -54.741619) (xy 378.909326 -54.765448)
			(xy 378.91466 -54.774338) (xy 378.931678 -54.78653) (xy 379.024896 -54.80685) (xy 379.04547 -54.802532)
			(xy 379.054106 -54.79669) (xy 379.078166 -54.780684) (xy 379.130099 -54.755343) (xy 379.185258 -54.738119)
			(xy 379.242383 -54.729406) (xy 379.271276 -54.728872) (xy 379.298527 -54.729378) (xy 379.352476 -54.737131)
			(xy 379.404772 -54.752483) (xy 379.45435 -54.775121) (xy 379.500203 -54.804585) (xy 379.541395 -54.840274)
			(xy 379.577089 -54.881462) (xy 379.606558 -54.927311) (xy 379.629202 -54.976887) (xy 379.64456 -55.029181)
			(xy 379.652319 -55.083129) (xy 379.652784 -55.11038) (xy 379.65231 -55.13775) (xy 379.644495 -55.191929)
			(xy 379.629008 -55.244432) (xy 379.606168 -55.294179) (xy 379.576445 -55.340146) (xy 379.558804 -55.361078)
			(xy 379.55855 -55.361332) (xy 379.55298 -55.36843) (xy 379.546724 -55.385338) (xy 379.546358 -55.394352)
			(xy 379.546358 -55.461408) (xy 379.546699 -55.470427) (xy 379.552956 -55.487344) (xy 379.55855 -55.494428)
			(xy 379.558804 -55.494428) (xy 379.558804 -55.494682) (xy 379.576424 -55.515631) (xy 379.606147 -55.561597)
			(xy 379.628992 -55.611341) (xy 379.644488 -55.66384) (xy 379.652318 -55.718016) (xy 379.65232 -55.772754)
			(xy 379.644495 -55.826931) (xy 379.629002 -55.879431) (xy 379.606162 -55.929177) (xy 379.576442 -55.975145)
			(xy 379.558804 -55.996078) (xy 379.55855 -55.996332) (xy 379.55298 -56.00343) (xy 379.546724 -56.020338)
			(xy 379.546358 -56.029352) (xy 379.546358 -56.096408) (xy 379.546699 -56.105427) (xy 379.552956 -56.122344)
			(xy 379.55855 -56.129428) (xy 379.558804 -56.129428) (xy 379.558804 -56.129682) (xy 379.576449 -56.15061)
			(xy 379.60616 -56.196584) (xy 379.628994 -56.246332) (xy 379.644484 -56.298834) (xy 379.652311 -56.353011)
			(xy 379.652784 -56.38038) (xy 379.652298 -56.407631) (xy 379.644542 -56.461579) (xy 379.629187 -56.513874)
			(xy 379.606545 -56.563451) (xy 379.577079 -56.609301) (xy 379.541388 -56.650492) (xy 379.500197 -56.686183)
			(xy 379.454347 -56.715649) (xy 379.40477 -56.738291) (xy 379.352475 -56.753646) (xy 379.298527 -56.761402)
			(xy 379.244025 -56.761402) (xy 379.190077 -56.753646) (xy 379.137782 -56.738291) (xy 379.088205 -56.715649)
			(xy 379.042355 -56.686183) (xy 379.001164 -56.650492) (xy 378.965473 -56.609301) (xy 378.936007 -56.563451)
			(xy 378.913365 -56.513874) (xy 378.89801 -56.461579) (xy 378.890254 -56.407631) (xy 378.889768 -56.38038)
			(xy 378.890206 -56.353009) (xy 378.898028 -56.298828) (xy 378.913523 -56.246324) (xy 378.936371 -56.196577)
			(xy 378.966103 -56.150612) (xy 378.983748 -56.129682) (xy 378.984002 -56.129428) (xy 378.989583 -56.122338)
			(xy 378.995833 -56.105424) (xy 378.996194 -56.096408) (xy 378.996194 -56.029352) (xy 378.995813 -56.020338)
			(xy 378.989582 -56.00342) (xy 378.984002 -55.996332) (xy 378.983748 -55.996332) (xy 378.983748 -55.996078)
			(xy 378.966087 -55.975162) (xy 378.936361 -55.929191) (xy 378.913516 -55.879443) (xy 378.89802 -55.826938)
			(xy 378.890193 -55.772757) (xy 378.890195 -55.718013) (xy 378.898027 -55.663833) (xy 378.913526 -55.611329)
			(xy 378.936376 -55.561582) (xy 378.966105 -55.515614) (xy 378.983748 -55.494682) (xy 378.984002 -55.494428)
			(xy 378.989583 -55.487338) (xy 378.995833 -55.470424) (xy 378.996194 -55.461408) (xy 378.996194 -55.394352)
			(xy 378.995813 -55.385338) (xy 378.989582 -55.36842) (xy 378.984002 -55.361332) (xy 378.983748 -55.360824)
			(xy 378.972801 -55.348092) (xy 378.952962 -55.320999) (xy 378.944124 -55.306722) (xy 378.93879 -55.297832)
			(xy 378.921772 -55.28564) (xy 378.828554 -55.26532) (xy 378.80798 -55.269638) (xy 378.799344 -55.27548)
			(xy 378.775268 -55.291461) (xy 378.723341 -55.316809) (xy 378.668187 -55.33404) (xy 378.611066 -55.342761)
			(xy 378.582174 -55.343298) (xy 378.554923 -55.34283) (xy 378.500977 -55.335071) (xy 378.448684 -55.319713)
			(xy 378.399109 -55.29707) (xy 378.35326 -55.267602) (xy 378.312072 -55.231909) (xy 378.276382 -55.190719)
			(xy 378.246918 -55.144868) (xy 378.224278 -55.095292) (xy 378.208924 -55.042998) (xy 378.201168 -54.989051)
			(xy 374.155125 -54.989051) (xy 373.925084 -55.219092) (xy 373.924576 -55.226458) (xy 373.924576 -55.722266)
			(xy 374.134124 -55.722266) (xy 374.138195 -55.666644) (xy 374.150321 -55.612207) (xy 374.170244 -55.560116)
			(xy 374.19754 -55.511481) (xy 374.231626 -55.467338) (xy 374.271775 -55.428629) (xy 374.317133 -55.396178)
			(xy 374.366733 -55.370677) (xy 374.419517 -55.35267) (xy 374.47436 -55.34254) (xy 374.530094 -55.340503)
			(xy 374.585531 -55.346603) (xy 374.639488 -55.360709) (xy 374.690817 -55.382521) (xy 374.738423 -55.411575)
			(xy 374.749569 -55.420851) (xy 376.524768 -55.420851) (xy 376.524768 -55.366349) (xy 376.532524 -55.312402)
			(xy 376.547878 -55.260108) (xy 376.570518 -55.210532) (xy 376.599982 -55.164681) (xy 376.635672 -55.123491)
			(xy 376.67686 -55.087798) (xy 376.722709 -55.05833) (xy 376.772284 -55.035687) (xy 376.824577 -55.020329)
			(xy 376.878523 -55.01257) (xy 376.905774 -55.012082) (xy 376.932087 -55.012572) (xy 376.984214 -55.019803)
			(xy 377.034856 -55.034118) (xy 377.083055 -55.055247) (xy 377.127899 -55.082788) (xy 377.16854 -55.116223)
			(xy 377.186698 -55.135272) (xy 377.194222 -55.142671) (xy 377.2135 -55.151198) (xy 377.224036 -55.151782)
			(xy 377.298712 -55.151782) (xy 377.309265 -55.151278) (xy 377.32856 -55.142726) (xy 377.33605 -55.135272)
			(xy 377.354183 -55.116194) (xy 377.394818 -55.08274) (xy 377.439663 -55.055184) (xy 377.487868 -55.03405)
			(xy 377.53852 -55.019738) (xy 377.590657 -55.012518) (xy 377.616974 -55.012082) (xy 377.644227 -55.012564)
			(xy 377.69818 -55.020317) (xy 377.750479 -55.035671) (xy 377.800061 -55.058311) (xy 377.845917 -55.087778)
			(xy 377.887111 -55.12347) (xy 377.922807 -55.164663) (xy 377.952276 -55.210516) (xy 377.97492 -55.260096)
			(xy 377.990277 -55.312395) (xy 377.998035 -55.366347) (xy 377.998035 -55.420853) (xy 377.990277 -55.474805)
			(xy 377.97492 -55.527104) (xy 377.952276 -55.576684) (xy 377.922807 -55.622537) (xy 377.887111 -55.66373)
			(xy 377.845917 -55.699422) (xy 377.800061 -55.728889) (xy 377.750479 -55.751529) (xy 377.69818 -55.766883)
			(xy 377.644227 -55.774636) (xy 377.616974 -55.775098) (xy 377.590659 -55.774649) (xy 377.53853 -55.76741)
			(xy 377.487887 -55.753088) (xy 377.439688 -55.731952) (xy 377.394845 -55.704402) (xy 377.354206 -55.670961)
			(xy 377.33605 -55.651908) (xy 377.328548 -55.644484) (xy 377.309253 -55.635972) (xy 377.298712 -55.635398)
			(xy 377.224036 -55.635398) (xy 377.213487 -55.635934) (xy 377.194192 -55.644464) (xy 377.186698 -55.651908)
			(xy 377.168538 -55.670959) (xy 377.127909 -55.704416) (xy 377.08307 -55.731976) (xy 377.03487 -55.753115)
			(xy 376.984223 -55.767433) (xy 376.93209 -55.774659) (xy 376.905774 -55.775098) (xy 376.878523 -55.77463)
			(xy 376.824577 -55.766871) (xy 376.772284 -55.751513) (xy 376.722709 -55.72887) (xy 376.67686 -55.699402)
			(xy 376.635672 -55.663709) (xy 376.599982 -55.622519) (xy 376.570518 -55.576668) (xy 376.547878 -55.527092)
			(xy 376.532524 -55.474798) (xy 376.524768 -55.420851) (xy 374.749569 -55.420851) (xy 374.781291 -55.44725)
			(xy 374.818508 -55.488787) (xy 374.849281 -55.5353) (xy 374.872953 -55.585797) (xy 374.889021 -55.639204)
			(xy 374.897141 -55.69438) (xy 374.89765 -55.722266) (xy 374.897141 -55.750152) (xy 374.889021 -55.805328)
			(xy 374.872953 -55.858735) (xy 374.849281 -55.909232) (xy 374.818508 -55.955745) (xy 374.781291 -55.997282)
			(xy 374.738423 -56.032957) (xy 374.690817 -56.062011) (xy 374.639488 -56.083823) (xy 374.585531 -56.097929)
			(xy 374.530094 -56.104029) (xy 374.47436 -56.101992) (xy 374.419517 -56.091862) (xy 374.366733 -56.073855)
			(xy 374.317133 -56.048354) (xy 374.271775 -56.015903) (xy 374.231626 -55.977194) (xy 374.19754 -55.933051)
			(xy 374.170244 -55.884416) (xy 374.150321 -55.832325) (xy 374.138195 -55.777888) (xy 374.134124 -55.722266)
			(xy 373.924576 -55.722266) (xy 373.924576 -56.570626) (xy 373.925268 -56.582494) (xy 373.936 -56.603675)
			(xy 373.94515 -56.611266) (xy 374.00992 -56.659272) (xy 374.018524 -56.665106) (xy 374.038718 -56.669947)
			(xy 374.049036 -56.66867) (xy 374.055894 -56.6674) (xy 374.059196 -56.666384) (xy 374.085705 -56.659027)
			(xy 374.140147 -56.651124) (xy 374.167654 -56.650636) (xy 374.167908 -56.650636) (xy 374.171718 -56.650636)
			(xy 374.174004 -56.650636) (xy 374.18391 -56.65089) (xy 374.188736 -56.651144) (xy 374.18899 -56.651144)
			(xy 374.215697 -56.65307) (xy 374.268221 -56.66347) (xy 374.318774 -56.681117) (xy 374.36636 -56.705664)
			(xy 374.410043 -56.736628) (xy 374.448963 -56.7734) (xy 374.482356 -56.815256) (xy 374.509563 -56.861372)
			(xy 374.53005 -56.910842) (xy 374.537224 -56.93664) (xy 374.539002 -56.943498) (xy 374.542304 -56.949086)
			(xy 374.549416 -56.958738) (xy 374.613424 -57.022492) (xy 374.61444 -57.023762) (xy 374.949466 -57.358788)
			(xy 374.956318 -57.366184) (xy 374.964062 -57.384783) (xy 374.964452 -57.394856) (xy 374.964452 -57.48528)
			(xy 378.906022 -57.48528) (xy 378.910093 -57.429658) (xy 378.922219 -57.375221) (xy 378.942142 -57.32313)
			(xy 378.969438 -57.274495) (xy 379.003524 -57.230352) (xy 379.043673 -57.191643) (xy 379.089031 -57.159192)
			(xy 379.138631 -57.133691) (xy 379.191415 -57.115684) (xy 379.246258 -57.105554) (xy 379.301992 -57.103517)
			(xy 379.357429 -57.109617) (xy 379.411386 -57.123723) (xy 379.462715 -57.145535) (xy 379.510321 -57.174589)
			(xy 379.553189 -57.210264) (xy 379.590406 -57.251801) (xy 379.621179 -57.298314) (xy 379.644851 -57.348811)
			(xy 379.660919 -57.402218) (xy 379.669039 -57.457394) (xy 379.669548 -57.48528) (xy 379.669039 -57.513166)
			(xy 379.660919 -57.568342) (xy 379.644851 -57.621749) (xy 379.621179 -57.672246) (xy 379.590406 -57.718759)
			(xy 379.553189 -57.760296) (xy 379.510321 -57.795971) (xy 379.462715 -57.825025) (xy 379.411386 -57.846837)
			(xy 379.357429 -57.860943) (xy 379.301992 -57.867043) (xy 379.246258 -57.865006) (xy 379.191415 -57.854876)
			(xy 379.138631 -57.836869) (xy 379.089031 -57.811368) (xy 379.043673 -57.778917) (xy 379.003524 -57.740208)
			(xy 378.969438 -57.696065) (xy 378.942142 -57.64743) (xy 378.922219 -57.595339) (xy 378.910093 -57.540902)
			(xy 378.906022 -57.48528) (xy 374.964452 -57.48528) (xy 374.964452 -57.796684) (xy 374.964561 -57.80103)
			(xy 374.966094 -57.809588) (xy 374.9675 -57.813702) (xy 374.975374 -57.836054) (xy 374.9802 -57.842404)
			(xy 374.999524 -57.869112) (xy 375.029662 -57.927735) (xy 375.040144 -57.95899) (xy 375.041922 -57.964832)
			(xy 375.048272 -57.9755) (xy 375.498868 -58.426096) (xy 375.5169 -58.444867) (xy 375.547479 -58.486984)
			(xy 375.571104 -58.53336) (xy 375.580163 -58.561224) (xy 380.86233 -58.561224) (xy 380.866401 -58.505602)
			(xy 380.878527 -58.451165) (xy 380.89845 -58.399074) (xy 380.925746 -58.350439) (xy 380.959832 -58.306296)
			(xy 380.999981 -58.267587) (xy 381.045339 -58.235136) (xy 381.094939 -58.209635) (xy 381.147723 -58.191628)
			(xy 381.202566 -58.181498) (xy 381.2583 -58.179461) (xy 381.313737 -58.185561) (xy 381.367694 -58.199667)
			(xy 381.419023 -58.221479) (xy 381.466629 -58.250533) (xy 381.509497 -58.286208) (xy 381.546714 -58.327745)
			(xy 381.577487 -58.374258) (xy 381.601159 -58.424755) (xy 381.617227 -58.478162) (xy 381.625347 -58.533338)
			(xy 381.625856 -58.561224) (xy 381.625347 -58.58911) (xy 381.617227 -58.644286) (xy 381.601159 -58.697693)
			(xy 381.577487 -58.74819) (xy 381.546714 -58.794703) (xy 381.509497 -58.83624) (xy 381.466629 -58.871915)
			(xy 381.419023 -58.900969) (xy 381.367694 -58.922781) (xy 381.313737 -58.936887) (xy 381.2583 -58.942987)
			(xy 381.202566 -58.94095) (xy 381.147723 -58.93082) (xy 381.094939 -58.912813) (xy 381.045339 -58.887312)
			(xy 380.999981 -58.854861) (xy 380.959832 -58.816152) (xy 380.925746 -58.772009) (xy 380.89845 -58.723374)
			(xy 380.878527 -58.671283) (xy 380.866401 -58.616846) (xy 380.86233 -58.561224) (xy 375.580163 -58.561224)
			(xy 375.587196 -58.582857) (xy 375.595359 -58.634261) (xy 375.595896 -58.660284) (xy 375.595896 -59.174634)
			(xy 379.393194 -59.174634) (xy 379.397265 -59.119012) (xy 379.409391 -59.064575) (xy 379.429314 -59.012484)
			(xy 379.45661 -58.963849) (xy 379.490696 -58.919706) (xy 379.530845 -58.880997) (xy 379.576203 -58.848546)
			(xy 379.625803 -58.823045) (xy 379.678587 -58.805038) (xy 379.73343 -58.794908) (xy 379.789164 -58.792871)
			(xy 379.844601 -58.798971) (xy 379.898558 -58.813077) (xy 379.949887 -58.834889) (xy 379.997493 -58.863943)
			(xy 380.040361 -58.899618) (xy 380.077578 -58.941155) (xy 380.108351 -58.987668) (xy 380.132023 -59.038165)
			(xy 380.148091 -59.091572) (xy 380.156211 -59.146748) (xy 380.15672 -59.174634) (xy 380.156211 -59.20252)
			(xy 380.148091 -59.257696) (xy 380.132023 -59.311103) (xy 380.108351 -59.3616) (xy 380.077578 -59.408113)
			(xy 380.040361 -59.44965) (xy 379.997493 -59.485325) (xy 379.949887 -59.514379) (xy 379.898558 -59.536191)
			(xy 379.844601 -59.550297) (xy 379.789164 -59.556397) (xy 379.73343 -59.55436) (xy 379.678587 -59.54423)
			(xy 379.625803 -59.526223) (xy 379.576203 -59.500722) (xy 379.530845 -59.468271) (xy 379.490696 -59.429562)
			(xy 379.45661 -59.385419) (xy 379.429314 -59.336784) (xy 379.409391 -59.284693) (xy 379.397265 -59.230256)
			(xy 379.393194 -59.174634) (xy 375.595896 -59.174634) (xy 375.595896 -60.633356) (xy 382.097024 -60.633356)
			(xy 382.101095 -60.577734) (xy 382.113221 -60.523297) (xy 382.133144 -60.471206) (xy 382.16044 -60.422571)
			(xy 382.194526 -60.378428) (xy 382.234675 -60.339719) (xy 382.280033 -60.307268) (xy 382.329633 -60.281767)
			(xy 382.382417 -60.26376) (xy 382.43726 -60.25363) (xy 382.492994 -60.251593) (xy 382.548431 -60.257693)
			(xy 382.602388 -60.271799) (xy 382.653717 -60.293611) (xy 382.701323 -60.322665) (xy 382.744191 -60.35834)
			(xy 382.781408 -60.399877) (xy 382.812181 -60.44639) (xy 382.835853 -60.496887) (xy 382.851921 -60.550294)
			(xy 382.860041 -60.60547) (xy 382.86055 -60.633356) (xy 382.860041 -60.661242) (xy 382.851921 -60.716418)
			(xy 382.835853 -60.769825) (xy 382.812181 -60.820322) (xy 382.781408 -60.866835) (xy 382.744191 -60.908372)
			(xy 382.701323 -60.944047) (xy 382.653717 -60.973101) (xy 382.602388 -60.994913) (xy 382.548431 -61.009019)
			(xy 382.492994 -61.015119) (xy 382.43726 -61.013082) (xy 382.382417 -61.002952) (xy 382.329633 -60.984945)
			(xy 382.280033 -60.959444) (xy 382.234675 -60.926993) (xy 382.194526 -60.888284) (xy 382.16044 -60.844141)
			(xy 382.133144 -60.795506) (xy 382.113221 -60.743415) (xy 382.101095 -60.688978) (xy 382.097024 -60.633356)
			(xy 375.595896 -60.633356) (xy 375.595896 -61.487812) (xy 380.60452 -61.487812) (xy 380.608591 -61.43219)
			(xy 380.620717 -61.377753) (xy 380.64064 -61.325662) (xy 380.667936 -61.277027) (xy 380.702022 -61.232884)
			(xy 380.742171 -61.194175) (xy 380.787529 -61.161724) (xy 380.837129 -61.136223) (xy 380.889913 -61.118216)
			(xy 380.944756 -61.108086) (xy 381.00049 -61.106049) (xy 381.055927 -61.112149) (xy 381.109884 -61.126255)
			(xy 381.161213 -61.148067) (xy 381.208819 -61.177121) (xy 381.251687 -61.212796) (xy 381.288904 -61.254333)
			(xy 381.319677 -61.300846) (xy 381.343349 -61.351343) (xy 381.359417 -61.40475) (xy 381.367537 -61.459926)
			(xy 381.368046 -61.487812) (xy 381.367537 -61.515698) (xy 381.359417 -61.570874) (xy 381.343349 -61.624281)
			(xy 381.319677 -61.674778) (xy 381.288904 -61.721291) (xy 381.251687 -61.762828) (xy 381.208819 -61.798503)
			(xy 381.161213 -61.827557) (xy 381.109884 -61.849369) (xy 381.055927 -61.863475) (xy 381.00049 -61.869575)
			(xy 380.944756 -61.867538) (xy 380.889913 -61.857408) (xy 380.837129 -61.839401) (xy 380.787529 -61.8139)
			(xy 380.742171 -61.781449) (xy 380.702022 -61.74274) (xy 380.667936 -61.698597) (xy 380.64064 -61.649962)
			(xy 380.620717 -61.597871) (xy 380.608591 -61.543434) (xy 380.60452 -61.487812) (xy 375.595896 -61.487812)
			(xy 375.595896 -62.121034) (xy 378.542294 -62.121034) (xy 378.546365 -62.065412) (xy 378.558491 -62.010975)
			(xy 378.578414 -61.958884) (xy 378.60571 -61.910249) (xy 378.639796 -61.866106) (xy 378.679945 -61.827397)
			(xy 378.725303 -61.794946) (xy 378.774903 -61.769445) (xy 378.827687 -61.751438) (xy 378.88253 -61.741308)
			(xy 378.938264 -61.739271) (xy 378.993701 -61.745371) (xy 379.047658 -61.759477) (xy 379.098987 -61.781289)
			(xy 379.146593 -61.810343) (xy 379.189461 -61.846018) (xy 379.226678 -61.887555) (xy 379.257451 -61.934068)
			(xy 379.281123 -61.984565) (xy 379.297191 -62.037972) (xy 379.305311 -62.093148) (xy 379.30582 -62.121034)
			(xy 379.305311 -62.14892) (xy 379.297191 -62.204096) (xy 379.281123 -62.257503) (xy 379.257451 -62.308)
			(xy 379.226678 -62.354513) (xy 379.189461 -62.39605) (xy 379.146593 -62.431725) (xy 379.098987 -62.460779)
			(xy 379.047658 -62.482591) (xy 378.993701 -62.496697) (xy 378.938264 -62.502797) (xy 378.88253 -62.50076)
			(xy 378.827687 -62.49063) (xy 378.774903 -62.472623) (xy 378.725303 -62.447122) (xy 378.679945 -62.414671)
			(xy 378.639796 -62.375962) (xy 378.60571 -62.331819) (xy 378.578414 -62.283184) (xy 378.558491 -62.231093)
			(xy 378.546365 -62.176656) (xy 378.542294 -62.121034) (xy 375.595896 -62.121034) (xy 375.595896 -62.778132)
			(xy 375.597166 -62.789308) (xy 375.600389 -62.800358) (xy 375.614774 -62.818288) (xy 375.624852 -62.823852)
			(xy 375.629424 -62.825884) (xy 375.719848 -62.858396) (xy 375.727265 -62.860688) (xy 375.742773 -62.861198)
			(xy 375.750328 -62.859412) (xy 375.757694 -62.85738) (xy 375.770648 -62.848998) (xy 375.775728 -62.842902)
			(xy 375.793941 -62.821671) (xy 375.835523 -62.784256) (xy 375.882124 -62.753316) (xy 375.932744 -62.729515)
			(xy 375.986298 -62.713363) (xy 376.041637 -62.705208) (xy 376.069606 -62.704726) (xy 376.096855 -62.705213)
			(xy 376.150797 -62.712969) (xy 376.203086 -62.728323) (xy 376.252658 -62.750963) (xy 376.298504 -62.780427)
			(xy 376.339689 -62.816115) (xy 376.375377 -62.857301) (xy 376.40484 -62.903147) (xy 376.427479 -62.95272)
			(xy 376.442832 -63.005009) (xy 376.450588 -63.058951) (xy 376.450588 -63.113449) (xy 376.442832 -63.167391)
			(xy 376.427479 -63.21968) (xy 376.40484 -63.269253) (xy 376.402154 -63.273432) (xy 377.876814 -63.273432)
			(xy 377.880885 -63.21781) (xy 377.893011 -63.163373) (xy 377.912934 -63.111282) (xy 377.94023 -63.062647)
			(xy 377.974316 -63.018504) (xy 378.014465 -62.979795) (xy 378.059823 -62.947344) (xy 378.109423 -62.921843)
			(xy 378.162207 -62.903836) (xy 378.21705 -62.893706) (xy 378.272784 -62.891669) (xy 378.328221 -62.897769)
			(xy 378.382178 -62.911875) (xy 378.433507 -62.933687) (xy 378.481113 -62.962741) (xy 378.523981 -62.998416)
			(xy 378.561198 -63.039953) (xy 378.591971 -63.086466) (xy 378.615643 -63.136963) (xy 378.631711 -63.19037)
			(xy 378.639831 -63.245546) (xy 378.64034 -63.273432) (xy 378.639831 -63.301318) (xy 378.631711 -63.356494)
			(xy 378.615643 -63.409901) (xy 378.591971 -63.460398) (xy 378.561198 -63.506911) (xy 378.523981 -63.548448)
			(xy 378.481113 -63.584123) (xy 378.433507 -63.613177) (xy 378.382178 -63.634989) (xy 378.328221 -63.649095)
			(xy 378.272784 -63.655195) (xy 378.21705 -63.653158) (xy 378.162207 -63.643028) (xy 378.109423 -63.625021)
			(xy 378.059823 -63.59952) (xy 378.014465 -63.567069) (xy 377.974316 -63.52836) (xy 377.94023 -63.484217)
			(xy 377.912934 -63.435582) (xy 377.893011 -63.383491) (xy 377.880885 -63.329054) (xy 377.876814 -63.273432)
			(xy 376.402154 -63.273432) (xy 376.375377 -63.315099) (xy 376.339689 -63.356285) (xy 376.298504 -63.391973)
			(xy 376.252658 -63.421437) (xy 376.203086 -63.444077) (xy 376.150797 -63.459431) (xy 376.096855 -63.467187)
			(xy 376.069606 -63.467742) (xy 376.041638 -63.467253) (xy 375.986302 -63.459089) (xy 375.93275 -63.442935)
			(xy 375.882129 -63.419137) (xy 375.835524 -63.388205) (xy 375.793934 -63.350802) (xy 375.775728 -63.329566)
			(xy 375.775474 -63.329312) (xy 375.770336 -63.323565) (xy 375.757408 -63.315181) (xy 375.750074 -63.312802)
			(xy 375.742708 -63.31077) (xy 375.727214 -63.311532) (xy 375.629424 -63.346584) (xy 375.624852 -63.348616)
			(xy 375.614675 -63.354052) (xy 375.600267 -63.372045) (xy 375.597166 -63.38316) (xy 375.595896 -63.394336)
			(xy 375.595896 -76.846938) (xy 375.59537 -76.872962) (xy 375.587205 -76.924368) (xy 375.571114 -76.973867)
			(xy 375.547491 -77.020247) (xy 375.516916 -77.06237) (xy 375.498868 -77.081126) (xy 372.25732 -80.32242)
			(xy 372.252973 -80.327113) (xy 372.246541 -80.338163) (xy 372.24462 -80.344264) (xy 372.242588 -80.358234)
			(xy 372.242588 -80.8228) (xy 377.396754 -80.8228) (xy 377.400825 -80.767178) (xy 377.412951 -80.712741)
			(xy 377.432874 -80.66065) (xy 377.46017 -80.612015) (xy 377.494256 -80.567872) (xy 377.534405 -80.529163)
			(xy 377.579763 -80.496712) (xy 377.629363 -80.471211) (xy 377.682147 -80.453204) (xy 377.73699 -80.443074)
			(xy 377.792724 -80.441037) (xy 377.848161 -80.447137) (xy 377.902118 -80.461243) (xy 377.953447 -80.483055)
			(xy 378.001053 -80.512109) (xy 378.043921 -80.547784) (xy 378.081138 -80.589321) (xy 378.111911 -80.635834)
			(xy 378.135583 -80.686331) (xy 378.151651 -80.739738) (xy 378.159771 -80.794914) (xy 378.16028 -80.8228)
			(xy 378.159771 -80.850686) (xy 378.151651 -80.905862) (xy 378.135583 -80.959269) (xy 378.111911 -81.009766)
			(xy 378.081138 -81.056279) (xy 378.043921 -81.097816) (xy 378.001053 -81.133491) (xy 377.953447 -81.162545)
			(xy 377.902118 -81.184357) (xy 377.848161 -81.198463) (xy 377.792724 -81.204563) (xy 377.73699 -81.202526)
			(xy 377.682147 -81.192396) (xy 377.629363 -81.174389) (xy 377.579763 -81.148888) (xy 377.534405 -81.116437)
			(xy 377.494256 -81.077728) (xy 377.46017 -81.033585) (xy 377.432874 -80.98495) (xy 377.412951 -80.932859)
			(xy 377.400825 -80.878422) (xy 377.396754 -80.8228) (xy 372.242588 -80.8228) (xy 372.242588 -81.9658)
			(xy 374.915428 -81.9658) (xy 374.919499 -81.910178) (xy 374.931625 -81.855741) (xy 374.951548 -81.80365)
			(xy 374.978844 -81.755015) (xy 375.01293 -81.710872) (xy 375.053079 -81.672163) (xy 375.098437 -81.639712)
			(xy 375.148037 -81.614211) (xy 375.200821 -81.596204) (xy 375.255664 -81.586074) (xy 375.311398 -81.584037)
			(xy 375.366835 -81.590137) (xy 375.420792 -81.604243) (xy 375.472121 -81.626055) (xy 375.519727 -81.655109)
			(xy 375.562595 -81.690784) (xy 375.599812 -81.732321) (xy 375.630585 -81.778834) (xy 375.654257 -81.829331)
			(xy 375.670325 -81.882738) (xy 375.678445 -81.937914) (xy 375.678954 -81.9658) (xy 377.153422 -81.9658)
			(xy 377.157493 -81.910178) (xy 377.169619 -81.855741) (xy 377.189542 -81.80365) (xy 377.216838 -81.755015)
			(xy 377.250924 -81.710872) (xy 377.291073 -81.672163) (xy 377.336431 -81.639712) (xy 377.386031 -81.614211)
			(xy 377.438815 -81.596204) (xy 377.493658 -81.586074) (xy 377.549392 -81.584037) (xy 377.604829 -81.590137)
			(xy 377.658786 -81.604243) (xy 377.710115 -81.626055) (xy 377.757721 -81.655109) (xy 377.800589 -81.690784)
			(xy 377.837806 -81.732321) (xy 377.868579 -81.778834) (xy 377.892251 -81.829331) (xy 377.908319 -81.882738)
			(xy 377.916439 -81.937914) (xy 377.916948 -81.9658) (xy 377.916439 -81.993686) (xy 377.908319 -82.048862)
			(xy 377.892251 -82.102269) (xy 377.868579 -82.152766) (xy 377.837806 -82.199279) (xy 377.800589 -82.240816)
			(xy 377.757721 -82.276491) (xy 377.710115 -82.305545) (xy 377.658786 -82.327357) (xy 377.604829 -82.341463)
			(xy 377.549392 -82.347563) (xy 377.493658 -82.345526) (xy 377.438815 -82.335396) (xy 377.386031 -82.317389)
			(xy 377.336431 -82.291888) (xy 377.291073 -82.259437) (xy 377.250924 -82.220728) (xy 377.216838 -82.176585)
			(xy 377.189542 -82.12795) (xy 377.169619 -82.075859) (xy 377.157493 -82.021422) (xy 377.153422 -81.9658)
			(xy 375.678954 -81.9658) (xy 375.678445 -81.993686) (xy 375.670325 -82.048862) (xy 375.654257 -82.102269)
			(xy 375.630585 -82.152766) (xy 375.599812 -82.199279) (xy 375.562595 -82.240816) (xy 375.519727 -82.276491)
			(xy 375.472121 -82.305545) (xy 375.420792 -82.327357) (xy 375.366835 -82.341463) (xy 375.311398 -82.347563)
			(xy 375.255664 -82.345526) (xy 375.200821 -82.335396) (xy 375.148037 -82.317389) (xy 375.098437 -82.291888)
			(xy 375.053079 -82.259437) (xy 375.01293 -82.220728) (xy 374.978844 -82.176585) (xy 374.951548 -82.12795)
			(xy 374.931625 -82.075859) (xy 374.919499 -82.021422) (xy 374.915428 -81.9658) (xy 372.242588 -81.9658)
			(xy 372.242588 -83.1088) (xy 374.915428 -83.1088) (xy 374.919499 -83.053178) (xy 374.931625 -82.998741)
			(xy 374.951548 -82.94665) (xy 374.978844 -82.898015) (xy 375.01293 -82.853872) (xy 375.053079 -82.815163)
			(xy 375.098437 -82.782712) (xy 375.148037 -82.757211) (xy 375.200821 -82.739204) (xy 375.255664 -82.729074)
			(xy 375.311398 -82.727037) (xy 375.366835 -82.733137) (xy 375.420792 -82.747243) (xy 375.472121 -82.769055)
			(xy 375.519727 -82.798109) (xy 375.562595 -82.833784) (xy 375.599812 -82.875321) (xy 375.630585 -82.921834)
			(xy 375.654257 -82.972331) (xy 375.670325 -83.025738) (xy 375.678445 -83.080914) (xy 375.678954 -83.1088)
			(xy 377.280422 -83.1088) (xy 377.284493 -83.053178) (xy 377.296619 -82.998741) (xy 377.316542 -82.94665)
			(xy 377.343838 -82.898015) (xy 377.377924 -82.853872) (xy 377.418073 -82.815163) (xy 377.463431 -82.782712)
			(xy 377.513031 -82.757211) (xy 377.565815 -82.739204) (xy 377.620658 -82.729074) (xy 377.676392 -82.727037)
			(xy 377.731829 -82.733137) (xy 377.785786 -82.747243) (xy 377.837115 -82.769055) (xy 377.884721 -82.798109)
			(xy 377.927589 -82.833784) (xy 377.964806 -82.875321) (xy 377.995579 -82.921834) (xy 378.019251 -82.972331)
			(xy 378.035319 -83.025738) (xy 378.043439 -83.080914) (xy 378.043948 -83.1088) (xy 378.043439 -83.136686)
			(xy 378.035319 -83.191862) (xy 378.019251 -83.245269) (xy 377.995579 -83.295766) (xy 377.964806 -83.342279)
			(xy 377.927589 -83.383816) (xy 377.884721 -83.419491) (xy 377.837115 -83.448545) (xy 377.785786 -83.470357)
			(xy 377.731829 -83.484463) (xy 377.676392 -83.490563) (xy 377.620658 -83.488526) (xy 377.565815 -83.478396)
			(xy 377.513031 -83.460389) (xy 377.463431 -83.434888) (xy 377.418073 -83.402437) (xy 377.377924 -83.363728)
			(xy 377.343838 -83.319585) (xy 377.316542 -83.27095) (xy 377.296619 -83.218859) (xy 377.284493 -83.164422)
			(xy 377.280422 -83.1088) (xy 375.678954 -83.1088) (xy 375.678445 -83.136686) (xy 375.670325 -83.191862)
			(xy 375.654257 -83.245269) (xy 375.630585 -83.295766) (xy 375.599812 -83.342279) (xy 375.562595 -83.383816)
			(xy 375.519727 -83.419491) (xy 375.472121 -83.448545) (xy 375.420792 -83.470357) (xy 375.366835 -83.484463)
			(xy 375.311398 -83.490563) (xy 375.255664 -83.488526) (xy 375.200821 -83.478396) (xy 375.148037 -83.460389)
			(xy 375.098437 -83.434888) (xy 375.053079 -83.402437) (xy 375.01293 -83.363728) (xy 374.978844 -83.319585)
			(xy 374.951548 -83.27095) (xy 374.931625 -83.218859) (xy 374.919499 -83.164422) (xy 374.915428 -83.1088)
			(xy 372.242588 -83.1088) (xy 372.242588 -84.2518) (xy 374.915428 -84.2518) (xy 374.919499 -84.196178)
			(xy 374.931625 -84.141741) (xy 374.951548 -84.08965) (xy 374.978844 -84.041015) (xy 375.01293 -83.996872)
			(xy 375.053079 -83.958163) (xy 375.098437 -83.925712) (xy 375.148037 -83.900211) (xy 375.200821 -83.882204)
			(xy 375.255664 -83.872074) (xy 375.311398 -83.870037) (xy 375.366835 -83.876137) (xy 375.420792 -83.890243)
			(xy 375.472121 -83.912055) (xy 375.519727 -83.941109) (xy 375.562595 -83.976784) (xy 375.599812 -84.018321)
			(xy 375.630585 -84.064834) (xy 375.654257 -84.115331) (xy 375.662608 -84.143088) (xy 377.35459 -84.143088)
			(xy 377.358661 -84.087466) (xy 377.370787 -84.033029) (xy 377.39071 -83.980938) (xy 377.418006 -83.932303)
			(xy 377.452092 -83.88816) (xy 377.492241 -83.849451) (xy 377.537599 -83.817) (xy 377.587199 -83.791499)
			(xy 377.639983 -83.773492) (xy 377.694826 -83.763362) (xy 377.75056 -83.761325) (xy 377.805997 -83.767425)
			(xy 377.859954 -83.781531) (xy 377.911283 -83.803343) (xy 377.958889 -83.832397) (xy 378.001757 -83.868072)
			(xy 378.038974 -83.909609) (xy 378.069747 -83.956122) (xy 378.093419 -84.006619) (xy 378.109487 -84.060026)
			(xy 378.117607 -84.115202) (xy 378.118116 -84.143088) (xy 378.117607 -84.170974) (xy 378.109487 -84.22615)
			(xy 378.093419 -84.279557) (xy 378.069747 -84.330054) (xy 378.038974 -84.376567) (xy 378.001757 -84.418104)
			(xy 377.958889 -84.453779) (xy 377.911283 -84.482833) (xy 377.859954 -84.504645) (xy 377.805997 -84.518751)
			(xy 377.75056 -84.524851) (xy 377.694826 -84.522814) (xy 377.639983 -84.512684) (xy 377.587199 -84.494677)
			(xy 377.537599 -84.469176) (xy 377.492241 -84.436725) (xy 377.452092 -84.398016) (xy 377.418006 -84.353873)
			(xy 377.39071 -84.305238) (xy 377.370787 -84.253147) (xy 377.358661 -84.19871) (xy 377.35459 -84.143088)
			(xy 375.662608 -84.143088) (xy 375.670325 -84.168738) (xy 375.678445 -84.223914) (xy 375.678954 -84.2518)
			(xy 375.678445 -84.279686) (xy 375.670325 -84.334862) (xy 375.654257 -84.388269) (xy 375.630585 -84.438766)
			(xy 375.599812 -84.485279) (xy 375.562595 -84.526816) (xy 375.519727 -84.562491) (xy 375.472121 -84.591545)
			(xy 375.420792 -84.613357) (xy 375.366835 -84.627463) (xy 375.311398 -84.633563) (xy 375.255664 -84.631526)
			(xy 375.200821 -84.621396) (xy 375.148037 -84.603389) (xy 375.098437 -84.577888) (xy 375.053079 -84.545437)
			(xy 375.01293 -84.506728) (xy 374.978844 -84.462585) (xy 374.951548 -84.41395) (xy 374.931625 -84.361859)
			(xy 374.919499 -84.307422) (xy 374.915428 -84.2518) (xy 372.242588 -84.2518) (xy 372.242588 -86.5378)
			(xy 374.915428 -86.5378) (xy 374.919499 -86.482178) (xy 374.931625 -86.427741) (xy 374.951548 -86.37565)
			(xy 374.978844 -86.327015) (xy 375.01293 -86.282872) (xy 375.053079 -86.244163) (xy 375.098437 -86.211712)
			(xy 375.148037 -86.186211) (xy 375.200821 -86.168204) (xy 375.255664 -86.158074) (xy 375.311398 -86.156037)
			(xy 375.366835 -86.162137) (xy 375.420792 -86.176243) (xy 375.472121 -86.198055) (xy 375.519727 -86.227109)
			(xy 375.562595 -86.262784) (xy 375.599812 -86.304321) (xy 375.630585 -86.350834) (xy 375.654257 -86.401331)
			(xy 375.666811 -86.443058) (xy 377.293884 -86.443058) (xy 377.297955 -86.387436) (xy 377.310081 -86.332999)
			(xy 377.330004 -86.280908) (xy 377.3573 -86.232273) (xy 377.391386 -86.18813) (xy 377.431535 -86.149421)
			(xy 377.476893 -86.11697) (xy 377.526493 -86.091469) (xy 377.579277 -86.073462) (xy 377.63412 -86.063332)
			(xy 377.689854 -86.061295) (xy 377.745291 -86.067395) (xy 377.799248 -86.081501) (xy 377.850577 -86.103313)
			(xy 377.898183 -86.132367) (xy 377.941051 -86.168042) (xy 377.978268 -86.209579) (xy 378.009041 -86.256092)
			(xy 378.032713 -86.306589) (xy 378.048781 -86.359996) (xy 378.056901 -86.415172) (xy 378.05741 -86.443058)
			(xy 378.056901 -86.470944) (xy 378.048781 -86.52612) (xy 378.032713 -86.579527) (xy 378.009041 -86.630024)
			(xy 377.978268 -86.676537) (xy 377.941051 -86.718074) (xy 377.898183 -86.753749) (xy 377.850577 -86.782803)
			(xy 377.799248 -86.804615) (xy 377.745291 -86.818721) (xy 377.689854 -86.824821) (xy 377.63412 -86.822784)
			(xy 377.579277 -86.812654) (xy 377.526493 -86.794647) (xy 377.476893 -86.769146) (xy 377.431535 -86.736695)
			(xy 377.391386 -86.697986) (xy 377.3573 -86.653843) (xy 377.330004 -86.605208) (xy 377.310081 -86.553117)
			(xy 377.297955 -86.49868) (xy 377.293884 -86.443058) (xy 375.666811 -86.443058) (xy 375.670325 -86.454738)
			(xy 375.678445 -86.509914) (xy 375.678954 -86.5378) (xy 375.678445 -86.565686) (xy 375.670325 -86.620862)
			(xy 375.654257 -86.674269) (xy 375.630585 -86.724766) (xy 375.599812 -86.771279) (xy 375.562595 -86.812816)
			(xy 375.519727 -86.848491) (xy 375.472121 -86.877545) (xy 375.420792 -86.899357) (xy 375.366835 -86.913463)
			(xy 375.311398 -86.919563) (xy 375.255664 -86.917526) (xy 375.200821 -86.907396) (xy 375.148037 -86.889389)
			(xy 375.098437 -86.863888) (xy 375.053079 -86.831437) (xy 375.01293 -86.792728) (xy 374.978844 -86.748585)
			(xy 374.951548 -86.69995) (xy 374.931625 -86.647859) (xy 374.919499 -86.593422) (xy 374.915428 -86.5378)
			(xy 372.242588 -86.5378) (xy 372.242588 -87.6808) (xy 374.915428 -87.6808) (xy 374.919499 -87.625178)
			(xy 374.931625 -87.570741) (xy 374.951548 -87.51865) (xy 374.978844 -87.470015) (xy 375.01293 -87.425872)
			(xy 375.053079 -87.387163) (xy 375.098437 -87.354712) (xy 375.148037 -87.329211) (xy 375.200821 -87.311204)
			(xy 375.255664 -87.301074) (xy 375.311398 -87.299037) (xy 375.366835 -87.305137) (xy 375.420792 -87.319243)
			(xy 375.472121 -87.341055) (xy 375.519727 -87.370109) (xy 375.562595 -87.405784) (xy 375.599812 -87.447321)
			(xy 375.630585 -87.493834) (xy 375.654257 -87.544331) (xy 375.670325 -87.597738) (xy 375.678445 -87.652914)
			(xy 375.678954 -87.6808) (xy 375.678445 -87.708686) (xy 375.670325 -87.763862) (xy 375.654257 -87.817269)
			(xy 375.630585 -87.867766) (xy 375.599812 -87.914279) (xy 375.562595 -87.955816) (xy 375.519727 -87.991491)
			(xy 375.472121 -88.020545) (xy 375.420792 -88.042357) (xy 375.366835 -88.056463) (xy 375.311398 -88.062563)
			(xy 375.255664 -88.060526) (xy 375.200821 -88.050396) (xy 375.148037 -88.032389) (xy 375.098437 -88.006888)
			(xy 375.053079 -87.974437) (xy 375.01293 -87.935728) (xy 374.978844 -87.891585) (xy 374.951548 -87.84295)
			(xy 374.931625 -87.790859) (xy 374.919499 -87.736422) (xy 374.915428 -87.6808) (xy 372.242588 -87.6808)
			(xy 372.242588 -92.58935) (xy 372.24716 -92.594684) (xy 372.437914 -92.785438) (xy 372.443344 -92.790419)
			(xy 372.456383 -92.797269) (xy 372.463568 -92.7989) (xy 372.464076 -92.7989) (xy 372.473474 -92.799916)
			(xy 373.740426 -92.799916) (xy 373.747284 -92.799408) (xy 375.047002 -91.49969) (xy 375.04751 -91.49461)
			(xy 375.047256 -91.456256) (xy 375.047002 -91.430348) (xy 375.046883 -91.425252) (xy 375.044824 -91.415272)
			(xy 375.042938 -91.410536) (xy 375.031508 -91.383866) (xy 375.024904 -91.377008) (xy 375.02465 -91.376754)
			(xy 375.004381 -91.355213) (xy 374.970066 -91.30704) (xy 374.94359 -91.254151) (xy 374.925584 -91.197813)
			(xy 374.91648 -91.139373) (xy 374.915938 -91.1098) (xy 374.916401 -91.082548) (xy 374.924159 -91.0286)
			(xy 374.939515 -90.976305) (xy 374.962158 -90.926727) (xy 374.991627 -90.880878) (xy 375.027321 -90.839689)
			(xy 375.068514 -90.803999) (xy 375.114368 -90.774536) (xy 375.163948 -90.751899) (xy 375.216245 -90.736549)
			(xy 375.270194 -90.728798) (xy 375.297446 -90.728292) (xy 375.299986 -90.728292) (xy 375.300494 -90.728292)
			(xy 375.301764 -90.728292) (xy 375.311924 -90.728546) (xy 375.325894 -90.726006) (xy 375.32818 -90.725244)
			(xy 375.332782 -90.723367) (xy 375.341225 -90.718127) (xy 375.344944 -90.71483) (xy 375.36755 -90.694002)
			(xy 375.3739 -90.68689) (xy 375.3739 -90.389456) (xy 375.36755 -90.382344) (xy 375.344436 -90.361262)
			(xy 375.337209 -90.355175) (xy 375.319589 -90.348395) (xy 375.310146 -90.348054) (xy 375.308876 -90.348054)
			(xy 375.300494 -90.348308) (xy 375.297446 -90.348308) (xy 375.270191 -90.347848) (xy 375.216235 -90.340096)
			(xy 375.163932 -90.324744) (xy 375.114346 -90.302104) (xy 375.068487 -90.272637) (xy 375.027289 -90.236944)
			(xy 374.99159 -90.19575) (xy 374.962118 -90.149895) (xy 374.939472 -90.100311) (xy 374.924114 -90.04801)
			(xy 374.916355 -89.994055) (xy 374.916355 -89.939545) (xy 374.924114 -89.88559) (xy 374.939472 -89.833289)
			(xy 374.962118 -89.783705) (xy 374.99159 -89.73785) (xy 375.027289 -89.696656) (xy 375.068487 -89.660963)
			(xy 375.114346 -89.631496) (xy 375.163932 -89.608856) (xy 375.216235 -89.593504) (xy 375.270191 -89.585752)
			(xy 375.297446 -89.585292) (xy 375.299986 -89.585292) (xy 375.300494 -89.585292) (xy 375.301764 -89.585292)
			(xy 375.311924 -89.585546) (xy 375.325894 -89.583006) (xy 375.32818 -89.582244) (xy 375.332782 -89.580367)
			(xy 375.341225 -89.575127) (xy 375.344944 -89.57183) (xy 375.36755 -89.551002) (xy 375.3739 -89.54389)
			(xy 375.3739 -89.246456) (xy 375.367296 -89.239344) (xy 375.338086 -89.212928) (xy 375.336816 -89.211658)
			(xy 375.318782 -89.2048) (xy 375.30913 -89.205054) (xy 375.308622 -89.205054) (xy 375.303542 -89.205308)
			(xy 375.299732 -89.205308) (xy 375.299224 -89.205308) (xy 375.296176 -89.205308) (xy 375.26904 -89.204743)
			(xy 375.215336 -89.196878) (xy 375.163289 -89.181482) (xy 375.11395 -89.158864) (xy 375.068314 -89.129482)
			(xy 375.027303 -89.093929) (xy 374.991745 -89.052923) (xy 374.962358 -89.007291) (xy 374.939734 -88.957954)
			(xy 374.924331 -88.905909) (xy 374.91646 -88.852207) (xy 374.915938 -88.82507) (xy 374.915938 -88.815926)
			(xy 374.917005 -88.788237) (xy 374.92615 -88.733586) (xy 374.943104 -88.680834) (xy 374.96751 -88.631088)
			(xy 374.998856 -88.585396) (xy 375.036481 -88.544719) (xy 375.079595 -88.509912) (xy 375.12729 -88.481707)
			(xy 375.178563 -88.460698) (xy 375.232336 -88.447327) (xy 375.259854 -88.44407) (xy 375.260108 -88.44407)
			(xy 375.262648 -88.443816) (xy 375.268236 -88.443308) (xy 375.26849 -88.443308) (xy 375.275348 -88.4428)
			(xy 375.28627 -88.442292) (xy 375.293128 -88.442292) (xy 375.297192 -88.442292) (xy 375.2977 -88.442292)
			(xy 375.327534 -88.44287) (xy 375.386474 -88.452164) (xy 375.443246 -88.470525) (xy 375.496466 -88.497505)
			(xy 375.544834 -88.532446) (xy 375.566432 -88.553036) (xy 375.579364 -88.566171) (xy 375.602904 -88.594541)
			(xy 375.613422 -88.609678) (xy 375.615962 -88.613742) (xy 375.630186 -88.627966) (xy 375.635439 -88.631301)
			(xy 375.64713 -88.635547) (xy 375.6533 -88.636348) (xy 375.694956 -88.640412) (xy 375.695464 -88.640412)
			(xy 375.708926 -88.641936) (xy 375.709434 -88.641936) (xy 375.73077 -88.644222) (xy 375.7422 -88.645492)
			(xy 377.121166 -87.266526) (xy 377.144731 -87.24363) (xy 377.196115 -87.20268) (xy 377.251759 -87.167735)
			(xy 377.310962 -87.139235) (xy 377.372982 -87.117538) (xy 377.437041 -87.102915) (xy 377.502333 -87.095552)
			(xy 377.535186 -87.095076) (xy 377.53544 -87.095076) (xy 377.570836 -87.095612) (xy 377.641111 -87.10415)
			(xy 377.709845 -87.121095) (xy 377.776035 -87.146202) (xy 377.838717 -87.179104) (xy 377.896975 -87.21932)
			(xy 377.949962 -87.266266) (xy 377.996904 -87.319256) (xy 378.037117 -87.377518) (xy 378.070014 -87.440201)
			(xy 378.095116 -87.506393) (xy 378.112057 -87.575128) (xy 378.12059 -87.645404) (xy 378.121164 -87.6808)
			(xy 378.121164 -87.681054) (xy 378.120723 -87.713909) (xy 378.11337 -87.779207) (xy 378.098753 -87.843271)
			(xy 378.077054 -87.905296) (xy 378.048547 -87.964501) (xy 378.01359 -88.020142) (xy 377.972623 -88.071518)
			(xy 377.949714 -88.095074) (xy 377.826524 -88.21801) (xy 377.82627 -88.230964) (xy 377.82881 -88.255602)
			(xy 377.82881 -88.25611) (xy 377.83389 -88.300814) (xy 377.834775 -88.30536) (xy 377.837962 -88.314054)
			(xy 377.84024 -88.318086) (xy 377.845066 -88.326214) (xy 377.855988 -88.333326) (xy 377.886097 -88.353668)
			(xy 377.941528 -88.400653) (xy 377.990722 -88.454133) (xy 378.032924 -88.513287) (xy 378.067485 -88.577206)
			(xy 378.093875 -88.64491) (xy 378.111688 -88.715358) (xy 378.120651 -88.787467) (xy 378.121164 -88.8238)
			(xy 378.120737 -88.856674) (xy 378.113405 -88.922012) (xy 378.098802 -88.986118) (xy 378.077109 -89.048184)
			(xy 378.048601 -89.10743) (xy 378.013636 -89.16311) (xy 377.972654 -89.214523) (xy 377.949714 -89.238074)
			(xy 377.231148 -89.95664) (xy 377.228443 -89.959492) (xy 377.223854 -89.965872) (xy 377.222004 -89.96934)
			(xy 377.21942 -89.974767) (xy 377.216596 -89.986446) (xy 377.216416 -89.992454) (xy 377.216416 -91.395296)
			(xy 377.215934 -91.428172) (xy 377.208535 -91.493506) (xy 377.193874 -91.557603) (xy 377.172135 -91.619658)
			(xy 377.14359 -91.678891) (xy 377.108599 -91.73456) (xy 377.067601 -91.785965) (xy 377.044712 -91.80957)
			(xy 375.459498 -93.39453) (xy 375.456795 -93.397383) (xy 375.452208 -93.403765) (xy 375.450354 -93.40723)
			(xy 375.447767 -93.412656) (xy 375.444937 -93.424336) (xy 375.444766 -93.430344) (xy 375.444766 -93.603064)
			(xy 375.71629 -93.603064) (xy 375.720361 -93.547442) (xy 375.732487 -93.493005) (xy 375.75241 -93.440914)
			(xy 375.779706 -93.392279) (xy 375.813792 -93.348136) (xy 375.853941 -93.309427) (xy 375.899299 -93.276976)
			(xy 375.948899 -93.251475) (xy 376.001683 -93.233468) (xy 376.056526 -93.223338) (xy 376.11226 -93.221301)
			(xy 376.167697 -93.227401) (xy 376.221654 -93.241507) (xy 376.272983 -93.263319) (xy 376.320589 -93.292373)
			(xy 376.363457 -93.328048) (xy 376.400674 -93.369585) (xy 376.431447 -93.416098) (xy 376.455119 -93.466595)
			(xy 376.471187 -93.520002) (xy 376.479307 -93.575178) (xy 376.479816 -93.603064) (xy 376.479307 -93.63095)
			(xy 376.471187 -93.686126) (xy 376.455119 -93.739533) (xy 376.431447 -93.79003) (xy 376.400674 -93.836543)
			(xy 376.363457 -93.87808) (xy 376.320589 -93.913755) (xy 376.272983 -93.942809) (xy 376.221654 -93.964621)
			(xy 376.167697 -93.978727) (xy 376.11226 -93.984827) (xy 376.056526 -93.98279) (xy 376.001683 -93.97266)
			(xy 375.948899 -93.954653) (xy 375.899299 -93.929152) (xy 375.853941 -93.896701) (xy 375.813792 -93.857992)
			(xy 375.779706 -93.813849) (xy 375.75241 -93.765214) (xy 375.732487 -93.713123) (xy 375.720361 -93.658686)
			(xy 375.71629 -93.603064) (xy 375.444766 -93.603064) (xy 375.444766 -94.410022) (xy 375.445782 -94.41942)
			(xy 375.445782 -94.419928) (xy 375.447491 -94.427085) (xy 375.45433 -94.440105) (xy 375.459244 -94.445582)
			(xy 375.553986 -94.540324) (xy 375.559419 -94.545299) (xy 375.572461 -94.552132) (xy 375.57964 -94.553786)
			(xy 375.580148 -94.553786) (xy 375.589546 -94.554802) (xy 376.935746 -94.554802) (xy 376.945376 -94.55433)
			(xy 376.963252 -94.547142) (xy 376.970544 -94.540832) (xy 377.442984 -94.068646) (xy 377.445016 -94.06636)
			(xy 377.446286 -94.06509) (xy 377.451719 -94.05783) (xy 377.457538 -94.04067) (xy 377.457003 -94.022557)
			(xy 377.453906 -94.014036) (xy 377.448318 -94.001336) (xy 377.446032 -93.995494) (xy 377.439936 -93.985842)
			(xy 377.43892 -93.984318) (xy 377.438412 -93.98381) (xy 377.434348 -93.97873) (xy 377.427998 -93.974412)
			(xy 377.40352 -93.95713) (xy 377.359133 -93.91688) (xy 377.320748 -93.870871) (xy 377.289107 -93.819988)
			(xy 377.264819 -93.765212) (xy 377.248352 -93.7076) (xy 377.240024 -93.648263) (xy 377.23953 -93.618304)
			(xy 377.239991 -93.590115) (xy 377.247348 -93.534218) (xy 377.261939 -93.47976) (xy 377.283513 -93.427672)
			(xy 377.3117 -93.378846) (xy 377.346019 -93.334116) (xy 377.385883 -93.294248) (xy 377.430609 -93.259925)
			(xy 377.479433 -93.231732) (xy 377.531518 -93.210153) (xy 377.585975 -93.195557) (xy 377.641871 -93.188193)
			(xy 377.67006 -93.187774) (xy 377.70014 -93.188295) (xy 377.759715 -93.196657) (xy 377.817549 -93.213225)
			(xy 377.872515 -93.237676) (xy 377.923546 -93.269536) (xy 377.96965 -93.308183) (xy 378.00993 -93.352868)
			(xy 378.027184 -93.377512) (xy 378.029724 -93.381576) (xy 378.04471 -93.396562) (xy 378.046742 -93.397832)
			(xy 378.051822 -93.40088) (xy 378.063252 -93.404182) (xy 378.074682 -93.404944) (xy 378.082556 -93.405452)
			(xy 378.091573 -93.405494) (xy 378.108741 -93.400019) (xy 378.116084 -93.394784) (xy 378.120656 -93.39072)
			(xy 378.850652 -92.660724) (xy 378.855224 -92.65539) (xy 378.855224 -77.635862) (xy 378.85497 -77.630528)
			(xy 378.853736 -77.622172) (xy 378.846606 -77.606873) (xy 378.841 -77.600556) (xy 378.38126 -77.14107)
			(xy 378.363229 -77.122299) (xy 378.332652 -77.080182) (xy 378.309029 -77.033805) (xy 378.292941 -76.984308)
			(xy 378.284783 -76.932905) (xy 378.284232 -76.906882) (xy 378.284232 -68.407788) (xy 378.284756 -68.381763)
			(xy 378.292918 -68.330356) (xy 378.309007 -68.280855) (xy 378.332629 -68.234473) (xy 378.363205 -68.192349)
			(xy 378.38126 -68.1736) (xy 380.905004 -65.649856) (xy 380.905871 -65.642677) (xy 380.903944 -65.62835)
			(xy 380.901194 -65.621662) (xy 380.88189 -65.578482) (xy 380.861062 -65.532) (xy 380.857664 -65.526016)
			(xy 380.848272 -65.515964) (xy 380.84252 -65.512188) (xy 380.835916 -65.508124) (xy 380.82093 -65.504314)
			(xy 380.815342 -65.504568) (xy 380.813056 -65.504822) (xy 380.789434 -65.505584) (xy 380.762183 -65.505123)
			(xy 380.708234 -65.497371) (xy 380.655938 -65.482021) (xy 380.606359 -65.459384) (xy 380.560506 -65.429922)
			(xy 380.519312 -65.394233) (xy 380.483617 -65.353046) (xy 380.454147 -65.307198) (xy 380.431502 -65.257623)
			(xy 380.416142 -65.205329) (xy 380.408381 -65.151382) (xy 380.408377 -65.096879) (xy 380.416129 -65.042931)
			(xy 380.43148 -64.990635) (xy 380.454118 -64.941056) (xy 380.48358 -64.895203) (xy 380.519269 -64.85401)
			(xy 380.560457 -64.818315) (xy 380.606305 -64.788846) (xy 380.65588 -64.766201) (xy 380.708174 -64.750842)
			(xy 380.762121 -64.743081) (xy 380.816624 -64.743077) (xy 380.870572 -64.75083) (xy 380.922868 -64.766182)
			(xy 380.972447 -64.788819) (xy 381.0183 -64.818282) (xy 381.059492 -64.853971) (xy 381.095187 -64.895159)
			(xy 381.124656 -64.941008) (xy 381.147301 -64.990584) (xy 381.162659 -65.042877) (xy 381.170419 -65.096825)
			(xy 381.170942 -65.124076) (xy 381.17018 -65.149476) (xy 381.169926 -65.15354) (xy 381.171196 -65.160398)
			(xy 381.172466 -65.165732) (xy 381.173736 -65.169034) (xy 381.177379 -65.177521) (xy 381.189619 -65.191331)
			(xy 381.197612 -65.195958) (xy 381.288544 -65.236852) (xy 381.294881 -65.239147) (xy 381.308266 -65.240687)
			(xy 381.31496 -65.2399) (xy 381.727202 -64.827658) (xy 382.56464 -63.990474) (xy 382.569713 -63.985007)
			(xy 382.576694 -63.971836) (xy 382.578356 -63.964566) (xy 382.579372 -63.95466) (xy 382.579372 -63.136272)
			(xy 382.578864 -63.135002) (xy 382.568958 -63.127636) (xy 382.568704 -63.127636) (xy 382.52146 -63.092076)
			(xy 382.502918 -63.078106) (xy 382.501394 -63.07709) (xy 382.495806 -63.074042) (xy 382.489764 -63.071328)
			(xy 382.476773 -63.068762) (xy 382.470152 -63.068962) (xy 382.462786 -63.069978) (xy 382.458214 -63.071248)
			(xy 382.431232 -63.078878) (xy 382.37576 -63.087045) (xy 382.347724 -63.087504) (xy 382.347216 -63.087504)
			(xy 382.319963 -63.087042) (xy 382.26601 -63.079287) (xy 382.213711 -63.063932) (xy 382.164129 -63.04129)
			(xy 382.118274 -63.011823) (xy 382.07708 -62.976129) (xy 382.041385 -62.934936) (xy 382.011915 -62.889082)
			(xy 381.989272 -62.839501) (xy 381.973916 -62.787202) (xy 381.966159 -62.733249) (xy 381.965708 -62.705996)
			(xy 381.966193 -62.678768) (xy 381.973937 -62.624867) (xy 381.989267 -62.572614) (xy 382.011871 -62.523072)
			(xy 382.041291 -62.477248) (xy 382.076927 -62.436073) (xy 382.118057 -62.400384) (xy 382.163843 -62.370906)
			(xy 382.213356 -62.348238) (xy 382.265589 -62.332841) (xy 382.319481 -62.325028) (xy 382.346708 -62.324488)
			(xy 382.34874 -62.324488) (xy 382.373291 -62.324984) (xy 382.421963 -62.331502) (xy 382.4694 -62.344196)
			(xy 382.49225 -62.35319) (xy 382.496822 -62.354968) (xy 382.506728 -62.357) (xy 382.514558 -62.358326)
			(xy 382.530338 -62.356638) (xy 382.537716 -62.353698) (xy 382.53797 -62.353444) (xy 382.542288 -62.351412)
			(xy 382.547993 -62.348) (xy 382.557522 -62.338737) (xy 382.561084 -62.333124) (xy 382.563878 -62.327028)
			(xy 382.575308 -62.300358) (xy 382.576757 -62.296821) (xy 382.578668 -62.289421) (xy 382.579118 -62.285626)
			(xy 382.579372 -62.280546) (xy 382.579372 -62.24016) (xy 382.576578 -62.234826) (xy 382.568671 -62.220001)
			(xy 382.55519 -62.189222) (xy 382.549654 -62.173358) (xy 382.540473 -62.144361) (xy 382.530387 -62.084383)
			(xy 382.529588 -62.053978) (xy 382.529588 -62.04712) (xy 382.530351 -62.020218) (xy 382.538511 -61.967023)
			(xy 382.554066 -61.915502) (xy 382.576706 -61.866678) (xy 382.605982 -61.82152) (xy 382.641313 -61.780924)
			(xy 382.681999 -61.745696) (xy 382.727232 -61.716535) (xy 382.776113 -61.69402) (xy 382.827674 -61.678597)
			(xy 382.88089 -61.670573) (xy 382.907794 -61.66993) (xy 382.916938 -61.66993) (xy 382.947046 -61.670795)
			(xy 383.006429 -61.680852) (xy 383.063492 -61.700124) (xy 383.09042 -61.713618) (xy 383.095952 -61.716309)
			(xy 383.107893 -61.719253) (xy 383.114042 -61.71946) (xy 383.261616 -61.71946) (xy 383.271268 -61.718444)
			(xy 383.27851 -61.716814) (xy 383.291674 -61.709967) (xy 383.297176 -61.704982) (xy 383.828036 -61.174122)
			(xy 383.828544 -61.166756) (xy 383.828544 -58.870596) (xy 383.828127 -58.861785) (xy 383.822089 -58.845224)
			(xy 383.810823 -58.831667) (xy 383.803398 -58.826908) (xy 383.7305 -58.784236) (xy 383.725007 -58.781385)
			(xy 383.71306 -58.778165) (xy 383.706878 -58.777886) (xy 383.693416 -58.777886) (xy 383.681478 -58.784744)
			(xy 383.659625 -58.79673) (xy 383.613494 -58.8156) (xy 383.565318 -58.828378) (xy 383.515898 -58.834852)
			(xy 383.490978 -58.83529) (xy 383.463436 -58.834797) (xy 383.408914 -58.826955) (xy 383.356062 -58.811434)
			(xy 383.305957 -58.788549) (xy 383.259619 -58.758767) (xy 383.217991 -58.722694) (xy 383.18192 -58.681063)
			(xy 383.15214 -58.634723) (xy 383.129258 -58.584617) (xy 383.11374 -58.531765) (xy 383.105901 -58.477242)
			(xy 383.105901 -58.422158) (xy 383.11374 -58.367635) (xy 383.129258 -58.314783) (xy 383.15214 -58.264677)
			(xy 383.18192 -58.218337) (xy 383.217991 -58.176706) (xy 383.259619 -58.140633) (xy 383.305957 -58.110851)
			(xy 383.356062 -58.087966) (xy 383.408914 -58.072445) (xy 383.463436 -58.064603) (xy 383.490978 -58.064146)
			(xy 383.491232 -58.064146) (xy 383.516148 -58.064517) (xy 383.565568 -58.070904) (xy 383.613749 -58.083621)
			(xy 383.659885 -58.102453) (xy 383.681732 -58.114438) (xy 383.685796 -58.116724) (xy 383.691044 -58.118942)
			(xy 383.702197 -58.121249) (xy 383.707894 -58.121296) (xy 383.720848 -58.121042) (xy 383.743962 -58.107326)
			(xy 383.74447 -58.107326) (xy 383.803652 -58.072274) (xy 383.809748 -58.067956) (xy 383.818144 -58.060339)
			(xy 383.827895 -58.039904) (xy 383.828544 -58.028586) (xy 383.828544 -54.858412) (xy 383.828 -54.854676)
			(xy 383.825956 -54.847409) (xy 383.82448 -54.843934) (xy 383.793492 -54.83098) (xy 383.782251 -54.827991)
			(xy 383.75925 -54.83131) (xy 383.749296 -54.83733) (xy 383.74193 -54.843426) (xy 380.718291 -57.867296)
			(xy 381.9431 -57.867296) (xy 381.947171 -57.811674) (xy 381.959297 -57.757237) (xy 381.97922 -57.705146)
			(xy 382.006516 -57.656511) (xy 382.040602 -57.612368) (xy 382.080751 -57.573659) (xy 382.126109 -57.541208)
			(xy 382.175709 -57.515707) (xy 382.228493 -57.4977) (xy 382.283336 -57.48757) (xy 382.33907 -57.485533)
			(xy 382.394507 -57.491633) (xy 382.448464 -57.505739) (xy 382.499793 -57.527551) (xy 382.547399 -57.556605)
			(xy 382.590267 -57.59228) (xy 382.627484 -57.633817) (xy 382.658257 -57.68033) (xy 382.681929 -57.730827)
			(xy 382.697997 -57.784234) (xy 382.706117 -57.83941) (xy 382.706626 -57.867296) (xy 382.706117 -57.895182)
			(xy 382.697997 -57.950358) (xy 382.681929 -58.003765) (xy 382.658257 -58.054262) (xy 382.627484 -58.100775)
			(xy 382.590267 -58.142312) (xy 382.547399 -58.177987) (xy 382.499793 -58.207041) (xy 382.448464 -58.228853)
			(xy 382.394507 -58.242959) (xy 382.33907 -58.249059) (xy 382.283336 -58.247022) (xy 382.228493 -58.236892)
			(xy 382.175709 -58.218885) (xy 382.126109 -58.193384) (xy 382.080751 -58.160933) (xy 382.040602 -58.122224)
			(xy 382.006516 -58.078081) (xy 381.97922 -58.029446) (xy 381.959297 -57.977355) (xy 381.947171 -57.922918)
			(xy 381.9431 -57.867296) (xy 380.718291 -57.867296) (xy 380.412752 -58.172858) (xy 380.406402 -58.183526)
			(xy 380.404624 -58.189368) (xy 380.396175 -58.214935) (xy 380.373095 -58.263583) (xy 380.343409 -58.308506)
			(xy 380.307705 -58.348812) (xy 380.266693 -58.383702) (xy 380.221185 -58.412484) (xy 380.172086 -58.434586)
			(xy 380.120367 -58.449571) (xy 380.067057 -58.457141) (xy 380.040134 -58.457592) (xy 380.01288 -58.457131)
			(xy 379.958926 -58.449378) (xy 379.906625 -58.434025) (xy 379.857042 -58.411384) (xy 379.811186 -58.381916)
			(xy 379.76999 -58.346223) (xy 379.734294 -58.305029) (xy 379.704825 -58.259174) (xy 379.682182 -58.209592)
			(xy 379.666826 -58.157291) (xy 379.65907 -58.103338) (xy 379.658626 -58.076084) (xy 379.658372 -58.076084)
			(xy 379.658829 -58.049149) (xy 379.666395 -57.995812) (xy 379.681389 -57.94407) (xy 379.703511 -57.894952)
			(xy 379.732323 -57.849434) (xy 379.767251 -57.808421) (xy 379.807601 -57.772729) (xy 379.85257 -57.743068)
			(xy 379.901265 -57.720028) (xy 379.92685 -57.711594) (xy 379.927104 -57.711594) (xy 379.932938 -57.709581)
			(xy 379.943471 -57.703158) (xy 379.947932 -57.698894) (xy 383.466594 -54.180232) (xy 383.471578 -54.174731)
			(xy 383.478412 -54.161563) (xy 383.480056 -54.154324) (xy 383.481072 -54.144672) (xy 383.481072 -46.19244)
			(xy 383.480637 -46.182375) (xy 383.472904 -46.163789) (xy 383.466086 -46.156372) (xy 377.628404 -40.318436)
			(xy 377.624233 -40.314502) (xy 377.614481 -40.308477) (xy 377.6091 -40.306498) (xy 377.605093 -40.305215)
			(xy 377.596796 -40.303814) (xy 377.59259 -40.303704) (xy 374.767094 -40.303704) (xy 374.762776 -40.30599)
			(xy 374.734349 -40.320901) (xy 374.673747 -40.342052) (xy 374.610465 -40.352793) (xy 374.578372 -40.353488)
			(xy 374.577864 -40.353488) (xy 374.550616 -40.352999) (xy 374.496675 -40.345239) (xy 374.444387 -40.329882)
			(xy 374.394817 -40.30724) (xy 374.348974 -40.277774) (xy 374.30779 -40.242084) (xy 374.272104 -40.200897)
			(xy 374.242643 -40.155051) (xy 374.220006 -40.105479) (xy 374.204653 -40.05319) (xy 374.196898 -39.999248)
			(xy 374.196898 -39.944752) (xy 374.204653 -39.89081) (xy 374.220006 -39.838521) (xy 374.242643 -39.788949)
			(xy 374.272104 -39.743103) (xy 374.30779 -39.701916) (xy 374.348974 -39.666226) (xy 374.394817 -39.63676)
			(xy 374.444387 -39.614118) (xy 374.496675 -39.598761) (xy 374.550616 -39.591001) (xy 374.577864 -39.590472)
			(xy 374.578118 -39.590472) (xy 374.602366 -39.590867) (xy 374.650467 -39.597036) (xy 374.697403 -39.609236)
			(xy 374.742421 -39.62727) (xy 374.763792 -39.638732) (xy 374.766586 -39.640256) (xy 377.334018 -39.640256)
			(xy 377.343539 -39.639857) (xy 377.361265 -39.632899) (xy 377.375227 -39.61995) (xy 377.379738 -39.611554)
			(xy 377.381008 -39.608506) (xy 377.383721 -39.601336) (xy 377.385156 -39.586079) (xy 377.383802 -39.578534)
			(xy 377.382532 -39.57193) (xy 377.375674 -39.55923) (xy 374.039892 -36.223448) (xy 374.037041 -36.220742)
			(xy 374.030663 -36.216149) (xy 374.027192 -36.214304) (xy 374.021766 -36.211717) (xy 374.010086 -36.208885)
			(xy 374.004078 -36.208716) (xy 373.038116 -36.208716) (xy 373.028464 -36.218368) (xy 372.997222 -36.261802)
			(xy 372.980712 -36.284916) (xy 372.976971 -36.291024) (xy 372.972701 -36.304688) (xy 372.97233 -36.31184)
			(xy 372.97233 -36.331906) (xy 372.974616 -36.339526) (xy 372.98278 -36.367329) (xy 372.991576 -36.424601)
			(xy 372.992142 -36.453572) (xy 372.991658 -36.480825) (xy 372.983905 -36.534778) (xy 372.968553 -36.587078)
			(xy 372.945914 -36.636661) (xy 372.916449 -36.682517) (xy 372.880758 -36.723714) (xy 372.839567 -36.759411)
			(xy 372.793715 -36.788884) (xy 372.744136 -36.811531) (xy 372.691839 -36.826892) (xy 372.637887 -36.834654)
			(xy 372.610634 -36.83508) (xy 372.583509 -36.834605) (xy 372.529805 -36.826924) (xy 372.477731 -36.811713)
			(xy 372.428337 -36.789277) (xy 372.38262 -36.76007) (xy 372.341502 -36.724681) (xy 372.305812 -36.683823)
			(xy 372.27627 -36.638322) (xy 372.253472 -36.589094) (xy 372.237879 -36.537133) (xy 372.229804 -36.483487)
			(xy 372.229126 -36.456366) (xy 372.229126 -36.45281) (xy 372.229687 -36.423839) (xy 372.238493 -36.366569)
			(xy 372.246652 -36.338764) (xy 372.247414 -36.336224) (xy 372.248938 -36.331398) (xy 372.250462 -36.318444)
			(xy 372.250733 -36.31029) (xy 372.246731 -36.294483) (xy 372.242588 -36.287456) (xy 372.223538 -36.260786)
			(xy 372.19255 -36.21786) (xy 372.183152 -36.208716) (xy 371.672866 -36.208716) (xy 371.666712 -36.208881)
			(xy 371.654761 -36.211827) (xy 371.649244 -36.214558) (xy 371.621685 -36.228299) (xy 371.563267 -36.247771)
			(xy 371.502486 -36.257642) (xy 371.471698 -36.258246) (xy 371.470936 -36.258246) (xy 371.443679 -36.257786)
			(xy 371.389718 -36.250032) (xy 371.337411 -36.234677) (xy 371.287821 -36.212035) (xy 371.241959 -36.182565)
			(xy 371.200758 -36.146867) (xy 371.165057 -36.10567) (xy 371.135583 -36.05981) (xy 371.112935 -36.010223)
			(xy 371.097576 -35.957917) (xy 371.089817 -35.903957) (xy 371.089817 -35.849443) (xy 371.097576 -35.795483)
			(xy 371.112935 -35.743177) (xy 371.135583 -35.69359) (xy 371.165057 -35.64773) (xy 371.200758 -35.606533)
			(xy 371.241959 -35.570835) (xy 371.287821 -35.541365) (xy 371.337411 -35.518723) (xy 371.389718 -35.503368)
			(xy 371.443679 -35.495614) (xy 371.470936 -35.49523) (xy 371.471952 -35.49523) (xy 371.502704 -35.495805)
			(xy 371.563413 -35.505656) (xy 371.621753 -35.525127) (xy 371.649244 -35.538918) (xy 371.654775 -35.541617)
			(xy 371.666715 -35.544579) (xy 371.672866 -35.54476) (xy 373.74576 -35.54476) (xy 373.754853 -35.544339)
			(xy 373.771861 -35.537892) (xy 373.785543 -35.525906) (xy 373.79021 -35.51809) (xy 373.792242 -35.51301)
			(xy 373.79497 -35.505978) (xy 373.796535 -35.490984) (xy 373.79529 -35.483546) (xy 373.79402 -35.476942)
			(xy 373.786908 -35.463734) (xy 371.443504 -33.12033) (xy 371.425472 -33.101559) (xy 371.394892 -33.059442)
			(xy 371.371265 -33.013066) (xy 371.355171 -32.963569) (xy 371.347005 -32.912166) (xy 371.346476 -32.886142)
			(xy 371.346476 -29.768038) (xy 371.347004 -29.742015) (xy 371.355173 -29.690613) (xy 371.37127 -29.641118)
			(xy 371.394899 -29.594743) (xy 371.42548 -29.552629) (xy 371.443504 -29.53385) (xy 372.088156 -28.889452)
			(xy 372.093666 -28.883493) (xy 372.100931 -28.868989) (xy 372.10238 -28.861004) (xy 372.102888 -28.853638)
			(xy 372.102888 -28.81122) (xy 372.098062 -28.805632) (xy 372.092474 -28.80106) (xy 369.560348 -28.80106)
			(xy 369.534262 -28.80057) (xy 369.482735 -28.792396) (xy 369.433122 -28.776258) (xy 369.386647 -28.752554)
			(xy 369.344454 -28.721867) (xy 369.325652 -28.703778) (xy 368.301778 -27.67965) (xy 368.295802 -27.674202)
			(xy 368.281296 -27.667072) (xy 368.27333 -27.66568) (xy 368.266218 -27.665172) (xy 367.036096 -27.665172)
			(xy 367.010074 -27.664641) (xy 366.958674 -27.656467) (xy 366.909182 -27.640367) (xy 366.86281 -27.616737)
			(xy 366.820697 -27.586156) (xy 366.801908 -27.568144) (xy 365.826548 -26.592784) (xy 365.81569 -26.594617)
			(xy 365.795059 -26.602299) (xy 365.785654 -26.608024) (xy 365.775234 -26.615211) (xy 365.75801 -26.633748)
			(xy 365.745878 -26.655954) (xy 365.739582 -26.680463) (xy 365.739172 -26.693114) (xy 365.739172 -27.342846)
			(xy 365.738682 -27.372814) (xy 365.730859 -27.432236) (xy 365.715346 -27.490129) (xy 365.69241 -27.545502)
			(xy 365.662443 -27.597408) (xy 365.625956 -27.644958) (xy 365.583576 -27.687338) (xy 365.536026 -27.723825)
			(xy 365.48412 -27.753792) (xy 365.428747 -27.776728) (xy 365.370854 -27.792241) (xy 365.311432 -27.800064)
			(xy 365.251496 -27.800064) (xy 365.192074 -27.792241) (xy 365.134181 -27.776728) (xy 365.078808 -27.753792)
			(xy 365.026902 -27.723825) (xy 364.979352 -27.687338) (xy 364.936972 -27.644958) (xy 364.900485 -27.597408)
			(xy 364.870518 -27.545502) (xy 364.847582 -27.490129) (xy 364.832069 -27.432236) (xy 364.824246 -27.372814)
			(xy 364.823756 -27.342846) (xy 364.823756 -26.737818) (xy 364.823502 -26.479246) (xy 364.824029 -26.447748)
			(xy 364.832668 -26.385347) (xy 364.849777 -26.324719) (xy 364.875031 -26.267007) (xy 364.907955 -26.213299)
			(xy 364.947928 -26.16461) (xy 364.994196 -26.121857) (xy 365.045885 -26.085847) (xy 365.102021 -26.05726)
			(xy 365.131604 -26.04643) (xy 365.136176 -26.044906) (xy 365.146161 -26.039642) (xy 365.16066 -26.022377)
			(xy 365.164116 -26.011632) (xy 365.165132 -26.008076) (xy 365.172244 -25.976326) (xy 365.172244 -25.975818)
			(xy 365.173006 -25.972516) (xy 365.174517 -25.964111) (xy 365.172516 -25.94716) (xy 365.165093 -25.931791)
			(xy 365.15929 -25.925526) (xy 364.615476 -25.381458) (xy 364.6082 -25.374775) (xy 364.590032 -25.367058)
			(xy 364.58017 -25.366472) (xy 363.005116 -25.366472) (xy 363.001814 -25.366472) (xy 362.992796 -25.367424)
			(xy 362.976266 -25.37485) (xy 362.969556 -25.38095) (xy 362.895642 -25.455118) (xy 362.863892 -25.486868)
			(xy 362.857542 -25.497536) (xy 362.855764 -25.503378) (xy 362.847314 -25.528942) (xy 362.824231 -25.577585)
			(xy 362.794543 -25.622501) (xy 362.758838 -25.662801) (xy 362.717825 -25.697684) (xy 362.672318 -25.726458)
			(xy 362.623219 -25.748553) (xy 362.571502 -25.76353) (xy 362.518195 -25.771091) (xy 362.491274 -25.771602)
			(xy 362.464024 -25.771114) (xy 362.41008 -25.763355) (xy 362.357788 -25.747997) (xy 362.308215 -25.725355)
			(xy 362.262368 -25.695888) (xy 362.221181 -25.660196) (xy 362.185493 -25.619006) (xy 362.15603 -25.573157)
			(xy 362.133391 -25.523582) (xy 362.118038 -25.471289) (xy 362.110283 -25.417344) (xy 362.109766 -25.390094)
			(xy 362.109512 -25.390094) (xy 362.109969 -25.363157) (xy 362.117533 -25.309818) (xy 362.132524 -25.258072)
			(xy 362.154644 -25.20895) (xy 362.183454 -25.163427) (xy 362.21838 -25.122408) (xy 362.258728 -25.08671)
			(xy 362.303696 -25.057042) (xy 362.352389 -25.033993) (xy 362.37799 -25.025604) (xy 362.378244 -25.025604)
			(xy 362.384082 -25.023597) (xy 362.394625 -25.017184) (xy 362.399072 -25.012904) (xy 362.44149 -24.970486)
			(xy 362.441932 -24.96688) (xy 362.441939 -24.959614) (xy 362.44149 -24.956008) (xy 362.0897 -24.604218)
			(xy 362.064518 -24.578274) (xy 362.020075 -24.521245) (xy 361.982984 -24.459182) (xy 361.953809 -24.393027)
			(xy 361.932991 -24.323787) (xy 361.926378 -24.288242) (xy 361.92206 -24.263604) (xy 361.917979 -24.259833)
			(xy 361.908493 -24.25405) (xy 361.903264 -24.252174) (xy 361.89412 -24.249126) (xy 361.82554 -24.22779)
			(xy 361.815888 -24.224742) (xy 361.810552 -24.223303) (xy 361.799529 -24.222539) (xy 361.794044 -24.223218)
			(xy 361.592622 -24.42464) (xy 361.573852 -24.442674) (xy 361.531737 -24.473258) (xy 361.485361 -24.496888)
			(xy 361.435863 -24.512984) (xy 361.384458 -24.521151) (xy 361.358434 -24.521668) (xy 360.170222 -24.521668)
			(xy 360.165904 -24.523954) (xy 360.137478 -24.538868) (xy 360.076877 -24.560026) (xy 360.013594 -24.570772)
			(xy 359.9815 -24.571452) (xy 359.980992 -24.571452) (xy 359.953738 -24.570966) (xy 359.899785 -24.563207)
			(xy 359.847485 -24.54785) (xy 359.797903 -24.525205) (xy 359.752048 -24.495736) (xy 359.710854 -24.46004)
			(xy 359.67516 -24.418845) (xy 359.645691 -24.37299) (xy 359.623048 -24.323407) (xy 359.607691 -24.271107)
			(xy 359.599934 -24.217154) (xy 359.599934 -24.162646) (xy 359.607691 -24.108693) (xy 359.623048 -24.056393)
			(xy 359.645691 -24.00681) (xy 359.67516 -23.960955) (xy 359.710854 -23.91976) (xy 359.752048 -23.884064)
			(xy 359.797903 -23.854595) (xy 359.847485 -23.83195) (xy 359.899785 -23.816593) (xy 359.953738 -23.808834)
			(xy 359.980992 -23.808436) (xy 359.981246 -23.808436) (xy 360.005493 -23.808832) (xy 360.053594 -23.815005)
			(xy 360.100529 -23.827206) (xy 360.145545 -23.845242) (xy 360.16692 -23.856696) (xy 360.169714 -23.85822)
			(xy 361.19943 -23.85822) (xy 361.202732 -23.85822) (xy 361.211754 -23.857277) (xy 361.228296 -23.849863)
			(xy 361.23499 -23.843742) (xy 361.315 -23.763478) (xy 361.354116 -23.724362) (xy 361.35437 -23.710646)
			(xy 361.352338 -23.701756) (xy 361.34294 -23.673562) (xy 361.34294 -23.673054) (xy 361.321604 -23.603712)
			(xy 361.314238 -23.597108) (xy 361.2896 -23.59279) (xy 361.256752 -23.586395) (xy 361.192677 -23.567079)
			(xy 361.131221 -23.540584) (xy 361.073186 -23.507257) (xy 361.019329 -23.467531) (xy 360.970352 -23.421924)
			(xy 360.926893 -23.371031) (xy 360.88952 -23.315515) (xy 360.858718 -23.256101) (xy 360.84637 -23.224998)
			(xy 360.837988 -23.203154) (xy 360.833955 -23.200571) (xy 360.825131 -23.196852) (xy 360.820462 -23.195788)
			(xy 360.771186 -23.185374) (xy 360.770678 -23.185374) (xy 360.734864 -23.177754) (xy 360.72064 -23.178008)
			(xy 360.45902 -23.439628) (xy 360.435444 -23.462575) (xy 360.384004 -23.503597) (xy 360.328294 -23.538601)
			(xy 360.269016 -23.567147) (xy 360.206914 -23.588876) (xy 360.142769 -23.603516) (xy 360.077389 -23.610882)
			(xy 360.044492 -23.611332) (xy 360.009064 -23.610797) (xy 359.938725 -23.602255) (xy 359.869929 -23.585298)
			(xy 359.803678 -23.560171) (xy 359.740938 -23.527242) (xy 359.682625 -23.486991) (xy 359.62959 -23.440005)
			(xy 359.582604 -23.386968) (xy 359.542354 -23.328655) (xy 359.509425 -23.265915) (xy 359.4843 -23.199664)
			(xy 359.467343 -23.130867) (xy 359.458803 -23.060528) (xy 359.45826 -23.0251) (xy 359.458721 -22.992204)
			(xy 359.466087 -22.926825) (xy 359.480727 -22.862682) (xy 359.502457 -22.800581) (xy 359.531003 -22.741304)
			(xy 359.566006 -22.685596) (xy 359.607027 -22.634157) (xy 359.629964 -22.610572) (xy 360.122724 -22.117812)
			(xy 360.146298 -22.094861) (xy 360.197736 -22.053832) (xy 360.253444 -22.01882) (xy 360.312723 -21.990266)
			(xy 360.374825 -21.968529) (xy 360.438971 -21.953882) (xy 360.504354 -21.94651) (xy 360.537252 -21.946108)
			(xy 360.558588 -21.946616) (xy 364.369096 -21.946616) (xy 364.37062 -21.94433) (xy 364.371636 -21.942806)
			(xy 364.402116 -21.892514) (xy 364.402116 -21.892006) (xy 364.41761 -21.866098) (xy 364.422436 -21.85416)
			(xy 364.42396 -21.842476) (xy 364.424214 -21.830792) (xy 364.418626 -21.818854) (xy 364.418118 -21.817838)
			(xy 364.404218 -21.790283) (xy 364.384532 -21.731793) (xy 364.374532 -21.670894) (xy 364.373922 -21.640038)
			(xy 364.373922 -21.63572) (xy 364.37469 -21.607317) (xy 364.383601 -21.551204) (xy 364.400739 -21.497034)
			(xy 364.425723 -21.446006) (xy 364.458 -21.399249) (xy 364.477046 -21.378164) (xy 364.483904 -21.371052)
			(xy 364.48746 -21.362162) (xy 364.49 -21.353018) (xy 364.490762 -21.344128) (xy 364.490762 -21.27377)
			(xy 364.490698 -21.269636) (xy 364.489428 -21.261468) (xy 364.488222 -21.257514) (xy 364.48746 -21.255736)
			(xy 364.484158 -21.2471) (xy 364.477046 -21.23948) (xy 364.457773 -21.218154) (xy 364.425202 -21.170791)
			(xy 364.400106 -21.119079) (xy 364.383052 -21.064186) (xy 364.374426 -21.007356) (xy 364.374424 -20.949876)
			(xy 364.383045 -20.893045) (xy 364.400094 -20.838151) (xy 364.425186 -20.786437) (xy 364.457752 -20.739071)
			(xy 364.477046 -20.717764) (xy 364.484158 -20.710144) (xy 364.48746 -20.701508) (xy 364.488222 -20.69973)
			(xy 364.489454 -20.695781) (xy 364.490731 -20.68761) (xy 364.490762 -20.683474) (xy 364.490762 -20.61337)
			(xy 364.490698 -20.609236) (xy 364.489428 -20.601068) (xy 364.488222 -20.597114) (xy 364.48746 -20.595336)
			(xy 364.484158 -20.5867) (xy 364.477046 -20.57908) (xy 364.457773 -20.557754) (xy 364.425202 -20.510391)
			(xy 364.400106 -20.458679) (xy 364.383052 -20.403786) (xy 364.374426 -20.346956) (xy 364.374424 -20.289476)
			(xy 364.383045 -20.232645) (xy 364.400094 -20.177751) (xy 364.425186 -20.126037) (xy 364.457752 -20.078671)
			(xy 364.477046 -20.057364) (xy 364.484158 -20.049744) (xy 364.48746 -20.041108) (xy 364.488222 -20.03933)
			(xy 364.489454 -20.035381) (xy 364.490731 -20.02721) (xy 364.490762 -20.023074) (xy 364.490762 -19.95297)
			(xy 364.490698 -19.948836) (xy 364.489428 -19.940668) (xy 364.488222 -19.936714) (xy 364.48746 -19.934936)
			(xy 364.484158 -19.9263) (xy 364.477046 -19.91868) (xy 364.457773 -19.897354) (xy 364.425202 -19.849991)
			(xy 364.400106 -19.798279) (xy 364.383052 -19.743386) (xy 364.374426 -19.686556) (xy 364.374424 -19.629076)
			(xy 364.383045 -19.572245) (xy 364.400094 -19.517351) (xy 364.425186 -19.465637) (xy 364.457752 -19.418271)
			(xy 364.477046 -19.396964) (xy 364.484158 -19.389344) (xy 364.48746 -19.380708) (xy 364.488222 -19.37893)
			(xy 364.489454 -19.374981) (xy 364.490731 -19.36681) (xy 364.490762 -19.362674) (xy 364.490762 -19.29257)
			(xy 364.490698 -19.288436) (xy 364.489428 -19.280268) (xy 364.488222 -19.276314) (xy 364.48746 -19.274536)
			(xy 364.484158 -19.2659) (xy 364.477046 -19.25828) (xy 364.457777 -19.236952) (xy 364.425216 -19.189588)
			(xy 364.400127 -19.137876) (xy 364.383077 -19.082986) (xy 364.374453 -19.02616) (xy 364.373922 -18.997422)
			(xy 364.374408 -18.970171) (xy 364.382164 -18.916223) (xy 364.397519 -18.863928) (xy 364.420161 -18.814351)
			(xy 364.449627 -18.768501) (xy 364.485318 -18.72731) (xy 364.526509 -18.691619) (xy 364.572359 -18.662153)
			(xy 364.621936 -18.639511) (xy 364.674231 -18.624156) (xy 364.728179 -18.6164) (xy 364.782681 -18.6164)
			(xy 364.836629 -18.624156) (xy 364.888924 -18.639511) (xy 364.938501 -18.662153) (xy 364.984351 -18.691619)
			(xy 365.025542 -18.72731) (xy 365.061233 -18.768501) (xy 365.090699 -18.814351) (xy 365.113341 -18.863928)
			(xy 365.128696 -18.916223) (xy 365.136452 -18.970171) (xy 365.136938 -18.997422) (xy 365.136415 -19.02616)
			(xy 365.127789 -19.082985) (xy 365.110734 -19.137873) (xy 365.085637 -19.18958) (xy 365.053066 -19.236937)
			(xy 365.033814 -19.25828) (xy 365.026702 -19.2659) (xy 365.0234 -19.274536) (xy 365.022638 -19.276314)
			(xy 365.021408 -19.280263) (xy 365.020137 -19.288434) (xy 365.020098 -19.29257) (xy 365.020098 -19.362674)
			(xy 365.020165 -19.366807) (xy 365.021441 -19.374974) (xy 365.022638 -19.37893) (xy 365.0234 -19.380708)
			(xy 365.026702 -19.389344) (xy 365.033814 -19.396964) (xy 365.053081 -19.418292) (xy 365.08564 -19.465654)
			(xy 365.110726 -19.517365) (xy 365.127771 -19.572254) (xy 365.13639 -19.629079) (xy 365.136388 -19.686553)
			(xy 365.127764 -19.743377) (xy 365.110714 -19.798264) (xy 365.085624 -19.849973) (xy 365.053061 -19.897333)
			(xy 365.033814 -19.91868) (xy 365.026702 -19.9263) (xy 365.0234 -19.934936) (xy 365.022638 -19.936714)
			(xy 365.021408 -19.940663) (xy 365.020137 -19.948834) (xy 365.020098 -19.95297) (xy 365.020098 -20.023074)
			(xy 365.020165 -20.027207) (xy 365.021441 -20.035374) (xy 365.022638 -20.03933) (xy 365.0234 -20.041108)
			(xy 365.026702 -20.049744) (xy 365.033814 -20.057364) (xy 365.053081 -20.078692) (xy 365.08564 -20.126054)
			(xy 365.110726 -20.177765) (xy 365.127771 -20.232654) (xy 365.13639 -20.289479) (xy 365.136388 -20.346953)
			(xy 365.127764 -20.403777) (xy 365.110714 -20.458664) (xy 365.085624 -20.510373) (xy 365.053061 -20.557733)
			(xy 365.033814 -20.57908) (xy 365.026702 -20.5867) (xy 365.0234 -20.595336) (xy 365.022638 -20.597114)
			(xy 365.021408 -20.601063) (xy 365.020137 -20.609234) (xy 365.020098 -20.61337) (xy 365.020098 -20.683474)
			(xy 365.020165 -20.687607) (xy 365.021441 -20.695774) (xy 365.022638 -20.69973) (xy 365.0234 -20.701508)
			(xy 365.026702 -20.710144) (xy 365.033814 -20.717764) (xy 365.053081 -20.739092) (xy 365.08564 -20.786454)
			(xy 365.110726 -20.838165) (xy 365.127771 -20.893054) (xy 365.13639 -20.949879) (xy 365.136388 -21.007353)
			(xy 365.127764 -21.064177) (xy 365.110714 -21.119064) (xy 365.085624 -21.170773) (xy 365.053061 -21.218133)
			(xy 365.033814 -21.23948) (xy 365.026702 -21.2471) (xy 365.0234 -21.255736) (xy 365.022638 -21.257514)
			(xy 365.021408 -21.261463) (xy 365.020137 -21.269634) (xy 365.020098 -21.27377) (xy 365.020098 -21.344128)
			(xy 365.02086 -21.353018) (xy 365.0234 -21.362162) (xy 365.026956 -21.371052) (xy 365.034322 -21.378672)
			(xy 365.053262 -21.39972) (xy 365.085355 -21.446369) (xy 365.1102 -21.497249) (xy 365.127254 -21.551241)
			(xy 365.13614 -21.607161) (xy 365.136938 -21.635466) (xy 365.136938 -21.63953) (xy 365.136337 -21.67047)
			(xy 365.12636 -21.73154) (xy 365.10667 -21.790204) (xy 365.092742 -21.817838) (xy 365.091218 -21.820632)
			(xy 365.089097 -21.825769) (xy 365.086912 -21.836664) (xy 365.0869 -21.842222) (xy 365.087154 -21.855684)
			(xy 365.108744 -21.892006) (xy 365.108744 -21.892514) (xy 365.139224 -21.942552) (xy 365.142018 -21.946616)
			(xy 369.552728 -21.946616) (xy 369.560437 -21.946388) (xy 369.575175 -21.941863) (xy 369.581684 -21.937726)
			(xy 369.585748 -21.934424) (xy 369.928902 -21.59127) (xy 369.92941 -21.583904) (xy 369.92941 -21.567902)
			(xy 369.926362 -21.556218) (xy 369.922044 -21.547836) (xy 369.908512 -21.520574) (xy 369.889319 -21.462819)
			(xy 369.879533 -21.402751) (xy 369.878864 -21.372322) (xy 369.878864 -21.36394) (xy 369.879859 -21.337046)
			(xy 369.888479 -21.283923) (xy 369.904481 -21.232539) (xy 369.927547 -21.183915) (xy 369.957219 -21.139016)
			(xy 369.992909 -21.098734) (xy 370.033906 -21.063869) (xy 370.079397 -21.035113) (xy 370.128479 -21.013037)
			(xy 370.180176 -20.99808) (xy 370.233463 -20.990539) (xy 370.260372 -20.990052) (xy 370.264182 -20.990052)
			(xy 370.273072 -20.990306) (xy 370.278152 -20.99056) (xy 370.289836 -20.988274) (xy 370.295058 -20.987155)
			(xy 370.304923 -20.983066) (xy 370.309394 -20.980146) (xy 370.315998 -20.974812) (xy 370.367052 -20.925536)
			(xy 370.37264 -20.919186) (xy 370.37264 -20.003008) (xy 370.372386 -19.453098) (xy 370.372919 -19.417376)
			(xy 370.381606 -19.346462) (xy 370.398852 -19.277131) (xy 370.4244 -19.210411) (xy 370.457871 -19.147292)
			(xy 370.498769 -19.088712) (xy 370.546486 -19.03554) (xy 370.573046 -19.011646) (xy 370.583968 -19.002248)
			(xy 370.586 -18.99793) (xy 370.588008 -18.993217) (xy 370.59031 -18.983235) (xy 370.590572 -18.978118)
			(xy 370.592096 -18.922238) (xy 370.592096 -18.921476) (xy 370.592604 -18.906998) (xy 370.54409 -18.858484)
			(xy 370.521178 -18.834907) (xy 370.480199 -18.783495) (xy 370.445233 -18.727818) (xy 370.416721 -18.668577)
			(xy 370.395019 -18.606516) (xy 370.380401 -18.542416) (xy 370.373051 -18.477083) (xy 370.37264 -18.44421)
			(xy 370.372386 -18.432018) (xy 370.373641 -18.397094) (xy 370.383435 -18.327899) (xy 370.401385 -18.260358)
			(xy 370.427236 -18.19543) (xy 370.460621 -18.134034) (xy 370.501068 -18.077043) (xy 370.548002 -18.025263)
			(xy 370.600758 -17.97943) (xy 370.658589 -17.940192) (xy 370.720673 -17.908107) (xy 370.786131 -17.883629)
			(xy 370.854035 -17.867105) (xy 370.923422 -17.85877) (xy 370.958364 -17.858232) (xy 370.967508 -17.858232)
			(xy 371.004805 -17.85941) (xy 371.078664 -17.870065) (xy 371.15057 -17.890016) (xy 371.185186 -17.903952)
			(xy 371.219929 -17.919178) (xy 371.285511 -17.9573) (xy 371.345632 -18.003558) (xy 371.372892 -18.029936)
			(xy 371.941344 -18.598388) (xy 371.96429 -18.621943) (xy 372.00531 -18.673341) (xy 372.040312 -18.729013)
			(xy 372.068857 -18.788255) (xy 372.090585 -18.850323) (xy 372.105221 -18.914434) (xy 372.112582 -18.979782)
			(xy 372.113048 -19.012662) (xy 372.113048 -21.475192) (xy 372.116709 -21.479732) (xy 372.125687 -21.48717)
			(xy 372.130828 -21.489924) (xy 372.20271 -21.520404) (xy 372.203218 -21.520404) (xy 372.220744 -21.527516)
			(xy 372.227189 -21.529916) (xy 372.240835 -21.531594) (xy 372.247668 -21.530818) (xy 372.836948 -20.941538)
			(xy 372.837456 -20.9296) (xy 372.823486 -20.84197) (xy 372.822245 -20.836841) (xy 372.8179 -20.827226)
			(xy 372.81485 -20.82292) (xy 372.80977 -20.816062) (xy 372.804182 -20.813268) (xy 372.780053 -20.801243)
			(xy 372.735137 -20.771429) (xy 372.694846 -20.735608) (xy 372.659979 -20.694491) (xy 372.631224 -20.648889)
			(xy 372.609149 -20.599705) (xy 372.594192 -20.54791) (xy 372.586647 -20.49453) (xy 372.58625 -20.467574)
			(xy 372.586738 -20.440196) (xy 372.594531 -20.385997) (xy 372.609958 -20.333458) (xy 372.632704 -20.28365)
			(xy 372.662308 -20.237586) (xy 372.698166 -20.196204) (xy 372.739548 -20.160346) (xy 372.785612 -20.130742)
			(xy 372.83542 -20.107996) (xy 372.887959 -20.092569) (xy 372.942158 -20.084776) (xy 372.996914 -20.084776)
			(xy 373.051113 -20.092569) (xy 373.103652 -20.107996) (xy 373.15346 -20.130742) (xy 373.199524 -20.160346)
			(xy 373.240906 -20.196204) (xy 373.276764 -20.237586) (xy 373.306368 -20.28365) (xy 373.329114 -20.333458)
			(xy 373.344541 -20.385997) (xy 373.352334 -20.440196) (xy 373.352822 -20.467574) (xy 373.352822 -20.468336)
			(xy 373.352146 -20.500184) (xy 373.341548 -20.562996) (xy 373.33174 -20.593304) (xy 373.328438 -20.602956)
			(xy 373.328184 -20.604734) (xy 373.327852 -20.613161) (xy 373.331989 -20.629498) (xy 373.336312 -20.636738)
			(xy 373.337582 -20.638516) (xy 373.38508 -20.705064) (xy 373.385842 -20.70608) (xy 374.957086 -20.70608)
			(xy 374.98994 -20.706539) (xy 375.055235 -20.713894) (xy 375.082211 -20.72005) (xy 379.48541 -20.72005)
			(xy 379.48938 -20.589916) (xy 379.501276 -20.460266) (xy 379.521055 -20.331583) (xy 379.548641 -20.204344)
			(xy 379.583934 -20.079025) (xy 379.6268 -19.956089) (xy 379.677082 -19.835996) (xy 379.734591 -19.719192)
			(xy 379.799115 -19.60611) (xy 379.870412 -19.497173) (xy 379.948217 -19.392785) (xy 380.032242 -19.293334)
			(xy 380.122174 -19.199191) (xy 380.217678 -19.110706) (xy 380.318398 -19.028207) (xy 380.42396 -18.952002)
			(xy 380.533972 -18.882375) (xy 380.648024 -18.819584) (xy 380.765692 -18.763862) (xy 380.886538 -18.715418)
			(xy 381.010113 -18.674431) (xy 381.135956 -18.641054) (xy 381.263601 -18.615411) (xy 381.392571 -18.597597)
			(xy 381.522387 -18.587679) (xy 381.652566 -18.585694) (xy 381.782625 -18.591648) (xy 381.912078 -18.605521)
			(xy 382.040445 -18.627259) (xy 382.167248 -18.656783) (xy 382.292015 -18.693982) (xy 382.414282 -18.738718)
			(xy 382.533595 -18.790826) (xy 382.649508 -18.850109) (xy 382.761593 -18.91635) (xy 382.86943 -18.9893)
			(xy 382.972619 -19.068688) (xy 383.070777 -19.15422) (xy 383.163538 -19.245577) (xy 383.250557 -19.342419)
			(xy 383.33151 -19.444386) (xy 383.406096 -19.551098) (xy 383.474037 -19.662159) (xy 383.535082 -19.777155)
			(xy 383.589003 -19.895659) (xy 383.635598 -20.01723) (xy 383.674696 -20.141415) (xy 383.70615 -20.267753)
			(xy 383.729844 -20.395774) (xy 383.745688 -20.525) (xy 383.753626 -20.654953) (xy 383.754122 -20.72005)
			(xy 383.753626 -20.785147) (xy 383.745688 -20.9151) (xy 383.729844 -21.044326) (xy 383.70615 -21.172347)
			(xy 383.674696 -21.298685) (xy 383.635598 -21.42287) (xy 383.589003 -21.544441) (xy 383.535082 -21.662945)
			(xy 383.474037 -21.777941) (xy 383.406096 -21.889002) (xy 383.33151 -21.995714) (xy 383.250557 -22.097681)
			(xy 383.163538 -22.194523) (xy 383.070777 -22.28588) (xy 382.972619 -22.371412) (xy 382.86943 -22.4508)
			(xy 382.761593 -22.52375) (xy 382.649508 -22.589991) (xy 382.533595 -22.649274) (xy 382.414282 -22.701382)
			(xy 382.292015 -22.746118) (xy 382.167248 -22.783317) (xy 382.040445 -22.812841) (xy 381.912078 -22.834579)
			(xy 381.782625 -22.848452) (xy 381.652566 -22.854406) (xy 381.522387 -22.852421) (xy 381.392571 -22.842503)
			(xy 381.263601 -22.824689) (xy 381.135956 -22.799046) (xy 381.010113 -22.765669) (xy 380.886538 -22.724682)
			(xy 380.765692 -22.676238) (xy 380.648024 -22.620516) (xy 380.533972 -22.557725) (xy 380.42396 -22.488098)
			(xy 380.318398 -22.411893) (xy 380.217678 -22.329394) (xy 380.122174 -22.240909) (xy 380.032242 -22.146766)
			(xy 379.948217 -22.047315) (xy 379.870412 -21.942927) (xy 379.799115 -21.83399) (xy 379.734591 -21.720908)
			(xy 379.677082 -21.604104) (xy 379.6268 -21.484011) (xy 379.583934 -21.361075) (xy 379.548641 -21.235756)
			(xy 379.521055 -21.108517) (xy 379.501276 -20.979834) (xy 379.48938 -20.850184) (xy 379.48541 -20.72005)
			(xy 375.082211 -20.72005) (xy 375.119296 -20.728513) (xy 375.181318 -20.750212) (xy 375.24052 -20.778719)
			(xy 375.296159 -20.813674) (xy 375.347535 -20.854639) (xy 375.371106 -20.87753) (xy 375.934986 -21.44141)
			(xy 375.95788 -21.464976) (xy 375.998825 -21.516362) (xy 376.033765 -21.572006) (xy 376.06226 -21.631209)
			(xy 376.083952 -21.693229) (xy 376.09857 -21.757287) (xy 376.105928 -21.822578) (xy 376.106306 -21.847048)
			(xy 376.37288 -21.847048) (xy 376.376951 -21.791426) (xy 376.389077 -21.736989) (xy 376.409 -21.684898)
			(xy 376.436296 -21.636263) (xy 376.470382 -21.59212) (xy 376.510531 -21.553411) (xy 376.555889 -21.52096)
			(xy 376.605489 -21.495459) (xy 376.658273 -21.477452) (xy 376.713116 -21.467322) (xy 376.76885 -21.465285)
			(xy 376.824287 -21.471385) (xy 376.878244 -21.485491) (xy 376.929573 -21.507303) (xy 376.977179 -21.536357)
			(xy 377.020047 -21.572032) (xy 377.057264 -21.613569) (xy 377.088037 -21.660082) (xy 377.111709 -21.710579)
			(xy 377.127777 -21.763986) (xy 377.135897 -21.819162) (xy 377.136406 -21.847048) (xy 377.135897 -21.874934)
			(xy 377.127777 -21.93011) (xy 377.111709 -21.983517) (xy 377.088037 -22.034014) (xy 377.057264 -22.080527)
			(xy 377.020047 -22.122064) (xy 376.977179 -22.157739) (xy 376.929573 -22.186793) (xy 376.878244 -22.208605)
			(xy 376.824287 -22.222711) (xy 376.76885 -22.228811) (xy 376.713116 -22.226774) (xy 376.658273 -22.216644)
			(xy 376.605489 -22.198637) (xy 376.555889 -22.173136) (xy 376.510531 -22.140685) (xy 376.470382 -22.101976)
			(xy 376.436296 -22.057833) (xy 376.409 -22.009198) (xy 376.389077 -21.957107) (xy 376.376951 -21.90267)
			(xy 376.37288 -21.847048) (xy 376.106306 -21.847048) (xy 376.106436 -21.85543) (xy 376.106436 -21.855684)
			(xy 376.105924 -21.891084) (xy 376.097392 -21.961367) (xy 376.08045 -22.030109) (xy 376.055346 -22.096308)
			(xy 376.022446 -22.158999) (xy 375.982229 -22.217266) (xy 375.935281 -22.270261) (xy 375.882288 -22.317211)
			(xy 375.824023 -22.357431) (xy 375.761334 -22.390335) (xy 375.695136 -22.415442) (xy 375.626394 -22.432387)
			(xy 375.556112 -22.440922) (xy 375.520712 -22.441408) (xy 375.520458 -22.441408) (xy 375.487603 -22.440951)
			(xy 375.422306 -22.4336) (xy 375.358242 -22.418985) (xy 375.296217 -22.397289) (xy 375.237012 -22.368785)
			(xy 375.18137 -22.333832) (xy 375.129991 -22.292868) (xy 375.106438 -22.269958) (xy 375.035826 -22.199092)
			(xy 375.025412 -22.198584) (xy 374.994932 -22.224238) (xy 374.968496 -22.245837) (xy 374.911488 -22.283397)
			(xy 374.850501 -22.314075) (xy 374.78636 -22.337455) (xy 374.719936 -22.35322) (xy 374.65213 -22.361155)
			(xy 374.617996 -22.361652) (xy 374.460262 -22.361652) (xy 374.451118 -22.370542) (xy 374.432576 -22.393656)
			(xy 374.399556 -22.43455) (xy 374.397016 -22.438614) (xy 374.392444 -22.450552) (xy 374.389142 -22.463252)
			(xy 374.38965 -22.46503) (xy 374.391682 -22.47519) (xy 374.395516 -22.494395) (xy 374.399711 -22.533333)
			(xy 374.400064 -22.552914) (xy 374.400064 -22.553422) (xy 374.400064 -22.559264) (xy 374.399301 -22.586806)
			(xy 374.390828 -22.641249) (xy 374.374614 -22.693906) (xy 374.350997 -22.743686) (xy 374.320468 -22.789552)
			(xy 374.283661 -22.830552) (xy 374.241342 -22.865834) (xy 374.194389 -22.894664) (xy 374.143779 -22.916444)
			(xy 374.090563 -22.93072) (xy 374.06326 -22.934422) (xy 374.049036 -22.935946) (xy 374.018556 -22.937216)
			(xy 373.990408 -22.936717) (xy 373.934722 -22.928457) (xy 373.880852 -22.912108) (xy 373.829968 -22.888023)
			(xy 373.783174 -22.856727) (xy 373.762016 -22.838156) (xy 373.761508 -22.837648) (xy 373.756013 -22.833065)
			(xy 373.743121 -22.826874) (xy 373.736108 -22.825456) (xy 373.728996 -22.82444) (xy 373.721884 -22.825202)
			(xy 373.71821 -22.825748) (xy 373.711068 -22.827788) (xy 373.70766 -22.829266) (xy 373.690388 -22.836886)
			(xy 373.621554 -22.867366) (xy 373.616006 -22.870163) (xy 373.606365 -22.877993) (xy 373.602504 -22.88286)
			(xy 373.602504 -23.0251) (xy 385.458716 -23.0251) (xy 385.458716 -23.024846) (xy 385.459154 -22.991992)
			(xy 385.466523 -22.926698) (xy 385.481151 -22.862638) (xy 385.502854 -22.800617) (xy 385.53136 -22.741414)
			(xy 385.56631 -22.685772) (xy 385.607267 -22.63439) (xy 385.630166 -22.610826) (xy 386.122926 -22.118066)
			(xy 386.146478 -22.095154) (xy 386.197856 -22.054187) (xy 386.253497 -22.019231) (xy 386.312703 -21.990725)
			(xy 386.374728 -21.969027) (xy 386.438792 -21.954409) (xy 386.504091 -21.947057) (xy 386.536946 -21.946616)
			(xy 390.286748 -21.946616) (xy 390.298381 -21.946085) (xy 390.31929 -21.93589) (xy 390.32688 -21.927058)
			(xy 390.376156 -21.863812) (xy 390.382852 -21.854294) (xy 390.387601 -21.831533) (xy 390.3853 -21.820124)
			(xy 390.379919 -21.797197) (xy 390.374188 -21.750453) (xy 390.37387 -21.726906) (xy 390.374405 -21.698168)
			(xy 390.383026 -21.641341) (xy 390.400074 -21.586451) (xy 390.425163 -21.534739) (xy 390.457725 -21.487376)
			(xy 390.476994 -21.466048) (xy 390.483598 -21.45919) (xy 390.49071 -21.441156) (xy 390.49071 -21.352256)
			(xy 390.483598 -21.334222) (xy 390.476994 -21.327364) (xy 390.45773 -21.306031) (xy 390.425168 -21.258669)
			(xy 390.400078 -21.206958) (xy 390.383029 -21.152068) (xy 390.374406 -21.095243) (xy 390.374406 -21.037766)
			(xy 390.383027 -20.98094) (xy 390.400074 -20.92605) (xy 390.425163 -20.874339) (xy 390.457725 -20.826975)
			(xy 390.476994 -20.805648) (xy 390.483598 -20.79879) (xy 390.49071 -20.780756) (xy 390.49071 -20.691856)
			(xy 390.483598 -20.673822) (xy 390.476994 -20.666964) (xy 390.45773 -20.645631) (xy 390.425168 -20.598269)
			(xy 390.400078 -20.546558) (xy 390.383029 -20.491668) (xy 390.374406 -20.434843) (xy 390.374406 -20.377366)
			(xy 390.383027 -20.32054) (xy 390.400074 -20.26565) (xy 390.425163 -20.213939) (xy 390.457725 -20.166575)
			(xy 390.476994 -20.145248) (xy 390.483598 -20.13839) (xy 390.49071 -20.120356) (xy 390.49071 -20.031456)
			(xy 390.483598 -20.013422) (xy 390.476994 -20.006564) (xy 390.45773 -19.985231) (xy 390.425168 -19.937869)
			(xy 390.400078 -19.886158) (xy 390.383029 -19.831268) (xy 390.374406 -19.774443) (xy 390.374406 -19.716966)
			(xy 390.383027 -19.66014) (xy 390.400074 -19.60525) (xy 390.425163 -19.553539) (xy 390.457725 -19.506175)
			(xy 390.476994 -19.484848) (xy 390.483598 -19.47799) (xy 390.49071 -19.459956) (xy 390.49071 -19.371056)
			(xy 390.483598 -19.353022) (xy 390.476994 -19.346164) (xy 390.457736 -19.324826) (xy 390.425166 -19.277468)
			(xy 390.40007 -19.225759) (xy 390.383017 -19.17087) (xy 390.374392 -19.114044) (xy 390.37387 -19.085306)
			(xy 390.374356 -19.058055) (xy 390.382112 -19.004107) (xy 390.397467 -18.951812) (xy 390.420109 -18.902235)
			(xy 390.449575 -18.856385) (xy 390.485266 -18.815194) (xy 390.526457 -18.779503) (xy 390.572307 -18.750037)
			(xy 390.621884 -18.727395) (xy 390.674179 -18.71204) (xy 390.728127 -18.704284) (xy 390.782629 -18.704284)
			(xy 390.836577 -18.71204) (xy 390.888872 -18.727395) (xy 390.938449 -18.750037) (xy 390.984299 -18.779503)
			(xy 391.02549 -18.815194) (xy 391.061181 -18.856385) (xy 391.090647 -18.902235) (xy 391.113289 -18.951812)
			(xy 391.128644 -19.004107) (xy 391.1364 -19.058055) (xy 391.136886 -19.085306) (xy 391.136343 -19.114044)
			(xy 391.127722 -19.170869) (xy 391.110675 -19.225759) (xy 391.085588 -19.277471) (xy 391.053029 -19.324835)
			(xy 391.033762 -19.346164) (xy 391.027158 -19.353022) (xy 391.020046 -19.371056) (xy 391.020046 -19.459956)
			(xy 391.027158 -19.47799) (xy 391.033762 -19.484848) (xy 391.053039 -19.506169) (xy 391.085606 -19.553532)
			(xy 391.110698 -19.605245) (xy 391.127748 -19.660137) (xy 391.13637 -19.716965) (xy 391.13637 -19.774444)
			(xy 391.127746 -19.831272) (xy 391.110695 -19.886163) (xy 391.085601 -19.937875) (xy 391.053034 -19.985238)
			(xy 391.033762 -20.006564) (xy 391.027158 -20.013422) (xy 391.020046 -20.031456) (xy 391.020046 -20.120356)
			(xy 391.027158 -20.13839) (xy 391.033762 -20.145248) (xy 391.053039 -20.166569) (xy 391.085606 -20.213932)
			(xy 391.110698 -20.265645) (xy 391.127748 -20.320537) (xy 391.13637 -20.377365) (xy 391.13637 -20.434844)
			(xy 391.127746 -20.491672) (xy 391.110695 -20.546563) (xy 391.085601 -20.598275) (xy 391.053034 -20.645638)
			(xy 391.033762 -20.666964) (xy 391.027158 -20.673822) (xy 391.020046 -20.691856) (xy 391.020046 -20.780756)
			(xy 391.027158 -20.79879) (xy 391.033762 -20.805648) (xy 391.053039 -20.826969) (xy 391.085606 -20.874332)
			(xy 391.110698 -20.926045) (xy 391.127748 -20.980937) (xy 391.13637 -21.037765) (xy 391.13637 -21.095244)
			(xy 391.127746 -21.152072) (xy 391.110695 -21.206963) (xy 391.085601 -21.258675) (xy 391.053034 -21.306038)
			(xy 391.033762 -21.327364) (xy 391.027158 -21.334222) (xy 391.020046 -21.352256) (xy 391.020046 -21.441156)
			(xy 391.027158 -21.45919) (xy 391.033762 -21.466048) (xy 391.053036 -21.487373) (xy 391.085601 -21.534735)
			(xy 391.110693 -21.586448) (xy 391.127743 -21.641339) (xy 391.136365 -21.698167) (xy 391.136886 -21.726906)
			(xy 391.136567 -21.750453) (xy 391.130838 -21.797198) (xy 391.125456 -21.820124) (xy 391.123116 -21.831529)
			(xy 391.127896 -21.854292) (xy 391.1346 -21.863812) (xy 391.183876 -21.927058) (xy 391.191493 -21.935854)
			(xy 391.212387 -21.946042) (xy 391.224008 -21.946616) (xy 395.552676 -21.946616) (xy 395.562747 -21.9462)
			(xy 395.581346 -21.938475) (xy 395.588744 -21.93163) (xy 395.912848 -21.607526) (xy 395.920079 -21.599527)
			(xy 395.927725 -21.579388) (xy 395.926505 -21.557881) (xy 395.921992 -21.54809) (xy 395.908434 -21.520745)
			(xy 395.889198 -21.462826) (xy 395.879434 -21.402582) (xy 395.878812 -21.372068) (xy 395.878812 -21.37156)
			(xy 395.879241 -21.344307) (xy 395.887003 -21.290356) (xy 395.902364 -21.238059) (xy 395.925012 -21.18848)
			(xy 395.954484 -21.142629) (xy 395.990181 -21.101439) (xy 396.031377 -21.065748) (xy 396.077233 -21.036283)
			(xy 396.126815 -21.013643) (xy 396.179115 -20.99829) (xy 396.233067 -20.990536) (xy 396.26032 -20.990052)
			(xy 396.273892 -20.990159) (xy 396.300969 -20.992063) (xy 396.314422 -20.993862) (xy 396.325304 -20.995017)
			(xy 396.346299 -20.988894) (xy 396.362866 -20.974617) (xy 396.372021 -20.954756) (xy 396.372588 -20.943824)
			(xy 396.372588 -19.453098) (xy 396.373091 -19.418649) (xy 396.381164 -19.350227) (xy 396.397211 -19.283224)
			(xy 396.421009 -19.218567) (xy 396.45223 -19.15715) (xy 396.490442 -19.099821) (xy 396.535118 -19.047372)
			(xy 396.56004 -19.023584) (xy 396.567208 -19.01631) (xy 396.575587 -18.997704) (xy 396.576296 -18.987516)
			(xy 396.577566 -18.91411) (xy 396.577313 -18.903869) (xy 396.569717 -18.884866) (xy 396.562834 -18.87728)
			(xy 396.544038 -18.858484) (xy 396.521138 -18.834921) (xy 396.480173 -18.783544) (xy 396.445219 -18.727904)
			(xy 396.416714 -18.6687) (xy 396.395016 -18.606677) (xy 396.380399 -18.542615) (xy 396.373046 -18.477318)
			(xy 396.372588 -18.444464) (xy 396.372588 -18.44421) (xy 396.373165 -18.408808) (xy 396.381696 -18.338521)
			(xy 396.398634 -18.269774) (xy 396.423733 -18.203569) (xy 396.456626 -18.140871) (xy 396.496835 -18.082593)
			(xy 396.543774 -18.029585) (xy 396.596758 -17.982619) (xy 396.655015 -17.942381) (xy 396.717697 -17.909455)
			(xy 396.783889 -17.884323) (xy 396.852628 -17.86735) (xy 396.922911 -17.858783) (xy 396.958312 -17.858232)
			(xy 396.991194 -17.858655) (xy 397.056543 -17.866024) (xy 397.120655 -17.880668) (xy 397.182722 -17.902402)
			(xy 397.241964 -17.930954) (xy 397.297635 -17.965962) (xy 397.349032 -18.006988) (xy 397.372586 -18.029936)
			(xy 397.941292 -18.598642) (xy 397.964201 -18.622228) (xy 398.005196 -18.673638) (xy 398.040183 -18.72931)
			(xy 398.068723 -18.788547) (xy 398.090459 -18.850604) (xy 398.105118 -18.914703) (xy 398.112515 -18.980039)
			(xy 398.112996 -19.012916) (xy 398.112996 -21.47189) (xy 398.112829 -21.489334) (xy 398.11067 -21.524155)
			(xy 398.108678 -21.541486) (xy 398.108047 -21.552934) (xy 398.115551 -21.574564) (xy 398.123156 -21.583142)
			(xy 398.12341 -21.583396) (xy 398.130822 -21.59008) (xy 398.149255 -21.597677) (xy 398.169193 -21.597677)
			(xy 398.187626 -21.59008) (xy 398.195038 -21.583396) (xy 398.813274 -20.96516) (xy 398.821258 -20.956281)
			(xy 398.828668 -20.933611) (xy 398.827498 -20.921726) (xy 398.813782 -20.829016) (xy 398.800066 -20.809712)
			(xy 398.789652 -20.80387) (xy 398.789144 -20.80387) (xy 398.763489 -20.789479) (xy 398.716541 -20.754041)
			(xy 398.675586 -20.71182) (xy 398.641595 -20.663815) (xy 398.615372 -20.611162) (xy 398.597539 -20.55511)
			(xy 398.588517 -20.496985) (xy 398.587976 -20.467574) (xy 398.588462 -20.440323) (xy 398.596218 -20.386375)
			(xy 398.611573 -20.33408) (xy 398.634215 -20.284503) (xy 398.663681 -20.238653) (xy 398.699372 -20.197462)
			(xy 398.740563 -20.161771) (xy 398.786413 -20.132305) (xy 398.83599 -20.109663) (xy 398.888285 -20.094308)
			(xy 398.942233 -20.086552) (xy 398.996735 -20.086552) (xy 399.050683 -20.094308) (xy 399.102978 -20.109663)
			(xy 399.152555 -20.132305) (xy 399.198405 -20.161771) (xy 399.239596 -20.197462) (xy 399.275287 -20.238653)
			(xy 399.304753 -20.284503) (xy 399.327395 -20.33408) (xy 399.34275 -20.386375) (xy 399.350506 -20.440323)
			(xy 399.350992 -20.467574) (xy 399.350992 -20.468336) (xy 399.35052 -20.495517) (xy 399.342736 -20.54932)
			(xy 399.335498 -20.575524) (xy 399.331942 -20.586954) (xy 399.33626 -20.610576) (xy 399.39214 -20.68576)
			(xy 399.399756 -20.694853) (xy 399.420937 -20.705456) (xy 399.43278 -20.70608) (xy 400.957034 -20.70608)
			(xy 400.989887 -20.706541) (xy 401.05518 -20.713907) (xy 401.104338 -20.72513) (xy 405.480532 -20.72513)
			(xy 405.484502 -20.594996) (xy 405.496398 -20.465346) (xy 405.516177 -20.336663) (xy 405.543763 -20.209424)
			(xy 405.579056 -20.084105) (xy 405.621922 -19.961169) (xy 405.672204 -19.841076) (xy 405.729713 -19.724272)
			(xy 405.794237 -19.61119) (xy 405.865534 -19.502253) (xy 405.943339 -19.397865) (xy 406.027364 -19.298414)
			(xy 406.117296 -19.204271) (xy 406.2128 -19.115786) (xy 406.31352 -19.033287) (xy 406.419082 -18.957082)
			(xy 406.529094 -18.887455) (xy 406.643146 -18.824664) (xy 406.760814 -18.768942) (xy 406.88166 -18.720498)
			(xy 407.005235 -18.679511) (xy 407.131078 -18.646134) (xy 407.258723 -18.620491) (xy 407.387693 -18.602677)
			(xy 407.517509 -18.592759) (xy 407.647688 -18.590774) (xy 407.777747 -18.596728) (xy 407.9072 -18.610601)
			(xy 408.035567 -18.632339) (xy 408.16237 -18.661863) (xy 408.287137 -18.699062) (xy 408.409404 -18.743798)
			(xy 408.528717 -18.795906) (xy 408.64463 -18.855189) (xy 408.756715 -18.92143) (xy 408.864552 -18.99438)
			(xy 408.967741 -19.073768) (xy 409.065899 -19.1593) (xy 409.15866 -19.250657) (xy 409.245679 -19.347499)
			(xy 409.326632 -19.449466) (xy 409.401218 -19.556178) (xy 409.469159 -19.667239) (xy 409.530204 -19.782235)
			(xy 409.584125 -19.900739) (xy 409.63072 -20.02231) (xy 409.669818 -20.146495) (xy 409.701272 -20.272833)
			(xy 409.724966 -20.400854) (xy 409.74081 -20.53008) (xy 409.748748 -20.660033) (xy 409.749244 -20.72513)
			(xy 409.748748 -20.790227) (xy 409.74081 -20.92018) (xy 409.724966 -21.049406) (xy 409.701272 -21.177427)
			(xy 409.669818 -21.303765) (xy 409.63072 -21.42795) (xy 409.584125 -21.549521) (xy 409.530204 -21.668025)
			(xy 409.469159 -21.783021) (xy 409.401218 -21.894082) (xy 409.326632 -22.000794) (xy 409.245679 -22.102761)
			(xy 409.15866 -22.199603) (xy 409.065899 -22.29096) (xy 408.967741 -22.376492) (xy 408.864552 -22.45588)
			(xy 408.756715 -22.52883) (xy 408.64463 -22.595071) (xy 408.528717 -22.654354) (xy 408.409404 -22.706462)
			(xy 408.287137 -22.751198) (xy 408.16237 -22.788397) (xy 408.035567 -22.817921) (xy 407.9072 -22.839659)
			(xy 407.777747 -22.853532) (xy 407.647688 -22.859486) (xy 407.517509 -22.857501) (xy 407.387693 -22.847583)
			(xy 407.258723 -22.829769) (xy 407.131078 -22.804126) (xy 407.005235 -22.770749) (xy 406.88166 -22.729762)
			(xy 406.760814 -22.681318) (xy 406.643146 -22.625596) (xy 406.529094 -22.562805) (xy 406.419082 -22.493178)
			(xy 406.31352 -22.416973) (xy 406.2128 -22.334474) (xy 406.117296 -22.245989) (xy 406.027364 -22.151846)
			(xy 405.943339 -22.052395) (xy 405.865534 -21.948007) (xy 405.794237 -21.83907) (xy 405.729713 -21.725988)
			(xy 405.672204 -21.609184) (xy 405.621922 -21.489091) (xy 405.579056 -21.366155) (xy 405.543763 -21.240836)
			(xy 405.516177 -21.113597) (xy 405.496398 -20.984914) (xy 405.484502 -20.855264) (xy 405.480532 -20.72513)
			(xy 401.104338 -20.72513) (xy 401.119239 -20.728532) (xy 401.181259 -20.750232) (xy 401.240463 -20.778734)
			(xy 401.296106 -20.813681) (xy 401.347489 -20.854633) (xy 401.371054 -20.87753) (xy 401.934934 -21.44141)
			(xy 401.957826 -21.46498) (xy 401.998792 -21.516355) (xy 402.033748 -21.571994) (xy 402.062255 -21.631197)
			(xy 402.083954 -21.693219) (xy 402.098572 -21.75728) (xy 402.105925 -21.822576) (xy 402.106267 -21.847048)
			(xy 402.372828 -21.847048) (xy 402.376899 -21.791426) (xy 402.389025 -21.736989) (xy 402.408948 -21.684898)
			(xy 402.436244 -21.636263) (xy 402.47033 -21.59212) (xy 402.510479 -21.553411) (xy 402.555837 -21.52096)
			(xy 402.605437 -21.495459) (xy 402.658221 -21.477452) (xy 402.713064 -21.467322) (xy 402.768798 -21.465285)
			(xy 402.824235 -21.471385) (xy 402.878192 -21.485491) (xy 402.929521 -21.507303) (xy 402.977127 -21.536357)
			(xy 403.019995 -21.572032) (xy 403.057212 -21.613569) (xy 403.087985 -21.660082) (xy 403.111657 -21.710579)
			(xy 403.127725 -21.763986) (xy 403.135845 -21.819162) (xy 403.136354 -21.847048) (xy 403.135845 -21.874934)
			(xy 403.127725 -21.93011) (xy 403.111657 -21.983517) (xy 403.087985 -22.034014) (xy 403.057212 -22.080527)
			(xy 403.019995 -22.122064) (xy 402.977127 -22.157739) (xy 402.929521 -22.186793) (xy 402.878192 -22.208605)
			(xy 402.824235 -22.222711) (xy 402.768798 -22.228811) (xy 402.713064 -22.226774) (xy 402.658221 -22.216644)
			(xy 402.605437 -22.198637) (xy 402.555837 -22.173136) (xy 402.510479 -22.140685) (xy 402.47033 -22.101976)
			(xy 402.436244 -22.057833) (xy 402.408948 -22.009198) (xy 402.389025 -21.957107) (xy 402.376899 -21.90267)
			(xy 402.372828 -21.847048) (xy 402.106267 -21.847048) (xy 402.106384 -21.85543) (xy 402.106384 -21.855684)
			(xy 402.105896 -21.891084) (xy 402.097363 -21.961368) (xy 402.080421 -22.03011) (xy 402.055315 -22.09631)
			(xy 402.022412 -22.159) (xy 401.982193 -22.217266) (xy 401.935243 -22.27026) (xy 401.882248 -22.317208)
			(xy 401.823979 -22.357425) (xy 401.761288 -22.390325) (xy 401.695088 -22.415428) (xy 401.626344 -22.432367)
			(xy 401.55606 -22.440897) (xy 401.52066 -22.441408) (xy 401.520406 -22.441408) (xy 401.487553 -22.440924)
			(xy 401.422261 -22.433562) (xy 401.358203 -22.418942) (xy 401.296182 -22.397246) (xy 401.236979 -22.368747)
			(xy 401.181335 -22.333803) (xy 401.129951 -22.292854) (xy 401.106386 -22.269958) (xy 401.063714 -22.227032)
			(xy 401.056738 -22.220563) (xy 401.039331 -22.212916) (xy 401.020333 -22.212148) (xy 401.002366 -22.218365)
			(xy 400.99488 -22.224238) (xy 400.968461 -22.24586) (xy 400.911452 -22.283423) (xy 400.850461 -22.314102)
			(xy 400.786317 -22.337481) (xy 400.71989 -22.353244) (xy 400.65208 -22.361175) (xy 400.617944 -22.361652)
			(xy 400.492722 -22.361652) (xy 400.481516 -22.362211) (xy 400.461214 -22.371694) (xy 400.453606 -22.37994)
			(xy 400.403568 -22.440392) (xy 400.396798 -22.449453) (xy 400.391275 -22.47136) (xy 400.3929 -22.482556)
			(xy 400.396212 -22.500599) (xy 400.399771 -22.537111) (xy 400.400012 -22.555454) (xy 400.399502 -22.582706)
			(xy 400.391751 -22.636655) (xy 400.376401 -22.688951) (xy 400.353764 -22.738531) (xy 400.324302 -22.784384)
			(xy 400.288613 -22.825577) (xy 400.247424 -22.861272) (xy 400.201575 -22.89074) (xy 400.151998 -22.913384)
			(xy 400.099704 -22.928741) (xy 400.045755 -22.936498) (xy 400.018504 -22.936962) (xy 399.993538 -22.936549)
			(xy 399.944031 -22.930046) (xy 399.895796 -22.917136) (xy 399.849659 -22.898042) (xy 399.806408 -22.87309)
			(xy 399.786348 -22.858222) (xy 399.778595 -22.852712) (xy 399.760367 -22.847335) (xy 399.741435 -22.849003)
			(xy 399.732754 -22.852888) (xy 399.650966 -22.893274) (xy 399.642676 -22.897787) (xy 399.629957 -22.911718)
			(xy 399.623143 -22.929308) (xy 399.622772 -22.93874) (xy 399.622772 -23.965154) (xy 400.377404 -23.965154)
			(xy 400.381475 -23.909532) (xy 400.393601 -23.855095) (xy 400.413524 -23.803004) (xy 400.44082 -23.754369)
			(xy 400.474906 -23.710226) (xy 400.515055 -23.671517) (xy 400.560413 -23.639066) (xy 400.610013 -23.613565)
			(xy 400.662797 -23.595558) (xy 400.71764 -23.585428) (xy 400.773374 -23.583391) (xy 400.828811 -23.589491)
			(xy 400.882768 -23.603597) (xy 400.934097 -23.625409) (xy 400.981703 -23.654463) (xy 401.024571 -23.690138)
			(xy 401.061788 -23.731675) (xy 401.092561 -23.778188) (xy 401.116233 -23.828685) (xy 401.132301 -23.882092)
			(xy 401.140421 -23.937268) (xy 401.140596 -23.946866) (xy 401.38045 -23.946866) (xy 401.384521 -23.891244)
			(xy 401.396647 -23.836807) (xy 401.41657 -23.784716) (xy 401.443866 -23.736081) (xy 401.477952 -23.691938)
			(xy 401.518101 -23.653229) (xy 401.563459 -23.620778) (xy 401.613059 -23.595277) (xy 401.665843 -23.57727)
			(xy 401.720686 -23.56714) (xy 401.77642 -23.565103) (xy 401.831857 -23.571203) (xy 401.885814 -23.585309)
			(xy 401.937143 -23.607121) (xy 401.984749 -23.636175) (xy 402.027617 -23.67185) (xy 402.064834 -23.713387)
			(xy 402.095607 -23.7599) (xy 402.119279 -23.810397) (xy 402.135347 -23.863804) (xy 402.143467 -23.91898)
			(xy 402.143976 -23.946866) (xy 402.143536 -23.970996) (xy 402.372828 -23.970996) (xy 402.376899 -23.915374)
			(xy 402.389025 -23.860937) (xy 402.408948 -23.808846) (xy 402.436244 -23.760211) (xy 402.47033 -23.716068)
			(xy 402.510479 -23.677359) (xy 402.555837 -23.644908) (xy 402.605437 -23.619407) (xy 402.658221 -23.6014)
			(xy 402.713064 -23.59127) (xy 402.768798 -23.589233) (xy 402.824235 -23.595333) (xy 402.878192 -23.609439)
			(xy 402.929521 -23.631251) (xy 402.977127 -23.660305) (xy 403.019995 -23.69598) (xy 403.057212 -23.737517)
			(xy 403.087985 -23.78403) (xy 403.111657 -23.834527) (xy 403.127725 -23.887934) (xy 403.135845 -23.94311)
			(xy 403.136354 -23.970996) (xy 403.135845 -23.998882) (xy 403.127725 -24.054058) (xy 403.111657 -24.107465)
			(xy 403.087985 -24.157962) (xy 403.057212 -24.204475) (xy 403.019995 -24.246012) (xy 402.977127 -24.281687)
			(xy 402.929521 -24.310741) (xy 402.878192 -24.332553) (xy 402.824235 -24.346659) (xy 402.768798 -24.352759)
			(xy 402.713064 -24.350722) (xy 402.658221 -24.340592) (xy 402.605437 -24.322585) (xy 402.555837 -24.297084)
			(xy 402.510479 -24.264633) (xy 402.47033 -24.225924) (xy 402.436244 -24.181781) (xy 402.408948 -24.133146)
			(xy 402.389025 -24.081055) (xy 402.376899 -24.026618) (xy 402.372828 -23.970996) (xy 402.143536 -23.970996)
			(xy 402.143467 -23.974752) (xy 402.135347 -24.029928) (xy 402.119279 -24.083335) (xy 402.095607 -24.133832)
			(xy 402.064834 -24.180345) (xy 402.027617 -24.221882) (xy 401.984749 -24.257557) (xy 401.937143 -24.286611)
			(xy 401.885814 -24.308423) (xy 401.831857 -24.322529) (xy 401.77642 -24.328629) (xy 401.720686 -24.326592)
			(xy 401.665843 -24.316462) (xy 401.613059 -24.298455) (xy 401.563459 -24.272954) (xy 401.518101 -24.240503)
			(xy 401.477952 -24.201794) (xy 401.443866 -24.157651) (xy 401.41657 -24.109016) (xy 401.396647 -24.056925)
			(xy 401.384521 -24.002488) (xy 401.38045 -23.946866) (xy 401.140596 -23.946866) (xy 401.14093 -23.965154)
			(xy 401.140421 -23.99304) (xy 401.132301 -24.048216) (xy 401.116233 -24.101623) (xy 401.092561 -24.15212)
			(xy 401.061788 -24.198633) (xy 401.024571 -24.24017) (xy 400.981703 -24.275845) (xy 400.934097 -24.304899)
			(xy 400.882768 -24.326711) (xy 400.828811 -24.340817) (xy 400.773374 -24.346917) (xy 400.71764 -24.34488)
			(xy 400.662797 -24.33475) (xy 400.610013 -24.316743) (xy 400.560413 -24.291242) (xy 400.515055 -24.258791)
			(xy 400.474906 -24.220082) (xy 400.44082 -24.175939) (xy 400.413524 -24.127304) (xy 400.393601 -24.075213)
			(xy 400.381475 -24.020776) (xy 400.377404 -23.965154) (xy 399.622772 -23.965154) (xy 399.622772 -24.807418)
			(xy 406.67127 -24.807418) (xy 406.675341 -24.751796) (xy 406.687467 -24.697359) (xy 406.70739 -24.645268)
			(xy 406.734686 -24.596633) (xy 406.768772 -24.55249) (xy 406.808921 -24.513781) (xy 406.854279 -24.48133)
			(xy 406.903879 -24.455829) (xy 406.956663 -24.437822) (xy 407.011506 -24.427692) (xy 407.06724 -24.425655)
			(xy 407.122677 -24.431755) (xy 407.176634 -24.445861) (xy 407.227963 -24.467673) (xy 407.275569 -24.496727)
			(xy 407.318437 -24.532402) (xy 407.355654 -24.573939) (xy 407.386427 -24.620452) (xy 407.410099 -24.670949)
			(xy 407.426167 -24.724356) (xy 407.434287 -24.779532) (xy 407.434796 -24.807418) (xy 407.434287 -24.835304)
			(xy 407.426167 -24.89048) (xy 407.410099 -24.943887) (xy 407.386427 -24.994384) (xy 407.355654 -25.040897)
			(xy 407.318437 -25.082434) (xy 407.275569 -25.118109) (xy 407.227963 -25.147163) (xy 407.176634 -25.168975)
			(xy 407.122677 -25.183081) (xy 407.06724 -25.189181) (xy 407.011506 -25.187144) (xy 406.956663 -25.177014)
			(xy 406.903879 -25.159007) (xy 406.854279 -25.133506) (xy 406.808921 -25.101055) (xy 406.768772 -25.062346)
			(xy 406.734686 -25.018203) (xy 406.70739 -24.969568) (xy 406.687467 -24.917477) (xy 406.675341 -24.86304)
			(xy 406.67127 -24.807418) (xy 399.622772 -24.807418) (xy 399.622772 -25.930352) (xy 399.640806 -25.95626)
			(xy 399.656046 -25.961848) (xy 399.683183 -25.972434) (xy 399.734119 -26.000689) (xy 399.776779 -26.03373)
			(xy 405.567894 -26.03373) (xy 405.571965 -25.978108) (xy 405.584091 -25.923671) (xy 405.604014 -25.87158)
			(xy 405.63131 -25.822945) (xy 405.665396 -25.778802) (xy 405.705545 -25.740093) (xy 405.750903 -25.707642)
			(xy 405.800503 -25.682141) (xy 405.853287 -25.664134) (xy 405.90813 -25.654004) (xy 405.963864 -25.651967)
			(xy 406.019301 -25.658067) (xy 406.073258 -25.672173) (xy 406.124587 -25.693985) (xy 406.172193 -25.723039)
			(xy 406.215061 -25.758714) (xy 406.252278 -25.800251) (xy 406.283051 -25.846764) (xy 406.306723 -25.897261)
			(xy 406.322791 -25.950668) (xy 406.330911 -26.005844) (xy 406.33142 -26.03373) (xy 406.330911 -26.061616)
			(xy 406.322791 -26.116792) (xy 406.306723 -26.170199) (xy 406.283051 -26.220696) (xy 406.252278 -26.267209)
			(xy 406.215061 -26.308746) (xy 406.172193 -26.344421) (xy 406.124587 -26.373475) (xy 406.073258 -26.395287)
			(xy 406.019301 -26.409393) (xy 405.963864 -26.415493) (xy 405.90813 -26.413456) (xy 405.853287 -26.403326)
			(xy 405.800503 -26.385319) (xy 405.750903 -26.359818) (xy 405.705545 -26.327367) (xy 405.665396 -26.288658)
			(xy 405.63131 -26.244515) (xy 405.604014 -26.19588) (xy 405.584091 -26.143789) (xy 405.571965 -26.089352)
			(xy 405.567894 -26.03373) (xy 399.776779 -26.03373) (xy 399.780169 -26.036356) (xy 399.820265 -26.078607)
			(xy 399.853475 -26.12646) (xy 399.879027 -26.178804) (xy 399.888202 -26.20645) (xy 399.888202 -26.206704)
			(xy 399.890201 -26.212389) (xy 399.896484 -26.222668) (xy 399.900648 -26.227024) (xy 400.856196 -27.182572)
			(xy 400.87423 -27.201341) (xy 400.90481 -27.243458) (xy 400.928437 -27.289835) (xy 400.944531 -27.339333)
			(xy 400.952697 -27.390736) (xy 400.953224 -27.41676) (xy 400.953224 -28.139136) (xy 402.697948 -28.139136)
			(xy 402.702019 -28.083514) (xy 402.714145 -28.029077) (xy 402.734068 -27.976986) (xy 402.761364 -27.928351)
			(xy 402.79545 -27.884208) (xy 402.835599 -27.845499) (xy 402.880957 -27.813048) (xy 402.930557 -27.787547)
			(xy 402.983341 -27.76954) (xy 403.038184 -27.75941) (xy 403.093918 -27.757373) (xy 403.149355 -27.763473)
			(xy 403.203312 -27.777579) (xy 403.254641 -27.799391) (xy 403.302247 -27.828445) (xy 403.345115 -27.86412)
			(xy 403.382332 -27.905657) (xy 403.413105 -27.95217) (xy 403.436777 -28.002667) (xy 403.452845 -28.056074)
			(xy 403.460965 -28.11125) (xy 403.461474 -28.139136) (xy 403.967948 -28.139136) (xy 403.972019 -28.083514)
			(xy 403.984145 -28.029077) (xy 404.004068 -27.976986) (xy 404.031364 -27.928351) (xy 404.06545 -27.884208)
			(xy 404.105599 -27.845499) (xy 404.150957 -27.813048) (xy 404.200557 -27.787547) (xy 404.253341 -27.76954)
			(xy 404.308184 -27.75941) (xy 404.363918 -27.757373) (xy 404.419355 -27.763473) (xy 404.473312 -27.777579)
			(xy 404.524641 -27.799391) (xy 404.572247 -27.828445) (xy 404.615115 -27.86412) (xy 404.652332 -27.905657)
			(xy 404.683105 -27.95217) (xy 404.706777 -28.002667) (xy 404.722845 -28.056074) (xy 404.730965 -28.11125)
			(xy 404.731474 -28.139136) (xy 404.730965 -28.167022) (xy 404.722845 -28.222198) (xy 404.706777 -28.275605)
			(xy 404.683105 -28.326102) (xy 404.652332 -28.372615) (xy 404.615115 -28.414152) (xy 404.572247 -28.449827)
			(xy 404.524641 -28.478881) (xy 404.473312 -28.500693) (xy 404.419355 -28.514799) (xy 404.363918 -28.520899)
			(xy 404.308184 -28.518862) (xy 404.253341 -28.508732) (xy 404.200557 -28.490725) (xy 404.150957 -28.465224)
			(xy 404.105599 -28.432773) (xy 404.06545 -28.394064) (xy 404.031364 -28.349921) (xy 404.004068 -28.301286)
			(xy 403.984145 -28.249195) (xy 403.972019 -28.194758) (xy 403.967948 -28.139136) (xy 403.461474 -28.139136)
			(xy 403.460965 -28.167022) (xy 403.452845 -28.222198) (xy 403.436777 -28.275605) (xy 403.413105 -28.326102)
			(xy 403.382332 -28.372615) (xy 403.345115 -28.414152) (xy 403.302247 -28.449827) (xy 403.254641 -28.478881)
			(xy 403.203312 -28.500693) (xy 403.149355 -28.514799) (xy 403.093918 -28.520899) (xy 403.038184 -28.518862)
			(xy 402.983341 -28.508732) (xy 402.930557 -28.490725) (xy 402.880957 -28.465224) (xy 402.835599 -28.432773)
			(xy 402.79545 -28.394064) (xy 402.761364 -28.349921) (xy 402.734068 -28.301286) (xy 402.714145 -28.249195)
			(xy 402.702019 -28.194758) (xy 402.697948 -28.139136) (xy 400.953224 -28.139136) (xy 400.953224 -30.252924)
			(xy 400.952684 -30.278947) (xy 400.944521 -30.33035) (xy 400.929395 -30.376876) (xy 401.188936 -30.376876)
			(xy 401.189496 -30.34796) (xy 401.198214 -30.290791) (xy 401.215463 -30.235592) (xy 401.240847 -30.18363)
			(xy 401.273784 -30.136095) (xy 401.313519 -30.094077) (xy 401.336002 -30.075886) (xy 401.344806 -30.068275)
			(xy 401.354991 -30.047377) (xy 401.35556 -30.035754) (xy 401.35556 -29.955998) (xy 401.355022 -29.944366)
			(xy 401.344834 -29.923455) (xy 401.336002 -29.915866) (xy 401.313503 -29.897694) (xy 401.273768 -29.85567)
			(xy 401.240831 -29.808131) (xy 401.215445 -29.756166) (xy 401.198193 -29.700965) (xy 401.189468 -29.643793)
			(xy 401.188936 -29.614876) (xy 401.189422 -29.587625) (xy 401.197178 -29.533677) (xy 401.212533 -29.481382)
			(xy 401.235175 -29.431805) (xy 401.264641 -29.385955) (xy 401.300332 -29.344764) (xy 401.341523 -29.309073)
			(xy 401.387373 -29.279607) (xy 401.43695 -29.256965) (xy 401.489245 -29.24161) (xy 401.543193 -29.233854)
			(xy 401.597695 -29.233854) (xy 401.651643 -29.24161) (xy 401.703938 -29.256965) (xy 401.753515 -29.279607)
			(xy 401.799365 -29.309073) (xy 401.840556 -29.344764) (xy 401.876247 -29.385955) (xy 401.905713 -29.431805)
			(xy 401.928355 -29.481382) (xy 401.94371 -29.533677) (xy 401.951466 -29.587625) (xy 401.951952 -29.614876)
			(xy 401.951435 -29.643793) (xy 401.942708 -29.700965) (xy 401.925451 -29.756165) (xy 401.900059 -29.808127)
			(xy 401.867115 -29.855661) (xy 401.827372 -29.897677) (xy 401.804886 -29.915866) (xy 401.796102 -29.923496)
			(xy 401.785906 -29.944379) (xy 401.785328 -29.955998) (xy 401.785328 -30.035754) (xy 401.785841 -30.047389)
			(xy 401.796047 -30.068299) (xy 401.804886 -30.075886) (xy 401.82736 -30.094088) (xy 401.867096 -30.136105)
			(xy 401.900037 -30.183638) (xy 401.925427 -30.235597) (xy 401.942685 -30.290793) (xy 401.951416 -30.347961)
			(xy 401.951952 -30.376876) (xy 401.951466 -30.404127) (xy 401.94371 -30.458075) (xy 401.928355 -30.51037)
			(xy 401.905713 -30.559947) (xy 401.876247 -30.605797) (xy 401.840556 -30.646988) (xy 401.799365 -30.682679)
			(xy 401.753515 -30.712145) (xy 401.703938 -30.734787) (xy 401.651643 -30.750142) (xy 401.597695 -30.757898)
			(xy 401.543193 -30.757898) (xy 401.489245 -30.750142) (xy 401.43695 -30.734787) (xy 401.387373 -30.712145)
			(xy 401.341523 -30.682679) (xy 401.300332 -30.646988) (xy 401.264641 -30.605797) (xy 401.235175 -30.559947)
			(xy 401.212533 -30.51037) (xy 401.197178 -30.458075) (xy 401.189422 -30.404127) (xy 401.188936 -30.376876)
			(xy 400.929395 -30.376876) (xy 400.928429 -30.379847) (xy 400.904805 -30.426223) (xy 400.874227 -30.468341)
			(xy 400.856196 -30.487112) (xy 399.87093 -31.472378) (xy 399.864111 -31.479795) (xy 399.856378 -31.498381)
			(xy 399.855944 -31.508446) (xy 399.855944 -31.567882) (xy 401.298662 -31.567882) (xy 401.302733 -31.51226)
			(xy 401.314859 -31.457823) (xy 401.334782 -31.405732) (xy 401.362078 -31.357097) (xy 401.396164 -31.312954)
			(xy 401.436313 -31.274245) (xy 401.481671 -31.241794) (xy 401.531271 -31.216293) (xy 401.584055 -31.198286)
			(xy 401.638898 -31.188156) (xy 401.694632 -31.186119) (xy 401.750069 -31.192219) (xy 401.804026 -31.206325)
			(xy 401.855355 -31.228137) (xy 401.902961 -31.257191) (xy 401.945829 -31.292866) (xy 401.983046 -31.334403)
			(xy 402.013819 -31.380916) (xy 402.037491 -31.431413) (xy 402.053559 -31.48482) (xy 402.061679 -31.539996)
			(xy 402.062188 -31.567882) (xy 402.061679 -31.595768) (xy 402.053559 -31.650944) (xy 402.037491 -31.704351)
			(xy 402.030499 -31.719266) (xy 402.585426 -31.719266) (xy 402.589497 -31.663644) (xy 402.601623 -31.609207)
			(xy 402.621546 -31.557116) (xy 402.648842 -31.508481) (xy 402.682928 -31.464338) (xy 402.723077 -31.425629)
			(xy 402.768435 -31.393178) (xy 402.818035 -31.367677) (xy 402.870819 -31.34967) (xy 402.925662 -31.33954)
			(xy 402.981396 -31.337503) (xy 403.036833 -31.343603) (xy 403.09079 -31.357709) (xy 403.142119 -31.379521)
			(xy 403.189725 -31.408575) (xy 403.232593 -31.44425) (xy 403.26981 -31.485787) (xy 403.300583 -31.5323)
			(xy 403.324255 -31.582797) (xy 403.340323 -31.636204) (xy 403.344473 -31.664402) (xy 403.861014 -31.664402)
			(xy 403.865085 -31.60878) (xy 403.877211 -31.554343) (xy 403.897134 -31.502252) (xy 403.92443 -31.453617)
			(xy 403.958516 -31.409474) (xy 403.998665 -31.370765) (xy 404.044023 -31.338314) (xy 404.093623 -31.312813)
			(xy 404.146407 -31.294806) (xy 404.20125 -31.284676) (xy 404.256984 -31.282639) (xy 404.312421 -31.288739)
			(xy 404.366378 -31.302845) (xy 404.417707 -31.324657) (xy 404.465313 -31.353711) (xy 404.508181 -31.389386)
			(xy 404.545398 -31.430923) (xy 404.576171 -31.477436) (xy 404.599843 -31.527933) (xy 404.615911 -31.58134)
			(xy 404.624031 -31.636516) (xy 404.62454 -31.664402) (xy 404.624031 -31.692288) (xy 404.615911 -31.747464)
			(xy 404.599843 -31.800871) (xy 404.576171 -31.851368) (xy 404.545398 -31.897881) (xy 404.508181 -31.939418)
			(xy 404.465313 -31.975093) (xy 404.417707 -32.004147) (xy 404.366378 -32.025959) (xy 404.312421 -32.040065)
			(xy 404.256984 -32.046165) (xy 404.20125 -32.044128) (xy 404.146407 -32.033998) (xy 404.093623 -32.015991)
			(xy 404.044023 -31.99049) (xy 403.998665 -31.958039) (xy 403.958516 -31.91933) (xy 403.92443 -31.875187)
			(xy 403.897134 -31.826552) (xy 403.877211 -31.774461) (xy 403.865085 -31.720024) (xy 403.861014 -31.664402)
			(xy 403.344473 -31.664402) (xy 403.348443 -31.69138) (xy 403.348952 -31.719266) (xy 403.348443 -31.747152)
			(xy 403.340323 -31.802328) (xy 403.324255 -31.855735) (xy 403.300583 -31.906232) (xy 403.26981 -31.952745)
			(xy 403.232593 -31.994282) (xy 403.189725 -32.029957) (xy 403.142119 -32.059011) (xy 403.09079 -32.080823)
			(xy 403.036833 -32.094929) (xy 402.981396 -32.101029) (xy 402.925662 -32.098992) (xy 402.870819 -32.088862)
			(xy 402.818035 -32.070855) (xy 402.768435 -32.045354) (xy 402.723077 -32.012903) (xy 402.682928 -31.974194)
			(xy 402.648842 -31.930051) (xy 402.621546 -31.881416) (xy 402.601623 -31.829325) (xy 402.589497 -31.774888)
			(xy 402.585426 -31.719266) (xy 402.030499 -31.719266) (xy 402.013819 -31.754848) (xy 401.983046 -31.801361)
			(xy 401.945829 -31.842898) (xy 401.902961 -31.878573) (xy 401.855355 -31.907627) (xy 401.804026 -31.929439)
			(xy 401.750069 -31.943545) (xy 401.694632 -31.949645) (xy 401.638898 -31.947608) (xy 401.584055 -31.937478)
			(xy 401.531271 -31.919471) (xy 401.481671 -31.89397) (xy 401.436313 -31.861519) (xy 401.396164 -31.82281)
			(xy 401.362078 -31.778667) (xy 401.334782 -31.730032) (xy 401.314859 -31.677941) (xy 401.302733 -31.623504)
			(xy 401.298662 -31.567882) (xy 399.855944 -31.567882) (xy 399.855944 -31.844996) (xy 399.85636 -31.855067)
			(xy 399.864086 -31.873665) (xy 399.87093 -31.881064) (xy 403.254718 -35.264852) (xy 404.20239 -35.264852)
			(xy 404.206461 -35.20923) (xy 404.218587 -35.154793) (xy 404.23851 -35.102702) (xy 404.265806 -35.054067)
			(xy 404.299892 -35.009924) (xy 404.340041 -34.971215) (xy 404.385399 -34.938764) (xy 404.434999 -34.913263)
			(xy 404.487783 -34.895256) (xy 404.542626 -34.885126) (xy 404.59836 -34.883089) (xy 404.653797 -34.889189)
			(xy 404.707754 -34.903295) (xy 404.759083 -34.925107) (xy 404.806689 -34.954161) (xy 404.849557 -34.989836)
			(xy 404.886774 -35.031373) (xy 404.917547 -35.077886) (xy 404.941219 -35.128383) (xy 404.957287 -35.18179)
			(xy 404.965407 -35.236966) (xy 404.965916 -35.264852) (xy 404.965407 -35.292738) (xy 404.957287 -35.347914)
			(xy 404.941219 -35.401321) (xy 404.917547 -35.451818) (xy 404.886774 -35.498331) (xy 404.849557 -35.539868)
			(xy 404.806689 -35.575543) (xy 404.759083 -35.604597) (xy 404.707754 -35.626409) (xy 404.653797 -35.640515)
			(xy 404.59836 -35.646615) (xy 404.542626 -35.644578) (xy 404.487783 -35.634448) (xy 404.434999 -35.616441)
			(xy 404.385399 -35.59094) (xy 404.340041 -35.558489) (xy 404.299892 -35.51978) (xy 404.265806 -35.475637)
			(xy 404.23851 -35.427002) (xy 404.218587 -35.374911) (xy 404.206461 -35.320474) (xy 404.20239 -35.264852)
			(xy 403.254718 -35.264852) (xy 404.276814 -36.286948) (xy 405.50033 -36.286948) (xy 405.504401 -36.231326)
			(xy 405.516527 -36.176889) (xy 405.53645 -36.124798) (xy 405.563746 -36.076163) (xy 405.597832 -36.03202)
			(xy 405.637981 -35.993311) (xy 405.683339 -35.96086) (xy 405.732939 -35.935359) (xy 405.785723 -35.917352)
			(xy 405.840566 -35.907222) (xy 405.8963 -35.905185) (xy 405.951737 -35.911285) (xy 406.005694 -35.925391)
			(xy 406.057023 -35.947203) (xy 406.104629 -35.976257) (xy 406.147497 -36.011932) (xy 406.184714 -36.053469)
			(xy 406.215487 -36.099982) (xy 406.239159 -36.150479) (xy 406.255227 -36.203886) (xy 406.263347 -36.259062)
			(xy 406.263856 -36.286948) (xy 406.263347 -36.314834) (xy 406.255227 -36.37001) (xy 406.239159 -36.423417)
			(xy 406.215487 -36.473914) (xy 406.184714 -36.520427) (xy 406.147497 -36.561964) (xy 406.104629 -36.597639)
			(xy 406.057023 -36.626693) (xy 406.005694 -36.648505) (xy 405.951737 -36.662611) (xy 405.8963 -36.668711)
			(xy 405.840566 -36.666674) (xy 405.785723 -36.656544) (xy 405.732939 -36.638537) (xy 405.683339 -36.613036)
			(xy 405.637981 -36.580585) (xy 405.597832 -36.541876) (xy 405.563746 -36.497733) (xy 405.53645 -36.449098)
			(xy 405.516527 -36.397007) (xy 405.504401 -36.34257) (xy 405.50033 -36.286948) (xy 404.276814 -36.286948)
			(xy 405.63546 -37.645594) (xy 405.644704 -37.653742) (xy 405.668188 -37.661055) (xy 405.680418 -37.659564)
			(xy 405.774906 -37.642546) (xy 405.794464 -37.627306) (xy 405.799544 -37.615876) (xy 405.811283 -37.591255)
			(xy 405.840756 -37.545358) (xy 405.876463 -37.504124) (xy 405.917676 -37.468393) (xy 405.963555 -37.438892)
			(xy 406.013167 -37.416223) (xy 406.0655 -37.400846) (xy 406.119489 -37.393077) (xy 406.146762 -37.39261)
			(xy 406.174015 -37.393091) (xy 406.227966 -37.400843) (xy 406.280265 -37.416195) (xy 406.329846 -37.438834)
			(xy 406.3757 -37.4683) (xy 406.416894 -37.503992) (xy 406.452588 -37.545184) (xy 406.482056 -37.591037)
			(xy 406.504698 -37.640617) (xy 406.520053 -37.692914) (xy 406.527808 -37.746865) (xy 406.52827 -37.774118)
			(xy 406.527802 -37.801393) (xy 406.520055 -37.85539) (xy 406.504693 -37.907732) (xy 406.48203 -37.957352)
			(xy 406.452528 -38.003235) (xy 406.41679 -38.044447) (xy 406.375544 -38.080147) (xy 406.329632 -38.109605)
			(xy 406.305004 -38.121336) (xy 406.293574 -38.126416) (xy 406.278334 -38.145974) (xy 406.261316 -38.240462)
			(xy 406.259829 -38.252692) (xy 406.267135 -38.276181) (xy 406.275286 -38.28542) (xy 407.298652 -39.308786)
			(xy 407.328624 -39.314882) (xy 407.342848 -39.308786) (xy 407.35199 -39.304597) (xy 407.366219 -39.290406)
			(xy 407.373921 -39.271844) (xy 407.374344 -39.261796) (xy 407.374344 -36.734496) (xy 407.374094 -36.727752)
			(xy 407.370491 -36.714751) (xy 407.367232 -36.708842) (xy 407.356405 -36.689782) (xy 407.338709 -36.649676)
			(xy 407.331926 -36.628832) (xy 407.331926 -36.628578) (xy 407.329946 -36.622885) (xy 407.32365 -36.61261)
			(xy 407.31948 -36.608258) (xy 405.828754 -35.117532) (xy 405.810663 -35.098732) (xy 405.779975 -35.056539)
			(xy 405.756271 -35.010063) (xy 405.740133 -34.96045) (xy 405.731961 -34.908922) (xy 405.731472 -34.882836)
			(xy 405.731472 -32.45358) (xy 405.73094 -32.442466) (xy 405.721577 -32.422307) (xy 405.713438 -32.414718)
			(xy 405.645112 -32.357314) (xy 405.623268 -32.351726) (xy 405.612092 -32.353758) (xy 405.586342 -32.358124)
			(xy 405.534322 -32.362833) (xy 405.508206 -32.363156) (xy 405.472791 -32.362659) (xy 405.402478 -32.354122)
			(xy 405.333706 -32.337172) (xy 405.26748 -32.312055) (xy 405.204763 -32.279139) (xy 405.146472 -32.238902)
			(xy 405.093456 -32.191933) (xy 405.046488 -32.138916) (xy 405.006253 -32.080623) (xy 404.973338 -32.017906)
			(xy 404.948224 -31.951678) (xy 404.931275 -31.882906) (xy 404.92274 -31.812593) (xy 404.922228 -31.777178)
			(xy 404.922228 -30.811978) (xy 404.921908 -30.803362) (xy 404.91625 -30.787089) (xy 404.905487 -30.773637)
			(xy 404.898352 -30.768798) (xy 404.814532 -30.715966) (xy 404.78837 -30.714696) (xy 404.776686 -30.720284)
			(xy 404.750665 -30.732313) (xy 404.695911 -30.749287) (xy 404.639232 -30.757869) (xy 404.61057 -30.758384)
			(xy 404.583317 -30.75795) (xy 404.529366 -30.750189) (xy 404.477069 -30.734829) (xy 404.42749 -30.712182)
			(xy 404.381639 -30.682711) (xy 404.340448 -30.647014) (xy 404.304757 -30.605818) (xy 404.275292 -30.559963)
			(xy 404.252652 -30.51038) (xy 404.2373 -30.458081) (xy 404.229546 -30.404129) (xy 404.229062 -30.376876)
			(xy 404.229612 -30.34796) (xy 404.238331 -30.290789) (xy 404.255581 -30.23559) (xy 404.280967 -30.183628)
			(xy 404.313906 -30.136093) (xy 404.353644 -30.094076) (xy 404.376128 -30.075886) (xy 404.384936 -30.06828)
			(xy 404.395118 -30.047378) (xy 404.395686 -30.035754) (xy 404.395686 -29.955998) (xy 404.395138 -29.944367)
			(xy 404.384956 -29.923457) (xy 404.376128 -29.915866) (xy 404.353634 -29.897687) (xy 404.313898 -29.855666)
			(xy 404.28096 -29.808129) (xy 404.255573 -29.756165) (xy 404.238319 -29.700965) (xy 404.229594 -29.643793)
			(xy 404.229062 -29.614876) (xy 404.229555 -29.587626) (xy 404.237314 -29.53368) (xy 404.252671 -29.481387)
			(xy 404.275313 -29.431812) (xy 404.304779 -29.385963) (xy 404.340469 -29.344774) (xy 404.381658 -29.309082)
			(xy 404.427506 -29.279616) (xy 404.477081 -29.256973) (xy 404.529374 -29.241616) (xy 404.58332 -29.233856)
			(xy 404.61057 -29.233368) (xy 404.637831 -29.233875) (xy 404.691797 -29.241639) (xy 404.74411 -29.256998)
			(xy 404.793707 -29.279641) (xy 404.83958 -29.309107) (xy 404.860506 -29.326586) (xy 404.868888 -29.333952)
			(xy 404.88997 -29.340048) (xy 404.988522 -29.32557) (xy 405.007064 -29.313378) (xy 405.012906 -29.30398)
			(xy 405.030646 -29.276728) (xy 405.071253 -29.225937) (xy 405.093932 -29.202634) (xy 407.532078 -26.764742)
			(xy 407.538889 -26.757319) (xy 407.546627 -26.738737) (xy 407.547064 -26.728674) (xy 407.547064 -24.158194)
			(xy 407.547559 -24.124108) (xy 407.555474 -24.056398) (xy 407.571195 -23.990064) (xy 407.594511 -23.926004)
			(xy 407.625106 -23.865084) (xy 407.662567 -23.808127) (xy 407.706387 -23.755905) (xy 407.755973 -23.709123)
			(xy 407.810655 -23.668414) (xy 407.869693 -23.634328) (xy 407.932289 -23.607327) (xy 407.997596 -23.587775)
			(xy 408.064732 -23.575937) (xy 408.132788 -23.571974) (xy 408.200844 -23.575937) (xy 408.26798 -23.587775)
			(xy 408.333287 -23.607327) (xy 408.395883 -23.634328) (xy 408.454921 -23.668414) (xy 408.509603 -23.709123)
			(xy 408.559189 -23.755905) (xy 408.603009 -23.808127) (xy 408.64047 -23.865084) (xy 408.671065 -23.926004)
			(xy 408.694381 -23.990064) (xy 408.710102 -24.056398) (xy 408.718017 -24.124108) (xy 408.718512 -24.158194)
			(xy 408.718512 -24.807418) (xy 408.920186 -24.807418) (xy 408.924257 -24.751796) (xy 408.936383 -24.697359)
			(xy 408.956306 -24.645268) (xy 408.983602 -24.596633) (xy 409.017688 -24.55249) (xy 409.057837 -24.513781)
			(xy 409.103195 -24.48133) (xy 409.152795 -24.455829) (xy 409.205579 -24.437822) (xy 409.260422 -24.427692)
			(xy 409.316156 -24.425655) (xy 409.371593 -24.431755) (xy 409.42555 -24.445861) (xy 409.476879 -24.467673)
			(xy 409.524485 -24.496727) (xy 409.567353 -24.532402) (xy 409.60457 -24.573939) (xy 409.635343 -24.620452)
			(xy 409.659015 -24.670949) (xy 409.675083 -24.724356) (xy 409.683203 -24.779532) (xy 409.683712 -24.807418)
			(xy 409.683203 -24.835304) (xy 409.675083 -24.89048) (xy 409.659015 -24.943887) (xy 409.635343 -24.994384)
			(xy 409.60457 -25.040897) (xy 409.567353 -25.082434) (xy 409.524485 -25.118109) (xy 409.476879 -25.147163)
			(xy 409.42555 -25.168975) (xy 409.371593 -25.183081) (xy 409.316156 -25.189181) (xy 409.260422 -25.187144)
			(xy 409.205579 -25.177014) (xy 409.152795 -25.159007) (xy 409.103195 -25.133506) (xy 409.057837 -25.101055)
			(xy 409.017688 -25.062346) (xy 408.983602 -25.018203) (xy 408.956306 -24.969568) (xy 408.936383 -24.917477)
			(xy 408.924257 -24.86304) (xy 408.920186 -24.807418) (xy 408.718512 -24.807418) (xy 408.718512 -26.683716)
			(xy 408.718975 -26.693726) (xy 408.726642 -26.712221) (xy 408.740803 -26.726374) (xy 408.759302 -26.73403)
			(xy 408.769312 -26.734516) (xy 409.041854 -26.734516) (xy 409.047718 -26.734338) (xy 409.059134 -26.731644)
			(xy 409.06446 -26.729182) (xy 409.065222 -26.728674) (xy 409.081478 -26.7208) (xy 409.083256 -26.720038)
			(xy 409.091942 -26.715122) (xy 409.104956 -26.700017) (xy 409.111234 -26.681092) (xy 409.109828 -26.661203)
			(xy 409.100949 -26.64335) (xy 409.085937 -26.630227) (xy 409.076652 -26.626566) (xy 409.052057 -26.61754)
			(xy 409.005403 -26.593704) (xy 408.962451 -26.563707) (xy 408.924007 -26.528115) (xy 408.890795 -26.487596)
			(xy 408.863441 -26.442914) (xy 408.842458 -26.394909) (xy 408.828242 -26.344485) (xy 408.82106 -26.292589)
			(xy 408.82062 -26.266394) (xy 408.821106 -26.239143) (xy 408.828862 -26.185195) (xy 408.844217 -26.1329)
			(xy 408.866859 -26.083323) (xy 408.896325 -26.037473) (xy 408.932016 -25.996282) (xy 408.973207 -25.960591)
			(xy 409.019057 -25.931125) (xy 409.068634 -25.908483) (xy 409.120929 -25.893128) (xy 409.174877 -25.885372)
			(xy 409.229379 -25.885372) (xy 409.283327 -25.893128) (xy 409.335622 -25.908483) (xy 409.385199 -25.931125)
			(xy 409.431049 -25.960591) (xy 409.47224 -25.996282) (xy 409.507931 -26.037473) (xy 409.537397 -26.083323)
			(xy 409.560039 -26.1329) (xy 409.575394 -26.185195) (xy 409.58315 -26.239143) (xy 409.583636 -26.266394)
			(xy 409.58307 -26.295881) (xy 409.573976 -26.35415) (xy 409.55602 -26.410325) (xy 409.529629 -26.463065)
			(xy 409.495434 -26.511113) (xy 409.454248 -26.553324) (xy 409.430982 -26.571448) (xy 409.421312 -26.579426)
			(xy 409.410664 -26.60209) (xy 409.410662 -26.614628) (xy 409.415234 -26.698956) (xy 409.416476 -26.711392)
			(xy 409.429276 -26.732829) (xy 409.439618 -26.73985) (xy 409.463359 -26.754748) (xy 409.506593 -26.790416)
			(xy 409.544144 -26.832025) (xy 409.575203 -26.87868) (xy 409.599102 -26.929377) (xy 409.615326 -26.983025)
			(xy 409.623527 -27.03847) (xy 409.624022 -27.066494) (xy 409.623517 -27.093744) (xy 409.615761 -27.147691)
			(xy 409.600408 -27.199984) (xy 409.577768 -27.249561) (xy 409.548304 -27.29541) (xy 409.512614 -27.3366)
			(xy 409.471426 -27.372292) (xy 409.425578 -27.401759) (xy 409.376003 -27.424401) (xy 409.32371 -27.439757)
			(xy 409.269764 -27.447515) (xy 409.242514 -27.448002) (xy 409.211712 -27.447381) (xy 409.150911 -27.43746)
			(xy 409.092497 -27.417891) (xy 409.064968 -27.40406) (xy 409.06446 -27.403806) (xy 409.059142 -27.401321)
			(xy 409.047722 -27.398624) (xy 409.041854 -27.398472) (xy 408.867356 -27.398472) (xy 408.857282 -27.398855)
			(xy 408.838683 -27.406603) (xy 408.831288 -27.413458) (xy 407.122376 -29.12237) (xy 408.90698 -29.12237)
			(xy 408.90698 -28.25877) (xy 408.90747 -28.228802) (xy 408.915293 -28.16938) (xy 408.930806 -28.111487)
			(xy 408.953742 -28.056114) (xy 408.983709 -28.004208) (xy 409.020196 -27.956658) (xy 409.062576 -27.914278)
			(xy 409.110126 -27.877791) (xy 409.162032 -27.847824) (xy 409.217405 -27.824888) (xy 409.275298 -27.809375)
			(xy 409.33472 -27.801552) (xy 409.394656 -27.801552) (xy 409.454078 -27.809375) (xy 409.511971 -27.824888)
			(xy 409.567344 -27.847824) (xy 409.61925 -27.877791) (xy 409.6668 -27.914278) (xy 409.70918 -27.956658)
			(xy 409.745667 -28.004208) (xy 409.775634 -28.056114) (xy 409.79857 -28.111487) (xy 409.814083 -28.16938)
			(xy 409.821906 -28.228802) (xy 409.822396 -28.25877) (xy 409.822396 -29.114242) (xy 419.147244 -29.114242)
			(xy 419.147244 -28.250642) (xy 419.147734 -28.220658) (xy 419.155562 -28.161202) (xy 419.171083 -28.103277)
			(xy 419.194032 -28.047873) (xy 419.224016 -27.995939) (xy 419.260522 -27.948363) (xy 419.302927 -27.905958)
			(xy 419.350503 -27.869452) (xy 419.402437 -27.839468) (xy 419.457841 -27.816519) (xy 419.515766 -27.800998)
			(xy 419.575222 -27.79317) (xy 419.63519 -27.79317) (xy 419.694646 -27.800998) (xy 419.752571 -27.816519)
			(xy 419.807975 -27.839468) (xy 419.859909 -27.869452) (xy 419.907485 -27.905958) (xy 419.94989 -27.948363)
			(xy 419.986396 -27.995939) (xy 420.01638 -28.047873) (xy 420.039329 -28.103277) (xy 420.05485 -28.161202)
			(xy 420.062678 -28.220658) (xy 420.063168 -28.250642) (xy 420.063168 -29.114242) (xy 420.062678 -29.144226)
			(xy 420.05485 -29.203682) (xy 420.039329 -29.261607) (xy 420.01638 -29.317011) (xy 419.986396 -29.368945)
			(xy 419.94989 -29.416521) (xy 419.907485 -29.458926) (xy 419.859909 -29.495432) (xy 419.807975 -29.525416)
			(xy 419.752571 -29.548365) (xy 419.694646 -29.563886) (xy 419.63519 -29.571714) (xy 419.575222 -29.571714)
			(xy 419.515766 -29.563886) (xy 419.457841 -29.548365) (xy 419.402437 -29.525416) (xy 419.350503 -29.495432)
			(xy 419.302927 -29.458926) (xy 419.260522 -29.416521) (xy 419.224016 -29.368945) (xy 419.194032 -29.317011)
			(xy 419.171083 -29.261607) (xy 419.155562 -29.203682) (xy 419.147734 -29.144226) (xy 419.147244 -29.114242)
			(xy 409.822396 -29.114242) (xy 409.822396 -29.12237) (xy 409.821906 -29.152338) (xy 409.814083 -29.21176)
			(xy 409.79857 -29.269653) (xy 409.775634 -29.325026) (xy 409.745667 -29.376932) (xy 409.70918 -29.424482)
			(xy 409.6668 -29.466862) (xy 409.61925 -29.503349) (xy 409.567344 -29.533316) (xy 409.511971 -29.556252)
			(xy 409.454078 -29.571765) (xy 409.394656 -29.579588) (xy 409.33472 -29.579588) (xy 409.275298 -29.571765)
			(xy 409.217405 -29.556252) (xy 409.162032 -29.533316) (xy 409.110126 -29.503349) (xy 409.062576 -29.466862)
			(xy 409.020196 -29.424482) (xy 408.983709 -29.376932) (xy 408.953742 -29.325026) (xy 408.930806 -29.269653)
			(xy 408.915293 -29.21176) (xy 408.90747 -29.152338) (xy 408.90698 -29.12237) (xy 407.122376 -29.12237)
			(xy 406.410414 -29.834332) (xy 406.403569 -29.841729) (xy 406.395852 -29.86033) (xy 406.395428 -29.8704)
			(xy 406.395428 -30.922468) (xy 407.05278 -30.922468) (xy 407.05278 -30.058868) (xy 407.05327 -30.0289)
			(xy 407.061093 -29.969478) (xy 407.076606 -29.911585) (xy 407.099542 -29.856212) (xy 407.129509 -29.804306)
			(xy 407.165996 -29.756756) (xy 407.208376 -29.714376) (xy 407.255926 -29.677889) (xy 407.307832 -29.647922)
			(xy 407.363205 -29.624986) (xy 407.421098 -29.609473) (xy 407.48052 -29.60165) (xy 407.540456 -29.60165)
			(xy 407.599878 -29.609473) (xy 407.657771 -29.624986) (xy 407.713144 -29.647922) (xy 407.76505 -29.677889)
			(xy 407.8126 -29.714376) (xy 407.85498 -29.756756) (xy 407.891467 -29.804306) (xy 407.921434 -29.856212)
			(xy 407.94437 -29.911585) (xy 407.959883 -29.969478) (xy 407.967706 -30.0289) (xy 407.968196 -30.058868)
			(xy 407.968196 -30.92069) (xy 421.789352 -30.92069) (xy 421.789352 -30.05709) (xy 421.789842 -30.027106)
			(xy 421.79767 -29.96765) (xy 421.813191 -29.909725) (xy 421.83614 -29.854321) (xy 421.866124 -29.802387)
			(xy 421.90263 -29.754811) (xy 421.945035 -29.712406) (xy 421.992611 -29.6759) (xy 422.044545 -29.645916)
			(xy 422.099949 -29.622967) (xy 422.157874 -29.607446) (xy 422.21733 -29.599618) (xy 422.277298 -29.599618)
			(xy 422.336754 -29.607446) (xy 422.394679 -29.622967) (xy 422.450083 -29.645916) (xy 422.502017 -29.6759)
			(xy 422.549593 -29.712406) (xy 422.591998 -29.754811) (xy 422.628504 -29.802387) (xy 422.658488 -29.854321)
			(xy 422.681437 -29.909725) (xy 422.696958 -29.96765) (xy 422.704786 -30.027106) (xy 422.705276 -30.05709)
			(xy 422.705276 -30.92069) (xy 422.704786 -30.950674) (xy 422.696958 -31.01013) (xy 422.681437 -31.068055)
			(xy 422.658488 -31.123459) (xy 422.628504 -31.175393) (xy 422.591998 -31.222969) (xy 422.549593 -31.265374)
			(xy 422.502017 -31.30188) (xy 422.450083 -31.331864) (xy 422.394679 -31.354813) (xy 422.336754 -31.370334)
			(xy 422.277298 -31.378162) (xy 422.21733 -31.378162) (xy 422.157874 -31.370334) (xy 422.099949 -31.354813)
			(xy 422.044545 -31.331864) (xy 421.992611 -31.30188) (xy 421.945035 -31.265374) (xy 421.90263 -31.222969)
			(xy 421.866124 -31.175393) (xy 421.83614 -31.123459) (xy 421.813191 -31.068055) (xy 421.79767 -31.01013)
			(xy 421.789842 -30.950674) (xy 421.789352 -30.92069) (xy 407.968196 -30.92069) (xy 407.968196 -30.922468)
			(xy 407.967706 -30.952436) (xy 407.959883 -31.011858) (xy 407.94437 -31.069751) (xy 407.921434 -31.125124)
			(xy 407.891467 -31.17703) (xy 407.85498 -31.22458) (xy 407.8126 -31.26696) (xy 407.76505 -31.303447)
			(xy 407.713144 -31.333414) (xy 407.657771 -31.35635) (xy 407.599878 -31.371863) (xy 407.540456 -31.379686)
			(xy 407.48052 -31.379686) (xy 407.421098 -31.371863) (xy 407.363205 -31.35635) (xy 407.307832 -31.333414)
			(xy 407.255926 -31.303447) (xy 407.208376 -31.26696) (xy 407.165996 -31.22458) (xy 407.129509 -31.17703)
			(xy 407.099542 -31.125124) (xy 407.076606 -31.069751) (xy 407.061093 -31.011858) (xy 407.05327 -30.952436)
			(xy 407.05278 -30.922468) (xy 406.395428 -30.922468) (xy 406.395428 -32.722312) (xy 408.90698 -32.722312)
			(xy 408.90698 -31.858712) (xy 408.90747 -31.828744) (xy 408.915293 -31.769322) (xy 408.930806 -31.711429)
			(xy 408.953742 -31.656056) (xy 408.983709 -31.60415) (xy 409.020196 -31.5566) (xy 409.062576 -31.51422)
			(xy 409.110126 -31.477733) (xy 409.162032 -31.447766) (xy 409.217405 -31.42483) (xy 409.275298 -31.409317)
			(xy 409.33472 -31.401494) (xy 409.394656 -31.401494) (xy 409.454078 -31.409317) (xy 409.511971 -31.42483)
			(xy 409.567344 -31.447766) (xy 409.61925 -31.477733) (xy 409.6668 -31.51422) (xy 409.70918 -31.5566)
			(xy 409.745667 -31.60415) (xy 409.775634 -31.656056) (xy 409.79857 -31.711429) (xy 409.814083 -31.769322)
			(xy 409.821906 -31.828744) (xy 409.822396 -31.858712) (xy 409.822396 -32.714184) (xy 419.147244 -32.714184)
			(xy 419.147244 -31.850584) (xy 419.147734 -31.8206) (xy 419.155562 -31.761144) (xy 419.171083 -31.703219)
			(xy 419.194032 -31.647815) (xy 419.224016 -31.595881) (xy 419.260522 -31.548305) (xy 419.302927 -31.5059)
			(xy 419.350503 -31.469394) (xy 419.402437 -31.43941) (xy 419.457841 -31.416461) (xy 419.515766 -31.40094)
			(xy 419.575222 -31.393112) (xy 419.63519 -31.393112) (xy 419.694646 -31.40094) (xy 419.752571 -31.416461)
			(xy 419.807975 -31.43941) (xy 419.859909 -31.469394) (xy 419.907485 -31.5059) (xy 419.94989 -31.548305)
			(xy 419.986396 -31.595881) (xy 420.01638 -31.647815) (xy 420.039329 -31.703219) (xy 420.05485 -31.761144)
			(xy 420.062678 -31.8206) (xy 420.063168 -31.850584) (xy 420.063168 -32.714184) (xy 420.062678 -32.744168)
			(xy 420.05485 -32.803624) (xy 420.039329 -32.861549) (xy 420.01638 -32.916953) (xy 419.986396 -32.968887)
			(xy 419.94989 -33.016463) (xy 419.907485 -33.058868) (xy 419.859909 -33.095374) (xy 419.807975 -33.125358)
			(xy 419.752571 -33.148307) (xy 419.694646 -33.163828) (xy 419.63519 -33.171656) (xy 419.575222 -33.171656)
			(xy 419.515766 -33.163828) (xy 419.457841 -33.148307) (xy 419.402437 -33.125358) (xy 419.350503 -33.095374)
			(xy 419.302927 -33.058868) (xy 419.260522 -33.016463) (xy 419.224016 -32.968887) (xy 419.194032 -32.916953)
			(xy 419.171083 -32.861549) (xy 419.155562 -32.803624) (xy 419.147734 -32.744168) (xy 419.147244 -32.714184)
			(xy 409.822396 -32.714184) (xy 409.822396 -32.722312) (xy 409.821906 -32.75228) (xy 409.814083 -32.811702)
			(xy 409.79857 -32.869595) (xy 409.775634 -32.924968) (xy 409.745667 -32.976874) (xy 409.70918 -33.024424)
			(xy 409.6668 -33.066804) (xy 409.61925 -33.103291) (xy 409.567344 -33.133258) (xy 409.511971 -33.156194)
			(xy 409.454078 -33.171707) (xy 409.394656 -33.17953) (xy 409.33472 -33.17953) (xy 409.275298 -33.171707)
			(xy 409.217405 -33.156194) (xy 409.162032 -33.133258) (xy 409.110126 -33.103291) (xy 409.062576 -33.066804)
			(xy 409.020196 -33.024424) (xy 408.983709 -32.976874) (xy 408.953742 -32.924968) (xy 408.930806 -32.869595)
			(xy 408.915293 -32.811702) (xy 408.90747 -32.75228) (xy 408.90698 -32.722312) (xy 406.395428 -32.722312)
			(xy 406.395428 -34.52241) (xy 407.05278 -34.52241) (xy 407.05278 -33.65881) (xy 407.05327 -33.628842)
			(xy 407.061093 -33.56942) (xy 407.076606 -33.511527) (xy 407.099542 -33.456154) (xy 407.129509 -33.404248)
			(xy 407.165996 -33.356698) (xy 407.208376 -33.314318) (xy 407.255926 -33.277831) (xy 407.307832 -33.247864)
			(xy 407.363205 -33.224928) (xy 407.421098 -33.209415) (xy 407.48052 -33.201592) (xy 407.540456 -33.201592)
			(xy 407.599878 -33.209415) (xy 407.657771 -33.224928) (xy 407.713144 -33.247864) (xy 407.76505 -33.277831)
			(xy 407.8126 -33.314318) (xy 407.85498 -33.356698) (xy 407.891467 -33.404248) (xy 407.921434 -33.456154)
			(xy 407.94437 -33.511527) (xy 407.959883 -33.56942) (xy 407.967706 -33.628842) (xy 407.968196 -33.65881)
			(xy 407.968196 -34.520886) (xy 421.789352 -34.520886) (xy 421.789352 -33.657286) (xy 421.789842 -33.627302)
			(xy 421.79767 -33.567846) (xy 421.813191 -33.509921) (xy 421.83614 -33.454517) (xy 421.866124 -33.402583)
			(xy 421.90263 -33.355007) (xy 421.945035 -33.312602) (xy 421.992611 -33.276096) (xy 422.044545 -33.246112)
			(xy 422.099949 -33.223163) (xy 422.157874 -33.207642) (xy 422.21733 -33.199814) (xy 422.277298 -33.199814)
			(xy 422.336754 -33.207642) (xy 422.394679 -33.223163) (xy 422.450083 -33.246112) (xy 422.502017 -33.276096)
			(xy 422.549593 -33.312602) (xy 422.591998 -33.355007) (xy 422.628504 -33.402583) (xy 422.658488 -33.454517)
			(xy 422.681437 -33.509921) (xy 422.696958 -33.567846) (xy 422.704786 -33.627302) (xy 422.705276 -33.657286)
			(xy 422.705276 -34.520886) (xy 422.704786 -34.55087) (xy 422.696958 -34.610326) (xy 422.681437 -34.668251)
			(xy 422.658488 -34.723655) (xy 422.628504 -34.775589) (xy 422.591998 -34.823165) (xy 422.549593 -34.86557)
			(xy 422.502017 -34.902076) (xy 422.450083 -34.93206) (xy 422.394679 -34.955009) (xy 422.336754 -34.97053)
			(xy 422.277298 -34.978358) (xy 422.21733 -34.978358) (xy 422.157874 -34.97053) (xy 422.099949 -34.955009)
			(xy 422.044545 -34.93206) (xy 421.992611 -34.902076) (xy 421.945035 -34.86557) (xy 421.90263 -34.823165)
			(xy 421.866124 -34.775589) (xy 421.83614 -34.723655) (xy 421.813191 -34.668251) (xy 421.79767 -34.610326)
			(xy 421.789842 -34.55087) (xy 421.789352 -34.520886) (xy 407.968196 -34.520886) (xy 407.968196 -34.52241)
			(xy 407.967706 -34.552378) (xy 407.959883 -34.6118) (xy 407.94437 -34.669693) (xy 407.921434 -34.725066)
			(xy 407.891467 -34.776972) (xy 407.85498 -34.824522) (xy 407.8126 -34.866902) (xy 407.76505 -34.903389)
			(xy 407.713144 -34.933356) (xy 407.657771 -34.956292) (xy 407.599878 -34.971805) (xy 407.540456 -34.979628)
			(xy 407.48052 -34.979628) (xy 407.421098 -34.971805) (xy 407.363205 -34.956292) (xy 407.307832 -34.933356)
			(xy 407.255926 -34.903389) (xy 407.208376 -34.866902) (xy 407.165996 -34.824522) (xy 407.129509 -34.776972)
			(xy 407.099542 -34.725066) (xy 407.076606 -34.669693) (xy 407.061093 -34.6118) (xy 407.05327 -34.552378)
			(xy 407.05278 -34.52241) (xy 406.395428 -34.52241) (xy 406.395428 -34.72434) (xy 406.395825 -34.734413)
			(xy 406.403565 -34.753011) (xy 406.410414 -34.760408) (xy 407.788872 -36.138866) (xy 407.793262 -36.142986)
			(xy 407.803528 -36.149269) (xy 407.809192 -36.151312) (xy 407.8097 -36.151312) (xy 407.835237 -36.159779)
			(xy 407.883838 -36.18285) (xy 407.928716 -36.21252) (xy 407.968982 -36.248199) (xy 408.003837 -36.28918)
			(xy 408.03259 -36.334651) (xy 408.054671 -36.38371) (xy 408.069642 -36.435384) (xy 408.077206 -36.488649)
			(xy 408.07767 -36.515548) (xy 408.077204 -36.543036) (xy 408.069316 -36.597443) (xy 408.06852 -36.60013)
			(xy 412.298649 -36.60013) (xy 412.302653 -36.512245) (xy 412.314633 -36.425088) (xy 412.334488 -36.339381)
			(xy 412.362055 -36.255836) (xy 412.397105 -36.175143) (xy 412.439347 -36.097971) (xy 412.488432 -36.024961)
			(xy 412.543953 -35.956717) (xy 412.60545 -35.893804) (xy 412.672412 -35.836744) (xy 412.744286 -35.78601)
			(xy 412.820476 -35.742022) (xy 412.90035 -35.705144) (xy 412.983247 -35.675683) (xy 413.068479 -35.653881)
			(xy 413.155341 -35.639921) (xy 413.243112 -35.633917) (xy 413.331066 -35.63592) (xy 413.418473 -35.645912)
			(xy 413.504609 -35.663812) (xy 413.588761 -35.68947) (xy 413.670231 -35.722674) (xy 413.748344 -35.763148)
			(xy 413.822452 -35.810559) (xy 413.891943 -35.864512) (xy 413.905034 -35.876738) (xy 419.017194 -35.876738)
			(xy 419.021265 -35.821116) (xy 419.033391 -35.766679) (xy 419.053314 -35.714588) (xy 419.08061 -35.665953)
			(xy 419.114696 -35.62181) (xy 419.154845 -35.583101) (xy 419.200203 -35.55065) (xy 419.249803 -35.525149)
			(xy 419.302587 -35.507142) (xy 419.35743 -35.497012) (xy 419.413164 -35.494975) (xy 419.468601 -35.501075)
			(xy 419.522558 -35.515181) (xy 419.573887 -35.536993) (xy 419.621493 -35.566047) (xy 419.664361 -35.601722)
			(xy 419.701578 -35.643259) (xy 419.732351 -35.689772) (xy 419.756023 -35.740269) (xy 419.772091 -35.793676)
			(xy 419.780211 -35.848852) (xy 419.78072 -35.876738) (xy 419.780211 -35.904624) (xy 419.772091 -35.9598)
			(xy 419.756023 -36.013207) (xy 419.732351 -36.063704) (xy 419.701578 -36.110217) (xy 419.664361 -36.151754)
			(xy 419.621493 -36.187429) (xy 419.573887 -36.216483) (xy 419.522558 -36.238295) (xy 419.468601 -36.252401)
			(xy 419.413164 -36.258501) (xy 419.35743 -36.256464) (xy 419.302587 -36.246334) (xy 419.249803 -36.228327)
			(xy 419.200203 -36.202826) (xy 419.154845 -36.170375) (xy 419.114696 -36.131666) (xy 419.08061 -36.087523)
			(xy 419.053314 -36.038888) (xy 419.033391 -35.986797) (xy 419.021265 -35.93236) (xy 419.017194 -35.876738)
			(xy 413.905034 -35.876738) (xy 413.956239 -35.92456) (xy 414.014808 -35.990207) (xy 414.067165 -36.060907)
			(xy 414.112877 -36.136076) (xy 414.151563 -36.21509) (xy 414.182904 -36.297295) (xy 414.206639 -36.382009)
			(xy 414.222573 -36.46853) (xy 414.226356 -36.50996) (xy 420.913812 -36.50996) (xy 420.917883 -36.454338)
			(xy 420.930009 -36.399901) (xy 420.949932 -36.34781) (xy 420.977228 -36.299175) (xy 421.011314 -36.255032)
			(xy 421.051463 -36.216323) (xy 421.096821 -36.183872) (xy 421.146421 -36.158371) (xy 421.199205 -36.140364)
			(xy 421.254048 -36.130234) (xy 421.309782 -36.128197) (xy 421.365219 -36.134297) (xy 421.419176 -36.148403)
			(xy 421.470505 -36.170215) (xy 421.518111 -36.199269) (xy 421.560979 -36.234944) (xy 421.598196 -36.276481)
			(xy 421.628969 -36.322994) (xy 421.652641 -36.373491) (xy 421.668709 -36.426898) (xy 421.676829 -36.482074)
			(xy 421.677338 -36.50996) (xy 421.676829 -36.537846) (xy 421.668709 -36.593022) (xy 421.652641 -36.646429)
			(xy 421.628969 -36.696926) (xy 421.598196 -36.743439) (xy 421.560979 -36.784976) (xy 421.518111 -36.820651)
			(xy 421.470505 -36.849705) (xy 421.419176 -36.871517) (xy 421.365219 -36.885623) (xy 421.309782 -36.891723)
			(xy 421.254048 -36.889686) (xy 421.199205 -36.879556) (xy 421.146421 -36.861549) (xy 421.096821 -36.836048)
			(xy 421.051463 -36.803597) (xy 421.011314 -36.764888) (xy 420.977228 -36.720745) (xy 420.949932 -36.67211)
			(xy 420.930009 -36.620019) (xy 420.917883 -36.565582) (xy 420.913812 -36.50996) (xy 414.226356 -36.50996)
			(xy 414.230573 -36.556142) (xy 414.231074 -36.60013) (xy 414.230573 -36.644118) (xy 414.222573 -36.73173)
			(xy 414.206639 -36.818251) (xy 414.182904 -36.902965) (xy 414.151563 -36.98517) (xy 414.112877 -37.064184)
			(xy 414.067165 -37.139353) (xy 414.014808 -37.210053) (xy 413.956239 -37.2757) (xy 413.891943 -37.335748)
			(xy 413.822452 -37.389701) (xy 413.748344 -37.437112) (xy 413.674913 -37.47516) (xy 418.059106 -37.47516)
			(xy 418.063177 -37.419538) (xy 418.075303 -37.365101) (xy 418.095226 -37.31301) (xy 418.122522 -37.264375)
			(xy 418.156608 -37.220232) (xy 418.196757 -37.181523) (xy 418.242115 -37.149072) (xy 418.291715 -37.123571)
			(xy 418.344499 -37.105564) (xy 418.399342 -37.095434) (xy 418.455076 -37.093397) (xy 418.510513 -37.099497)
			(xy 418.56447 -37.113603) (xy 418.615799 -37.135415) (xy 418.663405 -37.164469) (xy 418.706273 -37.200144)
			(xy 418.74349 -37.241681) (xy 418.774263 -37.288194) (xy 418.797935 -37.338691) (xy 418.814003 -37.392098)
			(xy 418.822123 -37.447274) (xy 418.822632 -37.47516) (xy 418.822123 -37.503046) (xy 418.814003 -37.558222)
			(xy 418.797935 -37.611629) (xy 418.774263 -37.662126) (xy 418.77411 -37.662358) (xy 420.248332 -37.662358)
			(xy 420.252403 -37.606736) (xy 420.264529 -37.552299) (xy 420.284452 -37.500208) (xy 420.311748 -37.451573)
			(xy 420.345834 -37.40743) (xy 420.385983 -37.368721) (xy 420.431341 -37.33627) (xy 420.480941 -37.310769)
			(xy 420.533725 -37.292762) (xy 420.588568 -37.282632) (xy 420.644302 -37.280595) (xy 420.699739 -37.286695)
			(xy 420.753696 -37.300801) (xy 420.805025 -37.322613) (xy 420.852631 -37.351667) (xy 420.895499 -37.387342)
			(xy 420.932716 -37.428879) (xy 420.963489 -37.475392) (xy 420.987161 -37.525889) (xy 421.003229 -37.579296)
			(xy 421.011349 -37.634472) (xy 421.011858 -37.662358) (xy 421.011349 -37.690244) (xy 421.003229 -37.74542)
			(xy 420.987161 -37.798827) (xy 420.963489 -37.849324) (xy 420.932716 -37.895837) (xy 420.895499 -37.937374)
			(xy 420.852631 -37.973049) (xy 420.805025 -38.002103) (xy 420.753696 -38.023915) (xy 420.699739 -38.038021)
			(xy 420.644302 -38.044121) (xy 420.588568 -38.042084) (xy 420.533725 -38.031954) (xy 420.480941 -38.013947)
			(xy 420.431341 -37.988446) (xy 420.385983 -37.955995) (xy 420.345834 -37.917286) (xy 420.311748 -37.873143)
			(xy 420.284452 -37.824508) (xy 420.264529 -37.772417) (xy 420.252403 -37.71798) (xy 420.248332 -37.662358)
			(xy 418.77411 -37.662358) (xy 418.74349 -37.708639) (xy 418.706273 -37.750176) (xy 418.663405 -37.785851)
			(xy 418.615799 -37.814905) (xy 418.56447 -37.836717) (xy 418.510513 -37.850823) (xy 418.455076 -37.856923)
			(xy 418.399342 -37.854886) (xy 418.344499 -37.844756) (xy 418.291715 -37.826749) (xy 418.242115 -37.801248)
			(xy 418.196757 -37.768797) (xy 418.156608 -37.730088) (xy 418.122522 -37.685945) (xy 418.095226 -37.63731)
			(xy 418.075303 -37.585219) (xy 418.063177 -37.530782) (xy 418.059106 -37.47516) (xy 413.674913 -37.47516)
			(xy 413.670231 -37.477586) (xy 413.588761 -37.51079) (xy 413.504609 -37.536448) (xy 413.418473 -37.554348)
			(xy 413.331066 -37.56434) (xy 413.243112 -37.566343) (xy 413.155341 -37.560339) (xy 413.068479 -37.546379)
			(xy 412.983247 -37.524577) (xy 412.90035 -37.495116) (xy 412.820476 -37.458238) (xy 412.744286 -37.41425)
			(xy 412.672412 -37.363516) (xy 412.60545 -37.306456) (xy 412.543953 -37.243543) (xy 412.488432 -37.175299)
			(xy 412.439347 -37.102289) (xy 412.397105 -37.025117) (xy 412.362055 -36.944424) (xy 412.334488 -36.860879)
			(xy 412.314633 -36.775172) (xy 412.302653 -36.688015) (xy 412.298649 -36.60013) (xy 408.06852 -36.60013)
			(xy 408.053696 -36.650153) (xy 408.042618 -36.675314) (xy 408.037792 -36.685474) (xy 408.037792 -38.729951)
			(xy 424.000897 -38.729951) (xy 424.000897 -38.675449) (xy 424.008654 -38.621501) (xy 424.02401 -38.569207)
			(xy 424.046652 -38.51963) (xy 424.07612 -38.47378) (xy 424.111813 -38.432592) (xy 424.153005 -38.396902)
			(xy 424.198856 -38.367438) (xy 424.248435 -38.3448) (xy 424.300731 -38.329448) (xy 424.354679 -38.321695)
			(xy 424.38193 -38.321234) (xy 424.410233 -38.321763) (xy 424.46622 -38.330106) (xy 424.520359 -38.346633)
			(xy 424.571461 -38.370981) (xy 424.618401 -38.402616) (xy 424.660149 -38.440843) (xy 424.695788 -38.48482)
			(xy 424.710606 -38.50894) (xy 424.71823 -38.520957) (xy 424.738843 -38.540558) (xy 424.764069 -38.5537)
			(xy 424.791945 -38.559362) (xy 424.8203 -38.557101) (xy 424.846927 -38.547095) (xy 424.869752 -38.530121)
			(xy 424.878754 -38.5191) (xy 424.896914 -38.496202) (xy 424.939083 -38.45574) (xy 424.986924 -38.422175)
			(xy 425.039321 -38.396291) (xy 425.09505 -38.378694) (xy 425.152809 -38.369794) (xy 425.18203 -38.36924)
			(xy 425.209283 -38.369632) (xy 425.263235 -38.377393) (xy 425.315532 -38.392753) (xy 425.365112 -38.415398)
			(xy 425.410964 -38.444869) (xy 425.452156 -38.480565) (xy 425.487849 -38.52176) (xy 425.517316 -38.567614)
			(xy 425.539958 -38.617196) (xy 425.555313 -38.669495) (xy 425.56307 -38.723447) (xy 425.56307 -38.777953)
			(xy 425.555313 -38.831905) (xy 425.539958 -38.884204) (xy 425.517316 -38.933786) (xy 425.487849 -38.97964)
			(xy 425.452156 -39.020835) (xy 425.410964 -39.056531) (xy 425.365112 -39.086002) (xy 425.315532 -39.108647)
			(xy 425.263235 -39.124007) (xy 425.209283 -39.131768) (xy 425.18203 -39.132256) (xy 425.153726 -39.131763)
			(xy 425.097736 -39.123415) (xy 425.043596 -39.106882) (xy 424.992495 -39.082527) (xy 424.945555 -39.050886)
			(xy 424.903808 -39.012655) (xy 424.86817 -38.968672) (xy 424.853354 -38.94455) (xy 424.845783 -38.932498)
			(xy 424.825158 -38.912896) (xy 424.79992 -38.899756) (xy 424.772035 -38.894099) (xy 424.743671 -38.896366)
			(xy 424.717038 -38.906381) (xy 424.694209 -38.923364) (xy 424.685206 -38.93439) (xy 424.667009 -38.957257)
			(xy 424.624848 -38.997722) (xy 424.577015 -39.031291) (xy 424.524625 -39.057179) (xy 424.468903 -39.074783)
			(xy 424.411149 -39.083692) (xy 424.38193 -39.08425) (xy 424.354679 -39.083705) (xy 424.300731 -39.075952)
			(xy 424.248435 -39.0606) (xy 424.198856 -39.037962) (xy 424.153005 -39.008498) (xy 424.111813 -38.972808)
			(xy 424.07612 -38.93162) (xy 424.046652 -38.88577) (xy 424.02401 -38.836193) (xy 424.008654 -38.783899)
			(xy 424.000897 -38.729951) (xy 408.037792 -38.729951) (xy 408.037792 -39.368222) (xy 408.038182 -39.378296)
			(xy 408.045925 -39.396895) (xy 408.052778 -39.40429) (xy 409.91734 -41.268757) (xy 416.143827 -41.268757)
			(xy 416.143827 -41.214243) (xy 416.151586 -41.160284) (xy 416.166945 -41.107978) (xy 416.189593 -41.058391)
			(xy 416.219068 -41.012532) (xy 416.254769 -40.971335) (xy 416.295971 -40.935639) (xy 416.341833 -40.90617)
			(xy 416.391423 -40.883529) (xy 416.443731 -40.868176) (xy 416.497691 -40.860424) (xy 416.524948 -40.859964)
			(xy 416.553688 -40.860468) (xy 416.610515 -40.869097) (xy 416.665406 -40.886152) (xy 416.717117 -40.911248)
			(xy 416.764479 -40.943816) (xy 416.785806 -40.963088) (xy 416.792664 -40.969692) (xy 416.810698 -40.976804)
			(xy 416.899598 -40.976804) (xy 416.917632 -40.969692) (xy 416.92449 -40.963088) (xy 416.945805 -40.943803)
			(xy 416.993169 -40.911237) (xy 417.044884 -40.886146) (xy 417.099778 -40.869099) (xy 417.156608 -40.860482)
			(xy 417.185348 -40.859964) (xy 417.212595 -40.860509) (xy 417.266533 -40.868271) (xy 417.318819 -40.883629)
			(xy 417.368386 -40.906271) (xy 417.414227 -40.935737) (xy 417.455408 -40.971426) (xy 417.491092 -41.012611)
			(xy 417.520552 -41.058456) (xy 417.543188 -41.108026) (xy 417.558539 -41.160313) (xy 417.566294 -41.214253)
			(xy 417.566294 -41.268747) (xy 417.558539 -41.322687) (xy 417.543188 -41.374974) (xy 417.520552 -41.424544)
			(xy 417.491092 -41.470389) (xy 417.455408 -41.511574) (xy 417.414227 -41.547263) (xy 417.368386 -41.576729)
			(xy 417.318819 -41.599371) (xy 417.266533 -41.614729) (xy 417.212595 -41.622491) (xy 417.185348 -41.62298)
			(xy 417.156609 -41.622467) (xy 417.099782 -41.613838) (xy 417.044892 -41.596784) (xy 416.993181 -41.571691)
			(xy 416.945818 -41.539126) (xy 416.92449 -41.519856) (xy 416.917632 -41.513252) (xy 416.899598 -41.50614)
			(xy 416.810698 -41.50614) (xy 416.792664 -41.513252) (xy 416.785806 -41.519856) (xy 416.764499 -41.53915)
			(xy 416.717132 -41.571714) (xy 416.665415 -41.596802) (xy 416.61052 -41.613847) (xy 416.553688 -41.622463)
			(xy 416.524948 -41.62298) (xy 416.497691 -41.622576) (xy 416.443731 -41.614824) (xy 416.391423 -41.599471)
			(xy 416.341833 -41.57683) (xy 416.295971 -41.547361) (xy 416.254769 -41.511665) (xy 416.219068 -41.470468)
			(xy 416.189593 -41.424609) (xy 416.166945 -41.375022) (xy 416.151586 -41.322716) (xy 416.143827 -41.268757)
			(xy 409.91734 -41.268757) (xy 411.953909 -43.305222) (xy 418.60724 -43.305222) (xy 418.607709 -43.277852)
			(xy 418.615525 -43.223672) (xy 418.631013 -43.171169) (xy 418.653854 -43.121422) (xy 418.683579 -43.075455)
			(xy 418.70122 -43.054524) (xy 418.701474 -43.05427) (xy 418.707046 -43.047174) (xy 418.7133 -43.030264)
			(xy 418.713666 -43.02125) (xy 418.713666 -42.954194) (xy 418.713319 -42.945176) (xy 418.707066 -42.928259)
			(xy 418.701474 -42.921174) (xy 418.70122 -42.921174) (xy 418.70122 -42.92092) (xy 418.68358 -42.899989)
			(xy 418.653868 -42.854016) (xy 418.631031 -42.804268) (xy 418.615541 -42.751767) (xy 418.607713 -42.697591)
			(xy 418.60724 -42.670222) (xy 418.607793 -42.641484) (xy 418.616411 -42.584659) (xy 418.633455 -42.529769)
			(xy 418.65854 -42.478057) (xy 418.691097 -42.430693) (xy 418.710364 -42.409364) (xy 418.716968 -42.402506)
			(xy 418.72408 -42.384472) (xy 418.72408 -42.295572) (xy 418.716968 -42.277538) (xy 418.710364 -42.27068)
			(xy 418.691113 -42.249335) (xy 418.658544 -42.201977) (xy 418.633448 -42.150268) (xy 418.616395 -42.09538)
			(xy 418.607769 -42.038554) (xy 418.607767 -41.981078) (xy 418.616388 -41.924251) (xy 418.633437 -41.869361)
			(xy 418.658528 -41.817651) (xy 418.691093 -41.77029) (xy 418.710364 -41.748964) (xy 418.716968 -41.742106)
			(xy 418.72408 -41.724072) (xy 418.72408 -41.635172) (xy 418.716968 -41.617138) (xy 418.710364 -41.61028)
			(xy 418.691108 -41.58894) (xy 418.658539 -41.541582) (xy 418.633443 -41.489874) (xy 418.616389 -41.434986)
			(xy 418.607763 -41.37816) (xy 418.60724 -41.349422) (xy 418.607726 -41.322171) (xy 418.615482 -41.268223)
			(xy 418.630837 -41.215928) (xy 418.653479 -41.166351) (xy 418.682945 -41.120501) (xy 418.718636 -41.07931)
			(xy 418.759827 -41.043619) (xy 418.805677 -41.014153) (xy 418.855254 -40.991511) (xy 418.907549 -40.976156)
			(xy 418.961497 -40.9684) (xy 419.015999 -40.9684) (xy 419.03912 -40.971724) (xy 426.893988 -40.971724)
			(xy 426.898059 -40.916102) (xy 426.910185 -40.861665) (xy 426.930108 -40.809574) (xy 426.957404 -40.760939)
			(xy 426.99149 -40.716796) (xy 427.031639 -40.678087) (xy 427.076997 -40.645636) (xy 427.126597 -40.620135)
			(xy 427.179381 -40.602128) (xy 427.234224 -40.591998) (xy 427.289958 -40.589961) (xy 427.345395 -40.596061)
			(xy 427.399352 -40.610167) (xy 427.450681 -40.631979) (xy 427.498287 -40.661033) (xy 427.541155 -40.696708)
			(xy 427.578372 -40.738245) (xy 427.609145 -40.784758) (xy 427.632817 -40.835255) (xy 427.648885 -40.888662)
			(xy 427.657005 -40.943838) (xy 427.657514 -40.971724) (xy 427.657005 -40.99961) (xy 427.648885 -41.054786)
			(xy 427.632817 -41.108193) (xy 427.609145 -41.15869) (xy 427.578372 -41.205203) (xy 427.541155 -41.24674)
			(xy 427.498287 -41.282415) (xy 427.450681 -41.311469) (xy 427.399352 -41.333281) (xy 427.345395 -41.347387)
			(xy 427.289958 -41.353487) (xy 427.234224 -41.35145) (xy 427.179381 -41.34132) (xy 427.126597 -41.323313)
			(xy 427.076997 -41.297812) (xy 427.031639 -41.265361) (xy 426.99149 -41.226652) (xy 426.957404 -41.182509)
			(xy 426.930108 -41.133874) (xy 426.910185 -41.081783) (xy 426.898059 -41.027346) (xy 426.893988 -40.971724)
			(xy 419.03912 -40.971724) (xy 419.069947 -40.976156) (xy 419.122242 -40.991511) (xy 419.171819 -41.014153)
			(xy 419.217669 -41.043619) (xy 419.25886 -41.07931) (xy 419.294551 -41.120501) (xy 419.324017 -41.166351)
			(xy 419.346659 -41.215928) (xy 419.362014 -41.268223) (xy 419.36977 -41.322171) (xy 419.370256 -41.349422)
			(xy 419.369731 -41.378161) (xy 419.361106 -41.434987) (xy 419.344056 -41.489877) (xy 419.318965 -41.541589)
			(xy 419.286402 -41.588952) (xy 419.267132 -41.61028) (xy 419.260528 -41.617138) (xy 419.253416 -41.635172)
			(xy 419.253416 -41.724072) (xy 419.260528 -41.742106) (xy 419.267132 -41.748964) (xy 419.286422 -41.770273)
			(xy 419.318982 -41.81764) (xy 419.344069 -41.869355) (xy 419.361114 -41.924248) (xy 419.369733 -41.981077)
			(xy 419.369731 -42.038555) (xy 419.361107 -42.095383) (xy 419.344057 -42.150275) (xy 419.318966 -42.201988)
			(xy 419.286402 -42.249352) (xy 419.267132 -42.27068) (xy 419.260528 -42.277538) (xy 419.253416 -42.295572)
			(xy 419.253416 -42.384472) (xy 419.260528 -42.402506) (xy 419.267132 -42.409364) (xy 419.286408 -42.430686)
			(xy 419.318975 -42.478049) (xy 419.344067 -42.529762) (xy 419.361116 -42.584654) (xy 419.369737 -42.641483)
			(xy 419.370256 -42.670222) (xy 419.369814 -42.697593) (xy 419.361992 -42.751774) (xy 419.346498 -42.804278)
			(xy 419.32594 -42.849038) (xy 421.191942 -42.849038) (xy 421.196013 -42.793416) (xy 421.208139 -42.738979)
			(xy 421.228062 -42.686888) (xy 421.255358 -42.638253) (xy 421.289444 -42.59411) (xy 421.329593 -42.555401)
			(xy 421.374951 -42.52295) (xy 421.424551 -42.497449) (xy 421.477335 -42.479442) (xy 421.532178 -42.469312)
			(xy 421.587912 -42.467275) (xy 421.643349 -42.473375) (xy 421.697306 -42.487481) (xy 421.748635 -42.509293)
			(xy 421.796241 -42.538347) (xy 421.839109 -42.574022) (xy 421.876326 -42.615559) (xy 421.907099 -42.662072)
			(xy 421.930771 -42.712569) (xy 421.946839 -42.765976) (xy 421.954959 -42.821152) (xy 421.95532 -42.84091)
			(xy 427.233078 -42.84091) (xy 427.237149 -42.785288) (xy 427.249275 -42.730851) (xy 427.269198 -42.67876)
			(xy 427.296494 -42.630125) (xy 427.33058 -42.585982) (xy 427.370729 -42.547273) (xy 427.416087 -42.514822)
			(xy 427.465687 -42.489321) (xy 427.518471 -42.471314) (xy 427.573314 -42.461184) (xy 427.629048 -42.459147)
			(xy 427.684485 -42.465247) (xy 427.738442 -42.479353) (xy 427.789771 -42.501165) (xy 427.837377 -42.530219)
			(xy 427.880245 -42.565894) (xy 427.917462 -42.607431) (xy 427.948235 -42.653944) (xy 427.971907 -42.704441)
			(xy 427.987975 -42.757848) (xy 427.996095 -42.813024) (xy 427.996604 -42.84091) (xy 427.996095 -42.868796)
			(xy 427.987975 -42.923972) (xy 427.971907 -42.977379) (xy 427.948235 -43.027876) (xy 427.917462 -43.074389)
			(xy 427.880245 -43.115926) (xy 427.837377 -43.151601) (xy 427.789771 -43.180655) (xy 427.738442 -43.202467)
			(xy 427.684485 -43.216573) (xy 427.629048 -43.222673) (xy 427.573314 -43.220636) (xy 427.518471 -43.210506)
			(xy 427.465687 -43.192499) (xy 427.416087 -43.166998) (xy 427.370729 -43.134547) (xy 427.33058 -43.095838)
			(xy 427.296494 -43.051695) (xy 427.269198 -43.00306) (xy 427.249275 -42.950969) (xy 427.237149 -42.896532)
			(xy 427.233078 -42.84091) (xy 421.95532 -42.84091) (xy 421.955468 -42.849038) (xy 421.954959 -42.876924)
			(xy 421.946839 -42.9321) (xy 421.930771 -42.985507) (xy 421.907099 -43.036004) (xy 421.876326 -43.082517)
			(xy 421.839109 -43.124054) (xy 421.796241 -43.159729) (xy 421.748635 -43.188783) (xy 421.697306 -43.210595)
			(xy 421.643349 -43.224701) (xy 421.587912 -43.230801) (xy 421.532178 -43.228764) (xy 421.477335 -43.218634)
			(xy 421.424551 -43.200627) (xy 421.374951 -43.175126) (xy 421.329593 -43.142675) (xy 421.289444 -43.103966)
			(xy 421.255358 -43.059823) (xy 421.228062 -43.011188) (xy 421.208139 -42.959097) (xy 421.196013 -42.90466)
			(xy 421.191942 -42.849038) (xy 419.32594 -42.849038) (xy 419.32365 -42.854024) (xy 419.29392 -42.899989)
			(xy 419.276276 -42.92092) (xy 419.276022 -42.921174) (xy 419.270431 -42.928257) (xy 419.264189 -42.945177)
			(xy 419.26383 -42.954194) (xy 419.26383 -43.02125) (xy 419.264204 -43.030265) (xy 419.270439 -43.047183)
			(xy 419.276022 -43.05427) (xy 419.276276 -43.05427) (xy 419.276276 -43.054524) (xy 419.293889 -43.075477)
			(xy 419.323606 -43.121444) (xy 419.346447 -43.171186) (xy 419.361944 -43.223682) (xy 419.369779 -43.277854)
			(xy 419.370256 -43.305222) (xy 419.36977 -43.332473) (xy 419.362014 -43.386421) (xy 419.346659 -43.438716)
			(xy 419.324017 -43.488293) (xy 419.294551 -43.534143) (xy 419.25886 -43.575334) (xy 419.217669 -43.611025)
			(xy 419.171819 -43.640491) (xy 419.122242 -43.663133) (xy 419.069947 -43.678488) (xy 419.015999 -43.686244)
			(xy 418.961497 -43.686244) (xy 418.907549 -43.678488) (xy 418.855254 -43.663133) (xy 418.805677 -43.640491)
			(xy 418.759827 -43.611025) (xy 418.718636 -43.575334) (xy 418.682945 -43.534143) (xy 418.653479 -43.488293)
			(xy 418.630837 -43.438716) (xy 418.615482 -43.386421) (xy 418.607726 -43.332473) (xy 418.60724 -43.305222)
			(xy 411.953909 -43.305222) (xy 412.384969 -43.73626) (xy 420.513 -43.73626) (xy 420.517071 -43.680638)
			(xy 420.529197 -43.626201) (xy 420.54912 -43.57411) (xy 420.576416 -43.525475) (xy 420.610502 -43.481332)
			(xy 420.650651 -43.442623) (xy 420.696009 -43.410172) (xy 420.745609 -43.384671) (xy 420.798393 -43.366664)
			(xy 420.853236 -43.356534) (xy 420.90897 -43.354497) (xy 420.964407 -43.360597) (xy 421.018364 -43.374703)
			(xy 421.069693 -43.396515) (xy 421.117299 -43.425569) (xy 421.160167 -43.461244) (xy 421.197384 -43.502781)
			(xy 421.228157 -43.549294) (xy 421.251829 -43.599791) (xy 421.267897 -43.653198) (xy 421.276017 -43.708374)
			(xy 421.276526 -43.73626) (xy 421.276017 -43.764146) (xy 421.267897 -43.819322) (xy 421.251829 -43.872729)
			(xy 421.228157 -43.923226) (xy 421.197384 -43.969739) (xy 421.160167 -44.011276) (xy 421.117299 -44.046951)
			(xy 421.069693 -44.076005) (xy 421.018364 -44.097817) (xy 420.964407 -44.111923) (xy 420.90897 -44.118023)
			(xy 420.853236 -44.115986) (xy 420.798393 -44.105856) (xy 420.745609 -44.087849) (xy 420.696009 -44.062348)
			(xy 420.650651 -44.029897) (xy 420.610502 -43.991188) (xy 420.576416 -43.947045) (xy 420.54912 -43.89841)
			(xy 420.529197 -43.846319) (xy 420.517071 -43.791882) (xy 420.513 -43.73626) (xy 412.384969 -43.73626)
			(xy 413.022034 -44.373292) (xy 413.040135 -44.392084) (xy 413.070822 -44.434278) (xy 413.094525 -44.480756)
			(xy 413.11066 -44.530372) (xy 413.118829 -44.581901) (xy 413.119316 -44.607988) (xy 413.119316 -45.114464)
			(xy 420.365426 -45.114464) (xy 420.369497 -45.058842) (xy 420.381623 -45.004405) (xy 420.401546 -44.952314)
			(xy 420.428842 -44.903679) (xy 420.462928 -44.859536) (xy 420.503077 -44.820827) (xy 420.548435 -44.788376)
			(xy 420.598035 -44.762875) (xy 420.650819 -44.744868) (xy 420.705662 -44.734738) (xy 420.761396 -44.732701)
			(xy 420.816833 -44.738801) (xy 420.87079 -44.752907) (xy 420.922119 -44.774719) (xy 420.969725 -44.803773)
			(xy 421.012593 -44.839448) (xy 421.04981 -44.880985) (xy 421.080583 -44.927498) (xy 421.104255 -44.977995)
			(xy 421.120323 -45.031402) (xy 421.128443 -45.086578) (xy 421.128952 -45.114464) (xy 421.128443 -45.14235)
			(xy 421.120323 -45.197526) (xy 421.104255 -45.250933) (xy 421.080583 -45.30143) (xy 421.04981 -45.347943)
			(xy 421.012593 -45.38948) (xy 420.969725 -45.425155) (xy 420.922119 -45.454209) (xy 420.87079 -45.476021)
			(xy 420.816833 -45.490127) (xy 420.761396 -45.496227) (xy 420.705662 -45.49419) (xy 420.650819 -45.48406)
			(xy 420.598035 -45.466053) (xy 420.548435 -45.440552) (xy 420.503077 -45.408101) (xy 420.462928 -45.369392)
			(xy 420.428842 -45.325249) (xy 420.401546 -45.276614) (xy 420.381623 -45.224523) (xy 420.369497 -45.170086)
			(xy 420.365426 -45.114464) (xy 413.119316 -45.114464) (xy 413.119316 -46.082204) (xy 418.352478 -46.082204)
			(xy 418.352981 -46.054953) (xy 418.360737 -46.001007) (xy 418.376091 -45.948714) (xy 418.398731 -45.899137)
			(xy 418.428195 -45.853288) (xy 418.463885 -45.812098) (xy 418.505073 -45.776406) (xy 418.550921 -45.746939)
			(xy 418.600497 -45.724297) (xy 418.65279 -45.708941) (xy 418.706736 -45.701183) (xy 418.733986 -45.700696)
			(xy 418.760888 -45.701169) (xy 418.814158 -45.708739) (xy 418.865836 -45.723716) (xy 418.914897 -45.745805)
			(xy 418.96037 -45.774565) (xy 419.001352 -45.809429) (xy 419.03703 -45.849703) (xy 419.052248 -45.871892)
			(xy 419.05936 -45.882814) (xy 419.08222 -45.894752) (xy 419.194488 -45.89272) (xy 419.21684 -45.879766)
			(xy 419.223698 -45.86859) (xy 419.238634 -45.844998) (xy 419.274311 -45.802047) (xy 419.315867 -45.764753)
			(xy 419.362414 -45.733915) (xy 419.412959 -45.71019) (xy 419.466422 -45.694085) (xy 419.521662 -45.685944)
			(xy 419.54958 -45.685456) (xy 419.576573 -45.685929) (xy 419.630021 -45.693532) (xy 419.681864 -45.708589)
			(xy 419.731069 -45.730801) (xy 419.776653 -45.759723) (xy 419.797484 -45.776896) (xy 419.805612 -45.784008)
			(xy 419.826186 -45.790104) (xy 419.91153 -45.779182) (xy 419.922081 -45.777432) (xy 419.940361 -45.76636)
			(xy 419.946836 -45.757846) (xy 419.962173 -45.736603) (xy 419.997763 -45.698151) (xy 420.038283 -45.664933)
			(xy 420.082969 -45.637576) (xy 420.130979 -45.616595) (xy 420.181411 -45.602384) (xy 420.233312 -45.595212)
			(xy 420.25951 -45.594778) (xy 420.28676 -45.595293) (xy 420.340704 -45.60305) (xy 420.392996 -45.618406)
			(xy 420.44257 -45.641047) (xy 420.488417 -45.670512) (xy 420.529605 -45.706202) (xy 420.565294 -45.747391)
			(xy 420.594758 -45.793239) (xy 420.617398 -45.842813) (xy 420.632752 -45.895105) (xy 420.640508 -45.94905)
			(xy 420.640508 -46.00355) (xy 420.632752 -46.057495) (xy 420.617398 -46.109787) (xy 420.594758 -46.159361)
			(xy 420.565294 -46.205209) (xy 420.529605 -46.246398) (xy 420.488417 -46.282088) (xy 420.44257 -46.311553)
			(xy 420.392996 -46.334194) (xy 420.340704 -46.34955) (xy 420.28676 -46.357307) (xy 420.25951 -46.357794)
			(xy 420.232517 -46.357315) (xy 420.179071 -46.349712) (xy 420.127228 -46.334655) (xy 420.078023 -46.312445)
			(xy 420.032437 -46.283526) (xy 420.011606 -46.266354) (xy 420.003478 -46.259242) (xy 419.982904 -46.253146)
			(xy 419.89756 -46.264068) (xy 419.887025 -46.26588) (xy 419.868739 -46.276909) (xy 419.862254 -46.285404)
			(xy 419.844644 -46.309707) (xy 419.803047 -46.352965) (xy 419.77945 -46.37151) (xy 419.771576 -46.377352)
			(xy 419.761162 -46.394878) (xy 419.747954 -46.485302) (xy 419.75278 -46.504606) (xy 419.758622 -46.51248)
			(xy 419.758622 -46.512734) (xy 419.776119 -46.537483) (xy 419.803924 -46.591333) (xy 419.822862 -46.648904)
			(xy 419.832456 -46.708745) (xy 419.833044 -46.739048) (xy 419.832567 -46.766299) (xy 419.824805 -46.820245)
			(xy 419.809445 -46.872538) (xy 419.786801 -46.922113) (xy 419.757333 -46.967961) (xy 419.721641 -47.00915)
			(xy 419.680451 -47.044841) (xy 419.634602 -47.074307) (xy 419.585026 -47.09695) (xy 419.532733 -47.112307)
			(xy 419.478787 -47.120068) (xy 419.451536 -47.120556) (xy 419.425503 -47.120081) (xy 419.373922 -47.113)
			(xy 419.323781 -47.098976) (xy 419.276009 -47.078272) (xy 419.231493 -47.051269) (xy 419.210998 -47.035212)
			(xy 419.203248 -47.029459) (xy 419.184832 -47.023725) (xy 419.175184 -47.024036) (xy 419.095428 -47.030386)
			(xy 419.077648 -47.039022) (xy 419.071298 -47.046388) (xy 419.053141 -47.066057) (xy 419.012228 -47.100577)
			(xy 418.966894 -47.129043) (xy 418.918028 -47.150897) (xy 418.866588 -47.165709) (xy 418.813583 -47.17319)
			(xy 418.786818 -47.173642) (xy 418.759569 -47.173105) (xy 418.705625 -47.165352) (xy 418.653333 -47.150001)
			(xy 418.603758 -47.127364) (xy 418.557909 -47.097903) (xy 418.51672 -47.062217) (xy 418.481028 -47.021032)
			(xy 418.451561 -46.975187) (xy 418.428917 -46.925616) (xy 418.413559 -46.873326) (xy 418.405799 -46.819383)
			(xy 418.40531 -46.792134) (xy 418.405832 -46.76336) (xy 418.414483 -46.706465) (xy 418.43158 -46.651515)
			(xy 418.456734 -46.599755) (xy 418.489375 -46.552359) (xy 418.508688 -46.531022) (xy 418.516054 -46.523148)
			(xy 418.523166 -46.503336) (xy 418.5158 -46.40707) (xy 418.505894 -46.388274) (xy 418.497512 -46.38167)
			(xy 418.475326 -46.363447) (xy 418.436116 -46.321511) (xy 418.403631 -46.274175) (xy 418.378603 -46.222507)
			(xy 418.361597 -46.167672) (xy 418.352996 -46.110909) (xy 418.352478 -46.082204) (xy 413.119316 -46.082204)
			(xy 413.119316 -48.753014) (xy 421.468294 -48.753014) (xy 421.472365 -48.697392) (xy 421.484491 -48.642955)
			(xy 421.504414 -48.590864) (xy 421.53171 -48.542229) (xy 421.565796 -48.498086) (xy 421.605945 -48.459377)
			(xy 421.651303 -48.426926) (xy 421.700903 -48.401425) (xy 421.753687 -48.383418) (xy 421.80853 -48.373288)
			(xy 421.864264 -48.371251) (xy 421.919701 -48.377351) (xy 421.973658 -48.391457) (xy 422.024987 -48.413269)
			(xy 422.072593 -48.442323) (xy 422.115461 -48.477998) (xy 422.152678 -48.519535) (xy 422.183451 -48.566048)
			(xy 422.207123 -48.616545) (xy 422.223191 -48.669952) (xy 422.231311 -48.725128) (xy 422.23182 -48.753014)
			(xy 422.231311 -48.7809) (xy 422.223191 -48.836076) (xy 422.212549 -48.871449) (xy 422.488378 -48.871449)
			(xy 422.488378 -48.816951) (xy 422.496133 -48.763006) (xy 422.511486 -48.710715) (xy 422.534124 -48.66114)
			(xy 422.563587 -48.615292) (xy 422.599274 -48.574103) (xy 422.64046 -48.538411) (xy 422.686305 -48.508944)
			(xy 422.735877 -48.4863) (xy 422.788167 -48.470942) (xy 422.842111 -48.463181) (xy 422.86936 -48.462692)
			(xy 422.896999 -48.463209) (xy 422.9517 -48.471182) (xy 423.004677 -48.486967) (xy 423.054821 -48.510232)
			(xy 423.101082 -48.540491) (xy 423.142491 -48.57711) (xy 423.178181 -48.619323) (xy 423.19321 -48.642524)
			(xy 423.200576 -48.654208) (xy 423.224706 -48.666908) (xy 423.341292 -48.661066) (xy 423.364406 -48.64608)
			(xy 423.370502 -48.633634) (xy 423.385032 -48.605108) (xy 423.419389 -48.551086) (xy 423.459432 -48.501133)
			(xy 423.481754 -48.478186) (xy 424.088306 -47.871634) (xy 424.095124 -47.864217) (xy 424.102857 -47.845631)
			(xy 424.103292 -47.835566) (xy 424.103292 -44.504356) (xy 424.102892 -44.494284) (xy 424.095154 -44.475686)
			(xy 424.088306 -44.468288) (xy 423.601134 -43.981116) (xy 423.578248 -43.957539) (xy 423.537283 -43.906165)
			(xy 423.502327 -43.850527) (xy 423.47382 -43.791326) (xy 423.45212 -43.729305) (xy 423.4375 -43.665244)
			(xy 423.430144 -43.59995) (xy 423.429684 -43.567096) (xy 423.429684 -43.566842) (xy 423.430295 -43.531441)
			(xy 423.438822 -43.461155) (xy 423.455757 -43.392409) (xy 423.480852 -43.326204) (xy 423.513742 -43.263506)
			(xy 423.553948 -43.205228) (xy 423.600884 -43.15222) (xy 423.653865 -43.105254) (xy 423.71212 -43.065015)
			(xy 423.774799 -43.032089) (xy 423.84099 -43.006956) (xy 423.909726 -42.989982) (xy 423.980008 -42.981416)
			(xy 424.015408 -42.980864) (xy 424.04829 -42.98128) (xy 424.113639 -42.988649) (xy 424.177752 -43.003293)
			(xy 424.23982 -43.025029) (xy 424.299062 -43.053581) (xy 424.354732 -43.088592) (xy 424.406129 -43.129619)
			(xy 424.429682 -43.152568) (xy 424.932094 -43.65498) (xy 424.940426 -43.662366) (xy 424.961355 -43.669885)
			(xy 424.97248 -43.669458) (xy 425.061634 -43.66133) (xy 425.081192 -43.6499) (xy 425.087542 -43.640502)
			(xy 425.102856 -43.619016) (xy 425.138489 -43.580103) (xy 425.179144 -43.546472) (xy 425.224046 -43.518764)
			(xy 425.272338 -43.497509) (xy 425.323098 -43.483111) (xy 425.375359 -43.475845) (xy 425.40174 -43.475402)
			(xy 425.42899 -43.475871) (xy 425.482935 -43.483632) (xy 425.535226 -43.498991) (xy 425.5848 -43.521635)
			(xy 425.630646 -43.551103) (xy 425.671833 -43.586795) (xy 425.707521 -43.627986) (xy 425.736984 -43.673835)
			(xy 425.759623 -43.723411) (xy 425.774977 -43.775704) (xy 425.782732 -43.82965) (xy 425.782732 -43.88415)
			(xy 425.774977 -43.938096) (xy 425.759623 -43.990389) (xy 425.736984 -44.039965) (xy 425.707521 -44.085814)
			(xy 425.671833 -44.127005) (xy 425.630646 -44.162697) (xy 425.5848 -44.192165) (xy 425.535226 -44.214809)
			(xy 425.482935 -44.230168) (xy 425.42899 -44.237929) (xy 425.40174 -44.238418) (xy 425.401486 -44.238418)
			(xy 425.381928 -44.23791) (xy 425.381674 -44.23791) (xy 425.371377 -44.237917) (xy 425.35211 -44.245128)
			(xy 425.344336 -44.25188) (xy 425.290996 -44.30268) (xy 425.283878 -44.310185) (xy 425.27574 -44.329179)
			(xy 425.275248 -44.33951) (xy 425.275248 -44.871132) (xy 425.27532 -44.87291) (xy 427.233078 -44.87291)
			(xy 427.237149 -44.817288) (xy 427.249275 -44.762851) (xy 427.269198 -44.71076) (xy 427.296494 -44.662125)
			(xy 427.33058 -44.617982) (xy 427.370729 -44.579273) (xy 427.416087 -44.546822) (xy 427.465687 -44.521321)
			(xy 427.518471 -44.503314) (xy 427.573314 -44.493184) (xy 427.629048 -44.491147) (xy 427.684485 -44.497247)
			(xy 427.738442 -44.511353) (xy 427.789771 -44.533165) (xy 427.837377 -44.562219) (xy 427.880245 -44.597894)
			(xy 427.917462 -44.639431) (xy 427.948235 -44.685944) (xy 427.971907 -44.736441) (xy 427.987975 -44.789848)
			(xy 427.996095 -44.845024) (xy 427.996604 -44.87291) (xy 427.996095 -44.900796) (xy 427.987975 -44.955972)
			(xy 427.971907 -45.009379) (xy 427.948235 -45.059876) (xy 427.917462 -45.106389) (xy 427.880245 -45.147926)
			(xy 427.837377 -45.183601) (xy 427.789771 -45.212655) (xy 427.738442 -45.234467) (xy 427.684485 -45.248573)
			(xy 427.629048 -45.254673) (xy 427.573314 -45.252636) (xy 427.518471 -45.242506) (xy 427.465687 -45.224499)
			(xy 427.416087 -45.198998) (xy 427.370729 -45.166547) (xy 427.33058 -45.127838) (xy 427.296494 -45.083695)
			(xy 427.269198 -45.03506) (xy 427.249275 -44.982969) (xy 427.237149 -44.928532) (xy 427.233078 -44.87291)
			(xy 425.27532 -44.87291) (xy 425.275659 -44.881294) (xy 425.283534 -44.90003) (xy 425.290488 -44.907454)
			(xy 425.349416 -44.965366) (xy 425.368466 -44.972986) (xy 425.378626 -44.972732) (xy 425.385738 -44.972732)
			(xy 425.41299 -44.97314) (xy 425.46694 -44.980902) (xy 425.519235 -44.996262) (xy 425.568813 -45.018908)
			(xy 425.614663 -45.048378) (xy 425.655853 -45.084074) (xy 425.691545 -45.125267) (xy 425.72101 -45.171121)
			(xy 425.743651 -45.2207) (xy 425.759006 -45.272998) (xy 425.766762 -45.326948) (xy 425.766762 -45.381452)
			(xy 425.759006 -45.435402) (xy 425.743651 -45.4877) (xy 425.72101 -45.53728) (xy 425.691545 -45.583133)
			(xy 425.655853 -45.624326) (xy 425.614663 -45.660022) (xy 425.568813 -45.689492) (xy 425.519235 -45.712138)
			(xy 425.46694 -45.727498) (xy 425.41299 -45.73526) (xy 425.385738 -45.735748) (xy 425.378626 -45.735748)
			(xy 425.368466 -45.735494) (xy 425.349416 -45.743114) (xy 425.290488 -45.801026) (xy 425.283553 -45.808459)
			(xy 425.275697 -45.827192) (xy 425.275248 -45.837348) (xy 425.275248 -46.211236) (xy 425.27569 -46.220965)
			(xy 425.283018 -46.238993) (xy 425.289472 -46.246288) (xy 425.337986 -46.297088) (xy 425.345128 -46.303805)
			(xy 425.363013 -46.311787) (xy 425.372784 -46.312582) (xy 425.399314 -46.314101) (xy 425.451605 -46.323548)
			(xy 425.50208 -46.340158) (xy 425.549762 -46.36361) (xy 425.593729 -46.393452) (xy 425.633131 -46.429104)
			(xy 425.667205 -46.469879) (xy 425.695293 -46.514987) (xy 425.716851 -46.563555) (xy 425.731461 -46.614645)
			(xy 425.738843 -46.667267) (xy 425.739306 -46.693836) (xy 425.738832 -46.720264) (xy 425.731523 -46.772611)
			(xy 425.71705 -46.823446) (xy 425.695691 -46.871793) (xy 425.682156 -46.894496) (xy 425.681902 -46.89475)
			(xy 425.676565 -46.904768) (xy 425.674306 -46.927319) (xy 425.677584 -46.938184) (xy 425.703746 -47.01286)
			(xy 425.708133 -47.023374) (xy 425.724219 -47.039463) (xy 425.734734 -47.043848) (xy 425.734988 -47.043848)
			(xy 425.759506 -47.052894) (xy 425.805957 -47.076841) (xy 425.848708 -47.106901) (xy 425.886958 -47.142512)
			(xy 425.919993 -47.183008) (xy 425.947196 -47.227631) (xy 425.968056 -47.275549) (xy 425.982186 -47.325864)
			(xy 425.989319 -47.377635) (xy 425.98975 -47.403766) (xy 425.98919 -47.431014) (xy 425.987667 -47.441612)
			(xy 427.26178 -47.441612) (xy 427.265851 -47.38599) (xy 427.277977 -47.331553) (xy 427.2979 -47.279462)
			(xy 427.325196 -47.230827) (xy 427.359282 -47.186684) (xy 427.399431 -47.147975) (xy 427.444789 -47.115524)
			(xy 427.494389 -47.090023) (xy 427.547173 -47.072016) (xy 427.602016 -47.061886) (xy 427.65775 -47.059849)
			(xy 427.713187 -47.065949) (xy 427.767144 -47.080055) (xy 427.818473 -47.101867) (xy 427.866079 -47.130921)
			(xy 427.908947 -47.166596) (xy 427.946164 -47.208133) (xy 427.976937 -47.254646) (xy 428.000609 -47.305143)
			(xy 428.016677 -47.35855) (xy 428.024797 -47.413726) (xy 428.025306 -47.441612) (xy 428.024797 -47.469498)
			(xy 428.016677 -47.524674) (xy 428.000609 -47.578081) (xy 427.976937 -47.628578) (xy 427.946164 -47.675091)
			(xy 427.908947 -47.716628) (xy 427.866079 -47.752303) (xy 427.818473 -47.781357) (xy 427.767144 -47.803169)
			(xy 427.713187 -47.817275) (xy 427.65775 -47.823375) (xy 427.602016 -47.821338) (xy 427.547173 -47.811208)
			(xy 427.494389 -47.793201) (xy 427.444789 -47.7677) (xy 427.399431 -47.735249) (xy 427.359282 -47.69654)
			(xy 427.325196 -47.652397) (xy 427.2979 -47.603762) (xy 427.277977 -47.551671) (xy 427.265851 -47.497234)
			(xy 427.26178 -47.441612) (xy 425.987667 -47.441612) (xy 425.981439 -47.484957) (xy 425.966091 -47.537248)
			(xy 425.943457 -47.586822) (xy 425.913998 -47.632671) (xy 425.878314 -47.67386) (xy 425.837132 -47.709552)
			(xy 425.791289 -47.73902) (xy 425.741719 -47.761664) (xy 425.689432 -47.777023) (xy 425.63549 -47.784785)
			(xy 425.608242 -47.785274) (xy 425.576431 -47.784636) (xy 425.513694 -47.774069) (xy 425.45358 -47.753238)
			(xy 425.425362 -47.738538) (xy 425.417479 -47.734738) (xy 425.400197 -47.732092) (xy 425.383031 -47.735413)
			(xy 425.375324 -47.739554) (xy 425.30014 -47.784004) (xy 425.292776 -47.788818) (xy 425.281573 -47.802364)
			(xy 425.275619 -47.818903) (xy 425.275248 -47.827692) (xy 425.275248 -47.902368) (xy 425.2976 -47.930054)
			(xy 425.31538 -47.933864) (xy 425.343489 -47.940415) (xy 425.397483 -47.960804) (xy 425.447788 -47.989095)
			(xy 425.493258 -48.02464) (xy 425.532855 -48.06663) (xy 425.565675 -48.114104) (xy 425.590969 -48.165981)
			(xy 425.60816 -48.221077) (xy 425.616855 -48.278133) (xy 425.617386 -48.30699) (xy 425.616935 -48.334244)
			(xy 425.609179 -48.388196) (xy 425.593823 -48.440496) (xy 425.57118 -48.490077) (xy 425.541711 -48.535931)
			(xy 425.506016 -48.577125) (xy 425.464822 -48.612819) (xy 425.418967 -48.642286) (xy 425.369384 -48.664927)
			(xy 425.317084 -48.680282) (xy 425.263132 -48.688036) (xy 425.235878 -48.688498) (xy 425.209905 -48.68804)
			(xy 425.158438 -48.681006) (xy 425.1084 -48.667055) (xy 425.060716 -48.646448) (xy 425.038266 -48.63338)
			(xy 425.023026 -48.624236) (xy 424.988482 -48.628554) (xy 424.98264 -48.634396) (xy 424.998712 -48.654882)
			(xy 425.02573 -48.699394) (xy 425.046443 -48.747167) (xy 425.060468 -48.797312) (xy 425.067544 -48.848899)
			(xy 425.067984 -48.874934) (xy 425.067554 -48.902187) (xy 425.062558 -48.93691) (xy 427.233078 -48.93691)
			(xy 427.237149 -48.881288) (xy 427.249275 -48.826851) (xy 427.269198 -48.77476) (xy 427.296494 -48.726125)
			(xy 427.33058 -48.681982) (xy 427.370729 -48.643273) (xy 427.416087 -48.610822) (xy 427.465687 -48.585321)
			(xy 427.518471 -48.567314) (xy 427.573314 -48.557184) (xy 427.629048 -48.555147) (xy 427.684485 -48.561247)
			(xy 427.738442 -48.575353) (xy 427.789771 -48.597165) (xy 427.837377 -48.626219) (xy 427.880245 -48.661894)
			(xy 427.917462 -48.703431) (xy 427.948235 -48.749944) (xy 427.971907 -48.800441) (xy 427.987975 -48.853848)
			(xy 427.996095 -48.909024) (xy 427.996604 -48.93691) (xy 427.996095 -48.964796) (xy 427.987975 -49.019972)
			(xy 427.971907 -49.073379) (xy 427.948235 -49.123876) (xy 427.917462 -49.170389) (xy 427.880245 -49.211926)
			(xy 427.837377 -49.247601) (xy 427.789771 -49.276655) (xy 427.738442 -49.298467) (xy 427.684485 -49.312573)
			(xy 427.629048 -49.318673) (xy 427.573314 -49.316636) (xy 427.518471 -49.306506) (xy 427.465687 -49.288499)
			(xy 427.416087 -49.262998) (xy 427.370729 -49.230547) (xy 427.33058 -49.191838) (xy 427.296494 -49.147695)
			(xy 427.269198 -49.09906) (xy 427.249275 -49.046969) (xy 427.237149 -48.992532) (xy 427.233078 -48.93691)
			(xy 425.062558 -48.93691) (xy 425.059792 -48.956138) (xy 425.044431 -49.008435) (xy 425.021784 -49.058014)
			(xy 424.992312 -49.103866) (xy 424.956615 -49.145056) (xy 424.915419 -49.180747) (xy 424.869563 -49.210212)
			(xy 424.819981 -49.232852) (xy 424.767681 -49.248204) (xy 424.713729 -49.255958) (xy 424.686476 -49.256442)
			(xy 424.659032 -49.255957) (xy 424.60471 -49.248088) (xy 424.552081 -49.232501) (xy 424.502235 -49.209521)
			(xy 424.478958 -49.194974) (xy 424.46888 -49.189136) (xy 424.445782 -49.186348) (xy 424.423805 -49.193979)
			(xy 424.415204 -49.201832) (xy 424.310302 -49.306734) (xy 424.286724 -49.329645) (xy 424.235317 -49.370632)
			(xy 424.179643 -49.405602) (xy 424.120402 -49.434115) (xy 424.058339 -49.455812) (xy 423.994237 -49.47042)
			(xy 423.928901 -49.477754) (xy 423.896028 -49.478184) (xy 423.860667 -49.477617) (xy 423.790459 -49.4691)
			(xy 423.721786 -49.452199) (xy 423.655644 -49.427158) (xy 423.592996 -49.394342) (xy 423.534751 -49.354228)
			(xy 423.481755 -49.307397) (xy 423.434777 -49.254531) (xy 423.394501 -49.196397) (xy 423.361512 -49.133841)
			(xy 423.348404 -49.100994) (xy 423.343578 -49.08804) (xy 423.322242 -49.070768) (xy 423.206672 -49.054004)
			(xy 423.181272 -49.064418) (xy 423.17289 -49.075594) (xy 423.154762 -49.098536) (xy 423.112625 -49.139075)
			(xy 423.064793 -49.172705) (xy 423.012388 -49.19864) (xy 422.956638 -49.21627) (xy 422.89885 -49.225183)
			(xy 422.869614 -49.225708) (xy 422.86936 -49.225708) (xy 422.842111 -49.225219) (xy 422.788167 -49.217458)
			(xy 422.735877 -49.2021) (xy 422.686305 -49.179456) (xy 422.64046 -49.149989) (xy 422.599274 -49.114297)
			(xy 422.563587 -49.073108) (xy 422.534124 -49.02726) (xy 422.511486 -48.977685) (xy 422.496133 -48.925394)
			(xy 422.488378 -48.871449) (xy 422.212549 -48.871449) (xy 422.207123 -48.889483) (xy 422.183451 -48.93998)
			(xy 422.152678 -48.986493) (xy 422.115461 -49.02803) (xy 422.072593 -49.063705) (xy 422.024987 -49.092759)
			(xy 421.973658 -49.114571) (xy 421.919701 -49.128677) (xy 421.864264 -49.134777) (xy 421.80853 -49.13274)
			(xy 421.753687 -49.12261) (xy 421.700903 -49.104603) (xy 421.651303 -49.079102) (xy 421.605945 -49.046651)
			(xy 421.565796 -49.007942) (xy 421.53171 -48.963799) (xy 421.504414 -48.915164) (xy 421.484491 -48.863073)
			(xy 421.472365 -48.808636) (xy 421.468294 -48.753014) (xy 413.119316 -48.753014) (xy 413.119316 -49.601953)
			(xy 432.412859 -49.601953) (xy 432.412859 -49.547447) (xy 432.420616 -49.493497) (xy 432.435972 -49.441199)
			(xy 432.458615 -49.39162) (xy 432.488083 -49.345767) (xy 432.523776 -49.304575) (xy 432.564968 -49.268881)
			(xy 432.610821 -49.239414) (xy 432.660401 -49.216772) (xy 432.712699 -49.201416) (xy 432.766649 -49.193659)
			(xy 432.793902 -49.193196) (xy 432.821272 -49.193662) (xy 432.875451 -49.20148) (xy 432.927954 -49.216969)
			(xy 432.977701 -49.239811) (xy 433.023668 -49.269535) (xy 433.0446 -49.287176) (xy 433.044854 -49.28743)
			(xy 433.051947 -49.293007) (xy 433.068859 -49.299258) (xy 433.077874 -49.299622) (xy 433.14493 -49.299622)
			(xy 433.153948 -49.299275) (xy 433.170864 -49.29302) (xy 433.17795 -49.28743) (xy 433.17795 -49.287176)
			(xy 433.178204 -49.287176) (xy 433.199137 -49.269535) (xy 433.245105 -49.239811) (xy 433.294851 -49.216965)
			(xy 433.347353 -49.201469) (xy 433.401531 -49.19364) (xy 433.456273 -49.19364) (xy 433.510451 -49.201469)
			(xy 433.562953 -49.216965) (xy 433.612699 -49.239811) (xy 433.658667 -49.269535) (xy 433.6796 -49.287176)
			(xy 433.679854 -49.28743) (xy 433.686947 -49.293007) (xy 433.703859 -49.299258) (xy 433.712874 -49.299622)
			(xy 433.77993 -49.299622) (xy 433.788948 -49.299275) (xy 433.805864 -49.29302) (xy 433.81295 -49.28743)
			(xy 433.81295 -49.287176) (xy 433.813204 -49.287176) (xy 433.834137 -49.269535) (xy 433.880105 -49.239811)
			(xy 433.929851 -49.216965) (xy 433.982353 -49.201469) (xy 434.036531 -49.19364) (xy 434.091273 -49.19364)
			(xy 434.145451 -49.201469) (xy 434.197953 -49.216965) (xy 434.247699 -49.239811) (xy 434.293667 -49.269535)
			(xy 434.3146 -49.287176) (xy 434.314854 -49.28743) (xy 434.321947 -49.293007) (xy 434.338859 -49.299258)
			(xy 434.347874 -49.299622) (xy 434.41493 -49.299622) (xy 434.423948 -49.299275) (xy 434.440864 -49.29302)
			(xy 434.44795 -49.28743) (xy 434.44795 -49.287176) (xy 434.448204 -49.287176) (xy 434.469121 -49.269518)
			(xy 434.515098 -49.23981) (xy 434.56485 -49.216978) (xy 434.617353 -49.201491) (xy 434.671532 -49.193668)
			(xy 434.698902 -49.193196) (xy 434.726153 -49.193674) (xy 434.780102 -49.201431) (xy 434.832397 -49.216786)
			(xy 434.881974 -49.239428) (xy 434.927825 -49.268894) (xy 434.969015 -49.304586) (xy 435.004707 -49.345777)
			(xy 435.034173 -49.391628) (xy 435.056814 -49.441205) (xy 435.07217 -49.4935) (xy 435.079926 -49.547449)
			(xy 435.079926 -49.601951) (xy 435.07217 -49.6559) (xy 435.056814 -49.708195) (xy 435.034173 -49.757772)
			(xy 435.004707 -49.803623) (xy 434.969015 -49.844814) (xy 434.927825 -49.880506) (xy 434.881974 -49.909972)
			(xy 434.832397 -49.932614) (xy 434.780102 -49.947969) (xy 434.726153 -49.955726) (xy 434.698902 -49.956212)
			(xy 434.671532 -49.955742) (xy 434.617353 -49.947925) (xy 434.56485 -49.932436) (xy 434.515103 -49.909596)
			(xy 434.469136 -49.879872) (xy 434.448204 -49.862232) (xy 434.44795 -49.861978) (xy 434.440855 -49.856404)
			(xy 434.423945 -49.85015) (xy 434.41493 -49.849786) (xy 434.347874 -49.849786) (xy 434.338856 -49.850134)
			(xy 434.32194 -49.856388) (xy 434.314854 -49.861978) (xy 434.3146 -49.862232) (xy 434.293667 -49.879873)
			(xy 434.247699 -49.909597) (xy 434.197953 -49.932443) (xy 434.145451 -49.947939) (xy 434.091273 -49.955768)
			(xy 434.036531 -49.955768) (xy 433.982353 -49.947939) (xy 433.929851 -49.932443) (xy 433.880105 -49.909597)
			(xy 433.834137 -49.879873) (xy 433.813204 -49.862232) (xy 433.81295 -49.861978) (xy 433.805855 -49.856404)
			(xy 433.788945 -49.85015) (xy 433.77993 -49.849786) (xy 433.712874 -49.849786) (xy 433.703856 -49.850134)
			(xy 433.68694 -49.856388) (xy 433.679854 -49.861978) (xy 433.679854 -49.862232) (xy 433.6796 -49.862232)
			(xy 433.658667 -49.879873) (xy 433.612699 -49.909597) (xy 433.562953 -49.932443) (xy 433.510451 -49.947939)
			(xy 433.456273 -49.955768) (xy 433.401531 -49.955768) (xy 433.347353 -49.947939) (xy 433.294851 -49.932443)
			(xy 433.245105 -49.909597) (xy 433.199137 -49.879873) (xy 433.178204 -49.862232) (xy 433.17795 -49.861978)
			(xy 433.170855 -49.856404) (xy 433.153945 -49.85015) (xy 433.14493 -49.849786) (xy 433.077874 -49.849786)
			(xy 433.068856 -49.850134) (xy 433.05194 -49.856388) (xy 433.044854 -49.861978) (xy 433.044854 -49.862232)
			(xy 433.0446 -49.862232) (xy 433.023683 -49.87989) (xy 432.977705 -49.909598) (xy 432.927954 -49.932429)
			(xy 432.87545 -49.947916) (xy 432.821272 -49.95574) (xy 432.793902 -49.956212) (xy 432.766649 -49.955741)
			(xy 432.712699 -49.947984) (xy 432.660401 -49.932628) (xy 432.610821 -49.909986) (xy 432.564968 -49.880519)
			(xy 432.523776 -49.844825) (xy 432.488083 -49.803633) (xy 432.458615 -49.75778) (xy 432.435972 -49.708201)
			(xy 432.420616 -49.655903) (xy 432.412859 -49.601953) (xy 413.119316 -49.601953) (xy 413.119316 -50.502312)
			(xy 423.116754 -50.502312) (xy 423.120825 -50.44669) (xy 423.132951 -50.392253) (xy 423.152874 -50.340162)
			(xy 423.18017 -50.291527) (xy 423.214256 -50.247384) (xy 423.254405 -50.208675) (xy 423.299763 -50.176224)
			(xy 423.349363 -50.150723) (xy 423.402147 -50.132716) (xy 423.45699 -50.122586) (xy 423.512724 -50.120549)
			(xy 423.568161 -50.126649) (xy 423.622118 -50.140755) (xy 423.673447 -50.162567) (xy 423.721053 -50.191621)
			(xy 423.763921 -50.227296) (xy 423.801138 -50.268833) (xy 423.831911 -50.315346) (xy 423.855583 -50.365843)
			(xy 423.871651 -50.41925) (xy 423.879771 -50.474426) (xy 423.88028 -50.502312) (xy 423.879771 -50.530198)
			(xy 423.871651 -50.585374) (xy 423.855583 -50.638781) (xy 423.831911 -50.689278) (xy 423.801138 -50.735791)
			(xy 423.763921 -50.777328) (xy 423.721053 -50.813003) (xy 423.673447 -50.842057) (xy 423.622118 -50.863869)
			(xy 423.568161 -50.877975) (xy 423.512724 -50.884075) (xy 423.45699 -50.882038) (xy 423.402147 -50.871908)
			(xy 423.349363 -50.853901) (xy 423.299763 -50.8284) (xy 423.254405 -50.795949) (xy 423.214256 -50.75724)
			(xy 423.18017 -50.713097) (xy 423.152874 -50.664462) (xy 423.132951 -50.612371) (xy 423.120825 -50.557934)
			(xy 423.116754 -50.502312) (xy 413.119316 -50.502312) (xy 413.119316 -51.019456) (xy 425.04944 -51.019456)
			(xy 425.053511 -50.963834) (xy 425.065637 -50.909397) (xy 425.08556 -50.857306) (xy 425.112856 -50.808671)
			(xy 425.146942 -50.764528) (xy 425.187091 -50.725819) (xy 425.232449 -50.693368) (xy 425.282049 -50.667867)
			(xy 425.334833 -50.64986) (xy 425.389676 -50.63973) (xy 425.44541 -50.637693) (xy 425.500847 -50.643793)
			(xy 425.554804 -50.657899) (xy 425.606133 -50.679711) (xy 425.653739 -50.708765) (xy 425.696607 -50.74444)
			(xy 425.733824 -50.785977) (xy 425.764597 -50.83249) (xy 425.788269 -50.882987) (xy 425.804337 -50.936394)
			(xy 425.812457 -50.99157) (xy 425.812966 -51.019456) (xy 425.812457 -51.047342) (xy 425.804337 -51.102518)
			(xy 425.788269 -51.155925) (xy 425.764597 -51.206422) (xy 425.739741 -51.243992) (xy 433.432966 -51.243992)
			(xy 433.433411 -51.216621) (xy 433.441232 -51.16244) (xy 433.456725 -51.109936) (xy 433.479571 -51.06019)
			(xy 433.509302 -51.014224) (xy 433.526946 -50.993294) (xy 433.5272 -50.99304) (xy 433.532776 -50.985946)
			(xy 433.539029 -50.969035) (xy 433.539392 -50.96002) (xy 433.539392 -50.892964) (xy 433.539054 -50.883945)
			(xy 433.532793 -50.867028) (xy 433.5272 -50.859944) (xy 433.526946 -50.859944) (xy 433.526946 -50.85969)
			(xy 433.509296 -50.838767) (xy 433.479584 -50.792792) (xy 433.45675 -50.743043) (xy 433.441261 -50.69054)
			(xy 433.433437 -50.636362) (xy 433.432966 -50.608992) (xy 433.43347 -50.581742) (xy 433.441227 -50.527796)
			(xy 433.456582 -50.475503) (xy 433.479222 -50.425928) (xy 433.508687 -50.380079) (xy 433.544376 -50.338889)
			(xy 433.585564 -50.303198) (xy 433.631412 -50.273731) (xy 433.680986 -50.251088) (xy 433.733278 -50.235731)
			(xy 433.787224 -50.227972) (xy 433.814474 -50.227484) (xy 433.843392 -50.227989) (xy 433.900565 -50.236716)
			(xy 433.955766 -50.253975) (xy 434.007728 -50.279369) (xy 434.055261 -50.312316) (xy 434.097276 -50.352062)
			(xy 434.115464 -50.37455) (xy 434.123088 -50.383339) (xy 434.143976 -50.393531) (xy 434.155596 -50.394108)
			(xy 434.235352 -50.394108) (xy 434.246985 -50.393582) (xy 434.267894 -50.383383) (xy 434.275484 -50.37455)
			(xy 434.293671 -50.352064) (xy 434.335693 -50.312331) (xy 434.38323 -50.279394) (xy 434.435191 -50.254006)
			(xy 434.490389 -50.23675) (xy 434.547558 -50.22802) (xy 434.576474 -50.227484) (xy 434.603726 -50.227979)
			(xy 434.657675 -50.235733) (xy 434.709972 -50.251085) (xy 434.759551 -50.273724) (xy 434.805404 -50.303188)
			(xy 434.846597 -50.338879) (xy 434.882291 -50.380068) (xy 434.91176 -50.425919) (xy 434.934403 -50.475496)
			(xy 434.94976 -50.527792) (xy 434.957518 -50.58174) (xy 434.957982 -50.608992) (xy 434.957515 -50.635306)
			(xy 434.950281 -50.687435) (xy 434.935962 -50.738078) (xy 434.91483 -50.786277) (xy 434.887283 -50.83112)
			(xy 434.853844 -50.87176) (xy 434.834792 -50.889916) (xy 434.82738 -50.897429) (xy 434.818862 -50.916716)
			(xy 434.818282 -50.927254) (xy 434.818282 -51.00193) (xy 434.818841 -51.012476) (xy 434.827356 -51.031772)
			(xy 434.834792 -51.039268) (xy 434.853872 -51.057399) (xy 434.887327 -51.098034) (xy 434.914883 -51.142879)
			(xy 434.936017 -51.191085) (xy 434.950329 -51.241737) (xy 434.957547 -51.293874) (xy 434.957982 -51.320192)
			(xy 434.957537 -51.347446) (xy 434.949781 -51.401399) (xy 434.934424 -51.453699) (xy 434.911781 -51.50328)
			(xy 434.882311 -51.549135) (xy 434.846615 -51.590328) (xy 434.80542 -51.626022) (xy 434.759565 -51.655489)
			(xy 434.709982 -51.678131) (xy 434.657681 -51.693484) (xy 434.603728 -51.701238) (xy 434.576474 -51.7017)
			(xy 434.548808 -51.701208) (xy 434.494058 -51.693205) (xy 434.441036 -51.677385) (xy 434.390852 -51.654079)
			(xy 434.344557 -51.623774) (xy 434.303119 -51.587106) (xy 434.267407 -51.544842) (xy 434.25237 -51.521614)
			(xy 434.245757 -51.511918) (xy 434.225878 -51.499485) (xy 434.21427 -51.497738) (xy 434.13426 -51.489864)
			(xy 434.122621 -51.489211) (xy 434.100782 -51.497305) (xy 434.09235 -51.505358) (xy 434.092096 -51.505612)
			(xy 434.074002 -51.52418) (xy 434.033672 -51.556759) (xy 433.989301 -51.583573) (xy 433.941705 -51.604128)
			(xy 433.891763 -51.618045) (xy 433.840396 -51.625066) (xy 433.814474 -51.6255) (xy 433.787222 -51.625046)
			(xy 433.733272 -51.617286) (xy 433.680977 -51.601927) (xy 433.631399 -51.579283) (xy 433.585548 -51.549813)
			(xy 433.544358 -51.514118) (xy 433.508667 -51.472925) (xy 433.479201 -51.427071) (xy 433.456561 -51.377491)
			(xy 433.441207 -51.325194) (xy 433.433451 -51.271244) (xy 433.432966 -51.243992) (xy 425.739741 -51.243992)
			(xy 425.733824 -51.252935) (xy 425.696607 -51.294472) (xy 425.653739 -51.330147) (xy 425.606133 -51.359201)
			(xy 425.554804 -51.381013) (xy 425.500847 -51.395119) (xy 425.44541 -51.401219) (xy 425.389676 -51.399182)
			(xy 425.334833 -51.389052) (xy 425.282049 -51.371045) (xy 425.232449 -51.345544) (xy 425.187091 -51.313093)
			(xy 425.146942 -51.274384) (xy 425.112856 -51.230241) (xy 425.08556 -51.181606) (xy 425.065637 -51.129515)
			(xy 425.053511 -51.075078) (xy 425.04944 -51.019456) (xy 413.119316 -51.019456) (xy 413.119316 -52.035456)
			(xy 427.241206 -52.035456) (xy 427.245277 -51.979834) (xy 427.257403 -51.925397) (xy 427.277326 -51.873306)
			(xy 427.304622 -51.824671) (xy 427.338708 -51.780528) (xy 427.378857 -51.741819) (xy 427.424215 -51.709368)
			(xy 427.473815 -51.683867) (xy 427.526599 -51.66586) (xy 427.581442 -51.65573) (xy 427.637176 -51.653693)
			(xy 427.692613 -51.659793) (xy 427.74657 -51.673899) (xy 427.797899 -51.695711) (xy 427.845505 -51.724765)
			(xy 427.888373 -51.76044) (xy 427.92559 -51.801977) (xy 427.956363 -51.84849) (xy 427.980035 -51.898987)
			(xy 427.996103 -51.952394) (xy 428.004223 -52.00757) (xy 428.004732 -52.035456) (xy 428.004223 -52.063342)
			(xy 427.996103 -52.118518) (xy 427.980035 -52.171925) (xy 427.956363 -52.222422) (xy 427.92559 -52.268935)
			(xy 427.888373 -52.310472) (xy 427.845505 -52.346147) (xy 427.797899 -52.375201) (xy 427.74657 -52.397013)
			(xy 427.692613 -52.411119) (xy 427.637176 -52.417219) (xy 427.581442 -52.415182) (xy 427.526599 -52.405052)
			(xy 427.473815 -52.387045) (xy 427.424215 -52.361544) (xy 427.378857 -52.329093) (xy 427.338708 -52.290384)
			(xy 427.304622 -52.246241) (xy 427.277326 -52.197606) (xy 427.257403 -52.145515) (xy 427.245277 -52.091078)
			(xy 427.241206 -52.035456) (xy 413.119316 -52.035456) (xy 413.119316 -54.731412) (xy 413.82061 -54.731412)
			(xy 413.821081 -54.704042) (xy 413.828897 -54.649863) (xy 413.844385 -54.59736) (xy 413.867226 -54.547613)
			(xy 413.896949 -54.501646) (xy 413.91459 -54.480714) (xy 413.914844 -54.48046) (xy 413.920417 -54.473364)
			(xy 413.926671 -54.456454) (xy 413.927036 -54.44744) (xy 413.927036 -54.380384) (xy 413.926679 -54.371367)
			(xy 413.920431 -54.354451) (xy 413.914844 -54.347364) (xy 413.91459 -54.347364) (xy 413.91459 -54.34711)
			(xy 413.896963 -54.326167) (xy 413.86724 -54.2802) (xy 413.844396 -54.230455) (xy 413.828901 -54.177955)
			(xy 413.821072 -54.123779) (xy 413.821071 -54.069039) (xy 413.828897 -54.014863) (xy 413.84439 -53.962362)
			(xy 413.867231 -53.912616) (xy 413.896952 -53.866647) (xy 413.91459 -53.845714) (xy 413.914844 -53.84546)
			(xy 413.920417 -53.838364) (xy 413.926671 -53.821454) (xy 413.927036 -53.81244) (xy 413.927036 -53.745384)
			(xy 413.926679 -53.736367) (xy 413.920431 -53.719451) (xy 413.914844 -53.712364) (xy 413.91459 -53.712364)
			(xy 413.91459 -53.71211) (xy 413.896963 -53.691167) (xy 413.86724 -53.6452) (xy 413.844396 -53.595455)
			(xy 413.828901 -53.542955) (xy 413.821072 -53.488779) (xy 413.821071 -53.434039) (xy 413.828897 -53.379863)
			(xy 413.84439 -53.327362) (xy 413.867231 -53.277616) (xy 413.896952 -53.231647) (xy 413.91459 -53.210714)
			(xy 413.914844 -53.21046) (xy 413.920417 -53.203364) (xy 413.926671 -53.186454) (xy 413.927036 -53.17744)
			(xy 413.927036 -53.110384) (xy 413.926679 -53.101367) (xy 413.920431 -53.084451) (xy 413.914844 -53.077364)
			(xy 413.91459 -53.077364) (xy 413.91459 -53.07711) (xy 413.896941 -53.056186) (xy 413.867231 -53.010211)
			(xy 413.844397 -52.960461) (xy 413.828908 -52.907959) (xy 413.821083 -52.853782) (xy 413.82061 -52.826412)
			(xy 413.821096 -52.799161) (xy 413.828852 -52.745213) (xy 413.844207 -52.692918) (xy 413.866849 -52.643341)
			(xy 413.896315 -52.597491) (xy 413.932006 -52.5563) (xy 413.973197 -52.520609) (xy 414.019047 -52.491143)
			(xy 414.068624 -52.468501) (xy 414.120919 -52.453146) (xy 414.174867 -52.44539) (xy 414.229369 -52.44539)
			(xy 414.283317 -52.453146) (xy 414.335612 -52.468501) (xy 414.385189 -52.491143) (xy 414.431039 -52.520609)
			(xy 414.47223 -52.5563) (xy 414.507921 -52.597491) (xy 414.537387 -52.643341) (xy 414.560029 -52.692918)
			(xy 414.575384 -52.745213) (xy 414.58314 -52.799161) (xy 414.583626 -52.826412) (xy 414.583185 -52.853783)
			(xy 414.575364 -52.907964) (xy 414.55987 -52.960468) (xy 414.537022 -53.010215) (xy 414.507291 -53.05618)
			(xy 414.489646 -53.07711) (xy 414.489392 -53.077364) (xy 414.483813 -53.084456) (xy 414.477562 -53.101369)
			(xy 414.4772 -53.110384) (xy 414.4772 -53.17744) (xy 414.477538 -53.186459) (xy 414.483799 -53.203376)
			(xy 414.489392 -53.21046) (xy 414.489646 -53.21046) (xy 414.489646 -53.210714) (xy 414.5073 -53.231637)
			(xy 414.537026 -53.277606) (xy 414.559872 -53.327353) (xy 414.575369 -53.379857) (xy 414.583197 -53.434038)
			(xy 414.583196 -53.488781) (xy 414.575365 -53.542961) (xy 414.559866 -53.595464) (xy 414.537017 -53.64521)
			(xy 414.507289 -53.691178) (xy 414.489646 -53.71211) (xy 414.489392 -53.712364) (xy 414.483813 -53.719456)
			(xy 414.477562 -53.736369) (xy 414.4772 -53.745384) (xy 414.4772 -53.81244) (xy 414.477538 -53.821459)
			(xy 414.483799 -53.838376) (xy 414.489392 -53.84546) (xy 414.489646 -53.84546) (xy 414.489646 -53.845714)
			(xy 414.5073 -53.866637) (xy 414.537026 -53.912606) (xy 414.559872 -53.962353) (xy 414.575369 -54.014857)
			(xy 414.583197 -54.069038) (xy 414.583196 -54.123781) (xy 414.575365 -54.177961) (xy 414.559866 -54.230464)
			(xy 414.537017 -54.28021) (xy 414.507289 -54.326178) (xy 414.489646 -54.34711) (xy 414.489392 -54.347364)
			(xy 414.483813 -54.354456) (xy 414.477562 -54.371369) (xy 414.4772 -54.380384) (xy 414.4772 -54.44744)
			(xy 414.477538 -54.456459) (xy 414.483799 -54.473376) (xy 414.489392 -54.48046) (xy 414.489646 -54.48046)
			(xy 414.489646 -54.480714) (xy 414.50725 -54.501675) (xy 414.536969 -54.547639) (xy 414.559812 -54.597379)
			(xy 414.575312 -54.649874) (xy 414.583148 -54.704045) (xy 414.583626 -54.731412) (xy 414.58314 -54.758663)
			(xy 414.578476 -54.791102) (xy 416.476434 -54.791102) (xy 416.476893 -54.763731) (xy 416.484711 -54.709552)
			(xy 416.500202 -54.657048) (xy 416.523045 -54.607301) (xy 416.552772 -54.561335) (xy 416.570414 -54.540404)
			(xy 416.570668 -54.54015) (xy 416.576248 -54.533059) (xy 416.582497 -54.516145) (xy 416.58286 -54.50713)
			(xy 416.58286 -54.440074) (xy 416.582524 -54.431055) (xy 416.576263 -54.414137) (xy 416.570668 -54.407054)
			(xy 416.570414 -54.407054) (xy 416.570414 -54.4068) (xy 416.552776 -54.385865) (xy 416.523052 -54.339898)
			(xy 416.500207 -54.290152) (xy 416.484711 -54.23765) (xy 416.476883 -54.183472) (xy 416.476883 -54.128731)
			(xy 416.484711 -54.074553) (xy 416.500206 -54.022051) (xy 416.52305 -53.972305) (xy 416.552774 -53.926337)
			(xy 416.570414 -53.905404) (xy 416.570668 -53.90515) (xy 416.576248 -53.898059) (xy 416.582497 -53.881145)
			(xy 416.58286 -53.87213) (xy 416.58286 -53.805074) (xy 416.582524 -53.796055) (xy 416.576263 -53.779137)
			(xy 416.570668 -53.772054) (xy 416.570414 -53.772054) (xy 416.570414 -53.7718) (xy 416.552776 -53.750865)
			(xy 416.523052 -53.704898) (xy 416.500207 -53.655152) (xy 416.484711 -53.60265) (xy 416.476883 -53.548472)
			(xy 416.476883 -53.493731) (xy 416.484711 -53.439553) (xy 416.500206 -53.387051) (xy 416.52305 -53.337305)
			(xy 416.552774 -53.291337) (xy 416.570414 -53.270404) (xy 416.570668 -53.27015) (xy 416.576248 -53.263059)
			(xy 416.582497 -53.246145) (xy 416.58286 -53.23713) (xy 416.58286 -53.170074) (xy 416.582524 -53.161055)
			(xy 416.576263 -53.144137) (xy 416.570668 -53.137054) (xy 416.570414 -53.137054) (xy 416.570414 -53.1368)
			(xy 416.552764 -53.115877) (xy 416.523053 -53.069902) (xy 416.500219 -53.020152) (xy 416.484731 -52.967649)
			(xy 416.476906 -52.913472) (xy 416.476434 -52.886102) (xy 416.47692 -52.858851) (xy 416.484676 -52.804903)
			(xy 416.500031 -52.752608) (xy 416.522673 -52.703031) (xy 416.552139 -52.657181) (xy 416.58783 -52.61599)
			(xy 416.629021 -52.580299) (xy 416.674871 -52.550833) (xy 416.724448 -52.528191) (xy 416.776743 -52.512836)
			(xy 416.830691 -52.50508) (xy 416.885193 -52.50508) (xy 416.939141 -52.512836) (xy 416.991436 -52.528191)
			(xy 417.03054 -52.54605) (xy 421.979596 -52.54605) (xy 421.979596 -52.49155) (xy 421.987352 -52.437605)
			(xy 422.002707 -52.385313) (xy 422.025347 -52.335738) (xy 422.054811 -52.28989) (xy 422.090501 -52.248702)
			(xy 422.131689 -52.213012) (xy 422.177537 -52.183547) (xy 422.227111 -52.160907) (xy 422.279403 -52.145553)
			(xy 422.333348 -52.137796) (xy 422.360598 -52.13731) (xy 422.387968 -52.137775) (xy 422.442148 -52.145593)
			(xy 422.494651 -52.161082) (xy 422.544398 -52.183924) (xy 422.590364 -52.213649) (xy 422.611296 -52.23129)
			(xy 422.61155 -52.231544) (xy 422.618643 -52.237121) (xy 422.635555 -52.243372) (xy 422.64457 -52.243736)
			(xy 422.711626 -52.243736) (xy 422.720643 -52.243384) (xy 422.73756 -52.237132) (xy 422.744646 -52.231544)
			(xy 422.744646 -52.23129) (xy 422.7449 -52.23129) (xy 422.765833 -52.213649) (xy 422.811801 -52.183925)
			(xy 422.861547 -52.161079) (xy 422.914049 -52.145583) (xy 422.968227 -52.137754) (xy 423.022969 -52.137754)
			(xy 423.077147 -52.145583) (xy 423.129649 -52.161079) (xy 423.179395 -52.183925) (xy 423.225363 -52.213649)
			(xy 423.246296 -52.23129) (xy 423.24655 -52.231544) (xy 423.253643 -52.237121) (xy 423.270555 -52.243372)
			(xy 423.27957 -52.243736) (xy 423.346626 -52.243736) (xy 423.355643 -52.243384) (xy 423.37256 -52.237132)
			(xy 423.379646 -52.231544) (xy 423.379646 -52.23129) (xy 423.3799 -52.23129) (xy 423.40082 -52.213636)
			(xy 423.446796 -52.183927) (xy 423.496547 -52.161094) (xy 423.54905 -52.145606) (xy 423.603228 -52.137782)
			(xy 423.630598 -52.13731) (xy 423.657852 -52.137737) (xy 423.711806 -52.145494) (xy 423.764107 -52.16085)
			(xy 423.813689 -52.183494) (xy 423.859545 -52.212963) (xy 423.90074 -52.248659) (xy 423.936435 -52.289853)
			(xy 423.965905 -52.335709) (xy 423.988549 -52.385292) (xy 424.003906 -52.437592) (xy 424.011663 -52.491546)
			(xy 424.011663 -52.546054) (xy 424.005719 -52.587398) (xy 425.055282 -52.587398) (xy 425.059353 -52.531776)
			(xy 425.071479 -52.477339) (xy 425.091402 -52.425248) (xy 425.118698 -52.376613) (xy 425.152784 -52.33247)
			(xy 425.192933 -52.293761) (xy 425.238291 -52.26131) (xy 425.287891 -52.235809) (xy 425.340675 -52.217802)
			(xy 425.395518 -52.207672) (xy 425.451252 -52.205635) (xy 425.506689 -52.211735) (xy 425.560646 -52.225841)
			(xy 425.611975 -52.247653) (xy 425.659581 -52.276707) (xy 425.702449 -52.312382) (xy 425.739666 -52.353919)
			(xy 425.770439 -52.400432) (xy 425.794111 -52.450929) (xy 425.810179 -52.504336) (xy 425.817775 -52.555952)
			(xy 432.883779 -52.555952) (xy 432.883779 -52.501448) (xy 432.891536 -52.447499) (xy 432.906892 -52.395203)
			(xy 432.929535 -52.345625) (xy 432.959002 -52.299774) (xy 432.994696 -52.258583) (xy 433.035888 -52.222892)
			(xy 433.081741 -52.193426) (xy 433.13132 -52.170786) (xy 433.183617 -52.155432) (xy 433.237566 -52.147678)
			(xy 433.264818 -52.147216) (xy 433.292189 -52.147668) (xy 433.346369 -52.155488) (xy 433.398872 -52.170981)
			(xy 433.448619 -52.193826) (xy 433.494585 -52.223553) (xy 433.515516 -52.241196) (xy 433.51577 -52.24145)
			(xy 433.522857 -52.247036) (xy 433.539774 -52.253282) (xy 433.54879 -52.253642) (xy 433.615846 -52.253642)
			(xy 433.624862 -52.253272) (xy 433.64178 -52.247035) (xy 433.648866 -52.24145) (xy 433.648866 -52.241196)
			(xy 433.64912 -52.241196) (xy 433.670071 -52.22358) (xy 433.716039 -52.193865) (xy 433.765781 -52.171025)
			(xy 433.818278 -52.155528) (xy 433.87245 -52.147694) (xy 433.899818 -52.147216) (xy 433.92707 -52.147655)
			(xy 433.981019 -52.155414) (xy 434.033315 -52.170772) (xy 434.082893 -52.193415) (xy 434.128744 -52.222884)
			(xy 434.169935 -52.258578) (xy 434.205627 -52.29977) (xy 434.235093 -52.345623) (xy 434.257734 -52.395202)
			(xy 434.27309 -52.447498) (xy 434.280846 -52.501448) (xy 434.280846 -52.555952) (xy 434.27309 -52.609902)
			(xy 434.257734 -52.662198) (xy 434.235093 -52.711777) (xy 434.205627 -52.75763) (xy 434.169935 -52.798822)
			(xy 434.128744 -52.834516) (xy 434.082893 -52.863985) (xy 434.033315 -52.886628) (xy 433.981019 -52.901986)
			(xy 433.92707 -52.909745) (xy 433.899818 -52.910232) (xy 433.872447 -52.909772) (xy 433.818267 -52.901955)
			(xy 433.765764 -52.886466) (xy 433.716017 -52.863622) (xy 433.670051 -52.833895) (xy 433.64912 -52.816252)
			(xy 433.648866 -52.815998) (xy 433.641765 -52.810433) (xy 433.624859 -52.804173) (xy 433.615846 -52.803806)
			(xy 433.54879 -52.803806) (xy 433.539772 -52.804157) (xy 433.522856 -52.810409) (xy 433.51577 -52.815998)
			(xy 433.51577 -52.816252) (xy 433.515516 -52.816252) (xy 433.494583 -52.83389) (xy 433.448611 -52.863603)
			(xy 433.398864 -52.88644) (xy 433.346363 -52.901932) (xy 433.292187 -52.909759) (xy 433.264818 -52.910232)
			(xy 433.237566 -52.909722) (xy 433.183617 -52.901968) (xy 433.13132 -52.886614) (xy 433.081741 -52.863974)
			(xy 433.035888 -52.834508) (xy 432.994696 -52.798817) (xy 432.959002 -52.757626) (xy 432.929535 -52.711775)
			(xy 432.906892 -52.662197) (xy 432.891536 -52.609901) (xy 432.883779 -52.555952) (xy 425.817775 -52.555952)
			(xy 425.818299 -52.559512) (xy 425.818808 -52.587398) (xy 425.818299 -52.615284) (xy 425.810179 -52.67046)
			(xy 425.794111 -52.723867) (xy 425.770439 -52.774364) (xy 425.739666 -52.820877) (xy 425.702449 -52.862414)
			(xy 425.659581 -52.898089) (xy 425.611975 -52.927143) (xy 425.560646 -52.948955) (xy 425.506689 -52.963061)
			(xy 425.451252 -52.969161) (xy 425.395518 -52.967124) (xy 425.340675 -52.956994) (xy 425.287891 -52.938987)
			(xy 425.238291 -52.913486) (xy 425.192933 -52.881035) (xy 425.152784 -52.842326) (xy 425.118698 -52.798183)
			(xy 425.091402 -52.749548) (xy 425.071479 -52.697457) (xy 425.059353 -52.64302) (xy 425.055282 -52.587398)
			(xy 424.005719 -52.587398) (xy 424.003906 -52.600008) (xy 423.988549 -52.652308) (xy 423.965905 -52.701891)
			(xy 423.936435 -52.747747) (xy 423.90074 -52.788941) (xy 423.859545 -52.824637) (xy 423.813689 -52.854106)
			(xy 423.764107 -52.87675) (xy 423.711806 -52.892106) (xy 423.657852 -52.899863) (xy 423.630598 -52.900326)
			(xy 423.603227 -52.899879) (xy 423.549046 -52.892059) (xy 423.496542 -52.876567) (xy 423.446796 -52.85372)
			(xy 423.40083 -52.82399) (xy 423.3799 -52.806346) (xy 423.379646 -52.806092) (xy 423.372551 -52.800518)
			(xy 423.355641 -52.794264) (xy 423.346626 -52.7939) (xy 423.27957 -52.7939) (xy 423.270552 -52.794243)
			(xy 423.253635 -52.8005) (xy 423.24655 -52.806092) (xy 423.246296 -52.806346) (xy 423.225363 -52.823987)
			(xy 423.179395 -52.853711) (xy 423.129649 -52.876557) (xy 423.077147 -52.892053) (xy 423.022969 -52.899882)
			(xy 422.968227 -52.899882) (xy 422.914049 -52.892053) (xy 422.861547 -52.876557) (xy 422.811801 -52.853711)
			(xy 422.765833 -52.823987) (xy 422.7449 -52.806346) (xy 422.744646 -52.806092) (xy 422.737551 -52.800518)
			(xy 422.720641 -52.794264) (xy 422.711626 -52.7939) (xy 422.64457 -52.7939) (xy 422.635552 -52.794243)
			(xy 422.618635 -52.8005) (xy 422.61155 -52.806092) (xy 422.61155 -52.806346) (xy 422.611296 -52.806346)
			(xy 422.590369 -52.823992) (xy 422.544396 -52.853705) (xy 422.494647 -52.87654) (xy 422.442145 -52.892029)
			(xy 422.387968 -52.899854) (xy 422.360598 -52.900326) (xy 422.333348 -52.899804) (xy 422.279403 -52.892047)
			(xy 422.227111 -52.876693) (xy 422.177537 -52.854053) (xy 422.131689 -52.824588) (xy 422.090501 -52.788898)
			(xy 422.054811 -52.74771) (xy 422.025347 -52.701862) (xy 422.002707 -52.652287) (xy 421.987352 -52.599995)
			(xy 421.979596 -52.54605) (xy 417.03054 -52.54605) (xy 417.041013 -52.550833) (xy 417.086863 -52.580299)
			(xy 417.128054 -52.61599) (xy 417.163745 -52.657181) (xy 417.193211 -52.703031) (xy 417.215853 -52.752608)
			(xy 417.231208 -52.804903) (xy 417.238964 -52.858851) (xy 417.23945 -52.886102) (xy 417.238997 -52.913473)
			(xy 417.231178 -52.967653) (xy 417.215687 -53.020157) (xy 417.192842 -53.069903) (xy 417.163113 -53.115869)
			(xy 417.14547 -53.1368) (xy 417.145216 -53.137054) (xy 417.139644 -53.144151) (xy 417.133388 -53.16106)
			(xy 417.133024 -53.170074) (xy 417.133024 -53.23713) (xy 417.133361 -53.246149) (xy 417.139622 -53.263066)
			(xy 417.145216 -53.27015) (xy 417.14547 -53.27015) (xy 417.14547 -53.270404) (xy 417.163113 -53.291335)
			(xy 417.192838 -53.337303) (xy 417.215683 -53.38705) (xy 417.231179 -53.439552) (xy 417.239008 -53.493731)
			(xy 417.239008 -53.548472) (xy 417.231179 -53.602651) (xy 417.215682 -53.655153) (xy 417.192836 -53.7049)
			(xy 417.163111 -53.750867) (xy 417.14654 -53.77053) (xy 417.510722 -53.77053) (xy 417.511254 -53.741613)
			(xy 417.519979 -53.684443) (xy 417.537233 -53.629244) (xy 417.562623 -53.577282) (xy 417.595564 -53.529747)
			(xy 417.635303 -53.48773) (xy 417.657788 -53.46954) (xy 417.666565 -53.461904) (xy 417.676766 -53.441025)
			(xy 417.677346 -53.429408) (xy 417.677346 -53.349652) (xy 417.676839 -53.338016) (xy 417.666629 -53.317105)
			(xy 417.657788 -53.30952) (xy 417.635312 -53.291321) (xy 417.595577 -53.249302) (xy 417.562637 -53.201769)
			(xy 417.537248 -53.149809) (xy 417.51999 -53.094614) (xy 417.511258 -53.037445) (xy 417.510722 -53.00853)
			(xy 417.511183 -52.981277) (xy 417.518937 -52.927324) (xy 417.534291 -52.875024) (xy 417.556932 -52.825442)
			(xy 417.5864 -52.779587) (xy 417.622094 -52.738394) (xy 417.663287 -52.7027) (xy 417.709142 -52.673232)
			(xy 417.758724 -52.650591) (xy 417.811024 -52.635237) (xy 417.864977 -52.627483) (xy 417.89223 -52.627022)
			(xy 417.918545 -52.627462) (xy 417.970675 -52.634702) (xy 418.021318 -52.649026) (xy 418.069517 -52.670163)
			(xy 418.11436 -52.697714) (xy 418.154998 -52.731158) (xy 418.173154 -52.750212) (xy 418.180652 -52.757641)
			(xy 418.19995 -52.76615) (xy 418.210492 -52.766722) (xy 418.285168 -52.766722) (xy 418.295716 -52.766182)
			(xy 418.315011 -52.757654) (xy 418.322506 -52.750212) (xy 418.340668 -52.731163) (xy 418.381296 -52.697705)
			(xy 418.426135 -52.670144) (xy 418.474334 -52.649005) (xy 418.524981 -52.634686) (xy 418.577114 -52.627461)
			(xy 418.60343 -52.627022) (xy 418.630683 -52.62745) (xy 418.684635 -52.635211) (xy 418.736932 -52.650572)
			(xy 418.786512 -52.673219) (xy 418.832363 -52.702691) (xy 418.873554 -52.738388) (xy 418.909245 -52.779585)
			(xy 418.93871 -52.825441) (xy 418.961349 -52.875024) (xy 418.976701 -52.927324) (xy 418.984454 -52.981277)
			(xy 418.984938 -53.00853) (xy 418.984478 -53.036197) (xy 418.976473 -53.09095) (xy 418.960649 -53.143974)
			(xy 418.937338 -53.194159) (xy 418.907028 -53.240455) (xy 418.870354 -53.28189) (xy 418.828083 -53.317599)
			(xy 418.804852 -53.332634) (xy 418.795162 -53.339255) (xy 418.782724 -53.359128) (xy 418.780976 -53.370734)
			(xy 418.773102 -53.450744) (xy 418.772465 -53.462382) (xy 418.78055 -53.484219) (xy 418.788596 -53.492654)
			(xy 418.78885 -53.492908) (xy 418.807408 -53.511012) (xy 418.83999 -53.551338) (xy 418.866808 -53.595707)
			(xy 418.887365 -53.643301) (xy 418.901283 -53.693242) (xy 418.908304 -53.744608) (xy 418.908738 -53.77053)
			(xy 418.90825 -53.797781) (xy 418.90049 -53.851727) (xy 418.885133 -53.90402) (xy 418.862491 -53.953595)
			(xy 418.833024 -53.999444) (xy 418.797333 -54.040633) (xy 418.756144 -54.076324) (xy 418.710295 -54.105791)
			(xy 418.66072 -54.128433) (xy 418.608427 -54.14379) (xy 418.554481 -54.15155) (xy 418.52723 -54.152038)
			(xy 418.49986 -54.151569) (xy 418.44568 -54.143755) (xy 418.393176 -54.128267) (xy 418.343429 -54.105425)
			(xy 418.297463 -54.0757) (xy 418.276532 -54.058058) (xy 418.276278 -54.057804) (xy 418.269202 -54.052203)
			(xy 418.252277 -54.045965) (xy 418.243258 -54.045612) (xy 418.176202 -54.045612) (xy 418.167185 -54.045967)
			(xy 418.150268 -54.052216) (xy 418.143182 -54.057804) (xy 418.143182 -54.058058) (xy 418.142928 -54.058058)
			(xy 418.121991 -54.075691) (xy 418.07602 -54.105405) (xy 418.026274 -54.128243) (xy 417.973774 -54.143735)
			(xy 417.919599 -54.151564) (xy 417.89223 -54.152038) (xy 417.864981 -54.151494) (xy 417.811037 -54.143742)
			(xy 417.758745 -54.128392) (xy 417.70917 -54.105757) (xy 417.663321 -54.076297) (xy 417.622131 -54.040611)
			(xy 417.586439 -53.999427) (xy 417.556972 -53.953583) (xy 417.534328 -53.904011) (xy 417.51897 -53.851722)
			(xy 417.51121 -53.797779) (xy 417.510722 -53.77053) (xy 417.14654 -53.77053) (xy 417.14547 -53.7718)
			(xy 417.145216 -53.772054) (xy 417.139644 -53.779151) (xy 417.133388 -53.79606) (xy 417.133024 -53.805074)
			(xy 417.133024 -53.87213) (xy 417.133361 -53.881149) (xy 417.139622 -53.898066) (xy 417.145216 -53.90515)
			(xy 417.14547 -53.90515) (xy 417.14547 -53.905404) (xy 417.163113 -53.926335) (xy 417.192838 -53.972303)
			(xy 417.215683 -54.02205) (xy 417.231179 -54.074552) (xy 417.239008 -54.128731) (xy 417.239008 -54.183472)
			(xy 417.231179 -54.237651) (xy 417.215682 -54.290153) (xy 417.20189 -54.320186) (xy 419.430454 -54.320186)
			(xy 419.430899 -54.292815) (xy 419.43872 -54.238634) (xy 419.454213 -54.18613) (xy 419.47706 -54.136384)
			(xy 419.50679 -54.090418) (xy 419.524434 -54.069488) (xy 419.524688 -54.069234) (xy 419.530265 -54.062141)
			(xy 419.536518 -54.045229) (xy 419.53688 -54.036214) (xy 419.53688 -53.969158) (xy 419.536499 -53.960143)
			(xy 419.530269 -53.943226) (xy 419.524688 -53.936138) (xy 419.524434 -53.936138) (xy 419.524434 -53.935884)
			(xy 419.506826 -53.914927) (xy 419.477108 -53.868961) (xy 419.454266 -53.81922) (xy 419.438768 -53.766725)
			(xy 419.430932 -53.712554) (xy 419.430454 -53.685186) (xy 419.43094 -53.657935) (xy 419.438696 -53.603987)
			(xy 419.454051 -53.551692) (xy 419.476693 -53.502115) (xy 419.506159 -53.456265) (xy 419.54185 -53.415074)
			(xy 419.583041 -53.379383) (xy 419.628891 -53.349917) (xy 419.678468 -53.327275) (xy 419.730763 -53.31192)
			(xy 419.784711 -53.304164) (xy 419.839213 -53.304164) (xy 419.893161 -53.31192) (xy 419.945456 -53.327275)
			(xy 419.995033 -53.349917) (xy 420.040883 -53.379383) (xy 420.082074 -53.415074) (xy 420.117765 -53.456265)
			(xy 420.147231 -53.502115) (xy 420.169873 -53.551692) (xy 420.185228 -53.603987) (xy 420.192984 -53.657935)
			(xy 420.19347 -53.685186) (xy 420.193003 -53.712556) (xy 420.185187 -53.766736) (xy 420.169698 -53.819239)
			(xy 420.146856 -53.868986) (xy 420.117132 -53.914953) (xy 420.09949 -53.935884) (xy 420.099236 -53.936138)
			(xy 420.093662 -53.943233) (xy 420.087409 -53.960143) (xy 420.087044 -53.969158) (xy 420.087044 -54.036214)
			(xy 420.087385 -54.045233) (xy 420.093642 -54.06215) (xy 420.099236 -54.069234) (xy 420.09949 -54.069234)
			(xy 420.09949 -54.069488) (xy 420.117135 -54.090415) (xy 420.146847 -54.136389) (xy 420.169682 -54.186138)
			(xy 420.185171 -54.23864) (xy 420.192997 -54.292816) (xy 420.19347 -54.320186) (xy 420.192984 -54.347437)
			(xy 420.185228 -54.401385) (xy 420.169873 -54.45368) (xy 420.147231 -54.503257) (xy 420.117765 -54.549107)
			(xy 420.082074 -54.590298) (xy 420.040883 -54.625989) (xy 419.995033 -54.655455) (xy 419.945456 -54.678097)
			(xy 419.893161 -54.693452) (xy 419.839213 -54.701208) (xy 419.784711 -54.701208) (xy 419.730763 -54.693452)
			(xy 419.678468 -54.678097) (xy 419.628891 -54.655455) (xy 419.583041 -54.625989) (xy 419.54185 -54.590298)
			(xy 419.506159 -54.549107) (xy 419.476693 -54.503257) (xy 419.454051 -54.45368) (xy 419.438696 -54.401385)
			(xy 419.43094 -54.347437) (xy 419.430454 -54.320186) (xy 417.20189 -54.320186) (xy 417.192836 -54.3399)
			(xy 417.163111 -54.385867) (xy 417.14547 -54.4068) (xy 417.145216 -54.407054) (xy 417.139644 -54.414151)
			(xy 417.133388 -54.43106) (xy 417.133024 -54.440074) (xy 417.133024 -54.50713) (xy 417.133361 -54.516149)
			(xy 417.139622 -54.533066) (xy 417.145216 -54.54015) (xy 417.14547 -54.54015) (xy 417.14547 -54.540404)
			(xy 417.16312 -54.561328) (xy 417.192831 -54.607302) (xy 417.215665 -54.657052) (xy 417.231154 -54.709555)
			(xy 417.238978 -54.763732) (xy 417.239095 -54.770528) (xy 420.371016 -54.770528) (xy 420.371495 -54.743158)
			(xy 420.379309 -54.688979) (xy 420.394795 -54.636476) (xy 420.417634 -54.586729) (xy 420.447356 -54.540762)
			(xy 420.464996 -54.51983) (xy 420.46525 -54.519576) (xy 420.470859 -54.512505) (xy 420.477091 -54.495576)
			(xy 420.477442 -54.486556) (xy 420.477442 -54.4195) (xy 420.477097 -54.410482) (xy 420.470843 -54.393564)
			(xy 420.46525 -54.38648) (xy 420.464996 -54.38648) (xy 420.464996 -54.386226) (xy 420.447355 -54.365295)
			(xy 420.417644 -54.319322) (xy 420.394808 -54.269574) (xy 420.379317 -54.217073) (xy 420.37149 -54.162897)
			(xy 420.371016 -54.135528) (xy 420.371502 -54.108277) (xy 420.379258 -54.054329) (xy 420.394613 -54.002034)
			(xy 420.417255 -53.952457) (xy 420.446721 -53.906607) (xy 420.482412 -53.865416) (xy 420.523603 -53.829725)
			(xy 420.569453 -53.800259) (xy 420.61903 -53.777617) (xy 420.671325 -53.762262) (xy 420.725273 -53.754506)
			(xy 420.779775 -53.754506) (xy 420.833723 -53.762262) (xy 420.886018 -53.777617) (xy 420.935595 -53.800259)
			(xy 420.981445 -53.829725) (xy 421.022636 -53.865416) (xy 421.058327 -53.906607) (xy 421.087793 -53.952457)
			(xy 421.092868 -53.96357) (xy 425.072046 -53.96357) (xy 425.076117 -53.907948) (xy 425.088243 -53.853511)
			(xy 425.108166 -53.80142) (xy 425.135462 -53.752785) (xy 425.169548 -53.708642) (xy 425.209697 -53.669933)
			(xy 425.255055 -53.637482) (xy 425.304655 -53.611981) (xy 425.357439 -53.593974) (xy 425.412282 -53.583844)
			(xy 425.468016 -53.581807) (xy 425.523453 -53.587907) (xy 425.57741 -53.602013) (xy 425.628739 -53.623825)
			(xy 425.676345 -53.652879) (xy 425.719213 -53.688554) (xy 425.75643 -53.730091) (xy 425.787203 -53.776604)
			(xy 425.810875 -53.827101) (xy 425.826943 -53.880508) (xy 425.835063 -53.935684) (xy 425.835572 -53.96357)
			(xy 425.835063 -53.991456) (xy 425.826943 -54.046632) (xy 425.810875 -54.100039) (xy 425.787203 -54.150536)
			(xy 425.75643 -54.197049) (xy 425.719213 -54.238586) (xy 425.676345 -54.274261) (xy 425.628739 -54.303315)
			(xy 425.57741 -54.325127) (xy 425.523453 -54.339233) (xy 425.468016 -54.345333) (xy 425.412282 -54.343296)
			(xy 425.357439 -54.333166) (xy 425.304655 -54.315159) (xy 425.255055 -54.289658) (xy 425.209697 -54.257207)
			(xy 425.169548 -54.218498) (xy 425.135462 -54.174355) (xy 425.108166 -54.12572) (xy 425.088243 -54.073629)
			(xy 425.076117 -54.019192) (xy 425.072046 -53.96357) (xy 421.092868 -53.96357) (xy 421.110435 -54.002034)
			(xy 421.12579 -54.054329) (xy 421.133546 -54.108277) (xy 421.134032 -54.135528) (xy 421.133599 -54.1629)
			(xy 421.125776 -54.217081) (xy 421.11028 -54.269585) (xy 421.08743 -54.319331) (xy 421.057697 -54.365296)
			(xy 421.040052 -54.386226) (xy 421.039798 -54.38648) (xy 421.034213 -54.393568) (xy 421.027966 -54.410484)
			(xy 421.027606 -54.4195) (xy 421.027606 -54.486556) (xy 421.027983 -54.495571) (xy 421.034217 -54.512488)
			(xy 421.039798 -54.519576) (xy 421.040052 -54.519576) (xy 421.040052 -54.51983) (xy 421.057664 -54.540784)
			(xy 421.087382 -54.58675) (xy 421.110224 -54.636492) (xy 421.125721 -54.688988) (xy 421.133555 -54.74316)
			(xy 421.134032 -54.770528) (xy 421.133546 -54.797779) (xy 421.12579 -54.851727) (xy 421.110435 -54.904022)
			(xy 421.087793 -54.953599) (xy 421.058327 -54.999449) (xy 421.022636 -55.04064) (xy 420.981445 -55.076331)
			(xy 420.935595 -55.105797) (xy 420.886018 -55.128439) (xy 420.833723 -55.143794) (xy 420.779775 -55.15155)
			(xy 420.725273 -55.15155) (xy 420.671325 -55.143794) (xy 420.61903 -55.128439) (xy 420.569453 -55.105797)
			(xy 420.523603 -55.076331) (xy 420.482412 -55.04064) (xy 420.446721 -54.999449) (xy 420.417255 -54.953599)
			(xy 420.394613 -54.904022) (xy 420.379258 -54.851727) (xy 420.371502 -54.797779) (xy 420.371016 -54.770528)
			(xy 417.239095 -54.770528) (xy 417.23945 -54.791102) (xy 417.238964 -54.818353) (xy 417.231208 -54.872301)
			(xy 417.215853 -54.924596) (xy 417.193211 -54.974173) (xy 417.163745 -55.020023) (xy 417.128054 -55.061214)
			(xy 417.086863 -55.096905) (xy 417.041013 -55.126371) (xy 416.991436 -55.149013) (xy 416.939141 -55.164368)
			(xy 416.885193 -55.172124) (xy 416.830691 -55.172124) (xy 416.776743 -55.164368) (xy 416.724448 -55.149013)
			(xy 416.674871 -55.126371) (xy 416.629021 -55.096905) (xy 416.58783 -55.061214) (xy 416.552139 -55.020023)
			(xy 416.522673 -54.974173) (xy 416.500031 -54.924596) (xy 416.484676 -54.872301) (xy 416.47692 -54.818353)
			(xy 416.476434 -54.791102) (xy 414.578476 -54.791102) (xy 414.575384 -54.812611) (xy 414.560029 -54.864906)
			(xy 414.537387 -54.914483) (xy 414.507921 -54.960333) (xy 414.47223 -55.001524) (xy 414.431039 -55.037215)
			(xy 414.385189 -55.066681) (xy 414.335612 -55.089323) (xy 414.283317 -55.104678) (xy 414.229369 -55.112434)
			(xy 414.174867 -55.112434) (xy 414.120919 -55.104678) (xy 414.068624 -55.089323) (xy 414.019047 -55.066681)
			(xy 413.973197 -55.037215) (xy 413.932006 -55.001524) (xy 413.896315 -54.960333) (xy 413.866849 -54.914483)
			(xy 413.844207 -54.864906) (xy 413.828852 -54.812611) (xy 413.821096 -54.758663) (xy 413.82061 -54.731412)
			(xy 413.119316 -54.731412) (xy 413.119316 -57.002934) (xy 421.86352 -57.002934) (xy 421.864023 -56.974843)
			(xy 421.872247 -56.919265) (xy 421.888535 -56.865495) (xy 421.912536 -56.814697) (xy 421.94373 -56.76797)
			(xy 421.981442 -56.726325) (xy 422.024855 -56.690664) (xy 422.048686 -56.675782) (xy 422.057576 -56.670448)
			(xy 422.069768 -56.65343) (xy 422.090088 -56.560212) (xy 422.08577 -56.539638) (xy 422.079928 -56.531002)
			(xy 422.06393 -56.506937) (xy 422.038586 -56.455006) (xy 422.02136 -56.399849) (xy 422.012644 -56.342724)
			(xy 422.01211 -56.313832) (xy 422.012585 -56.286579) (xy 422.020338 -56.232628) (xy 422.035691 -56.180329)
			(xy 422.058331 -56.130748) (xy 422.087798 -56.084894) (xy 422.12349 -56.0437) (xy 422.164682 -56.008006)
			(xy 422.210535 -55.978538) (xy 422.260116 -55.955896) (xy 422.312414 -55.940541) (xy 422.366365 -55.932786)
			(xy 422.393618 -55.932324) (xy 422.420989 -55.932774) (xy 422.475169 -55.940595) (xy 422.527672 -55.956087)
			(xy 422.577419 -55.978933) (xy 422.623385 -56.008661) (xy 422.644316 -56.026304) (xy 422.64457 -56.026558)
			(xy 422.651656 -56.032145) (xy 422.668573 -56.03839) (xy 422.67759 -56.03875) (xy 422.744646 -56.03875)
			(xy 422.753662 -56.038378) (xy 422.770579 -56.032142) (xy 422.777666 -56.026558) (xy 422.777666 -56.026304)
			(xy 422.77792 -56.026304) (xy 422.798853 -56.008663) (xy 422.844821 -55.978939) (xy 422.894567 -55.956093)
			(xy 422.947069 -55.940597) (xy 423.001247 -55.932768) (xy 423.055989 -55.932768) (xy 423.110167 -55.940597)
			(xy 423.162669 -55.956093) (xy 423.212415 -55.978939) (xy 423.258383 -56.008663) (xy 423.279316 -56.026304)
			(xy 423.27957 -56.026558) (xy 423.286656 -56.032145) (xy 423.303573 -56.03839) (xy 423.31259 -56.03875)
			(xy 423.379646 -56.03875) (xy 423.388662 -56.038378) (xy 423.405579 -56.032142) (xy 423.412666 -56.026558)
			(xy 423.412666 -56.026304) (xy 423.41292 -56.026304) (xy 423.433872 -56.00869) (xy 423.479839 -55.978974)
			(xy 423.529582 -55.956133) (xy 423.582078 -55.940636) (xy 423.63625 -55.932802) (xy 423.663618 -55.932324)
			(xy 423.690871 -55.932747) (xy 423.744821 -55.940506) (xy 423.797118 -55.955864) (xy 423.846697 -55.978508)
			(xy 423.892549 -56.007978) (xy 423.933741 -56.043672) (xy 423.969433 -56.084865) (xy 423.9989 -56.130719)
			(xy 424.021542 -56.180299) (xy 424.036897 -56.232597) (xy 424.044654 -56.286547) (xy 424.044654 -56.341053)
			(xy 424.036897 -56.395003) (xy 424.021542 -56.447301) (xy 423.9989 -56.496881) (xy 423.969433 -56.542735)
			(xy 423.933741 -56.583928) (xy 423.892549 -56.619622) (xy 423.846697 -56.649092) (xy 423.797118 -56.671736)
			(xy 423.744821 -56.687094) (xy 423.690871 -56.694853) (xy 423.663618 -56.69534) (xy 423.636247 -56.694878)
			(xy 423.582068 -56.687061) (xy 423.529564 -56.671572) (xy 423.479817 -56.648729) (xy 423.433851 -56.619003)
			(xy 423.41292 -56.60136) (xy 423.412666 -56.601106) (xy 423.405564 -56.595542) (xy 423.388659 -56.589281)
			(xy 423.379646 -56.588914) (xy 423.31259 -56.588914) (xy 423.303572 -56.589263) (xy 423.286655 -56.595516)
			(xy 423.27957 -56.601106) (xy 423.27957 -56.60136) (xy 423.279316 -56.60136) (xy 423.258383 -56.619001)
			(xy 423.212415 -56.648725) (xy 423.162669 -56.671571) (xy 423.110167 -56.687067) (xy 423.055989 -56.694896)
			(xy 423.001247 -56.694896) (xy 422.947069 -56.687067) (xy 422.894567 -56.671571) (xy 422.844821 -56.648725)
			(xy 422.798853 -56.619001) (xy 422.77792 -56.60136) (xy 422.777666 -56.601106) (xy 422.770564 -56.595542)
			(xy 422.753659 -56.589281) (xy 422.744646 -56.588914) (xy 422.67759 -56.588914) (xy 422.668572 -56.589263)
			(xy 422.651655 -56.595516) (xy 422.64457 -56.601106) (xy 422.644062 -56.60136) (xy 422.631328 -56.612304)
			(xy 422.604236 -56.632145) (xy 422.58996 -56.640984) (xy 422.58107 -56.646318) (xy 422.568878 -56.663336)
			(xy 422.548558 -56.756554) (xy 422.552876 -56.777128) (xy 422.558718 -56.785764) (xy 422.574707 -56.809835)
			(xy 422.600052 -56.861764) (xy 422.61728 -56.91692) (xy 422.625999 -56.974042) (xy 422.626536 -57.002934)
			(xy 422.62605 -57.030185) (xy 422.618294 -57.084133) (xy 422.602939 -57.136428) (xy 422.580297 -57.186005)
			(xy 422.550831 -57.231855) (xy 422.51514 -57.273046) (xy 422.473949 -57.308737) (xy 422.428099 -57.338203)
			(xy 422.378522 -57.360845) (xy 422.326227 -57.3762) (xy 422.272279 -57.383956) (xy 422.217777 -57.383956)
			(xy 422.163829 -57.3762) (xy 422.111534 -57.360845) (xy 422.061957 -57.338203) (xy 422.016107 -57.308737)
			(xy 421.974916 -57.273046) (xy 421.939225 -57.231855) (xy 421.909759 -57.186005) (xy 421.887117 -57.136428)
			(xy 421.871762 -57.084133) (xy 421.864006 -57.030185) (xy 421.86352 -57.002934) (xy 413.119316 -57.002934)
			(xy 413.119316 -58.679334) (xy 422.29532 -58.679334) (xy 422.295737 -58.653018) (xy 422.302981 -58.600887)
			(xy 422.31731 -58.550243) (xy 422.338452 -58.502044) (xy 422.366007 -58.457202) (xy 422.399454 -58.416565)
			(xy 422.41851 -58.39841) (xy 422.425911 -58.390888) (xy 422.434435 -58.371608) (xy 422.43502 -58.361072)
			(xy 422.43502 -58.286396) (xy 422.434501 -58.275845) (xy 422.425958 -58.25655) (xy 422.41851 -58.249058)
			(xy 422.399443 -58.230914) (xy 422.365986 -58.190282) (xy 422.338429 -58.145439) (xy 422.317292 -58.097236)
			(xy 422.302978 -58.046587) (xy 422.295756 -57.994451) (xy 422.29532 -57.968134) (xy 422.295806 -57.940883)
			(xy 422.303562 -57.886935) (xy 422.318917 -57.83464) (xy 422.341559 -57.785063) (xy 422.371025 -57.739213)
			(xy 422.406716 -57.698022) (xy 422.447907 -57.662331) (xy 422.493757 -57.632865) (xy 422.543334 -57.610223)
			(xy 422.595629 -57.594868) (xy 422.649577 -57.587112) (xy 422.704079 -57.587112) (xy 422.758027 -57.594868)
			(xy 422.810322 -57.610223) (xy 422.859899 -57.632865) (xy 422.905749 -57.662331) (xy 422.94694 -57.698022)
			(xy 422.982631 -57.739213) (xy 423.012097 -57.785063) (xy 423.034739 -57.83464) (xy 423.050094 -57.886935)
			(xy 423.05785 -57.940883) (xy 423.058336 -57.968134) (xy 423.05788 -57.994448) (xy 423.050641 -58.046577)
			(xy 423.036319 -58.097219) (xy 423.015184 -58.145418) (xy 422.987637 -58.190261) (xy 422.954198 -58.230901)
			(xy 422.935146 -58.249058) (xy 422.927768 -58.2566) (xy 422.919229 -58.275864) (xy 422.918636 -58.286396)
			(xy 422.918636 -58.361072) (xy 422.919156 -58.371623) (xy 422.927697 -58.390919) (xy 422.935146 -58.39841)
			(xy 422.954208 -58.416559) (xy 422.987663 -58.457191) (xy 423.01522 -58.502033) (xy 423.036357 -58.550235)
			(xy 423.050673 -58.600883) (xy 423.057898 -58.653018) (xy 423.058336 -58.679334) (xy 423.05785 -58.706585)
			(xy 423.050094 -58.760533) (xy 423.034739 -58.812828) (xy 423.012097 -58.862405) (xy 422.982631 -58.908255)
			(xy 422.94694 -58.949446) (xy 422.905749 -58.985137) (xy 422.859899 -59.014603) (xy 422.810322 -59.037245)
			(xy 422.758027 -59.0526) (xy 422.704079 -59.060356) (xy 422.649577 -59.060356) (xy 422.595629 -59.0526)
			(xy 422.543334 -59.037245) (xy 422.493757 -59.014603) (xy 422.447907 -58.985137) (xy 422.406716 -58.949446)
			(xy 422.371025 -58.908255) (xy 422.341559 -58.862405) (xy 422.318917 -58.812828) (xy 422.303562 -58.760533)
			(xy 422.295806 -58.706585) (xy 422.29532 -58.679334) (xy 413.119316 -58.679334) (xy 413.119316 -60.01925)
			(xy 422.435784 -60.01925) (xy 422.435784 -59.96475) (xy 422.44354 -59.910805) (xy 422.458894 -59.858512)
			(xy 422.481533 -59.808937) (xy 422.510997 -59.763088) (xy 422.546686 -59.721899) (xy 422.587874 -59.686208)
			(xy 422.633721 -59.656742) (xy 422.683295 -59.6341) (xy 422.735587 -59.618743) (xy 422.789532 -59.610985)
			(xy 422.816782 -59.610498) (xy 422.844152 -59.610975) (xy 422.89833 -59.61879) (xy 422.950833 -59.634277)
			(xy 423.00058 -59.657116) (xy 423.046548 -59.686838) (xy 423.06748 -59.704478) (xy 423.067734 -59.704732)
			(xy 423.074833 -59.710301) (xy 423.09174 -59.716557) (xy 423.100754 -59.716924) (xy 423.16781 -59.716924)
			(xy 423.176827 -59.716566) (xy 423.193743 -59.710319) (xy 423.20083 -59.704732) (xy 423.20083 -59.704478)
			(xy 423.201084 -59.704478) (xy 423.222017 -59.686837) (xy 423.267985 -59.657113) (xy 423.317731 -59.634267)
			(xy 423.370233 -59.618771) (xy 423.424411 -59.610942) (xy 423.479153 -59.610942) (xy 423.533331 -59.618771)
			(xy 423.585833 -59.634267) (xy 423.635579 -59.657113) (xy 423.681547 -59.686837) (xy 423.70248 -59.704478)
			(xy 423.702734 -59.704732) (xy 423.709833 -59.710301) (xy 423.72674 -59.716557) (xy 423.735754 -59.716924)
			(xy 423.80281 -59.716924) (xy 423.811827 -59.716566) (xy 423.828743 -59.710319) (xy 423.83583 -59.704732)
			(xy 423.83583 -59.704478) (xy 423.836084 -59.704478) (xy 423.857008 -59.68683) (xy 423.902984 -59.65712)
			(xy 423.952733 -59.634286) (xy 424.005235 -59.618797) (xy 424.059412 -59.610971) (xy 424.086782 -59.610498)
			(xy 424.114036 -59.610948) (xy 424.16799 -59.618703) (xy 424.220291 -59.634058) (xy 424.269874 -59.6567)
			(xy 424.31573 -59.686168) (xy 424.356925 -59.721862) (xy 424.392622 -59.763056) (xy 424.422092 -59.80891)
			(xy 424.444736 -59.858492) (xy 424.460093 -59.910793) (xy 424.467851 -59.964746) (xy 424.467851 -60.019254)
			(xy 424.460093 -60.073207) (xy 424.444736 -60.125508) (xy 424.422092 -60.17509) (xy 424.392622 -60.220944)
			(xy 424.356925 -60.262138) (xy 424.31573 -60.297832) (xy 424.269874 -60.3273) (xy 424.220291 -60.349942)
			(xy 424.16799 -60.365297) (xy 424.114036 -60.373052) (xy 424.086782 -60.373514) (xy 424.059412 -60.373055)
			(xy 424.005232 -60.365235) (xy 423.952729 -60.349744) (xy 423.902983 -60.326901) (xy 423.857016 -60.297175)
			(xy 423.836084 -60.279534) (xy 423.83583 -60.27928) (xy 423.828741 -60.273698) (xy 423.811826 -60.267449)
			(xy 423.80281 -60.267088) (xy 423.735754 -60.267088) (xy 423.72674 -60.267473) (xy 423.709823 -60.273701)
			(xy 423.702734 -60.27928) (xy 423.70248 -60.279534) (xy 423.681547 -60.297175) (xy 423.635579 -60.326899)
			(xy 423.585833 -60.349745) (xy 423.533331 -60.365241) (xy 423.479153 -60.37307) (xy 423.424411 -60.37307)
			(xy 423.370233 -60.365241) (xy 423.317731 -60.349745) (xy 423.267985 -60.326899) (xy 423.222017 -60.297175)
			(xy 423.201084 -60.279534) (xy 423.20083 -60.27928) (xy 423.193741 -60.273698) (xy 423.176826 -60.267449)
			(xy 423.16781 -60.267088) (xy 423.100754 -60.267088) (xy 423.09174 -60.267473) (xy 423.074823 -60.273701)
			(xy 423.067734 -60.27928) (xy 423.067734 -60.279534) (xy 423.06748 -60.279534) (xy 423.046533 -60.297154)
			(xy 423.000564 -60.326868) (xy 422.95082 -60.349707) (xy 422.898323 -60.365202) (xy 422.84415 -60.373037)
			(xy 422.816782 -60.373514) (xy 422.789532 -60.373015) (xy 422.735587 -60.365257) (xy 422.683295 -60.3499)
			(xy 422.633721 -60.327258) (xy 422.587874 -60.297792) (xy 422.546686 -60.262101) (xy 422.510997 -60.220912)
			(xy 422.481533 -60.175063) (xy 422.458894 -60.125488) (xy 422.44354 -60.073195) (xy 422.435784 -60.01925)
			(xy 413.119316 -60.01925) (xy 413.119316 -64.47155) (xy 413.118807 -64.497636) (xy 413.110647 -64.549167)
			(xy 413.094521 -64.598785) (xy 413.070825 -64.645266) (xy 413.040145 -64.687465) (xy 413.022034 -64.706246)
			(xy 407.795222 -69.933058) (xy 407.788411 -69.940481) (xy 407.780673 -69.959063) (xy 407.780236 -69.969126)
			(xy 407.780236 -84.410804) (xy 408.03652 -84.410804) (xy 408.040591 -84.355182) (xy 408.052717 -84.300745)
			(xy 408.07264 -84.248654) (xy 408.099936 -84.200019) (xy 408.134022 -84.155876) (xy 408.174171 -84.117167)
			(xy 408.219529 -84.084716) (xy 408.269129 -84.059215) (xy 408.321913 -84.041208) (xy 408.376756 -84.031078)
			(xy 408.43249 -84.029041) (xy 408.487927 -84.035141) (xy 408.541884 -84.049247) (xy 408.593213 -84.071059)
			(xy 408.640819 -84.100113) (xy 408.683687 -84.135788) (xy 408.720904 -84.177325) (xy 408.751677 -84.223838)
			(xy 408.775349 -84.274335) (xy 408.791417 -84.327742) (xy 408.799537 -84.382918) (xy 408.800046 -84.410804)
			(xy 408.799537 -84.43869) (xy 408.791417 -84.493866) (xy 408.775349 -84.547273) (xy 408.751677 -84.59777)
			(xy 408.720904 -84.644283) (xy 408.683687 -84.68582) (xy 408.640819 -84.721495) (xy 408.593213 -84.750549)
			(xy 408.541884 -84.772361) (xy 408.487927 -84.786467) (xy 408.43249 -84.792567) (xy 408.376756 -84.79053)
			(xy 408.321913 -84.7804) (xy 408.269129 -84.762393) (xy 408.219529 -84.736892) (xy 408.174171 -84.704441)
			(xy 408.134022 -84.665732) (xy 408.099936 -84.621589) (xy 408.07264 -84.572954) (xy 408.052717 -84.520863)
			(xy 408.040591 -84.466426) (xy 408.03652 -84.410804) (xy 407.780236 -84.410804) (xy 407.780236 -85.160866)
			(xy 407.78067 -85.170934) (xy 407.788384 -85.189533) (xy 407.795222 -85.196934) (xy 408.778456 -86.180168)
			(xy 408.796499 -86.198929) (xy 408.827075 -86.24105) (xy 408.8507 -86.287429) (xy 408.866792 -86.336927)
			(xy 408.874957 -86.388332) (xy 408.875484 -86.414356) (xy 408.875484 -87.565738) (xy 408.874964 -87.591762)
			(xy 408.866798 -87.643166) (xy 408.850702 -87.692664) (xy 408.827073 -87.73904) (xy 408.79649 -87.781156)
			(xy 408.778456 -87.799926) (xy 407.319734 -89.258648) (xy 407.315619 -89.263043) (xy 407.309333 -89.273306)
			(xy 407.307288 -89.278968) (xy 407.307288 -89.279476) (xy 407.298807 -89.305008) (xy 407.275738 -89.353609)
			(xy 407.246071 -89.398488) (xy 407.210394 -89.438755) (xy 407.169415 -89.473611) (xy 407.123946 -89.502364)
			(xy 407.074888 -89.524446) (xy 407.023215 -89.539417) (xy 406.969951 -89.546982) (xy 406.943052 -89.547446)
			(xy 406.915801 -89.546967) (xy 406.861855 -89.539205) (xy 406.809563 -89.523846) (xy 406.759988 -89.501202)
			(xy 406.71414 -89.471734) (xy 406.672951 -89.436042) (xy 406.63726 -89.394852) (xy 406.607794 -89.349003)
			(xy 406.585151 -89.299428) (xy 406.569793 -89.247135) (xy 406.562032 -89.193189) (xy 406.561544 -89.165938)
			(xy 406.561958 -89.139026) (xy 406.569544 -89.085738) (xy 406.584542 -89.034044) (xy 406.606656 -88.984971)
			(xy 406.635445 -88.939493) (xy 406.67034 -88.898511) (xy 406.710646 -88.862838) (xy 406.755566 -88.833184)
			(xy 406.804207 -88.810135) (xy 406.829768 -88.801702) (xy 406.830022 -88.801702) (xy 406.835709 -88.799707)
			(xy 406.845987 -88.793421) (xy 406.850342 -88.789256) (xy 407.799286 -87.840566) (xy 407.807599 -87.831197)
			(xy 407.8148 -87.80724) (xy 407.813002 -87.794846) (xy 407.79446 -87.699596) (xy 407.778458 -87.680038)
			(xy 407.766774 -87.675212) (xy 407.741228 -87.663893) (xy 407.693499 -87.634841) (xy 407.650516 -87.599141)
			(xy 407.613196 -87.557556) (xy 407.582336 -87.510976) (xy 407.558596 -87.460394) (xy 407.542483 -87.406893)
			(xy 407.534341 -87.351614) (xy 407.533856 -87.323676) (xy 407.534456 -87.292873) (xy 407.544385 -87.232071)
			(xy 407.563962 -87.173658) (xy 407.577798 -87.14613) (xy 407.580502 -87.140601) (xy 407.583466 -87.12866)
			(xy 407.58364 -87.122508) (xy 407.58364 -86.629748) (xy 407.583206 -86.619679) (xy 407.575493 -86.601081)
			(xy 407.568654 -86.59368) (xy 406.742392 -85.767672) (xy 406.724377 -85.748886) (xy 406.693795 -85.706773)
			(xy 406.670164 -85.6604) (xy 406.654066 -85.610907) (xy 406.645894 -85.559507) (xy 406.645364 -85.533484)
			(xy 406.645364 -74.796904) (xy 406.628346 -74.77125) (xy 406.613868 -74.765408) (xy 406.604474 -74.76207)
			(xy 406.584561 -74.762063) (xy 406.566151 -74.769652) (xy 406.55875 -74.77633) (xy 406.377648 -74.957432)
			(xy 406.354056 -74.980335) (xy 406.302648 -75.021332) (xy 406.246977 -75.056321) (xy 406.187742 -75.084863)
			(xy 406.125685 -75.1066) (xy 406.061586 -75.121259) (xy 405.99625 -75.128655) (xy 405.963374 -75.129136)
			(xy 405.434038 -75.129136) (xy 405.407015 -75.128778) (xy 405.353207 -75.123693) (xy 405.326596 -75.118976)
			(xy 405.31542 -75.116944) (xy 405.293576 -75.122532) (xy 405.224488 -75.179936) (xy 405.216264 -75.187559)
			(xy 405.20678 -75.207853) (xy 405.2062 -75.219052) (xy 405.2062 -83.854544) (xy 405.206576 -83.864619)
			(xy 405.214328 -83.883218) (xy 405.221186 -83.890612) (xy 406.29205 -84.961222) (xy 406.314951 -84.984784)
			(xy 406.355916 -85.036161) (xy 406.39087 -85.091801) (xy 406.419376 -85.151005) (xy 406.441073 -85.213028)
			(xy 406.45569 -85.277091) (xy 406.463042 -85.342387) (xy 406.4635 -85.375242) (xy 406.4635 -88.266778)
			(xy 406.463008 -88.299631) (xy 406.455648 -88.364922) (xy 406.441029 -88.428981) (xy 406.419334 -88.491001)
			(xy 406.390837 -88.550205) (xy 406.355894 -88.605848) (xy 406.314945 -88.657233) (xy 406.29205 -88.680798)
			(xy 405.408638 -89.56421) (xy 405.385103 -89.587166) (xy 405.333687 -89.628147) (xy 405.278004 -89.663111)
			(xy 405.218756 -89.691617) (xy 405.156687 -89.713306) (xy 405.092579 -89.727907) (xy 405.027239 -89.735235)
			(xy 404.994364 -89.73566) (xy 404.957943 -89.735117) (xy 404.885663 -89.726089) (xy 404.815058 -89.708175)
			(xy 404.747216 -89.681653) (xy 404.683182 -89.646931) (xy 404.653242 -89.626186) (xy 404.641812 -89.617804)
			(xy 404.61311 -89.615772) (xy 404.519892 -89.663778) (xy 404.511848 -89.668447) (xy 404.499503 -89.682337)
			(xy 404.492881 -89.699699) (xy 404.49246 -89.70899) (xy 404.49246 -93.96476) (xy 404.49289 -93.974829)
			(xy 404.500606 -93.993428) (xy 404.507446 -94.000828) (xy 405.540972 -95.0341) (xy 405.545358 -95.038225)
			(xy 405.555627 -95.044505) (xy 405.561292 -95.046546) (xy 405.5618 -95.046546) (xy 405.587348 -95.054983)
			(xy 405.63595 -95.078057) (xy 405.680829 -95.10773) (xy 405.721095 -95.143413) (xy 405.75595 -95.184398)
			(xy 405.784702 -95.229873) (xy 405.80678 -95.278936) (xy 405.821748 -95.330613) (xy 405.829308 -95.383881)
			(xy 405.82977 -95.410782) (xy 405.829265 -95.439359) (xy 405.820769 -95.495877) (xy 405.803933 -95.550495)
			(xy 405.779136 -95.601988) (xy 405.746932 -95.649205) (xy 405.708042 -95.691087) (xy 405.663338 -95.726697)
			(xy 405.61382 -95.755236) (xy 405.560598 -95.776067) (xy 405.532844 -95.782892) (xy 405.519128 -95.78594)
			(xy 405.499316 -95.80499) (xy 405.470868 -95.903796) (xy 405.468649 -95.912543) (xy 405.469958 -95.930533)
			(xy 405.477455 -95.946939) (xy 405.483568 -95.95358) (xy 405.612346 -96.082358) (xy 405.616742 -96.086471)
			(xy 405.627004 -96.092758) (xy 405.632666 -96.094804) (xy 405.633174 -96.094804) (xy 405.658703 -96.103293)
			(xy 405.707304 -96.126361) (xy 405.752183 -96.156027) (xy 405.792449 -96.191703) (xy 405.827305 -96.232681)
			(xy 405.85606 -96.27815) (xy 405.878142 -96.327206) (xy 405.893114 -96.378878) (xy 405.900679 -96.432141)
			(xy 405.901144 -96.45904) (xy 405.90066 -96.486291) (xy 405.892898 -96.540236) (xy 405.87754 -96.592529)
			(xy 405.854897 -96.642104) (xy 405.82543 -96.687952) (xy 405.789738 -96.729141) (xy 405.748549 -96.764832)
			(xy 405.702701 -96.794299) (xy 405.653125 -96.816942) (xy 405.600833 -96.832299) (xy 405.546887 -96.84006)
			(xy 405.519636 -96.840548) (xy 405.492726 -96.840072) (xy 405.439444 -96.832488) (xy 405.387756 -96.817493)
			(xy 405.338686 -96.795386) (xy 405.29321 -96.766604) (xy 405.252228 -96.731718) (xy 405.216553 -96.691421)
			(xy 405.186894 -96.646512) (xy 405.163838 -96.597881) (xy 405.1554 -96.572324) (xy 405.1554 -96.57207)
			(xy 405.153408 -96.566382) (xy 405.14712 -96.556105) (xy 405.142954 -96.55175) (xy 403.356826 -94.765622)
			(xy 403.338725 -94.746831) (xy 403.30804 -94.704635) (xy 403.284338 -94.658157) (xy 403.268202 -94.608542)
			(xy 403.260032 -94.557012) (xy 403.259544 -94.530926) (xy 403.259544 -69.432678) (xy 403.25999 -69.406589)
			(xy 403.268163 -69.355055) (xy 403.284303 -69.305435) (xy 403.308013 -69.258955) (xy 403.338708 -69.21676)
			(xy 403.356826 -69.197982) (xy 407.688542 -64.866266) (xy 407.695458 -64.858682) (xy 407.703136 -64.839668)
			(xy 407.702734 -64.819167) (xy 407.698956 -64.809624) (xy 407.65349 -64.708278) (xy 407.626566 -64.692022)
			(xy 407.610818 -64.693038) (xy 407.610564 -64.693038) (xy 407.587958 -64.6938) (xy 407.560711 -64.693277)
			(xy 407.506771 -64.685516) (xy 407.454485 -64.670157) (xy 407.404917 -64.647515) (xy 407.359076 -64.618048)
			(xy 407.317895 -64.582358) (xy 407.282212 -64.54117) (xy 407.252753 -64.495324) (xy 407.230119 -64.445752)
			(xy 407.21477 -64.393463) (xy 407.207018 -64.339522) (xy 407.207022 -64.285027) (xy 407.214781 -64.231087)
			(xy 407.230137 -64.178801) (xy 407.252777 -64.129232) (xy 407.282242 -64.083389) (xy 407.31793 -64.042206)
			(xy 407.359117 -64.006522) (xy 407.404962 -63.977061) (xy 407.454533 -63.954425) (xy 407.506821 -63.939073)
			(xy 407.560761 -63.931319) (xy 407.615256 -63.931321) (xy 407.669196 -63.939077) (xy 407.721483 -63.954431)
			(xy 407.771054 -63.977069) (xy 407.816897 -64.006532) (xy 407.858082 -64.042219) (xy 407.893768 -64.083403)
			(xy 407.923231 -64.129247) (xy 407.945869 -64.178817) (xy 407.961223 -64.231104) (xy 407.968979 -64.285045)
			(xy 407.969466 -64.312292) (xy 407.968704 -64.334898) (xy 407.968624 -64.345163) (xy 407.975609 -64.364449)
			(xy 407.989527 -64.379517) (xy 407.998676 -64.384174) (xy 408.08529 -64.42329) (xy 408.09485 -64.426985)
			(xy 408.115321 -64.427354) (xy 408.134331 -64.419748) (xy 408.141932 -64.412876) (xy 408.564334 -63.990728)
			(xy 408.571159 -63.983316) (xy 408.578887 -63.964726) (xy 408.57932 -63.95466) (xy 408.57932 -63.17107)
			(xy 408.57867 -63.159326) (xy 408.568231 -63.138282) (xy 408.559254 -63.130684) (xy 408.484832 -63.074296)
			(xy 408.461718 -63.069978) (xy 408.450288 -63.07328) (xy 408.425027 -63.079932) (xy 408.373282 -63.087074)
			(xy 408.347164 -63.087504) (xy 408.319914 -63.087024) (xy 408.26597 -63.079263) (xy 408.213679 -63.063905)
			(xy 408.164106 -63.041261) (xy 408.118259 -63.011794) (xy 408.077073 -62.976102) (xy 408.041385 -62.934912)
			(xy 408.011922 -62.889063) (xy 407.989283 -62.839487) (xy 407.973929 -62.787195) (xy 407.966174 -62.73325)
			(xy 407.966174 -62.67875) (xy 407.973929 -62.624805) (xy 407.989283 -62.572513) (xy 408.011922 -62.522937)
			(xy 408.041385 -62.477088) (xy 408.077073 -62.435898) (xy 408.118259 -62.400206) (xy 408.164106 -62.370739)
			(xy 408.213679 -62.348095) (xy 408.26597 -62.332737) (xy 408.319914 -62.324976) (xy 408.347164 -62.324488)
			(xy 408.347672 -62.324488) (xy 408.375117 -62.324983) (xy 408.429436 -62.332878) (xy 408.482062 -62.34848)
			(xy 408.507184 -62.35954) (xy 408.517344 -62.364366) (xy 408.52852 -62.364366) (xy 408.538547 -62.363996)
			(xy 408.557071 -62.356313) (xy 408.571243 -62.342125) (xy 408.578906 -62.323593) (xy 408.57932 -62.313566)
			(xy 408.57932 -62.252606) (xy 408.57913 -62.246456) (xy 408.576175 -62.234515) (xy 408.573478 -62.228984)
			(xy 408.559666 -62.201446) (xy 408.540093 -62.143035) (xy 408.530151 -62.082239) (xy 408.529536 -62.051438)
			(xy 408.529991 -62.024184) (xy 408.537744 -61.970231) (xy 408.553097 -61.91793) (xy 408.575738 -61.868347)
			(xy 408.605207 -61.822491) (xy 408.640901 -61.781297) (xy 408.682096 -61.745603) (xy 408.727952 -61.716136)
			(xy 408.777535 -61.693495) (xy 408.829836 -61.678142) (xy 408.88379 -61.67039) (xy 408.911044 -61.66993)
			(xy 408.941847 -61.670525) (xy 409.002649 -61.680456) (xy 409.061062 -61.700036) (xy 409.08859 -61.713872)
			(xy 409.089098 -61.714126) (xy 409.094425 -61.716587) (xy 409.105839 -61.71929) (xy 409.111704 -61.71946)
			(xy 409.261564 -61.71946) (xy 409.271633 -61.719026) (xy 409.290231 -61.711312) (xy 409.297632 -61.704474)
			(xy 409.803854 -61.198252) (xy 409.810657 -61.190823) (xy 409.8184 -61.172246) (xy 409.81884 -61.162184)
			(xy 409.81884 -58.876438) (xy 409.818457 -58.867718) (xy 409.812543 -58.851307) (xy 409.801486 -58.837815)
			(xy 409.794202 -58.833004) (xy 409.71978 -58.788046) (xy 409.712078 -58.783893) (xy 409.694933 -58.78047)
			(xy 409.677633 -58.782998) (xy 409.669742 -58.786776) (xy 409.642065 -58.800734) (xy 409.58333 -58.820532)
			(xy 409.52217 -58.830594) (xy 409.49118 -58.831226) (xy 409.490926 -58.831226) (xy 409.463673 -58.830728)
			(xy 409.409722 -58.822975) (xy 409.357424 -58.807622) (xy 409.307842 -58.784982) (xy 409.261988 -58.755516)
			(xy 409.220794 -58.719824) (xy 409.1851 -58.678633) (xy 409.155631 -58.63278) (xy 409.132987 -58.583201)
			(xy 409.117631 -58.530903) (xy 409.109873 -58.476953) (xy 409.109873 -58.422447) (xy 409.117631 -58.368497)
			(xy 409.132987 -58.316199) (xy 409.155631 -58.26662) (xy 409.1851 -58.220767) (xy 409.220794 -58.179576)
			(xy 409.261988 -58.143884) (xy 409.307842 -58.114418) (xy 409.357424 -58.091778) (xy 409.409722 -58.076425)
			(xy 409.463673 -58.068672) (xy 409.490926 -58.06821) (xy 409.49118 -58.06821) (xy 409.522174 -58.068816)
			(xy 409.583344 -58.078853) (xy 409.642081 -58.098666) (xy 409.669742 -58.11266) (xy 409.677619 -58.116484)
			(xy 409.694934 -58.119022) (xy 409.712093 -58.115586) (xy 409.71978 -58.11139) (xy 409.794202 -58.066432)
			(xy 409.80152 -58.061657) (xy 409.812615 -58.048173) (xy 409.818491 -58.03173) (xy 409.81884 -58.022998)
			(xy 409.81884 -54.873398) (xy 409.801822 -54.847998) (xy 409.787598 -54.842156) (xy 409.778173 -54.83869)
			(xy 409.758104 -54.838754) (xy 409.739591 -54.846503) (xy 409.732226 -54.853332) (xy 406.718262 -57.867296)
			(xy 407.943048 -57.867296) (xy 407.947119 -57.811674) (xy 407.959245 -57.757237) (xy 407.979168 -57.705146)
			(xy 408.006464 -57.656511) (xy 408.04055 -57.612368) (xy 408.080699 -57.573659) (xy 408.126057 -57.541208)
			(xy 408.175657 -57.515707) (xy 408.228441 -57.4977) (xy 408.283284 -57.48757) (xy 408.339018 -57.485533)
			(xy 408.394455 -57.491633) (xy 408.448412 -57.505739) (xy 408.499741 -57.527551) (xy 408.547347 -57.556605)
			(xy 408.590215 -57.59228) (xy 408.627432 -57.633817) (xy 408.658205 -57.68033) (xy 408.681877 -57.730827)
			(xy 408.697945 -57.784234) (xy 408.706065 -57.83941) (xy 408.706574 -57.867296) (xy 408.706065 -57.895182)
			(xy 408.697945 -57.950358) (xy 408.681877 -58.003765) (xy 408.658205 -58.054262) (xy 408.627432 -58.100775)
			(xy 408.590215 -58.142312) (xy 408.547347 -58.177987) (xy 408.499741 -58.207041) (xy 408.448412 -58.228853)
			(xy 408.394455 -58.242959) (xy 408.339018 -58.249059) (xy 408.283284 -58.247022) (xy 408.228441 -58.236892)
			(xy 408.175657 -58.218885) (xy 408.126057 -58.193384) (xy 408.080699 -58.160933) (xy 408.04055 -58.122224)
			(xy 408.006464 -58.078081) (xy 407.979168 -58.029446) (xy 407.959245 -57.977355) (xy 407.947119 -57.922918)
			(xy 407.943048 -57.867296) (xy 406.718262 -57.867296) (xy 406.416764 -58.168794) (xy 406.412653 -58.173191)
			(xy 406.406365 -58.183453) (xy 406.404318 -58.189114) (xy 406.404318 -58.189622) (xy 406.395865 -58.215165)
			(xy 406.372798 -58.26377) (xy 406.34313 -58.308653) (xy 406.30745 -58.348922) (xy 406.266467 -58.383778)
			(xy 406.220993 -58.412531) (xy 406.17193 -58.434609) (xy 406.120251 -58.449575) (xy 406.066983 -58.457132)
			(xy 406.040082 -58.457592) (xy 406.01283 -58.457139) (xy 405.95888 -58.44938) (xy 405.906584 -58.434021)
			(xy 405.857005 -58.411377) (xy 405.811154 -58.381907) (xy 405.769964 -58.346212) (xy 405.734272 -58.305019)
			(xy 405.704807 -58.259165) (xy 405.682167 -58.209585) (xy 405.666813 -58.157287) (xy 405.659059 -58.103336)
			(xy 405.658574 -58.076084) (xy 405.659078 -58.049175) (xy 405.666656 -57.995893) (xy 405.681645 -57.944205)
			(xy 405.703748 -57.895135) (xy 405.732526 -57.849657) (xy 405.767409 -57.808675) (xy 405.807704 -57.773)
			(xy 405.852612 -57.743341) (xy 405.901242 -57.720285) (xy 405.926798 -57.711848) (xy 405.927052 -57.711848)
			(xy 405.932746 -57.709872) (xy 405.943021 -57.703573) (xy 405.947372 -57.699402) (xy 409.439618 -54.207156)
			(xy 409.446472 -54.199767) (xy 409.454183 -54.181159) (xy 409.454604 -54.171088) (xy 409.454604 -46.137322)
			(xy 409.454193 -46.127251) (xy 409.446465 -46.108651) (xy 409.439618 -46.101254) (xy 403.657308 -40.31869)
			(xy 403.6499 -40.31186) (xy 403.631307 -40.304135) (xy 403.62124 -40.303704) (xy 400.77898 -40.303704)
			(xy 400.772829 -40.303883) (xy 400.760888 -40.306845) (xy 400.755358 -40.309546) (xy 400.727821 -40.323361)
			(xy 400.66941 -40.342934) (xy 400.608613 -40.352874) (xy 400.577812 -40.353488) (xy 400.550557 -40.353066)
			(xy 400.496602 -40.34531) (xy 400.4443 -40.329954) (xy 400.394716 -40.307311) (xy 400.348859 -40.277842)
			(xy 400.307662 -40.242146) (xy 400.271965 -40.200951) (xy 400.242495 -40.155095) (xy 400.21985 -40.105511)
			(xy 400.204493 -40.05321) (xy 400.196735 -39.999255) (xy 400.196735 -39.944745) (xy 400.204493 -39.89079)
			(xy 400.21985 -39.838489) (xy 400.242495 -39.788905) (xy 400.271965 -39.743049) (xy 400.307662 -39.701854)
			(xy 400.348859 -39.666158) (xy 400.394716 -39.636689) (xy 400.4443 -39.614046) (xy 400.496602 -39.59869)
			(xy 400.550557 -39.590934) (xy 400.577812 -39.590472) (xy 400.608615 -39.591086) (xy 400.669415 -39.60101)
			(xy 400.727829 -39.620582) (xy 400.755358 -39.634414) (xy 400.760888 -39.637116) (xy 400.772829 -39.64008)
			(xy 400.77898 -39.640256) (xy 403.378162 -39.640256) (xy 403.403816 -39.623238) (xy 403.409658 -39.60876)
			(xy 403.412986 -39.599364) (xy 403.41299 -39.579455) (xy 403.405408 -39.561045) (xy 403.398736 -39.553642)
			(xy 400.068796 -36.223702) (xy 400.061391 -36.216868) (xy 400.042796 -36.209145) (xy 400.032728 -36.208716)
			(xy 399.071846 -36.208716) (xy 399.059898 -36.20931) (xy 399.03856 -36.220057) (xy 399.030952 -36.22929)
			(xy 398.975072 -36.304982) (xy 398.971262 -36.328858) (xy 398.974818 -36.340288) (xy 398.982866 -36.367916)
			(xy 398.991544 -36.424801) (xy 398.99209 -36.453572) (xy 398.991604 -36.480823) (xy 398.983848 -36.534771)
			(xy 398.968493 -36.587066) (xy 398.945851 -36.636643) (xy 398.916385 -36.682493) (xy 398.880694 -36.723684)
			(xy 398.839503 -36.759375) (xy 398.793653 -36.788841) (xy 398.744076 -36.811483) (xy 398.691781 -36.826838)
			(xy 398.637833 -36.834594) (xy 398.583331 -36.834594) (xy 398.529383 -36.826838) (xy 398.477088 -36.811483)
			(xy 398.427511 -36.788841) (xy 398.381661 -36.759375) (xy 398.34047 -36.723684) (xy 398.304779 -36.682493)
			(xy 398.275313 -36.636643) (xy 398.252671 -36.587066) (xy 398.237316 -36.534771) (xy 398.22956 -36.480823)
			(xy 398.229074 -36.453572) (xy 398.229607 -36.4248) (xy 398.238282 -36.367912) (xy 398.246346 -36.340288)
			(xy 398.249902 -36.328858) (xy 398.246092 -36.304982) (xy 398.190212 -36.22929) (xy 398.182607 -36.220064)
			(xy 398.16126 -36.20935) (xy 398.149318 -36.208716) (xy 397.665448 -36.208716) (xy 397.654272 -36.211256)
			(xy 397.648938 -36.21405) (xy 397.647922 -36.214558) (xy 397.620444 -36.228274) (xy 397.562198 -36.247731)
			(xy 397.501588 -36.257609) (xy 397.470884 -36.258246) (xy 397.443636 -36.257683) (xy 397.389696 -36.249925)
			(xy 397.337408 -36.23457) (xy 397.287838 -36.21193) (xy 397.241994 -36.182467) (xy 397.20081 -36.146779)
			(xy 397.165124 -36.105593) (xy 397.135662 -36.059748) (xy 397.113024 -36.010177) (xy 397.097671 -35.957889)
			(xy 397.089916 -35.903948) (xy 397.089916 -35.849452) (xy 397.097671 -35.795511) (xy 397.113024 -35.743223)
			(xy 397.135662 -35.693652) (xy 397.165124 -35.647807) (xy 397.20081 -35.606621) (xy 397.241994 -35.570933)
			(xy 397.287838 -35.54147) (xy 397.337408 -35.51883) (xy 397.389696 -35.503475) (xy 397.443636 -35.495717)
			(xy 397.470884 -35.49523) (xy 397.501686 -35.495849) (xy 397.562487 -35.50577) (xy 397.620901 -35.52534)
			(xy 397.64843 -35.539172) (xy 397.648938 -35.539426) (xy 397.65426 -35.5419) (xy 397.665678 -35.544595)
			(xy 397.671544 -35.54476) (xy 399.87601 -35.54476) (xy 399.90141 -35.527742) (xy 399.907252 -35.513518)
			(xy 399.910699 -35.504088) (xy 399.910641 -35.484023) (xy 399.9029 -35.465512) (xy 399.896076 -35.458146)
			(xy 397.443452 -33.005522) (xy 397.425406 -32.986764) (xy 397.394829 -32.944643) (xy 397.371206 -32.898263)
			(xy 397.355114 -32.848764) (xy 397.34695 -32.797358) (xy 397.346424 -32.771334) (xy 397.346424 -29.729938)
			(xy 397.346926 -29.703913) (xy 397.355097 -29.652508) (xy 397.371196 -29.60301) (xy 397.39483 -29.556634)
			(xy 397.425417 -29.514519) (xy 397.443452 -29.49575) (xy 398.062704 -28.876498) (xy 398.068546 -28.846526)
			(xy 398.062704 -28.832302) (xy 398.058381 -28.823276) (xy 398.044188 -28.809194) (xy 398.02571 -28.801558)
			(xy 398.015714 -28.80106) (xy 395.373352 -28.80106) (xy 395.347265 -28.800566) (xy 395.295733 -28.792405)
			(xy 395.246114 -28.776276) (xy 395.199633 -28.752576) (xy 395.157436 -28.721891) (xy 395.138656 -28.703778)
			(xy 394.11529 -27.680158) (xy 394.107892 -27.673315) (xy 394.089291 -27.665598) (xy 394.079222 -27.665172)
			(xy 393.0396 -27.665172) (xy 393.012423 -27.664582) (xy 392.958802 -27.655678) (xy 392.907349 -27.638158)
			(xy 392.883136 -27.625802) (xy 392.229848 -27.274774) (xy 392.206218 -27.261477) (xy 392.163235 -27.228431)
			(xy 392.126211 -27.188824) (xy 392.110722 -27.16657) (xy 391.832084 -26.749248) (xy 391.825618 -26.740533)
			(xy 391.807202 -26.729095) (xy 391.785708 -26.726268) (xy 391.775188 -26.728928) (xy 391.764943 -26.732548)
			(xy 391.748594 -26.746824) (xy 391.739623 -26.766589) (xy 391.73912 -26.777442) (xy 391.73912 -27.342846)
			(xy 391.73863 -27.372814) (xy 391.730807 -27.432236) (xy 391.715294 -27.490129) (xy 391.692358 -27.545502)
			(xy 391.662391 -27.597408) (xy 391.625904 -27.644958) (xy 391.583524 -27.687338) (xy 391.535974 -27.723825)
			(xy 391.484068 -27.753792) (xy 391.428695 -27.776728) (xy 391.370802 -27.792241) (xy 391.31138 -27.800064)
			(xy 391.251444 -27.800064) (xy 391.192022 -27.792241) (xy 391.134129 -27.776728) (xy 391.078756 -27.753792)
			(xy 391.02685 -27.723825) (xy 390.9793 -27.687338) (xy 390.93692 -27.644958) (xy 390.900433 -27.597408)
			(xy 390.870466 -27.545502) (xy 390.84753 -27.490129) (xy 390.832017 -27.432236) (xy 390.824194 -27.372814)
			(xy 390.823704 -27.342846) (xy 390.823704 -26.479246) (xy 390.824132 -26.449654) (xy 390.83174 -26.390962)
			(xy 390.846848 -26.333739) (xy 390.869204 -26.27894) (xy 390.898435 -26.227479) (xy 390.934054 -26.180213)
			(xy 390.975466 -26.137932) (xy 391.021982 -26.10134) (xy 391.072825 -26.071047) (xy 391.099802 -26.058876)
			(xy 391.111486 -26.053796) (xy 391.127234 -26.034238) (xy 391.145268 -25.939242) (xy 391.146949 -25.926877)
			(xy 391.139647 -25.903048) (xy 391.131298 -25.893776) (xy 390.61898 -25.381458) (xy 390.611586 -25.374611)
			(xy 390.592982 -25.366897) (xy 390.582912 -25.366472) (xy 389.005064 -25.366472) (xy 388.99499 -25.366859)
			(xy 388.976391 -25.374605) (xy 388.968996 -25.381458) (xy 388.867904 -25.482804) (xy 388.863795 -25.487204)
			(xy 388.857506 -25.497463) (xy 388.855458 -25.503124) (xy 388.855458 -25.503632) (xy 388.846977 -25.529164)
			(xy 388.823911 -25.577768) (xy 388.794246 -25.622649) (xy 388.75857 -25.662917) (xy 388.71759 -25.697774)
			(xy 388.67212 -25.726528) (xy 388.623061 -25.748609) (xy 388.571386 -25.763578) (xy 388.518121 -25.77114)
			(xy 388.491222 -25.771602) (xy 388.463969 -25.771124) (xy 388.410019 -25.76337) (xy 388.357721 -25.748017)
			(xy 388.30814 -25.725376) (xy 388.262287 -25.69591) (xy 388.221094 -25.660218) (xy 388.1854 -25.619026)
			(xy 388.155932 -25.573174) (xy 388.133289 -25.523594) (xy 388.117933 -25.471297) (xy 388.110177 -25.417347)
			(xy 388.109714 -25.390094) (xy 388.110198 -25.363184) (xy 388.117776 -25.3099) (xy 388.132766 -25.25821)
			(xy 388.15487 -25.209138) (xy 388.183651 -25.16366) (xy 388.218537 -25.122677) (xy 388.258835 -25.087003)
			(xy 388.303747 -25.057346) (xy 388.35238 -25.034293) (xy 388.377938 -25.025858) (xy 388.378192 -25.025858)
			(xy 388.383879 -25.023863) (xy 388.394157 -25.017578) (xy 388.398512 -25.013412) (xy 388.412736 -24.999188)
			(xy 388.419526 -24.991783) (xy 388.427271 -24.973268) (xy 388.427284 -24.953198) (xy 388.419564 -24.934673)
			(xy 388.412736 -24.927306) (xy 388.089648 -24.604218) (xy 388.065938 -24.579845) (xy 388.023768 -24.526502)
			(xy 387.98805 -24.468638) (xy 387.959265 -24.407032) (xy 387.937798 -24.34251) (xy 387.93039 -24.309324)
			(xy 387.927596 -24.295608) (xy 387.9088 -24.275034) (xy 387.809486 -24.245316) (xy 387.800655 -24.243084)
			(xy 387.782495 -24.244352) (xy 387.765916 -24.251868) (xy 387.759194 -24.258016) (xy 387.59257 -24.42464)
			(xy 387.57379 -24.442662) (xy 387.531675 -24.473242) (xy 387.485301 -24.49687) (xy 387.435806 -24.512967)
			(xy 387.384405 -24.521138) (xy 387.358382 -24.521668) (xy 386.182108 -24.521668) (xy 386.175958 -24.52186)
			(xy 386.164017 -24.524814) (xy 386.158486 -24.52751) (xy 386.130947 -24.54132) (xy 386.072536 -24.560894)
			(xy 386.011741 -24.570837) (xy 385.98094 -24.571452) (xy 385.953688 -24.570904) (xy 385.899739 -24.563152)
			(xy 385.847443 -24.547801) (xy 385.797863 -24.525164) (xy 385.75201 -24.4957) (xy 385.710818 -24.460011)
			(xy 385.675124 -24.418822) (xy 385.645656 -24.372972) (xy 385.623013 -24.323395) (xy 385.607656 -24.2711)
			(xy 385.599899 -24.217152) (xy 385.599899 -24.162648) (xy 385.607656 -24.1087) (xy 385.623013 -24.056405)
			(xy 385.645656 -24.006828) (xy 385.675124 -23.960978) (xy 385.710818 -23.919789) (xy 385.75201 -23.8841)
			(xy 385.797863 -23.854636) (xy 385.847443 -23.831999) (xy 385.899739 -23.816648) (xy 385.953688 -23.808896)
			(xy 385.98094 -23.808436) (xy 386.011743 -23.809032) (xy 386.072545 -23.818963) (xy 386.130958 -23.838542)
			(xy 386.158486 -23.852378) (xy 386.164013 -23.855087) (xy 386.175956 -23.858047) (xy 386.182108 -23.85822)
			(xy 387.199378 -23.85822) (xy 387.209449 -23.857804) (xy 387.228048 -23.850079) (xy 387.235446 -23.843234)
			(xy 387.318758 -23.759668) (xy 387.324954 -23.752975) (xy 387.332557 -23.736409) (xy 387.333898 -23.718231)
			(xy 387.331712 -23.709376) (xy 387.306566 -23.623778) (xy 387.30371 -23.615186) (xy 387.292899 -23.600672)
			(xy 387.277722 -23.590814) (xy 387.268974 -23.588472) (xy 387.268466 -23.588472) (xy 387.234297 -23.580436)
			(xy 387.168004 -23.55736) (xy 387.104945 -23.526526) (xy 387.046023 -23.488375) (xy 386.992085 -23.443454)
			(xy 386.943903 -23.392408) (xy 386.902168 -23.335968) (xy 386.867479 -23.274945) (xy 386.85343 -23.242778)
			(xy 386.848604 -23.231094) (xy 386.829046 -23.215092) (xy 386.733796 -23.196296) (xy 386.721303 -23.194469)
			(xy 386.697176 -23.201788) (xy 386.687822 -23.210266) (xy 386.458714 -23.439374) (xy 386.43514 -23.462262)
			(xy 386.383765 -23.503227) (xy 386.328126 -23.538182) (xy 386.268925 -23.566689) (xy 386.206903 -23.588389)
			(xy 386.142843 -23.603008) (xy 386.077548 -23.610364) (xy 386.044694 -23.610824) (xy 386.04444 -23.610824)
			(xy 386.009042 -23.610273) (xy 385.938762 -23.601744) (xy 385.870023 -23.584806) (xy 385.803826 -23.559705)
			(xy 385.741138 -23.526807) (xy 385.682873 -23.486593) (xy 385.62988 -23.439649) (xy 385.582932 -23.386659)
			(xy 385.542714 -23.328396) (xy 385.509812 -23.26571) (xy 385.484706 -23.199516) (xy 385.467763 -23.130777)
			(xy 385.459229 -23.060498) (xy 385.458716 -23.0251) (xy 373.602504 -23.0251) (xy 373.602504 -23.965154)
			(xy 374.377456 -23.965154) (xy 374.381527 -23.909532) (xy 374.393653 -23.855095) (xy 374.413576 -23.803004)
			(xy 374.440872 -23.754369) (xy 374.474958 -23.710226) (xy 374.515107 -23.671517) (xy 374.560465 -23.639066)
			(xy 374.610065 -23.613565) (xy 374.662849 -23.595558) (xy 374.717692 -23.585428) (xy 374.773426 -23.583391)
			(xy 374.828863 -23.589491) (xy 374.88282 -23.603597) (xy 374.934149 -23.625409) (xy 374.981755 -23.654463)
			(xy 375.024623 -23.690138) (xy 375.06184 -23.731675) (xy 375.092613 -23.778188) (xy 375.116285 -23.828685)
			(xy 375.132353 -23.882092) (xy 375.140473 -23.937268) (xy 375.140648 -23.946866) (xy 375.380502 -23.946866)
			(xy 375.384573 -23.891244) (xy 375.396699 -23.836807) (xy 375.416622 -23.784716) (xy 375.443918 -23.736081)
			(xy 375.478004 -23.691938) (xy 375.518153 -23.653229) (xy 375.563511 -23.620778) (xy 375.613111 -23.595277)
			(xy 375.665895 -23.57727) (xy 375.720738 -23.56714) (xy 375.776472 -23.565103) (xy 375.831909 -23.571203)
			(xy 375.885866 -23.585309) (xy 375.937195 -23.607121) (xy 375.984801 -23.636175) (xy 376.027669 -23.67185)
			(xy 376.064886 -23.713387) (xy 376.095659 -23.7599) (xy 376.119331 -23.810397) (xy 376.135399 -23.863804)
			(xy 376.143519 -23.91898) (xy 376.144028 -23.946866) (xy 376.143588 -23.970996) (xy 376.37288 -23.970996)
			(xy 376.376951 -23.915374) (xy 376.389077 -23.860937) (xy 376.409 -23.808846) (xy 376.436296 -23.760211)
			(xy 376.470382 -23.716068) (xy 376.510531 -23.677359) (xy 376.555889 -23.644908) (xy 376.605489 -23.619407)
			(xy 376.658273 -23.6014) (xy 376.713116 -23.59127) (xy 376.76885 -23.589233) (xy 376.824287 -23.595333)
			(xy 376.878244 -23.609439) (xy 376.929573 -23.631251) (xy 376.977179 -23.660305) (xy 377.020047 -23.69598)
			(xy 377.057264 -23.737517) (xy 377.088037 -23.78403) (xy 377.111709 -23.834527) (xy 377.127777 -23.887934)
			(xy 377.135897 -23.94311) (xy 377.136406 -23.970996) (xy 377.135897 -23.998882) (xy 377.127777 -24.054058)
			(xy 377.111709 -24.107465) (xy 377.088037 -24.157962) (xy 377.057264 -24.204475) (xy 377.020047 -24.246012)
			(xy 376.977179 -24.281687) (xy 376.929573 -24.310741) (xy 376.878244 -24.332553) (xy 376.824287 -24.346659)
			(xy 376.76885 -24.352759) (xy 376.713116 -24.350722) (xy 376.658273 -24.340592) (xy 376.605489 -24.322585)
			(xy 376.555889 -24.297084) (xy 376.510531 -24.264633) (xy 376.470382 -24.225924) (xy 376.436296 -24.181781)
			(xy 376.409 -24.133146) (xy 376.389077 -24.081055) (xy 376.376951 -24.026618) (xy 376.37288 -23.970996)
			(xy 376.143588 -23.970996) (xy 376.143519 -23.974752) (xy 376.135399 -24.029928) (xy 376.119331 -24.083335)
			(xy 376.095659 -24.133832) (xy 376.064886 -24.180345) (xy 376.027669 -24.221882) (xy 375.984801 -24.257557)
			(xy 375.937195 -24.286611) (xy 375.885866 -24.308423) (xy 375.831909 -24.322529) (xy 375.776472 -24.328629)
			(xy 375.720738 -24.326592) (xy 375.665895 -24.316462) (xy 375.613111 -24.298455) (xy 375.563511 -24.272954)
			(xy 375.518153 -24.240503) (xy 375.478004 -24.201794) (xy 375.443918 -24.157651) (xy 375.416622 -24.109016)
			(xy 375.396699 -24.056925) (xy 375.384573 -24.002488) (xy 375.380502 -23.946866) (xy 375.140648 -23.946866)
			(xy 375.140982 -23.965154) (xy 375.140473 -23.99304) (xy 375.132353 -24.048216) (xy 375.116285 -24.101623)
			(xy 375.092613 -24.15212) (xy 375.06184 -24.198633) (xy 375.024623 -24.24017) (xy 374.981755 -24.275845)
			(xy 374.934149 -24.304899) (xy 374.88282 -24.326711) (xy 374.828863 -24.340817) (xy 374.773426 -24.346917)
			(xy 374.717692 -24.34488) (xy 374.662849 -24.33475) (xy 374.610065 -24.316743) (xy 374.560465 -24.291242)
			(xy 374.515107 -24.258791) (xy 374.474958 -24.220082) (xy 374.440872 -24.175939) (xy 374.413576 -24.127304)
			(xy 374.393653 -24.075213) (xy 374.381527 -24.020776) (xy 374.377456 -23.965154) (xy 373.602504 -23.965154)
			(xy 373.602504 -24.807418) (xy 380.671322 -24.807418) (xy 380.675393 -24.751796) (xy 380.687519 -24.697359)
			(xy 380.707442 -24.645268) (xy 380.734738 -24.596633) (xy 380.768824 -24.55249) (xy 380.808973 -24.513781)
			(xy 380.854331 -24.48133) (xy 380.903931 -24.455829) (xy 380.956715 -24.437822) (xy 381.011558 -24.427692)
			(xy 381.067292 -24.425655) (xy 381.122729 -24.431755) (xy 381.176686 -24.445861) (xy 381.228015 -24.467673)
			(xy 381.275621 -24.496727) (xy 381.318489 -24.532402) (xy 381.355706 -24.573939) (xy 381.386479 -24.620452)
			(xy 381.410151 -24.670949) (xy 381.426219 -24.724356) (xy 381.434339 -24.779532) (xy 381.434848 -24.807418)
			(xy 381.434339 -24.835304) (xy 381.426219 -24.89048) (xy 381.410151 -24.943887) (xy 381.386479 -24.994384)
			(xy 381.355706 -25.040897) (xy 381.318489 -25.082434) (xy 381.275621 -25.118109) (xy 381.228015 -25.147163)
			(xy 381.176686 -25.168975) (xy 381.122729 -25.183081) (xy 381.067292 -25.189181) (xy 381.011558 -25.187144)
			(xy 380.956715 -25.177014) (xy 380.903931 -25.159007) (xy 380.854331 -25.133506) (xy 380.808973 -25.101055)
			(xy 380.768824 -25.062346) (xy 380.734738 -25.018203) (xy 380.707442 -24.969568) (xy 380.687519 -24.917477)
			(xy 380.675393 -24.86304) (xy 380.671322 -24.807418) (xy 373.602504 -24.807418) (xy 373.602504 -25.93467)
			(xy 373.606786 -25.940005) (xy 373.617604 -25.948367) (xy 373.62384 -25.95118) (xy 373.631968 -25.95372)
			(xy 373.659306 -25.962325) (xy 373.711234 -25.986577) (xy 373.75896 -26.018309) (xy 373.775966 -26.03373)
			(xy 379.567946 -26.03373) (xy 379.572017 -25.978108) (xy 379.584143 -25.923671) (xy 379.604066 -25.87158)
			(xy 379.631362 -25.822945) (xy 379.665448 -25.778802) (xy 379.705597 -25.740093) (xy 379.750955 -25.707642)
			(xy 379.800555 -25.682141) (xy 379.853339 -25.664134) (xy 379.908182 -25.654004) (xy 379.963916 -25.651967)
			(xy 380.019353 -25.658067) (xy 380.07331 -25.672173) (xy 380.124639 -25.693985) (xy 380.172245 -25.723039)
			(xy 380.215113 -25.758714) (xy 380.25233 -25.800251) (xy 380.283103 -25.846764) (xy 380.306775 -25.897261)
			(xy 380.322843 -25.950668) (xy 380.330963 -26.005844) (xy 380.331472 -26.03373) (xy 380.330963 -26.061616)
			(xy 380.322843 -26.116792) (xy 380.306775 -26.170199) (xy 380.283103 -26.220696) (xy 380.25233 -26.267209)
			(xy 380.215113 -26.308746) (xy 380.172245 -26.344421) (xy 380.124639 -26.373475) (xy 380.07331 -26.395287)
			(xy 380.019353 -26.409393) (xy 379.963916 -26.415493) (xy 379.908182 -26.413456) (xy 379.853339 -26.403326)
			(xy 379.800555 -26.385319) (xy 379.750955 -26.359818) (xy 379.705597 -26.327367) (xy 379.665448 -26.288658)
			(xy 379.631362 -26.244515) (xy 379.604066 -26.19588) (xy 379.584143 -26.143789) (xy 379.572017 -26.089352)
			(xy 379.567946 -26.03373) (xy 373.775966 -26.03373) (xy 373.801416 -26.056808) (xy 373.819928 -26.078688)
			(xy 373.834928 -26.097717) (xy 373.860512 -26.138868) (xy 373.880687 -26.182924) (xy 373.888254 -26.205942)
			(xy 373.888762 -26.206958) (xy 373.889016 -26.207974) (xy 373.891078 -26.213413) (xy 373.89724 -26.223278)
			(xy 373.901208 -26.227532) (xy 374.836944 -27.163268) (xy 374.854979 -27.182038) (xy 374.885564 -27.224153)
			(xy 374.909195 -27.270529) (xy 374.925292 -27.320027) (xy 374.93346 -27.371432) (xy 374.933972 -27.397456)
			(xy 374.933972 -28.139136) (xy 376.698 -28.139136) (xy 376.702071 -28.083514) (xy 376.714197 -28.029077)
			(xy 376.73412 -27.976986) (xy 376.761416 -27.928351) (xy 376.795502 -27.884208) (xy 376.835651 -27.845499)
			(xy 376.881009 -27.813048) (xy 376.930609 -27.787547) (xy 376.983393 -27.76954) (xy 377.038236 -27.75941)
			(xy 377.09397 -27.757373) (xy 377.149407 -27.763473) (xy 377.203364 -27.777579) (xy 377.254693 -27.799391)
			(xy 377.302299 -27.828445) (xy 377.345167 -27.86412) (xy 377.382384 -27.905657) (xy 377.413157 -27.95217)
			(xy 377.436829 -28.002667) (xy 377.452897 -28.056074) (xy 377.461017 -28.11125) (xy 377.461526 -28.139136)
			(xy 377.968 -28.139136) (xy 377.972071 -28.083514) (xy 377.984197 -28.029077) (xy 378.00412 -27.976986)
			(xy 378.031416 -27.928351) (xy 378.065502 -27.884208) (xy 378.105651 -27.845499) (xy 378.151009 -27.813048)
			(xy 378.200609 -27.787547) (xy 378.253393 -27.76954) (xy 378.308236 -27.75941) (xy 378.36397 -27.757373)
			(xy 378.419407 -27.763473) (xy 378.473364 -27.777579) (xy 378.524693 -27.799391) (xy 378.572299 -27.828445)
			(xy 378.615167 -27.86412) (xy 378.652384 -27.905657) (xy 378.683157 -27.95217) (xy 378.706829 -28.002667)
			(xy 378.722897 -28.056074) (xy 378.731017 -28.11125) (xy 378.731526 -28.139136) (xy 378.731017 -28.167022)
			(xy 378.722897 -28.222198) (xy 378.706829 -28.275605) (xy 378.683157 -28.326102) (xy 378.652384 -28.372615)
			(xy 378.615167 -28.414152) (xy 378.572299 -28.449827) (xy 378.524693 -28.478881) (xy 378.473364 -28.500693)
			(xy 378.419407 -28.514799) (xy 378.36397 -28.520899) (xy 378.308236 -28.518862) (xy 378.253393 -28.508732)
			(xy 378.200609 -28.490725) (xy 378.151009 -28.465224) (xy 378.105651 -28.432773) (xy 378.065502 -28.394064)
			(xy 378.031416 -28.349921) (xy 378.00412 -28.301286) (xy 377.984197 -28.249195) (xy 377.972071 -28.194758)
			(xy 377.968 -28.139136) (xy 377.461526 -28.139136) (xy 377.461017 -28.167022) (xy 377.452897 -28.222198)
			(xy 377.436829 -28.275605) (xy 377.413157 -28.326102) (xy 377.382384 -28.372615) (xy 377.345167 -28.414152)
			(xy 377.302299 -28.449827) (xy 377.254693 -28.478881) (xy 377.203364 -28.500693) (xy 377.149407 -28.514799)
			(xy 377.09397 -28.520899) (xy 377.038236 -28.518862) (xy 376.983393 -28.508732) (xy 376.930609 -28.490725)
			(xy 376.881009 -28.465224) (xy 376.835651 -28.432773) (xy 376.795502 -28.394064) (xy 376.761416 -28.349921)
			(xy 376.73412 -28.301286) (xy 376.714197 -28.249195) (xy 376.702071 -28.194758) (xy 376.698 -28.139136)
			(xy 374.933972 -28.139136) (xy 374.933972 -30.175454) (xy 374.933444 -30.201478) (xy 374.925277 -30.252881)
			(xy 374.909184 -30.302379) (xy 374.885558 -30.348756) (xy 374.865143 -30.376876) (xy 375.188988 -30.376876)
			(xy 375.189528 -30.347959) (xy 375.198248 -30.290788) (xy 375.215499 -30.235588) (xy 375.240887 -30.183625)
			(xy 375.273828 -30.136091) (xy 375.313569 -30.094075) (xy 375.336054 -30.075886) (xy 375.344867 -30.068285)
			(xy 375.355045 -30.047379) (xy 375.355612 -30.035754) (xy 375.355612 -29.955998) (xy 375.355056 -29.944368)
			(xy 375.344879 -29.923459) (xy 375.336054 -29.915866) (xy 375.313545 -29.897706) (xy 375.273813 -29.855678)
			(xy 375.240879 -29.808137) (xy 375.215495 -29.756169) (xy 375.198244 -29.700967) (xy 375.18952 -29.643794)
			(xy 375.188988 -29.614876) (xy 375.189474 -29.587625) (xy 375.19723 -29.533677) (xy 375.212585 -29.481382)
			(xy 375.235227 -29.431805) (xy 375.264693 -29.385955) (xy 375.300384 -29.344764) (xy 375.341575 -29.309073)
			(xy 375.387425 -29.279607) (xy 375.437002 -29.256965) (xy 375.489297 -29.24161) (xy 375.543245 -29.233854)
			(xy 375.597747 -29.233854) (xy 375.651695 -29.24161) (xy 375.70399 -29.256965) (xy 375.753567 -29.279607)
			(xy 375.799417 -29.309073) (xy 375.840608 -29.344764) (xy 375.876299 -29.385955) (xy 375.905765 -29.431805)
			(xy 375.928407 -29.481382) (xy 375.943762 -29.533677) (xy 375.951518 -29.587625) (xy 375.952004 -29.614876)
			(xy 375.951505 -29.643794) (xy 375.942777 -29.700968) (xy 375.925518 -29.756169) (xy 375.900123 -29.808131)
			(xy 375.867174 -29.855664) (xy 375.827427 -29.897678) (xy 375.804938 -29.915866) (xy 375.796146 -29.923487)
			(xy 375.785956 -29.944378) (xy 375.78538 -29.955998) (xy 375.78538 -30.035754) (xy 375.785909 -30.047387)
			(xy 375.796106 -30.068296) (xy 375.804938 -30.075886) (xy 375.827423 -30.094075) (xy 375.867156 -30.136097)
			(xy 375.900094 -30.183632) (xy 375.925482 -30.235594) (xy 375.942738 -30.290791) (xy 375.951468 -30.34796)
			(xy 375.952004 -30.376876) (xy 375.951518 -30.404127) (xy 375.943762 -30.458075) (xy 375.928407 -30.51037)
			(xy 375.905765 -30.559947) (xy 375.876299 -30.605797) (xy 375.840608 -30.646988) (xy 375.799417 -30.682679)
			(xy 375.753567 -30.712145) (xy 375.70399 -30.734787) (xy 375.651695 -30.750142) (xy 375.597747 -30.757898)
			(xy 375.543245 -30.757898) (xy 375.489297 -30.750142) (xy 375.437002 -30.734787) (xy 375.387425 -30.712145)
			(xy 375.341575 -30.682679) (xy 375.300384 -30.646988) (xy 375.264693 -30.605797) (xy 375.235227 -30.559947)
			(xy 375.212585 -30.51037) (xy 375.19723 -30.458075) (xy 375.189474 -30.404127) (xy 375.188988 -30.376876)
			(xy 374.865143 -30.376876) (xy 374.85498 -30.390875) (xy 374.836944 -30.409642) (xy 373.891048 -31.355538)
			(xy 373.888343 -31.35839) (xy 373.883754 -31.36477) (xy 373.881904 -31.368238) (xy 373.87932 -31.373665)
			(xy 373.876495 -31.385344) (xy 373.876316 -31.391352) (xy 373.876316 -31.567882) (xy 375.298714 -31.567882)
			(xy 375.302785 -31.51226) (xy 375.314911 -31.457823) (xy 375.334834 -31.405732) (xy 375.36213 -31.357097)
			(xy 375.396216 -31.312954) (xy 375.436365 -31.274245) (xy 375.481723 -31.241794) (xy 375.531323 -31.216293)
			(xy 375.584107 -31.198286) (xy 375.63895 -31.188156) (xy 375.694684 -31.186119) (xy 375.750121 -31.192219)
			(xy 375.804078 -31.206325) (xy 375.855407 -31.228137) (xy 375.903013 -31.257191) (xy 375.945881 -31.292866)
			(xy 375.983098 -31.334403) (xy 376.013871 -31.380916) (xy 376.037543 -31.431413) (xy 376.053611 -31.48482)
			(xy 376.061731 -31.539996) (xy 376.06224 -31.567882) (xy 376.061731 -31.595768) (xy 376.053611 -31.650944)
			(xy 376.037543 -31.704351) (xy 376.030551 -31.719266) (xy 376.585478 -31.719266) (xy 376.589549 -31.663644)
			(xy 376.601675 -31.609207) (xy 376.621598 -31.557116) (xy 376.648894 -31.508481) (xy 376.68298 -31.464338)
			(xy 376.723129 -31.425629) (xy 376.768487 -31.393178) (xy 376.818087 -31.367677) (xy 376.870871 -31.34967)
			(xy 376.925714 -31.33954) (xy 376.981448 -31.337503) (xy 377.036885 -31.343603) (xy 377.090842 -31.357709)
			(xy 377.142171 -31.379521) (xy 377.189777 -31.408575) (xy 377.232645 -31.44425) (xy 377.269862 -31.485787)
			(xy 377.300635 -31.5323) (xy 377.324307 -31.582797) (xy 377.340375 -31.636204) (xy 377.344525 -31.664402)
			(xy 377.861066 -31.664402) (xy 377.865137 -31.60878) (xy 377.877263 -31.554343) (xy 377.897186 -31.502252)
			(xy 377.924482 -31.453617) (xy 377.958568 -31.409474) (xy 377.998717 -31.370765) (xy 378.044075 -31.338314)
			(xy 378.093675 -31.312813) (xy 378.146459 -31.294806) (xy 378.201302 -31.284676) (xy 378.257036 -31.282639)
			(xy 378.312473 -31.288739) (xy 378.36643 -31.302845) (xy 378.417759 -31.324657) (xy 378.465365 -31.353711)
			(xy 378.508233 -31.389386) (xy 378.54545 -31.430923) (xy 378.576223 -31.477436) (xy 378.599895 -31.527933)
			(xy 378.615963 -31.58134) (xy 378.624083 -31.636516) (xy 378.624592 -31.664402) (xy 378.624083 -31.692288)
			(xy 378.615963 -31.747464) (xy 378.599895 -31.800871) (xy 378.576223 -31.851368) (xy 378.54545 -31.897881)
			(xy 378.508233 -31.939418) (xy 378.465365 -31.975093) (xy 378.417759 -32.004147) (xy 378.36643 -32.025959)
			(xy 378.312473 -32.040065) (xy 378.257036 -32.046165) (xy 378.201302 -32.044128) (xy 378.146459 -32.033998)
			(xy 378.093675 -32.015991) (xy 378.044075 -31.99049) (xy 377.998717 -31.958039) (xy 377.958568 -31.91933)
			(xy 377.924482 -31.875187) (xy 377.897186 -31.826552) (xy 377.877263 -31.774461) (xy 377.865137 -31.720024)
			(xy 377.861066 -31.664402) (xy 377.344525 -31.664402) (xy 377.348495 -31.69138) (xy 377.349004 -31.719266)
			(xy 377.348495 -31.747152) (xy 377.340375 -31.802328) (xy 377.324307 -31.855735) (xy 377.300635 -31.906232)
			(xy 377.269862 -31.952745) (xy 377.232645 -31.994282) (xy 377.189777 -32.029957) (xy 377.142171 -32.059011)
			(xy 377.090842 -32.080823) (xy 377.036885 -32.094929) (xy 376.981448 -32.101029) (xy 376.925714 -32.098992)
			(xy 376.870871 -32.088862) (xy 376.818087 -32.070855) (xy 376.768487 -32.045354) (xy 376.723129 -32.012903)
			(xy 376.68298 -31.974194) (xy 376.648894 -31.930051) (xy 376.621598 -31.881416) (xy 376.601675 -31.829325)
			(xy 376.589549 -31.774888) (xy 376.585478 -31.719266) (xy 376.030551 -31.719266) (xy 376.013871 -31.754848)
			(xy 375.983098 -31.801361) (xy 375.945881 -31.842898) (xy 375.903013 -31.878573) (xy 375.855407 -31.907627)
			(xy 375.804078 -31.929439) (xy 375.750121 -31.943545) (xy 375.694684 -31.949645) (xy 375.63895 -31.947608)
			(xy 375.584107 -31.937478) (xy 375.531323 -31.919471) (xy 375.481723 -31.89397) (xy 375.436365 -31.861519)
			(xy 375.396216 -31.82281) (xy 375.36213 -31.778667) (xy 375.334834 -31.730032) (xy 375.314911 -31.677941)
			(xy 375.302785 -31.623504) (xy 375.298714 -31.567882) (xy 373.876316 -31.567882) (xy 373.876316 -31.992316)
			(xy 373.876636 -32.000833) (xy 373.882211 -32.01693) (xy 373.887238 -32.023812) (xy 377.128135 -35.264852)
			(xy 378.202442 -35.264852) (xy 378.206513 -35.20923) (xy 378.218639 -35.154793) (xy 378.238562 -35.102702)
			(xy 378.265858 -35.054067) (xy 378.299944 -35.009924) (xy 378.340093 -34.971215) (xy 378.385451 -34.938764)
			(xy 378.435051 -34.913263) (xy 378.487835 -34.895256) (xy 378.542678 -34.885126) (xy 378.598412 -34.883089)
			(xy 378.653849 -34.889189) (xy 378.707806 -34.903295) (xy 378.759135 -34.925107) (xy 378.806741 -34.954161)
			(xy 378.849609 -34.989836) (xy 378.886826 -35.031373) (xy 378.917599 -35.077886) (xy 378.941271 -35.128383)
			(xy 378.957339 -35.18179) (xy 378.965459 -35.236966) (xy 378.965968 -35.264852) (xy 378.965459 -35.292738)
			(xy 378.957339 -35.347914) (xy 378.941271 -35.401321) (xy 378.917599 -35.451818) (xy 378.886826 -35.498331)
			(xy 378.849609 -35.539868) (xy 378.806741 -35.575543) (xy 378.759135 -35.604597) (xy 378.707806 -35.626409)
			(xy 378.653849 -35.640515) (xy 378.598412 -35.646615) (xy 378.542678 -35.644578) (xy 378.487835 -35.634448)
			(xy 378.435051 -35.616441) (xy 378.385451 -35.59094) (xy 378.340093 -35.558489) (xy 378.299944 -35.51978)
			(xy 378.265858 -35.475637) (xy 378.238562 -35.427002) (xy 378.218639 -35.374911) (xy 378.206513 -35.320474)
			(xy 378.202442 -35.264852) (xy 377.128135 -35.264852) (xy 378.150186 -36.286948) (xy 379.500382 -36.286948)
			(xy 379.504453 -36.231326) (xy 379.516579 -36.176889) (xy 379.536502 -36.124798) (xy 379.563798 -36.076163)
			(xy 379.597884 -36.03202) (xy 379.638033 -35.993311) (xy 379.683391 -35.96086) (xy 379.732991 -35.935359)
			(xy 379.785775 -35.917352) (xy 379.840618 -35.907222) (xy 379.896352 -35.905185) (xy 379.951789 -35.911285)
			(xy 380.005746 -35.925391) (xy 380.057075 -35.947203) (xy 380.104681 -35.976257) (xy 380.147549 -36.011932)
			(xy 380.184766 -36.053469) (xy 380.215539 -36.099982) (xy 380.239211 -36.150479) (xy 380.255279 -36.203886)
			(xy 380.263399 -36.259062) (xy 380.263908 -36.286948) (xy 380.263399 -36.314834) (xy 380.255279 -36.37001)
			(xy 380.239211 -36.423417) (xy 380.215539 -36.473914) (xy 380.184766 -36.520427) (xy 380.147549 -36.561964)
			(xy 380.104681 -36.597639) (xy 380.057075 -36.626693) (xy 380.005746 -36.648505) (xy 379.951789 -36.662611)
			(xy 379.896352 -36.668711) (xy 379.840618 -36.666674) (xy 379.785775 -36.656544) (xy 379.732991 -36.638537)
			(xy 379.683391 -36.613036) (xy 379.638033 -36.580585) (xy 379.597884 -36.541876) (xy 379.563798 -36.497733)
			(xy 379.536502 -36.449098) (xy 379.516579 -36.397007) (xy 379.504453 -36.34257) (xy 379.500382 -36.286948)
			(xy 378.150186 -36.286948) (xy 379.630178 -37.767006) (xy 379.634825 -37.767521) (xy 379.644159 -37.767017)
			(xy 379.64872 -37.76599) (xy 379.678946 -37.756846) (xy 379.679454 -37.756846) (xy 379.726952 -37.742114)
			(xy 379.735334 -37.73805) (xy 379.745748 -37.729922) (xy 379.7554 -37.719) (xy 379.755908 -37.718492)
			(xy 379.764036 -37.709602) (xy 379.770386 -37.69995) (xy 379.773688 -37.6936) (xy 379.774704 -37.689536)
			(xy 379.775212 -37.686996) (xy 379.782229 -37.65944) (xy 379.803309 -37.606632) (xy 379.831988 -37.557534)
			(xy 379.867631 -37.513231) (xy 379.909449 -37.474704) (xy 379.956519 -37.442805) (xy 380.007798 -37.418238)
			(xy 380.062154 -37.401548) (xy 380.118384 -37.393103) (xy 380.146814 -37.39261) (xy 380.174066 -37.393074)
			(xy 380.228014 -37.400833) (xy 380.280309 -37.41619) (xy 380.329887 -37.438834) (xy 380.375737 -37.468303)
			(xy 380.416926 -37.503997) (xy 380.452617 -37.545189) (xy 380.482081 -37.591042) (xy 380.504721 -37.640621)
			(xy 380.520074 -37.692917) (xy 380.527828 -37.746866) (xy 380.528322 -37.774118) (xy 380.527797 -37.802547)
			(xy 380.519361 -37.858776) (xy 380.502677 -37.913131) (xy 380.478115 -37.96441) (xy 380.446219 -38.011479)
			(xy 380.407694 -38.053296) (xy 380.363392 -38.088936) (xy 380.314294 -38.11761) (xy 380.261486 -38.138684)
			(xy 380.233936 -38.14572) (xy 380.233682 -38.14572) (xy 380.22657 -38.147498) (xy 380.216156 -38.152832)
			(xy 380.209298 -38.158928) (xy 380.209044 -38.159182) (xy 380.20244 -38.165024) (xy 380.201932 -38.165532)
			(xy 380.19101 -38.175184) (xy 380.182882 -38.185598) (xy 380.178818 -38.19398) (xy 380.164086 -38.241478)
			(xy 380.164086 -38.241986) (xy 380.154942 -38.272212) (xy 380.153952 -38.276778) (xy 380.153449 -38.286106)
			(xy 380.153926 -38.290754) (xy 386.222494 -44.359322) (xy 386.228095 -44.363739) (xy 386.241118 -44.369545)
			(xy 386.248148 -44.370752) (xy 386.262573 -44.372278) (xy 386.291267 -44.368116) (xy 386.317636 -44.356062)
			(xy 386.339557 -44.337087) (xy 386.355266 -44.312718) (xy 386.363498 -44.284917) (xy 386.363972 -44.270422)
			(xy 386.363972 -44.213272) (xy 386.363807 -44.207262) (xy 386.360986 -44.195578) (xy 386.358384 -44.190158)
			(xy 386.356543 -44.186685) (xy 386.351946 -44.180309) (xy 386.34924 -44.177458) (xy 381.471424 -39.299642)
			(xy 381.45339 -39.280872) (xy 381.422807 -39.238756) (xy 381.399177 -39.19238) (xy 381.38308 -39.142882)
			(xy 381.374911 -39.091478) (xy 381.374396 -39.065454) (xy 381.374396 -36.741354) (xy 381.372364 -36.727384)
			(xy 381.367284 -36.709096) (xy 381.365252 -36.705286) (xy 381.354584 -36.685982) (xy 381.354584 -36.685474)
			(xy 381.347804 -36.671677) (xy 381.336235 -36.643194) (xy 381.33147 -36.628578) (xy 381.329692 -36.622736)
			(xy 381.323342 -36.612068) (xy 379.828806 -35.117532) (xy 379.810694 -35.098751) (xy 379.780012 -35.056554)
			(xy 379.756316 -35.010072) (xy 379.740189 -34.960454) (xy 379.73203 -34.908923) (xy 379.731524 -34.882836)
			(xy 379.731524 -32.410654) (xy 379.727206 -32.405574) (xy 379.674628 -32.362394) (xy 379.663452 -32.35325)
			(xy 379.660594 -32.350958) (xy 379.654346 -32.347135) (xy 379.651006 -32.34563) (xy 379.629924 -32.350202)
			(xy 379.599866 -32.356212) (xy 379.538908 -32.362699) (xy 379.508258 -32.363156) (xy 379.472847 -32.362619)
			(xy 379.402543 -32.354078) (xy 379.333781 -32.337124) (xy 379.267563 -32.312006) (xy 379.204856 -32.27909)
			(xy 379.146573 -32.238856) (xy 379.093565 -32.191889) (xy 379.046605 -32.138876) (xy 379.006377 -32.080589)
			(xy 378.973467 -32.017879) (xy 378.948357 -31.951658) (xy 378.931411 -31.882894) (xy 378.922877 -31.812589)
			(xy 378.92228 -31.777178) (xy 378.92228 -30.776164) (xy 378.919864 -30.773071) (xy 378.914253 -30.767584)
			(xy 378.911104 -30.765242) (xy 378.876306 -30.743906) (xy 378.838714 -30.720792) (xy 378.8283 -30.715966)
			(xy 378.826014 -30.715204) (xy 378.816765 -30.712962) (xy 378.797835 -30.714793) (xy 378.789184 -30.71876)
			(xy 378.78893 -30.71876) (xy 378.778262 -30.724094) (xy 378.752033 -30.736186) (xy 378.696858 -30.753259)
			(xy 378.639754 -30.761913) (xy 378.610876 -30.762448) (xy 378.610622 -30.762448) (xy 378.583078 -30.761981)
			(xy 378.528552 -30.754144) (xy 378.475695 -30.738626) (xy 378.425586 -30.715743) (xy 378.379243 -30.685962)
			(xy 378.337611 -30.649887) (xy 378.301537 -30.608255) (xy 378.271756 -30.561912) (xy 378.248873 -30.511803)
			(xy 378.233355 -30.458946) (xy 378.225519 -30.40442) (xy 378.22505 -30.376876) (xy 378.225573 -30.347906)
			(xy 378.234249 -30.29062) (xy 378.251401 -30.235277) (xy 378.276643 -30.183125) (xy 378.309407 -30.135338)
			(xy 378.348954 -30.092994) (xy 378.371354 -30.074616) (xy 378.375725 -30.070962) (xy 378.382911 -30.062124)
			(xy 378.385578 -30.05709) (xy 378.39015 -30.047692) (xy 378.390404 -30.047184) (xy 378.392867 -30.041859)
			(xy 378.395566 -30.030443) (xy 378.395738 -30.024578) (xy 378.395738 -29.967682) (xy 378.395596 -29.962242)
			(xy 378.393288 -29.951611) (xy 378.391166 -29.9466) (xy 378.387864 -29.939742) (xy 378.387864 -29.939234)
			(xy 378.381006 -29.925518) (xy 378.372624 -29.914088) (xy 378.367798 -29.909262) (xy 378.36602 -29.907738)
			(xy 378.344995 -29.889499) (xy 378.307934 -29.847972) (xy 378.277295 -29.801505) (xy 378.253726 -29.751083)
			(xy 378.237726 -29.697773) (xy 378.229635 -29.642705) (xy 378.229114 -29.614876) (xy 378.229602 -29.587626)
			(xy 378.237361 -29.533683) (xy 378.252719 -29.481392) (xy 378.275362 -29.431819) (xy 378.304829 -29.385974)
			(xy 378.340521 -29.344788) (xy 378.38171 -29.309101) (xy 378.42756 -29.279639) (xy 378.477135 -29.257003)
			(xy 378.529428 -29.241652) (xy 378.583372 -29.233899) (xy 378.610622 -29.233368) (xy 378.63605 -29.23379)
			(xy 378.686454 -29.240549) (xy 378.735514 -29.253944) (xy 378.78236 -29.273738) (xy 378.826161 -29.299581)
			(xy 378.86614 -29.331013) (xy 378.88418 -29.348938) (xy 378.891038 -29.35605) (xy 378.926598 -29.371798)
			(xy 378.941076 -29.37129) (xy 378.949748 -29.370245) (xy 378.965668 -29.363092) (xy 378.978248 -29.350993)
			(xy 378.982478 -29.34335) (xy 378.982732 -29.342842) (xy 378.99725 -29.314309) (xy 379.031613 -29.260291)
			(xy 379.071662 -29.210343) (xy 379.093984 -29.187394) (xy 381.534924 -26.746454) (xy 381.538226 -26.74239)
			(xy 381.542357 -26.735879) (xy 381.546874 -26.721142) (xy 381.547116 -26.713434) (xy 381.547116 -24.158194)
			(xy 381.547611 -24.124108) (xy 381.555526 -24.056398) (xy 381.571247 -23.990064) (xy 381.594563 -23.926004)
			(xy 381.625158 -23.865084) (xy 381.662619 -23.808127) (xy 381.706439 -23.755905) (xy 381.756025 -23.709123)
			(xy 381.810707 -23.668414) (xy 381.869745 -23.634328) (xy 381.932341 -23.607327) (xy 381.997648 -23.587775)
			(xy 382.064784 -23.575937) (xy 382.13284 -23.571974) (xy 382.200896 -23.575937) (xy 382.268032 -23.587775)
			(xy 382.333339 -23.607327) (xy 382.395935 -23.634328) (xy 382.454973 -23.668414) (xy 382.509655 -23.709123)
			(xy 382.559241 -23.755905) (xy 382.603061 -23.808127) (xy 382.640522 -23.865084) (xy 382.671117 -23.926004)
			(xy 382.694433 -23.990064) (xy 382.710154 -24.056398) (xy 382.718069 -24.124108) (xy 382.718564 -24.158194)
			(xy 382.718564 -24.807418) (xy 382.920238 -24.807418) (xy 382.924309 -24.751796) (xy 382.936435 -24.697359)
			(xy 382.956358 -24.645268) (xy 382.983654 -24.596633) (xy 383.01774 -24.55249) (xy 383.057889 -24.513781)
			(xy 383.103247 -24.48133) (xy 383.152847 -24.455829) (xy 383.205631 -24.437822) (xy 383.260474 -24.427692)
			(xy 383.316208 -24.425655) (xy 383.371645 -24.431755) (xy 383.425602 -24.445861) (xy 383.476931 -24.467673)
			(xy 383.524537 -24.496727) (xy 383.567405 -24.532402) (xy 383.604622 -24.573939) (xy 383.635395 -24.620452)
			(xy 383.659067 -24.670949) (xy 383.675135 -24.724356) (xy 383.683255 -24.779532) (xy 383.683764 -24.807418)
			(xy 383.683255 -24.835304) (xy 383.675135 -24.89048) (xy 383.659067 -24.943887) (xy 383.635395 -24.994384)
			(xy 383.604622 -25.040897) (xy 383.567405 -25.082434) (xy 383.524537 -25.118109) (xy 383.476931 -25.147163)
			(xy 383.425602 -25.168975) (xy 383.371645 -25.183081) (xy 383.316208 -25.189181) (xy 383.260474 -25.187144)
			(xy 383.205631 -25.177014) (xy 383.152847 -25.159007) (xy 383.103247 -25.133506) (xy 383.057889 -25.101055)
			(xy 383.01774 -25.062346) (xy 382.983654 -25.018203) (xy 382.956358 -24.969568) (xy 382.936435 -24.917477)
			(xy 382.924309 -24.86304) (xy 382.920238 -24.807418) (xy 382.718564 -24.807418) (xy 382.718564 -26.724356)
			(xy 382.72339 -26.729944) (xy 382.728978 -26.734516) (xy 383.038096 -26.734516) (xy 383.043885 -26.73439)
			(xy 383.055174 -26.731826) (xy 383.060448 -26.729436) (xy 383.064766 -26.72715) (xy 383.065528 -26.726642)
			(xy 383.080006 -26.708608) (xy 383.08661 -26.697686) (xy 383.088896 -26.69286) (xy 383.0828 -26.665682)
			(xy 383.082292 -26.663396) (xy 383.080796 -26.657704) (xy 383.075538 -26.647177) (xy 383.071878 -26.642568)
			(xy 383.054098 -26.620724) (xy 383.046478 -26.614628) (xy 383.040382 -26.611834) (xy 383.016116 -26.599945)
			(xy 382.970911 -26.570344) (xy 382.930334 -26.534661) (xy 382.895196 -26.493611) (xy 382.8662 -26.448015)
			(xy 382.843927 -26.398784) (xy 382.828821 -26.346904) (xy 382.821185 -26.293411) (xy 382.820672 -26.266394)
			(xy 382.821158 -26.239143) (xy 382.828914 -26.185195) (xy 382.844269 -26.1329) (xy 382.866911 -26.083323)
			(xy 382.896377 -26.037473) (xy 382.932068 -25.996282) (xy 382.973259 -25.960591) (xy 383.019109 -25.931125)
			(xy 383.068686 -25.908483) (xy 383.120981 -25.893128) (xy 383.174929 -25.885372) (xy 383.229431 -25.885372)
			(xy 383.283379 -25.893128) (xy 383.335674 -25.908483) (xy 383.385251 -25.931125) (xy 383.431101 -25.960591)
			(xy 383.472292 -25.996282) (xy 383.507983 -26.037473) (xy 383.537449 -26.083323) (xy 383.560091 -26.1329)
			(xy 383.575446 -26.185195) (xy 383.583202 -26.239143) (xy 383.583688 -26.266394) (xy 383.583154 -26.295311)
			(xy 383.574428 -26.352482) (xy 383.557174 -26.407682) (xy 383.531788 -26.459646) (xy 383.498851 -26.507184)
			(xy 383.459118 -26.549208) (xy 383.436622 -26.567384) (xy 383.43205 -26.57094) (xy 383.422652 -26.582624)
			(xy 383.417315 -26.589602) (xy 383.411327 -26.606105) (xy 383.410968 -26.614882) (xy 383.410968 -26.617422)
			(xy 383.412492 -26.648156) (xy 383.412492 -26.648664) (xy 383.415032 -26.688034) (xy 383.415286 -26.690828)
			(xy 383.416032 -26.695979) (xy 383.419361 -26.705837) (xy 383.42189 -26.710386) (xy 383.425954 -26.717244)
			(xy 383.431034 -26.725372) (xy 383.4384 -26.73477) (xy 383.443988 -26.740358) (xy 383.44856 -26.743152)
			(xy 383.471482 -26.758334) (xy 383.513137 -26.794217) (xy 383.549241 -26.83568) (xy 383.579055 -26.881874)
			(xy 383.601967 -26.931851) (xy 383.617508 -26.984588) (xy 383.62536 -27.039004) (xy 383.625852 -27.066494)
			(xy 383.625387 -27.093873) (xy 383.617594 -27.148074) (xy 383.602167 -27.200615) (xy 383.579419 -27.250425)
			(xy 383.549813 -27.29649) (xy 383.513953 -27.337872) (xy 383.472567 -27.37373) (xy 383.4265 -27.403332)
			(xy 383.376689 -27.426077) (xy 383.324147 -27.4415) (xy 383.269945 -27.449289) (xy 383.242566 -27.44978)
			(xy 383.242312 -27.44978) (xy 383.211432 -27.449133) (xy 383.150477 -27.439191) (xy 383.091897 -27.419625)
			(xy 383.064258 -27.405838) (xy 383.061718 -27.404568) (xy 383.043938 -27.399996) (xy 383.031492 -27.398472)
			(xy 382.87833 -27.398472) (xy 382.873504 -27.403552) (xy 382.871726 -27.405076) (xy 382.870456 -27.406092)
			(xy 381.154178 -29.12237) (xy 382.907032 -29.12237) (xy 382.907032 -28.25877) (xy 382.907522 -28.228802)
			(xy 382.915345 -28.16938) (xy 382.930858 -28.111487) (xy 382.953794 -28.056114) (xy 382.983761 -28.004208)
			(xy 383.020248 -27.956658) (xy 383.062628 -27.914278) (xy 383.110178 -27.877791) (xy 383.162084 -27.847824)
			(xy 383.217457 -27.824888) (xy 383.27535 -27.809375) (xy 383.334772 -27.801552) (xy 383.394708 -27.801552)
			(xy 383.45413 -27.809375) (xy 383.512023 -27.824888) (xy 383.567396 -27.847824) (xy 383.619302 -27.877791)
			(xy 383.666852 -27.914278) (xy 383.709232 -27.956658) (xy 383.745719 -28.004208) (xy 383.775686 -28.056114)
			(xy 383.798622 -28.111487) (xy 383.814135 -28.16938) (xy 383.821958 -28.228802) (xy 383.822448 -28.25877)
			(xy 383.822448 -29.114242) (xy 393.147296 -29.114242) (xy 393.147296 -28.250642) (xy 393.147786 -28.220658)
			(xy 393.155614 -28.161202) (xy 393.171135 -28.103277) (xy 393.194084 -28.047873) (xy 393.224068 -27.995939)
			(xy 393.260574 -27.948363) (xy 393.302979 -27.905958) (xy 393.350555 -27.869452) (xy 393.402489 -27.839468)
			(xy 393.457893 -27.816519) (xy 393.515818 -27.800998) (xy 393.575274 -27.79317) (xy 393.635242 -27.79317)
			(xy 393.694698 -27.800998) (xy 393.752623 -27.816519) (xy 393.808027 -27.839468) (xy 393.859961 -27.869452)
			(xy 393.907537 -27.905958) (xy 393.949942 -27.948363) (xy 393.986448 -27.995939) (xy 394.016432 -28.047873)
			(xy 394.039381 -28.103277) (xy 394.054902 -28.161202) (xy 394.06273 -28.220658) (xy 394.06322 -28.250642)
			(xy 394.06322 -29.114242) (xy 394.06273 -29.144226) (xy 394.054902 -29.203682) (xy 394.039381 -29.261607)
			(xy 394.016432 -29.317011) (xy 393.986448 -29.368945) (xy 393.949942 -29.416521) (xy 393.907537 -29.458926)
			(xy 393.859961 -29.495432) (xy 393.808027 -29.525416) (xy 393.752623 -29.548365) (xy 393.694698 -29.563886)
			(xy 393.635242 -29.571714) (xy 393.575274 -29.571714) (xy 393.515818 -29.563886) (xy 393.457893 -29.548365)
			(xy 393.402489 -29.525416) (xy 393.350555 -29.495432) (xy 393.302979 -29.458926) (xy 393.260574 -29.416521)
			(xy 393.224068 -29.368945) (xy 393.194084 -29.317011) (xy 393.171135 -29.261607) (xy 393.155614 -29.203682)
			(xy 393.147786 -29.144226) (xy 393.147296 -29.114242) (xy 383.822448 -29.114242) (xy 383.822448 -29.12237)
			(xy 383.821958 -29.152338) (xy 383.814135 -29.21176) (xy 383.798622 -29.269653) (xy 383.775686 -29.325026)
			(xy 383.745719 -29.376932) (xy 383.709232 -29.424482) (xy 383.666852 -29.466862) (xy 383.619302 -29.503349)
			(xy 383.567396 -29.533316) (xy 383.512023 -29.556252) (xy 383.45413 -29.571765) (xy 383.394708 -29.579588)
			(xy 383.334772 -29.579588) (xy 383.27535 -29.571765) (xy 383.217457 -29.556252) (xy 383.162084 -29.533316)
			(xy 383.110178 -29.503349) (xy 383.062628 -29.466862) (xy 383.020248 -29.424482) (xy 382.983761 -29.376932)
			(xy 382.953794 -29.325026) (xy 382.930858 -29.269653) (xy 382.915345 -29.21176) (xy 382.907522 -29.152338)
			(xy 382.907032 -29.12237) (xy 381.154178 -29.12237) (xy 380.397258 -29.87929) (xy 380.39548 -29.881576)
			(xy 380.39548 -30.922468) (xy 381.052832 -30.922468) (xy 381.052832 -30.058868) (xy 381.053322 -30.0289)
			(xy 381.061145 -29.969478) (xy 381.076658 -29.911585) (xy 381.099594 -29.856212) (xy 381.129561 -29.804306)
			(xy 381.166048 -29.756756) (xy 381.208428 -29.714376) (xy 381.255978 -29.677889) (xy 381.307884 -29.647922)
			(xy 381.363257 -29.624986) (xy 381.42115 -29.609473) (xy 381.480572 -29.60165) (xy 381.540508 -29.60165)
			(xy 381.59993 -29.609473) (xy 381.657823 -29.624986) (xy 381.713196 -29.647922) (xy 381.765102 -29.677889)
			(xy 381.812652 -29.714376) (xy 381.855032 -29.756756) (xy 381.891519 -29.804306) (xy 381.921486 -29.856212)
			(xy 381.944422 -29.911585) (xy 381.959935 -29.969478) (xy 381.967758 -30.0289) (xy 381.968248 -30.058868)
			(xy 381.968248 -30.92069) (xy 395.789404 -30.92069) (xy 395.789404 -30.05709) (xy 395.789894 -30.027106)
			(xy 395.797722 -29.96765) (xy 395.813243 -29.909725) (xy 395.836192 -29.854321) (xy 395.866176 -29.802387)
			(xy 395.902682 -29.754811) (xy 395.945087 -29.712406) (xy 395.992663 -29.6759) (xy 396.044597 -29.645916)
			(xy 396.100001 -29.622967) (xy 396.157926 -29.607446) (xy 396.217382 -29.599618) (xy 396.27735 -29.599618)
			(xy 396.336806 -29.607446) (xy 396.394731 -29.622967) (xy 396.450135 -29.645916) (xy 396.502069 -29.6759)
			(xy 396.549645 -29.712406) (xy 396.59205 -29.754811) (xy 396.628556 -29.802387) (xy 396.65854 -29.854321)
			(xy 396.681489 -29.909725) (xy 396.69701 -29.96765) (xy 396.704838 -30.027106) (xy 396.705328 -30.05709)
			(xy 396.705328 -30.92069) (xy 396.704838 -30.950674) (xy 396.69701 -31.01013) (xy 396.681489 -31.068055)
			(xy 396.65854 -31.123459) (xy 396.628556 -31.175393) (xy 396.59205 -31.222969) (xy 396.549645 -31.265374)
			(xy 396.502069 -31.30188) (xy 396.450135 -31.331864) (xy 396.394731 -31.354813) (xy 396.336806 -31.370334)
			(xy 396.27735 -31.378162) (xy 396.217382 -31.378162) (xy 396.157926 -31.370334) (xy 396.100001 -31.354813)
			(xy 396.044597 -31.331864) (xy 395.992663 -31.30188) (xy 395.945087 -31.265374) (xy 395.902682 -31.222969)
			(xy 395.866176 -31.175393) (xy 395.836192 -31.123459) (xy 395.813243 -31.068055) (xy 395.797722 -31.01013)
			(xy 395.789894 -30.950674) (xy 395.789404 -30.92069) (xy 381.968248 -30.92069) (xy 381.968248 -30.922468)
			(xy 381.967758 -30.952436) (xy 381.959935 -31.011858) (xy 381.944422 -31.069751) (xy 381.921486 -31.125124)
			(xy 381.891519 -31.17703) (xy 381.855032 -31.22458) (xy 381.812652 -31.26696) (xy 381.765102 -31.303447)
			(xy 381.713196 -31.333414) (xy 381.657823 -31.35635) (xy 381.59993 -31.371863) (xy 381.540508 -31.379686)
			(xy 381.480572 -31.379686) (xy 381.42115 -31.371863) (xy 381.363257 -31.35635) (xy 381.307884 -31.333414)
			(xy 381.255978 -31.303447) (xy 381.208428 -31.26696) (xy 381.166048 -31.22458) (xy 381.129561 -31.17703)
			(xy 381.099594 -31.125124) (xy 381.076658 -31.069751) (xy 381.061145 -31.011858) (xy 381.053322 -30.952436)
			(xy 381.052832 -30.922468) (xy 380.39548 -30.922468) (xy 380.39548 -32.722312) (xy 382.907032 -32.722312)
			(xy 382.907032 -31.858712) (xy 382.907522 -31.828744) (xy 382.915345 -31.769322) (xy 382.930858 -31.711429)
			(xy 382.953794 -31.656056) (xy 382.983761 -31.60415) (xy 383.020248 -31.5566) (xy 383.062628 -31.51422)
			(xy 383.110178 -31.477733) (xy 383.162084 -31.447766) (xy 383.217457 -31.42483) (xy 383.27535 -31.409317)
			(xy 383.334772 -31.401494) (xy 383.394708 -31.401494) (xy 383.45413 -31.409317) (xy 383.512023 -31.42483)
			(xy 383.567396 -31.447766) (xy 383.619302 -31.477733) (xy 383.666852 -31.51422) (xy 383.709232 -31.5566)
			(xy 383.745719 -31.60415) (xy 383.775686 -31.656056) (xy 383.798622 -31.711429) (xy 383.814135 -31.769322)
			(xy 383.821958 -31.828744) (xy 383.822448 -31.858712) (xy 383.822448 -32.714184) (xy 393.147296 -32.714184)
			(xy 393.147296 -31.850584) (xy 393.147786 -31.8206) (xy 393.155614 -31.761144) (xy 393.171135 -31.703219)
			(xy 393.194084 -31.647815) (xy 393.224068 -31.595881) (xy 393.260574 -31.548305) (xy 393.302979 -31.5059)
			(xy 393.350555 -31.469394) (xy 393.402489 -31.43941) (xy 393.457893 -31.416461) (xy 393.515818 -31.40094)
			(xy 393.575274 -31.393112) (xy 393.635242 -31.393112) (xy 393.694698 -31.40094) (xy 393.752623 -31.416461)
			(xy 393.808027 -31.43941) (xy 393.859961 -31.469394) (xy 393.907537 -31.5059) (xy 393.949942 -31.548305)
			(xy 393.986448 -31.595881) (xy 394.016432 -31.647815) (xy 394.039381 -31.703219) (xy 394.054902 -31.761144)
			(xy 394.06273 -31.8206) (xy 394.06322 -31.850584) (xy 394.06322 -32.714184) (xy 394.06273 -32.744168)
			(xy 394.054902 -32.803624) (xy 394.039381 -32.861549) (xy 394.016432 -32.916953) (xy 393.986448 -32.968887)
			(xy 393.949942 -33.016463) (xy 393.907537 -33.058868) (xy 393.859961 -33.095374) (xy 393.808027 -33.125358)
			(xy 393.752623 -33.148307) (xy 393.694698 -33.163828) (xy 393.635242 -33.171656) (xy 393.575274 -33.171656)
			(xy 393.515818 -33.163828) (xy 393.457893 -33.148307) (xy 393.402489 -33.125358) (xy 393.350555 -33.095374)
			(xy 393.302979 -33.058868) (xy 393.260574 -33.016463) (xy 393.224068 -32.968887) (xy 393.194084 -32.916953)
			(xy 393.171135 -32.861549) (xy 393.155614 -32.803624) (xy 393.147786 -32.744168) (xy 393.147296 -32.714184)
			(xy 383.822448 -32.714184) (xy 383.822448 -32.722312) (xy 383.821958 -32.75228) (xy 383.814135 -32.811702)
			(xy 383.798622 -32.869595) (xy 383.775686 -32.924968) (xy 383.745719 -32.976874) (xy 383.709232 -33.024424)
			(xy 383.666852 -33.066804) (xy 383.619302 -33.103291) (xy 383.567396 -33.133258) (xy 383.512023 -33.156194)
			(xy 383.45413 -33.171707) (xy 383.394708 -33.17953) (xy 383.334772 -33.17953) (xy 383.27535 -33.171707)
			(xy 383.217457 -33.156194) (xy 383.162084 -33.133258) (xy 383.110178 -33.103291) (xy 383.062628 -33.066804)
			(xy 383.020248 -33.024424) (xy 382.983761 -32.976874) (xy 382.953794 -32.924968) (xy 382.930858 -32.869595)
			(xy 382.915345 -32.811702) (xy 382.907522 -32.75228) (xy 382.907032 -32.722312) (xy 380.39548 -32.722312)
			(xy 380.39548 -34.52241) (xy 381.052832 -34.52241) (xy 381.052832 -33.65881) (xy 381.053322 -33.628842)
			(xy 381.061145 -33.56942) (xy 381.076658 -33.511527) (xy 381.099594 -33.456154) (xy 381.129561 -33.404248)
			(xy 381.166048 -33.356698) (xy 381.208428 -33.314318) (xy 381.255978 -33.277831) (xy 381.307884 -33.247864)
			(xy 381.363257 -33.224928) (xy 381.42115 -33.209415) (xy 381.480572 -33.201592) (xy 381.540508 -33.201592)
			(xy 381.59993 -33.209415) (xy 381.657823 -33.224928) (xy 381.713196 -33.247864) (xy 381.765102 -33.277831)
			(xy 381.812652 -33.314318) (xy 381.855032 -33.356698) (xy 381.891519 -33.404248) (xy 381.921486 -33.456154)
			(xy 381.944422 -33.511527) (xy 381.959935 -33.56942) (xy 381.967758 -33.628842) (xy 381.968248 -33.65881)
			(xy 381.968248 -34.520886) (xy 395.789404 -34.520886) (xy 395.789404 -33.657286) (xy 395.789894 -33.627302)
			(xy 395.797722 -33.567846) (xy 395.813243 -33.509921) (xy 395.836192 -33.454517) (xy 395.866176 -33.402583)
			(xy 395.902682 -33.355007) (xy 395.945087 -33.312602) (xy 395.992663 -33.276096) (xy 396.044597 -33.246112)
			(xy 396.100001 -33.223163) (xy 396.157926 -33.207642) (xy 396.217382 -33.199814) (xy 396.27735 -33.199814)
			(xy 396.336806 -33.207642) (xy 396.394731 -33.223163) (xy 396.450135 -33.246112) (xy 396.502069 -33.276096)
			(xy 396.549645 -33.312602) (xy 396.59205 -33.355007) (xy 396.628556 -33.402583) (xy 396.65854 -33.454517)
			(xy 396.681489 -33.509921) (xy 396.69701 -33.567846) (xy 396.704838 -33.627302) (xy 396.705328 -33.657286)
			(xy 396.705328 -34.520886) (xy 396.704838 -34.55087) (xy 396.69701 -34.610326) (xy 396.681489 -34.668251)
			(xy 396.65854 -34.723655) (xy 396.628556 -34.775589) (xy 396.59205 -34.823165) (xy 396.549645 -34.86557)
			(xy 396.502069 -34.902076) (xy 396.450135 -34.93206) (xy 396.394731 -34.955009) (xy 396.336806 -34.97053)
			(xy 396.27735 -34.978358) (xy 396.217382 -34.978358) (xy 396.157926 -34.97053) (xy 396.100001 -34.955009)
			(xy 396.044597 -34.93206) (xy 395.992663 -34.902076) (xy 395.945087 -34.86557) (xy 395.902682 -34.823165)
			(xy 395.866176 -34.775589) (xy 395.836192 -34.723655) (xy 395.813243 -34.668251) (xy 395.797722 -34.610326)
			(xy 395.789894 -34.55087) (xy 395.789404 -34.520886) (xy 381.968248 -34.520886) (xy 381.968248 -34.52241)
			(xy 381.967758 -34.552378) (xy 381.959935 -34.6118) (xy 381.944422 -34.669693) (xy 381.921486 -34.725066)
			(xy 381.891519 -34.776972) (xy 381.855032 -34.824522) (xy 381.812652 -34.866902) (xy 381.765102 -34.903389)
			(xy 381.713196 -34.933356) (xy 381.657823 -34.956292) (xy 381.59993 -34.971805) (xy 381.540508 -34.979628)
			(xy 381.480572 -34.979628) (xy 381.42115 -34.971805) (xy 381.363257 -34.956292) (xy 381.307884 -34.933356)
			(xy 381.255978 -34.903389) (xy 381.208428 -34.866902) (xy 381.166048 -34.824522) (xy 381.129561 -34.776972)
			(xy 381.099594 -34.725066) (xy 381.076658 -34.669693) (xy 381.061145 -34.6118) (xy 381.053322 -34.552378)
			(xy 381.052832 -34.52241) (xy 380.39548 -34.52241) (xy 380.39548 -34.72434) (xy 380.396496 -34.733992)
			(xy 380.398127 -34.741234) (xy 380.404973 -34.754399) (xy 380.409958 -34.7599) (xy 381.79756 -36.147502)
			(xy 381.804164 -36.149534) (xy 381.829974 -36.157635) (xy 381.87918 -36.18011) (xy 381.924717 -36.209312)
			(xy 381.965671 -36.244654) (xy 382.001222 -36.285428) (xy 382.030654 -36.330815) (xy 382.053379 -36.379906)
			(xy 382.068941 -36.431715) (xy 382.077026 -36.485203) (xy 382.077722 -36.512246) (xy 382.077722 -36.519104)
			(xy 382.077144 -36.543004) (xy 382.070779 -36.590388) (xy 382.068362 -36.60013) (xy 386.298193 -36.60013)
			(xy 386.302198 -36.512222) (xy 386.314181 -36.425042) (xy 386.334041 -36.339313) (xy 386.361616 -36.255745)
			(xy 386.396675 -36.175031) (xy 386.438928 -36.097839) (xy 386.488026 -36.02481) (xy 386.543562 -35.956548)
			(xy 386.605074 -35.893618) (xy 386.672055 -35.836544) (xy 386.743948 -35.785796) (xy 386.820157 -35.741796)
			(xy 386.900052 -35.704909) (xy 386.982971 -35.67544) (xy 387.068226 -35.653633) (xy 387.15511 -35.639669)
			(xy 387.242904 -35.633663) (xy 387.330881 -35.635667) (xy 387.418311 -35.645662) (xy 387.50447 -35.663566)
			(xy 387.588644 -35.68923) (xy 387.670135 -35.722443) (xy 387.748269 -35.762929) (xy 387.822397 -35.810351)
			(xy 387.891905 -35.864318) (xy 387.905204 -35.876738) (xy 393.017246 -35.876738) (xy 393.021317 -35.821116)
			(xy 393.033443 -35.766679) (xy 393.053366 -35.714588) (xy 393.080662 -35.665953) (xy 393.114748 -35.62181)
			(xy 393.154897 -35.583101) (xy 393.200255 -35.55065) (xy 393.249855 -35.525149) (xy 393.302639 -35.507142)
			(xy 393.357482 -35.497012) (xy 393.413216 -35.494975) (xy 393.468653 -35.501075) (xy 393.52261 -35.515181)
			(xy 393.573939 -35.536993) (xy 393.621545 -35.566047) (xy 393.664413 -35.601722) (xy 393.70163 -35.643259)
			(xy 393.732403 -35.689772) (xy 393.756075 -35.740269) (xy 393.772143 -35.793676) (xy 393.780263 -35.848852)
			(xy 393.780772 -35.876738) (xy 393.780263 -35.904624) (xy 393.772143 -35.9598) (xy 393.756075 -36.013207)
			(xy 393.732403 -36.063704) (xy 393.70163 -36.110217) (xy 393.664413 -36.151754) (xy 393.621545 -36.187429)
			(xy 393.573939 -36.216483) (xy 393.52261 -36.238295) (xy 393.468653 -36.252401) (xy 393.413216 -36.258501)
			(xy 393.357482 -36.256464) (xy 393.302639 -36.246334) (xy 393.249855 -36.228327) (xy 393.200255 -36.202826)
			(xy 393.154897 -36.170375) (xy 393.114748 -36.131666) (xy 393.080662 -36.087523) (xy 393.053366 -36.038888)
			(xy 393.033443 -35.986797) (xy 393.021317 -35.93236) (xy 393.017246 -35.876738) (xy 387.905204 -35.876738)
			(xy 387.956219 -35.924383) (xy 388.014803 -35.990047) (xy 388.067174 -36.060766) (xy 388.112897 -36.135954)
			(xy 388.151594 -36.214989) (xy 388.182943 -36.297215) (xy 388.206685 -36.381951) (xy 388.222623 -36.468495)
			(xy 388.226409 -36.50996) (xy 394.913864 -36.50996) (xy 394.917935 -36.454338) (xy 394.930061 -36.399901)
			(xy 394.949984 -36.34781) (xy 394.97728 -36.299175) (xy 395.011366 -36.255032) (xy 395.051515 -36.216323)
			(xy 395.096873 -36.183872) (xy 395.146473 -36.158371) (xy 395.199257 -36.140364) (xy 395.2541 -36.130234)
			(xy 395.309834 -36.128197) (xy 395.365271 -36.134297) (xy 395.419228 -36.148403) (xy 395.470557 -36.170215)
			(xy 395.518163 -36.199269) (xy 395.561031 -36.234944) (xy 395.598248 -36.276481) (xy 395.629021 -36.322994)
			(xy 395.652693 -36.373491) (xy 395.668761 -36.426898) (xy 395.676881 -36.482074) (xy 395.67739 -36.50996)
			(xy 395.676881 -36.537846) (xy 395.668761 -36.593022) (xy 395.652693 -36.646429) (xy 395.629021 -36.696926)
			(xy 395.598248 -36.743439) (xy 395.561031 -36.784976) (xy 395.518163 -36.820651) (xy 395.470557 -36.849705)
			(xy 395.419228 -36.871517) (xy 395.365271 -36.885623) (xy 395.309834 -36.891723) (xy 395.2541 -36.889686)
			(xy 395.199257 -36.879556) (xy 395.146473 -36.861549) (xy 395.096873 -36.836048) (xy 395.051515 -36.803597)
			(xy 395.011366 -36.764888) (xy 394.97728 -36.720745) (xy 394.949984 -36.67211) (xy 394.930061 -36.620019)
			(xy 394.917935 -36.565582) (xy 394.913864 -36.50996) (xy 388.226409 -36.50996) (xy 388.230625 -36.55613)
			(xy 388.231126 -36.60013) (xy 388.230625 -36.64413) (xy 388.222623 -36.731765) (xy 388.206685 -36.818309)
			(xy 388.182943 -36.903045) (xy 388.151594 -36.985271) (xy 388.112897 -37.064306) (xy 388.067174 -37.139494)
			(xy 388.014803 -37.210213) (xy 387.956219 -37.275877) (xy 387.891905 -37.335942) (xy 387.822397 -37.389909)
			(xy 387.748269 -37.437331) (xy 387.675263 -37.47516) (xy 392.059158 -37.47516) (xy 392.063229 -37.419538)
			(xy 392.075355 -37.365101) (xy 392.095278 -37.31301) (xy 392.122574 -37.264375) (xy 392.15666 -37.220232)
			(xy 392.196809 -37.181523) (xy 392.242167 -37.149072) (xy 392.291767 -37.123571) (xy 392.344551 -37.105564)
			(xy 392.399394 -37.095434) (xy 392.455128 -37.093397) (xy 392.510565 -37.099497) (xy 392.564522 -37.113603)
			(xy 392.615851 -37.135415) (xy 392.663457 -37.164469) (xy 392.706325 -37.200144) (xy 392.743542 -37.241681)
			(xy 392.774315 -37.288194) (xy 392.797987 -37.338691) (xy 392.814055 -37.392098) (xy 392.822175 -37.447274)
			(xy 392.822684 -37.47516) (xy 392.822175 -37.503046) (xy 392.814055 -37.558222) (xy 392.797987 -37.611629)
			(xy 392.774315 -37.662126) (xy 392.774162 -37.662358) (xy 394.248384 -37.662358) (xy 394.252455 -37.606736)
			(xy 394.264581 -37.552299) (xy 394.284504 -37.500208) (xy 394.3118 -37.451573) (xy 394.345886 -37.40743)
			(xy 394.386035 -37.368721) (xy 394.431393 -37.33627) (xy 394.480993 -37.310769) (xy 394.533777 -37.292762)
			(xy 394.58862 -37.282632) (xy 394.644354 -37.280595) (xy 394.699791 -37.286695) (xy 394.753748 -37.300801)
			(xy 394.805077 -37.322613) (xy 394.852683 -37.351667) (xy 394.895551 -37.387342) (xy 394.932768 -37.428879)
			(xy 394.963541 -37.475392) (xy 394.987213 -37.525889) (xy 395.003281 -37.579296) (xy 395.011401 -37.634472)
			(xy 395.01191 -37.662358) (xy 395.011401 -37.690244) (xy 395.003281 -37.74542) (xy 394.987213 -37.798827)
			(xy 394.963541 -37.849324) (xy 394.932768 -37.895837) (xy 394.895551 -37.937374) (xy 394.852683 -37.973049)
			(xy 394.805077 -38.002103) (xy 394.753748 -38.023915) (xy 394.699791 -38.038021) (xy 394.644354 -38.044121)
			(xy 394.58862 -38.042084) (xy 394.533777 -38.031954) (xy 394.480993 -38.013947) (xy 394.431393 -37.988446)
			(xy 394.386035 -37.955995) (xy 394.345886 -37.917286) (xy 394.3118 -37.873143) (xy 394.284504 -37.824508)
			(xy 394.264581 -37.772417) (xy 394.252455 -37.71798) (xy 394.248384 -37.662358) (xy 392.774162 -37.662358)
			(xy 392.743542 -37.708639) (xy 392.706325 -37.750176) (xy 392.663457 -37.785851) (xy 392.615851 -37.814905)
			(xy 392.564522 -37.836717) (xy 392.510565 -37.850823) (xy 392.455128 -37.856923) (xy 392.399394 -37.854886)
			(xy 392.344551 -37.844756) (xy 392.291767 -37.826749) (xy 392.242167 -37.801248) (xy 392.196809 -37.768797)
			(xy 392.15666 -37.730088) (xy 392.122574 -37.685945) (xy 392.095278 -37.63731) (xy 392.075355 -37.585219)
			(xy 392.063229 -37.530782) (xy 392.059158 -37.47516) (xy 387.675263 -37.47516) (xy 387.670135 -37.477817)
			(xy 387.588644 -37.51103) (xy 387.50447 -37.536694) (xy 387.418311 -37.554598) (xy 387.330881 -37.564593)
			(xy 387.242904 -37.566597) (xy 387.15511 -37.560591) (xy 387.068226 -37.546627) (xy 386.982971 -37.52482)
			(xy 386.900052 -37.495351) (xy 386.820157 -37.458464) (xy 386.743948 -37.414464) (xy 386.672055 -37.363716)
			(xy 386.605074 -37.306642) (xy 386.543562 -37.243712) (xy 386.488026 -37.17545) (xy 386.438928 -37.102421)
			(xy 386.396675 -37.025229) (xy 386.361616 -36.944515) (xy 386.334041 -36.860947) (xy 386.314181 -36.775218)
			(xy 386.302198 -36.688038) (xy 386.298193 -36.60013) (xy 382.068362 -36.60013) (xy 382.065022 -36.613592)
			(xy 382.053592 -36.64966) (xy 382.050544 -36.657788) (xy 382.044956 -36.67125) (xy 382.042924 -36.675822)
			(xy 382.041908 -36.678108) (xy 382.04013 -36.681664) (xy 382.037844 -36.691824) (xy 382.037844 -38.729947)
			(xy 398.00102 -38.729947) (xy 398.00102 -38.675453) (xy 398.008775 -38.621512) (xy 398.024128 -38.569225)
			(xy 398.046765 -38.519654) (xy 398.076226 -38.47381) (xy 398.111912 -38.432625) (xy 398.153096 -38.396937)
			(xy 398.198939 -38.367474) (xy 398.248508 -38.344834) (xy 398.300795 -38.329479) (xy 398.354735 -38.321721)
			(xy 398.381982 -38.321234) (xy 398.410286 -38.321722) (xy 398.466276 -38.330072) (xy 398.520416 -38.346607)
			(xy 398.571517 -38.370962) (xy 398.618457 -38.402603) (xy 398.660204 -38.440835) (xy 398.695841 -38.484818)
			(xy 398.710658 -38.50894) (xy 398.718214 -38.521004) (xy 398.738841 -38.540607) (xy 398.764082 -38.553749)
			(xy 398.791972 -38.559405) (xy 398.820338 -38.557135) (xy 398.846973 -38.547117) (xy 398.869804 -38.530129)
			(xy 398.878806 -38.5191) (xy 398.896994 -38.496225) (xy 398.939156 -38.455761) (xy 398.986992 -38.422194)
			(xy 399.039383 -38.396306) (xy 399.095108 -38.378704) (xy 399.152863 -38.369797) (xy 399.182082 -38.36924)
			(xy 399.209339 -38.369606) (xy 399.263299 -38.377362) (xy 399.315606 -38.392718) (xy 399.365194 -38.415362)
			(xy 399.411055 -38.444834) (xy 399.452255 -38.480532) (xy 399.487956 -38.52173) (xy 399.517429 -38.56759)
			(xy 399.540076 -38.617178) (xy 399.555435 -38.669484) (xy 399.563193 -38.723443) (xy 399.563193 -38.777957)
			(xy 399.555435 -38.831916) (xy 399.540076 -38.884222) (xy 399.517429 -38.93381) (xy 399.487956 -38.97967)
			(xy 399.452255 -39.020868) (xy 399.411055 -39.056566) (xy 399.365194 -39.086038) (xy 399.315606 -39.108682)
			(xy 399.263299 -39.124038) (xy 399.209339 -39.131794) (xy 399.182082 -39.132256) (xy 399.153779 -39.131722)
			(xy 399.097792 -39.123381) (xy 399.043653 -39.106855) (xy 398.992551 -39.082508) (xy 398.945611 -39.050873)
			(xy 398.903862 -39.012647) (xy 398.868223 -38.968669) (xy 398.853406 -38.94455) (xy 398.845767 -38.932544)
			(xy 398.825156 -38.912946) (xy 398.799933 -38.899804) (xy 398.772061 -38.894142) (xy 398.743709 -38.8964)
			(xy 398.717085 -38.906403) (xy 398.69426 -38.923371) (xy 398.685258 -38.93439) (xy 398.667088 -38.95728)
			(xy 398.624922 -38.997743) (xy 398.577083 -39.03131) (xy 398.524688 -39.057194) (xy 398.46896 -39.074793)
			(xy 398.411202 -39.083695) (xy 398.381982 -39.08425) (xy 398.354735 -39.083679) (xy 398.300795 -39.075921)
			(xy 398.248508 -39.060566) (xy 398.198939 -39.037926) (xy 398.153096 -39.008463) (xy 398.111912 -38.972775)
			(xy 398.076226 -38.93159) (xy 398.046765 -38.885746) (xy 398.024128 -38.836175) (xy 398.008775 -38.783888)
			(xy 398.00102 -38.729947) (xy 382.037844 -38.729947) (xy 382.037844 -38.90645) (xy 382.03791 -38.910459)
			(xy 382.039182 -38.918374) (xy 382.040384 -38.922198) (xy 382.042393 -38.927777) (xy 382.048551 -38.937909)
			(xy 382.052576 -38.942264) (xy 384.379185 -41.268753) (xy 390.14395 -41.268753) (xy 390.14395 -41.214247)
			(xy 390.151707 -41.160295) (xy 390.167063 -41.107996) (xy 390.189706 -41.058416) (xy 390.219174 -41.012562)
			(xy 390.254869 -40.971369) (xy 390.296062 -40.935674) (xy 390.341916 -40.906206) (xy 390.391496 -40.883563)
			(xy 390.443795 -40.868207) (xy 390.497747 -40.86045) (xy 390.525 -40.859964) (xy 390.553738 -40.860497)
			(xy 390.610565 -40.869119) (xy 390.665455 -40.886167) (xy 390.717167 -40.911257) (xy 390.76453 -40.943819)
			(xy 390.785858 -40.963088) (xy 390.792716 -40.969692) (xy 390.81075 -40.976804) (xy 390.89965 -40.976804)
			(xy 390.917684 -40.969692) (xy 390.924542 -40.963088) (xy 390.945876 -40.943826) (xy 390.993235 -40.911256)
			(xy 391.044945 -40.886161) (xy 391.099835 -40.869109) (xy 391.156661 -40.860485) (xy 391.1854 -40.859964)
			(xy 391.212649 -40.860506) (xy 391.266593 -40.868262) (xy 391.318884 -40.883616) (xy 391.368457 -40.906256)
			(xy 391.414304 -40.93572) (xy 391.455491 -40.971409) (xy 391.49118 -41.012596) (xy 391.520644 -41.058443)
			(xy 391.543284 -41.108016) (xy 391.558638 -41.160307) (xy 391.566394 -41.214251) (xy 391.566394 -41.268749)
			(xy 391.558638 -41.322693) (xy 391.543284 -41.374984) (xy 391.520644 -41.424557) (xy 391.49118 -41.470404)
			(xy 391.455491 -41.511591) (xy 391.414304 -41.54728) (xy 391.368457 -41.576744) (xy 391.318884 -41.599384)
			(xy 391.266593 -41.614738) (xy 391.212649 -41.622494) (xy 391.1854 -41.62298) (xy 391.156662 -41.622435)
			(xy 391.099837 -41.613814) (xy 391.044947 -41.596768) (xy 390.993235 -41.571682) (xy 390.945871 -41.539123)
			(xy 390.924542 -41.519856) (xy 390.917684 -41.513252) (xy 390.89965 -41.50614) (xy 390.81075 -41.50614)
			(xy 390.792716 -41.513252) (xy 390.785858 -41.519856) (xy 390.76453 -41.539126) (xy 390.717168 -41.571692)
			(xy 390.665457 -41.596785) (xy 390.610566 -41.613836) (xy 390.553739 -41.622459) (xy 390.525 -41.62298)
			(xy 390.497747 -41.62255) (xy 390.443795 -41.614793) (xy 390.391496 -41.599437) (xy 390.341916 -41.576794)
			(xy 390.296062 -41.547326) (xy 390.254869 -41.511631) (xy 390.219174 -41.470438) (xy 390.189706 -41.424584)
			(xy 390.167063 -41.375004) (xy 390.151707 -41.322705) (xy 390.14395 -41.268753) (xy 384.379185 -41.268753)
			(xy 386.415759 -43.305222) (xy 392.607292 -43.305222) (xy 392.607773 -43.277852) (xy 392.615587 -43.223674)
			(xy 392.631073 -43.171171) (xy 392.653912 -43.121424) (xy 392.683633 -43.075456) (xy 392.701272 -43.054524)
			(xy 392.701526 -43.05427) (xy 392.707092 -43.04717) (xy 392.71335 -43.030263) (xy 392.713718 -43.02125)
			(xy 392.713718 -42.954194) (xy 392.71336 -42.945177) (xy 392.707113 -42.928261) (xy 392.701526 -42.921174)
			(xy 392.701272 -42.921174) (xy 392.701272 -42.92092) (xy 392.683624 -42.899995) (xy 392.653915 -42.85402)
			(xy 392.631081 -42.80427) (xy 392.615592 -42.751768) (xy 392.607765 -42.697592) (xy 392.607292 -42.670222)
			(xy 392.607831 -42.641484) (xy 392.61645 -42.584657) (xy 392.633497 -42.529767) (xy 392.658585 -42.478055)
			(xy 392.691147 -42.430691) (xy 392.710416 -42.409364) (xy 392.71702 -42.402506) (xy 392.724132 -42.384472)
			(xy 392.724132 -42.295572) (xy 392.71702 -42.277538) (xy 392.710416 -42.27068) (xy 392.691167 -42.249334)
			(xy 392.658602 -42.201975) (xy 392.63351 -42.150266) (xy 392.616459 -42.095378) (xy 392.607834 -42.038554)
			(xy 392.607832 -41.981078) (xy 392.616451 -41.924253) (xy 392.633498 -41.869364) (xy 392.658586 -41.817653)
			(xy 392.691147 -41.770291) (xy 392.710416 -41.748964) (xy 392.71702 -41.742106) (xy 392.724132 -41.724072)
			(xy 392.724132 -41.635172) (xy 392.71702 -41.617138) (xy 392.710416 -41.61028) (xy 392.691152 -41.588947)
			(xy 392.658586 -41.541586) (xy 392.633492 -41.489876) (xy 392.61644 -41.434987) (xy 392.607815 -41.378161)
			(xy 392.607292 -41.349422) (xy 392.607778 -41.322171) (xy 392.615534 -41.268223) (xy 392.630889 -41.215928)
			(xy 392.653531 -41.166351) (xy 392.682997 -41.120501) (xy 392.718688 -41.07931) (xy 392.759879 -41.043619)
			(xy 392.805729 -41.014153) (xy 392.855306 -40.991511) (xy 392.907601 -40.976156) (xy 392.961549 -40.9684)
			(xy 393.016051 -40.9684) (xy 393.039172 -40.971724) (xy 400.89404 -40.971724) (xy 400.898111 -40.916102)
			(xy 400.910237 -40.861665) (xy 400.93016 -40.809574) (xy 400.957456 -40.760939) (xy 400.991542 -40.716796)
			(xy 401.031691 -40.678087) (xy 401.077049 -40.645636) (xy 401.126649 -40.620135) (xy 401.179433 -40.602128)
			(xy 401.234276 -40.591998) (xy 401.29001 -40.589961) (xy 401.345447 -40.596061) (xy 401.399404 -40.610167)
			(xy 401.450733 -40.631979) (xy 401.498339 -40.661033) (xy 401.541207 -40.696708) (xy 401.578424 -40.738245)
			(xy 401.609197 -40.784758) (xy 401.632869 -40.835255) (xy 401.648937 -40.888662) (xy 401.657057 -40.943838)
			(xy 401.657566 -40.971724) (xy 401.657057 -40.99961) (xy 401.648937 -41.054786) (xy 401.632869 -41.108193)
			(xy 401.609197 -41.15869) (xy 401.578424 -41.205203) (xy 401.541207 -41.24674) (xy 401.498339 -41.282415)
			(xy 401.450733 -41.311469) (xy 401.399404 -41.333281) (xy 401.345447 -41.347387) (xy 401.29001 -41.353487)
			(xy 401.234276 -41.35145) (xy 401.179433 -41.34132) (xy 401.126649 -41.323313) (xy 401.077049 -41.297812)
			(xy 401.031691 -41.265361) (xy 400.991542 -41.226652) (xy 400.957456 -41.182509) (xy 400.93016 -41.133874)
			(xy 400.910237 -41.081783) (xy 400.898111 -41.027346) (xy 400.89404 -40.971724) (xy 393.039172 -40.971724)
			(xy 393.069999 -40.976156) (xy 393.122294 -40.991511) (xy 393.171871 -41.014153) (xy 393.217721 -41.043619)
			(xy 393.258912 -41.07931) (xy 393.294603 -41.120501) (xy 393.324069 -41.166351) (xy 393.346711 -41.215928)
			(xy 393.362066 -41.268223) (xy 393.369822 -41.322171) (xy 393.370308 -41.349422) (xy 393.369796 -41.378161)
			(xy 393.36117 -41.434989) (xy 393.344117 -41.48988) (xy 393.319023 -41.541591) (xy 393.286456 -41.588953)
			(xy 393.267184 -41.61028) (xy 393.26058 -41.617138) (xy 393.253468 -41.635172) (xy 393.253468 -41.724072)
			(xy 393.26058 -41.742106) (xy 393.267184 -41.748964) (xy 393.286476 -41.770272) (xy 393.31904 -41.817638)
			(xy 393.34413 -41.869353) (xy 393.361178 -41.924246) (xy 393.369798 -41.981076) (xy 393.369796 -42.038556)
			(xy 393.361171 -42.095385) (xy 393.344118 -42.150277) (xy 393.319024 -42.20199) (xy 393.286456 -42.249353)
			(xy 393.267184 -42.27068) (xy 393.26058 -42.277538) (xy 393.253468 -42.295572) (xy 393.253468 -42.384472)
			(xy 393.26058 -42.402506) (xy 393.267184 -42.409364) (xy 393.286469 -42.430679) (xy 393.319032 -42.478045)
			(xy 393.344122 -42.529759) (xy 393.361169 -42.584653) (xy 393.369789 -42.641482) (xy 393.370308 -42.670222)
			(xy 393.369853 -42.697593) (xy 393.362032 -42.751772) (xy 393.34654 -42.804275) (xy 393.325985 -42.849038)
			(xy 395.191994 -42.849038) (xy 395.196065 -42.793416) (xy 395.208191 -42.738979) (xy 395.228114 -42.686888)
			(xy 395.25541 -42.638253) (xy 395.289496 -42.59411) (xy 395.329645 -42.555401) (xy 395.375003 -42.52295)
			(xy 395.424603 -42.497449) (xy 395.477387 -42.479442) (xy 395.53223 -42.469312) (xy 395.587964 -42.467275)
			(xy 395.643401 -42.473375) (xy 395.697358 -42.487481) (xy 395.748687 -42.509293) (xy 395.796293 -42.538347)
			(xy 395.839161 -42.574022) (xy 395.876378 -42.615559) (xy 395.907151 -42.662072) (xy 395.930823 -42.712569)
			(xy 395.946891 -42.765976) (xy 395.955011 -42.821152) (xy 395.955372 -42.84091) (xy 401.23313 -42.84091)
			(xy 401.237201 -42.785288) (xy 401.249327 -42.730851) (xy 401.26925 -42.67876) (xy 401.296546 -42.630125)
			(xy 401.330632 -42.585982) (xy 401.370781 -42.547273) (xy 401.416139 -42.514822) (xy 401.465739 -42.489321)
			(xy 401.518523 -42.471314) (xy 401.573366 -42.461184) (xy 401.6291 -42.459147) (xy 401.684537 -42.465247)
			(xy 401.738494 -42.479353) (xy 401.789823 -42.501165) (xy 401.837429 -42.530219) (xy 401.880297 -42.565894)
			(xy 401.917514 -42.607431) (xy 401.948287 -42.653944) (xy 401.971959 -42.704441) (xy 401.988027 -42.757848)
			(xy 401.996147 -42.813024) (xy 401.996656 -42.84091) (xy 401.996147 -42.868796) (xy 401.988027 -42.923972)
			(xy 401.971959 -42.977379) (xy 401.948287 -43.027876) (xy 401.917514 -43.074389) (xy 401.880297 -43.115926)
			(xy 401.837429 -43.151601) (xy 401.789823 -43.180655) (xy 401.738494 -43.202467) (xy 401.684537 -43.216573)
			(xy 401.6291 -43.222673) (xy 401.573366 -43.220636) (xy 401.518523 -43.210506) (xy 401.465739 -43.192499)
			(xy 401.416139 -43.166998) (xy 401.370781 -43.134547) (xy 401.330632 -43.095838) (xy 401.296546 -43.051695)
			(xy 401.26925 -43.00306) (xy 401.249327 -42.950969) (xy 401.237201 -42.896532) (xy 401.23313 -42.84091)
			(xy 395.955372 -42.84091) (xy 395.95552 -42.849038) (xy 395.955011 -42.876924) (xy 395.946891 -42.9321)
			(xy 395.930823 -42.985507) (xy 395.907151 -43.036004) (xy 395.876378 -43.082517) (xy 395.839161 -43.124054)
			(xy 395.796293 -43.159729) (xy 395.748687 -43.188783) (xy 395.697358 -43.210595) (xy 395.643401 -43.224701)
			(xy 395.587964 -43.230801) (xy 395.53223 -43.228764) (xy 395.477387 -43.218634) (xy 395.424603 -43.200627)
			(xy 395.375003 -43.175126) (xy 395.329645 -43.142675) (xy 395.289496 -43.103966) (xy 395.25541 -43.059823)
			(xy 395.228114 -43.011188) (xy 395.208191 -42.959097) (xy 395.196065 -42.90466) (xy 395.191994 -42.849038)
			(xy 393.325985 -42.849038) (xy 393.323696 -42.854022) (xy 393.29397 -42.899988) (xy 393.276328 -42.92092)
			(xy 393.276074 -42.921174) (xy 393.270489 -42.928262) (xy 393.264242 -42.945178) (xy 393.263882 -42.954194)
			(xy 393.263882 -43.02125) (xy 393.264267 -43.030264) (xy 393.270495 -43.047181) (xy 393.276074 -43.05427)
			(xy 393.276328 -43.05427) (xy 393.276328 -43.054524) (xy 393.293949 -43.07547) (xy 393.323663 -43.12144)
			(xy 393.346502 -43.171184) (xy 393.361997 -43.223681) (xy 393.369831 -43.277854) (xy 393.370308 -43.305222)
			(xy 393.369822 -43.332473) (xy 393.362066 -43.386421) (xy 393.346711 -43.438716) (xy 393.324069 -43.488293)
			(xy 393.294603 -43.534143) (xy 393.258912 -43.575334) (xy 393.217721 -43.611025) (xy 393.171871 -43.640491)
			(xy 393.122294 -43.663133) (xy 393.069999 -43.678488) (xy 393.016051 -43.686244) (xy 392.961549 -43.686244)
			(xy 392.907601 -43.678488) (xy 392.855306 -43.663133) (xy 392.805729 -43.640491) (xy 392.759879 -43.611025)
			(xy 392.718688 -43.575334) (xy 392.682997 -43.534143) (xy 392.653531 -43.488293) (xy 392.630889 -43.438716)
			(xy 392.615534 -43.386421) (xy 392.607778 -43.332473) (xy 392.607292 -43.305222) (xy 386.415759 -43.305222)
			(xy 386.846819 -43.73626) (xy 394.513052 -43.73626) (xy 394.517123 -43.680638) (xy 394.529249 -43.626201)
			(xy 394.549172 -43.57411) (xy 394.576468 -43.525475) (xy 394.610554 -43.481332) (xy 394.650703 -43.442623)
			(xy 394.696061 -43.410172) (xy 394.745661 -43.384671) (xy 394.798445 -43.366664) (xy 394.853288 -43.356534)
			(xy 394.909022 -43.354497) (xy 394.964459 -43.360597) (xy 395.018416 -43.374703) (xy 395.069745 -43.396515)
			(xy 395.117351 -43.425569) (xy 395.160219 -43.461244) (xy 395.197436 -43.502781) (xy 395.228209 -43.549294)
			(xy 395.251881 -43.599791) (xy 395.267949 -43.653198) (xy 395.276069 -43.708374) (xy 395.276578 -43.73626)
			(xy 395.276069 -43.764146) (xy 395.267949 -43.819322) (xy 395.251881 -43.872729) (xy 395.228209 -43.923226)
			(xy 395.197436 -43.969739) (xy 395.160219 -44.011276) (xy 395.117351 -44.046951) (xy 395.069745 -44.076005)
			(xy 395.018416 -44.097817) (xy 394.964459 -44.111923) (xy 394.909022 -44.118023) (xy 394.853288 -44.115986)
			(xy 394.798445 -44.105856) (xy 394.745661 -44.087849) (xy 394.696061 -44.062348) (xy 394.650703 -44.029897)
			(xy 394.610554 -43.991188) (xy 394.576468 -43.947045) (xy 394.549172 -43.89841) (xy 394.529249 -43.846319)
			(xy 394.517123 -43.791882) (xy 394.513052 -43.73626) (xy 386.846819 -43.73626) (xy 386.981446 -43.87088)
			(xy 386.999554 -43.889662) (xy 387.03023 -43.931862) (xy 387.053922 -43.978343) (xy 387.070044 -44.027961)
			(xy 387.0782 -44.07949) (xy 387.078728 -44.105576) (xy 387.078728 -45.114464) (xy 394.365478 -45.114464)
			(xy 394.369549 -45.058842) (xy 394.381675 -45.004405) (xy 394.401598 -44.952314) (xy 394.428894 -44.903679)
			(xy 394.46298 -44.859536) (xy 394.503129 -44.820827) (xy 394.548487 -44.788376) (xy 394.598087 -44.762875)
			(xy 394.650871 -44.744868) (xy 394.705714 -44.734738) (xy 394.761448 -44.732701) (xy 394.816885 -44.738801)
			(xy 394.870842 -44.752907) (xy 394.922171 -44.774719) (xy 394.969777 -44.803773) (xy 395.012645 -44.839448)
			(xy 395.049862 -44.880985) (xy 395.080635 -44.927498) (xy 395.104307 -44.977995) (xy 395.120375 -45.031402)
			(xy 395.128495 -45.086578) (xy 395.129004 -45.114464) (xy 395.128495 -45.14235) (xy 395.120375 -45.197526)
			(xy 395.104307 -45.250933) (xy 395.080635 -45.30143) (xy 395.049862 -45.347943) (xy 395.012645 -45.38948)
			(xy 394.969777 -45.425155) (xy 394.922171 -45.454209) (xy 394.870842 -45.476021) (xy 394.816885 -45.490127)
			(xy 394.761448 -45.496227) (xy 394.705714 -45.49419) (xy 394.650871 -45.48406) (xy 394.598087 -45.466053)
			(xy 394.548487 -45.440552) (xy 394.503129 -45.408101) (xy 394.46298 -45.369392) (xy 394.428894 -45.325249)
			(xy 394.401598 -45.276614) (xy 394.381675 -45.224523) (xy 394.369549 -45.170086) (xy 394.365478 -45.114464)
			(xy 387.078728 -45.114464) (xy 387.078728 -46.082204) (xy 392.35253 -46.082204) (xy 392.352959 -46.05495)
			(xy 392.360717 -46.000995) (xy 392.376074 -45.948695) (xy 392.398719 -45.899112) (xy 392.42819 -45.853257)
			(xy 392.463887 -45.812063) (xy 392.505084 -45.77637) (xy 392.550942 -45.746903) (xy 392.600526 -45.724262)
			(xy 392.652829 -45.708909) (xy 392.706783 -45.701157) (xy 392.734038 -45.700696) (xy 392.760942 -45.701129)
			(xy 392.814213 -45.708706) (xy 392.865892 -45.723691) (xy 392.914954 -45.745785) (xy 392.960426 -45.774552)
			(xy 393.001406 -45.809421) (xy 393.037083 -45.8497) (xy 393.0523 -45.871892) (xy 393.059412 -45.882814)
			(xy 393.082272 -45.894752) (xy 393.19454 -45.89272) (xy 393.216892 -45.879766) (xy 393.22375 -45.86859)
			(xy 393.238651 -45.844975) (xy 393.274333 -45.802023) (xy 393.315895 -45.764731) (xy 393.362449 -45.733895)
			(xy 393.413 -45.710174) (xy 393.466468 -45.694074) (xy 393.521712 -45.68594) (xy 393.549632 -45.685456)
			(xy 393.576626 -45.685899) (xy 393.630075 -45.693509) (xy 393.681919 -45.708574) (xy 393.731123 -45.730792)
			(xy 393.776706 -45.75972) (xy 393.797536 -45.776896) (xy 393.805664 -45.784008) (xy 393.826238 -45.790104)
			(xy 393.911582 -45.779182) (xy 393.922127 -45.777409) (xy 393.94041 -45.766354) (xy 393.946888 -45.757846)
			(xy 393.962255 -45.736626) (xy 393.99784 -45.698173) (xy 394.038355 -45.664953) (xy 394.083035 -45.637594)
			(xy 394.131041 -45.616608) (xy 394.181468 -45.602393) (xy 394.233366 -45.595215) (xy 394.259562 -45.594778)
			(xy 394.286816 -45.595267) (xy 394.340769 -45.603019) (xy 394.393069 -45.618371) (xy 394.442652 -45.641011)
			(xy 394.488508 -45.670477) (xy 394.529704 -45.706169) (xy 394.565401 -45.747361) (xy 394.594871 -45.793214)
			(xy 394.617516 -45.842795) (xy 394.632873 -45.895094) (xy 394.640631 -45.949046) (xy 394.640631 -46.003554)
			(xy 394.632873 -46.057506) (xy 394.617516 -46.109805) (xy 394.594871 -46.159386) (xy 394.565401 -46.205239)
			(xy 394.529704 -46.246431) (xy 394.488508 -46.282123) (xy 394.442652 -46.311589) (xy 394.393069 -46.334229)
			(xy 394.340769 -46.349581) (xy 394.286816 -46.357333) (xy 394.259562 -46.357794) (xy 394.232568 -46.357343)
			(xy 394.17912 -46.349733) (xy 394.127277 -46.33467) (xy 394.078073 -46.312454) (xy 394.032489 -46.283528)
			(xy 394.011658 -46.266354) (xy 394.00353 -46.259242) (xy 393.982956 -46.253146) (xy 393.897612 -46.264068)
			(xy 393.887071 -46.265856) (xy 393.868788 -46.276902) (xy 393.862306 -46.285404) (xy 393.844689 -46.309701)
			(xy 393.803096 -46.352963) (xy 393.779502 -46.37151) (xy 393.771628 -46.377352) (xy 393.761214 -46.394878)
			(xy 393.748006 -46.485302) (xy 393.752832 -46.504606) (xy 393.758674 -46.51248) (xy 393.758674 -46.512734)
			(xy 393.776177 -46.537478) (xy 393.80398 -46.591331) (xy 393.822916 -46.648903) (xy 393.832509 -46.708745)
			(xy 393.833096 -46.739048) (xy 393.832667 -46.766301) (xy 393.824903 -46.820251) (xy 393.809542 -46.872548)
			(xy 393.786894 -46.922126) (xy 393.757422 -46.967977) (xy 393.721724 -47.009167) (xy 393.680529 -47.044858)
			(xy 393.634673 -47.074323) (xy 393.585092 -47.096963) (xy 393.532793 -47.112316) (xy 393.478841 -47.120071)
			(xy 393.451588 -47.120556) (xy 393.425554 -47.120109) (xy 393.373972 -47.113021) (xy 393.32383 -47.098991)
			(xy 393.276059 -47.07828) (xy 393.231544 -47.051272) (xy 393.21105 -47.035212) (xy 393.203285 -47.029483)
			(xy 393.184881 -47.023734) (xy 393.175236 -47.024036) (xy 393.09548 -47.030386) (xy 393.0777 -47.039022)
			(xy 393.07135 -47.046388) (xy 393.053167 -47.066032) (xy 393.01226 -47.100554) (xy 392.966931 -47.129023)
			(xy 392.91807 -47.150881) (xy 392.866635 -47.165699) (xy 392.813634 -47.173186) (xy 392.78687 -47.173642)
			(xy 392.75962 -47.17315) (xy 392.705674 -47.16539) (xy 392.653381 -47.150033) (xy 392.603806 -47.127391)
			(xy 392.557958 -47.097925) (xy 392.516769 -47.062234) (xy 392.481078 -47.021046) (xy 392.451611 -46.975197)
			(xy 392.428968 -46.925622) (xy 392.41361 -46.87333) (xy 392.40585 -46.819384) (xy 392.405362 -46.792134)
			(xy 392.405897 -46.76336) (xy 392.414547 -46.706467) (xy 392.431641 -46.651517) (xy 392.456792 -46.599757)
			(xy 392.48943 -46.55236) (xy 392.50874 -46.531022) (xy 392.516106 -46.523148) (xy 392.523218 -46.503336)
			(xy 392.515852 -46.40707) (xy 392.505946 -46.388274) (xy 392.497564 -46.38167) (xy 392.475388 -46.363434)
			(xy 392.436176 -46.321503) (xy 392.403688 -46.27417) (xy 392.378657 -46.222504) (xy 392.36165 -46.167671)
			(xy 392.353048 -46.110909) (xy 392.35253 -46.082204) (xy 387.078728 -46.082204) (xy 387.078728 -48.753014)
			(xy 395.468346 -48.753014) (xy 395.472417 -48.697392) (xy 395.484543 -48.642955) (xy 395.504466 -48.590864)
			(xy 395.531762 -48.542229) (xy 395.565848 -48.498086) (xy 395.605997 -48.459377) (xy 395.651355 -48.426926)
			(xy 395.700955 -48.401425) (xy 395.753739 -48.383418) (xy 395.808582 -48.373288) (xy 395.864316 -48.371251)
			(xy 395.919753 -48.377351) (xy 395.97371 -48.391457) (xy 396.025039 -48.413269) (xy 396.072645 -48.442323)
			(xy 396.115513 -48.477998) (xy 396.15273 -48.519535) (xy 396.183503 -48.566048) (xy 396.207175 -48.616545)
			(xy 396.223243 -48.669952) (xy 396.231363 -48.725128) (xy 396.231872 -48.753014) (xy 396.231363 -48.7809)
			(xy 396.223243 -48.836076) (xy 396.207175 -48.889483) (xy 396.205779 -48.89246) (xy 397.310356 -48.89246)
			(xy 397.310356 -48.892206) (xy 397.31085 -48.859354) (xy 397.318212 -48.794062) (xy 397.332831 -48.730005)
			(xy 397.354526 -48.667984) (xy 397.383023 -48.608781) (xy 397.417964 -48.553137) (xy 397.458912 -48.501752)
			(xy 397.481806 -48.478186) (xy 398.088358 -47.871634) (xy 398.09517 -47.864211) (xy 398.102907 -47.84563)
			(xy 398.103344 -47.835566) (xy 398.103344 -44.504356) (xy 398.102956 -44.494282) (xy 398.095211 -44.475684)
			(xy 398.088358 -44.468288) (xy 397.601186 -43.981116) (xy 397.578298 -43.957541) (xy 397.537329 -43.906168)
			(xy 397.50237 -43.850531) (xy 397.47386 -43.791329) (xy 397.452158 -43.729308) (xy 397.437536 -43.665246)
			(xy 397.43018 -43.59995) (xy 397.429736 -43.567096) (xy 397.429736 -43.566842) (xy 397.430295 -43.531439)
			(xy 397.438823 -43.461149) (xy 397.45576 -43.392399) (xy 397.480858 -43.326192) (xy 397.513751 -43.263491)
			(xy 397.553962 -43.205211) (xy 397.600902 -43.152202) (xy 397.653889 -43.105236) (xy 397.712149 -43.064997)
			(xy 397.774834 -43.032073) (xy 397.84103 -43.006944) (xy 397.909772 -42.989974) (xy 397.980058 -42.981413)
			(xy 398.01546 -42.980864) (xy 398.048341 -42.981311) (xy 398.113689 -42.988675) (xy 398.177801 -43.003314)
			(xy 398.239869 -43.025044) (xy 398.299111 -43.053592) (xy 398.354782 -43.088598) (xy 398.40618 -43.129621)
			(xy 398.429734 -43.152568) (xy 398.932146 -43.65498) (xy 398.940459 -43.662392) (xy 398.961403 -43.669895)
			(xy 398.972532 -43.669458) (xy 399.061686 -43.66133) (xy 399.081244 -43.6499) (xy 399.087594 -43.640502)
			(xy 399.102938 -43.619039) (xy 399.138566 -43.580125) (xy 399.179216 -43.546492) (xy 399.224113 -43.518782)
			(xy 399.2724 -43.497523) (xy 399.323156 -43.48312) (xy 399.375412 -43.475849) (xy 399.401792 -43.475402)
			(xy 399.429046 -43.475844) (xy 399.482999 -43.483601) (xy 399.535299 -43.498956) (xy 399.584882 -43.521599)
			(xy 399.630737 -43.551068) (xy 399.671932 -43.586762) (xy 399.707628 -43.627956) (xy 399.737097 -43.673811)
			(xy 399.759741 -43.723393) (xy 399.775098 -43.775693) (xy 399.782855 -43.829646) (xy 399.782855 -43.884154)
			(xy 399.775098 -43.938107) (xy 399.759741 -43.990407) (xy 399.737097 -44.039989) (xy 399.707628 -44.085844)
			(xy 399.671932 -44.127038) (xy 399.630737 -44.162732) (xy 399.584882 -44.192201) (xy 399.535299 -44.214844)
			(xy 399.482999 -44.230199) (xy 399.429046 -44.237956) (xy 399.401792 -44.238418) (xy 399.401538 -44.238418)
			(xy 399.38198 -44.23791) (xy 399.381726 -44.23791) (xy 399.371427 -44.237891) (xy 399.35216 -44.24512)
			(xy 399.344388 -44.25188) (xy 399.291048 -44.30268) (xy 399.283923 -44.310179) (xy 399.275791 -44.329178)
			(xy 399.2753 -44.33951) (xy 399.2753 -44.871132) (xy 399.275369 -44.87291) (xy 401.23313 -44.87291)
			(xy 401.237201 -44.817288) (xy 401.249327 -44.762851) (xy 401.26925 -44.71076) (xy 401.296546 -44.662125)
			(xy 401.330632 -44.617982) (xy 401.370781 -44.579273) (xy 401.416139 -44.546822) (xy 401.465739 -44.521321)
			(xy 401.518523 -44.503314) (xy 401.573366 -44.493184) (xy 401.6291 -44.491147) (xy 401.684537 -44.497247)
			(xy 401.738494 -44.511353) (xy 401.789823 -44.533165) (xy 401.837429 -44.562219) (xy 401.880297 -44.597894)
			(xy 401.917514 -44.639431) (xy 401.948287 -44.685944) (xy 401.971959 -44.736441) (xy 401.988027 -44.789848)
			(xy 401.996147 -44.845024) (xy 401.996656 -44.87291) (xy 401.996147 -44.900796) (xy 401.988027 -44.955972)
			(xy 401.971959 -45.009379) (xy 401.948287 -45.059876) (xy 401.917514 -45.106389) (xy 401.880297 -45.147926)
			(xy 401.837429 -45.183601) (xy 401.789823 -45.212655) (xy 401.738494 -45.234467) (xy 401.684537 -45.248573)
			(xy 401.6291 -45.254673) (xy 401.573366 -45.252636) (xy 401.518523 -45.242506) (xy 401.465739 -45.224499)
			(xy 401.416139 -45.198998) (xy 401.370781 -45.166547) (xy 401.330632 -45.127838) (xy 401.296546 -45.083695)
			(xy 401.26925 -45.03506) (xy 401.249327 -44.982969) (xy 401.237201 -44.928532) (xy 401.23313 -44.87291)
			(xy 399.275369 -44.87291) (xy 399.275697 -44.881296) (xy 399.28358 -44.900033) (xy 399.29054 -44.907454)
			(xy 399.349468 -44.965366) (xy 399.368518 -44.972986) (xy 399.378678 -44.972732) (xy 399.38579 -44.972732)
			(xy 399.413046 -44.973114) (xy 399.467004 -44.980871) (xy 399.519309 -44.996228) (xy 399.568895 -45.018872)
			(xy 399.614754 -45.048343) (xy 399.655953 -45.08404) (xy 399.691651 -45.125238) (xy 399.721123 -45.171096)
			(xy 399.743769 -45.220682) (xy 399.759127 -45.272986) (xy 399.766885 -45.326944) (xy 399.766885 -45.381456)
			(xy 399.759127 -45.435414) (xy 399.743769 -45.487718) (xy 399.721123 -45.537304) (xy 399.691651 -45.583162)
			(xy 399.655953 -45.62436) (xy 399.614754 -45.660057) (xy 399.568895 -45.689528) (xy 399.519309 -45.712172)
			(xy 399.467004 -45.727529) (xy 399.413046 -45.735286) (xy 399.38579 -45.735748) (xy 399.378678 -45.735748)
			(xy 399.368518 -45.735494) (xy 399.349468 -45.743114) (xy 399.29054 -45.801026) (xy 399.283613 -45.808465)
			(xy 399.275751 -45.827193) (xy 399.2753 -45.837348) (xy 399.2753 -46.211236) (xy 399.275754 -46.220963)
			(xy 399.283075 -46.238991) (xy 399.289524 -46.246288) (xy 399.338038 -46.297088) (xy 399.345163 -46.303826)
			(xy 399.363061 -46.311796) (xy 399.372836 -46.312582) (xy 399.399363 -46.314144) (xy 399.451653 -46.323584)
			(xy 399.502127 -46.340188) (xy 399.54981 -46.363635) (xy 399.593777 -46.393472) (xy 399.63318 -46.42912)
			(xy 399.667255 -46.469891) (xy 399.695343 -46.514996) (xy 399.716902 -46.563561) (xy 399.731513 -46.614648)
			(xy 399.738895 -46.667268) (xy 399.739358 -46.693836) (xy 399.738891 -46.720264) (xy 399.731581 -46.772612)
			(xy 399.717106 -46.823447) (xy 399.695744 -46.871793) (xy 399.682208 -46.894496) (xy 399.681954 -46.89475)
			(xy 399.676617 -46.904768) (xy 399.67436 -46.927318) (xy 399.677636 -46.938184) (xy 399.703798 -47.01286)
			(xy 399.708161 -47.023386) (xy 399.724264 -47.03947) (xy 399.734786 -47.043848) (xy 399.73504 -47.043848)
			(xy 399.759547 -47.052921) (xy 399.806 -47.076863) (xy 399.848752 -47.106918) (xy 399.887004 -47.142525)
			(xy 399.920041 -47.183017) (xy 399.947245 -47.227638) (xy 399.968107 -47.275553) (xy 399.982237 -47.325866)
			(xy 399.989371 -47.377636) (xy 399.989802 -47.403766) (xy 399.989313 -47.431018) (xy 399.987791 -47.441612)
			(xy 401.261832 -47.441612) (xy 401.265903 -47.38599) (xy 401.278029 -47.331553) (xy 401.297952 -47.279462)
			(xy 401.325248 -47.230827) (xy 401.359334 -47.186684) (xy 401.399483 -47.147975) (xy 401.444841 -47.115524)
			(xy 401.494441 -47.090023) (xy 401.547225 -47.072016) (xy 401.602068 -47.061886) (xy 401.657802 -47.059849)
			(xy 401.713239 -47.065949) (xy 401.767196 -47.080055) (xy 401.818525 -47.101867) (xy 401.866131 -47.130921)
			(xy 401.908999 -47.166596) (xy 401.946216 -47.208133) (xy 401.976989 -47.254646) (xy 402.000661 -47.305143)
			(xy 402.016729 -47.35855) (xy 402.024849 -47.413726) (xy 402.025358 -47.441612) (xy 402.024849 -47.469498)
			(xy 402.016729 -47.524674) (xy 402.000661 -47.578081) (xy 401.976989 -47.628578) (xy 401.946216 -47.675091)
			(xy 401.908999 -47.716628) (xy 401.866131 -47.752303) (xy 401.818525 -47.781357) (xy 401.767196 -47.803169)
			(xy 401.713239 -47.817275) (xy 401.657802 -47.823375) (xy 401.602068 -47.821338) (xy 401.547225 -47.811208)
			(xy 401.494441 -47.793201) (xy 401.444841 -47.7677) (xy 401.399483 -47.735249) (xy 401.359334 -47.69654)
			(xy 401.325248 -47.652397) (xy 401.297952 -47.603762) (xy 401.278029 -47.551671) (xy 401.265903 -47.497234)
			(xy 401.261832 -47.441612) (xy 399.987791 -47.441612) (xy 399.981561 -47.484969) (xy 399.966209 -47.537266)
			(xy 399.94357 -47.586847) (xy 399.914105 -47.6327) (xy 399.878413 -47.673894) (xy 399.837223 -47.709588)
			(xy 399.791371 -47.739056) (xy 399.741793 -47.761699) (xy 399.689496 -47.777055) (xy 399.635546 -47.784811)
			(xy 399.608294 -47.785274) (xy 399.576483 -47.784655) (xy 399.513744 -47.77408) (xy 399.453631 -47.753241)
			(xy 399.425414 -47.738538) (xy 399.417547 -47.734701) (xy 399.400254 -47.732068) (xy 399.383083 -47.735405)
			(xy 399.375376 -47.739554) (xy 399.300192 -47.784004) (xy 399.292818 -47.788804) (xy 399.281621 -47.802358)
			(xy 399.27567 -47.818901) (xy 399.2753 -47.827692) (xy 399.2753 -47.902368) (xy 399.297652 -47.930054)
			(xy 399.315432 -47.933864) (xy 399.34355 -47.940378) (xy 399.397543 -47.960775) (xy 399.447848 -47.989072)
			(xy 399.493316 -48.024623) (xy 399.532912 -48.066617) (xy 399.56573 -48.114095) (xy 399.591023 -48.165975)
			(xy 399.608212 -48.221073) (xy 399.616907 -48.278131) (xy 399.617438 -48.30699) (xy 399.616913 -48.33424)
			(xy 399.609158 -48.388184) (xy 399.593806 -48.440476) (xy 399.571168 -48.490052) (xy 399.541706 -48.535901)
			(xy 399.506018 -48.57709) (xy 399.464833 -48.612782) (xy 399.418987 -48.642249) (xy 399.369414 -48.664892)
			(xy 399.317123 -48.68025) (xy 399.26318 -48.68801) (xy 399.23593 -48.688498) (xy 399.209956 -48.688062)
			(xy 399.158488 -48.681021) (xy 399.10845 -48.667064) (xy 399.060768 -48.646451) (xy 399.038318 -48.63338)
			(xy 399.023078 -48.624236) (xy 398.988534 -48.628554) (xy 398.982692 -48.634396) (xy 398.998757 -48.654887)
			(xy 399.025777 -48.699398) (xy 399.046493 -48.747169) (xy 399.060519 -48.797313) (xy 399.067596 -48.848899)
			(xy 399.068036 -48.874934) (xy 399.067554 -48.902185) (xy 399.062558 -48.93691) (xy 401.23313 -48.93691)
			(xy 401.237201 -48.881288) (xy 401.249327 -48.826851) (xy 401.26925 -48.77476) (xy 401.296546 -48.726125)
			(xy 401.330632 -48.681982) (xy 401.370781 -48.643273) (xy 401.416139 -48.610822) (xy 401.465739 -48.585321)
			(xy 401.518523 -48.567314) (xy 401.573366 -48.557184) (xy 401.6291 -48.555147) (xy 401.684537 -48.561247)
			(xy 401.738494 -48.575353) (xy 401.789823 -48.597165) (xy 401.837429 -48.626219) (xy 401.880297 -48.661894)
			(xy 401.917514 -48.703431) (xy 401.948287 -48.749944) (xy 401.971959 -48.800441) (xy 401.988027 -48.853848)
			(xy 401.996147 -48.909024) (xy 401.996656 -48.93691) (xy 401.996147 -48.964796) (xy 401.988027 -49.019972)
			(xy 401.971959 -49.073379) (xy 401.948287 -49.123876) (xy 401.917514 -49.170389) (xy 401.880297 -49.211926)
			(xy 401.837429 -49.247601) (xy 401.789823 -49.276655) (xy 401.738494 -49.298467) (xy 401.684537 -49.312573)
			(xy 401.6291 -49.318673) (xy 401.573366 -49.316636) (xy 401.518523 -49.306506) (xy 401.465739 -49.288499)
			(xy 401.416139 -49.262998) (xy 401.370781 -49.230547) (xy 401.330632 -49.191838) (xy 401.296546 -49.147695)
			(xy 401.26925 -49.09906) (xy 401.249327 -49.046969) (xy 401.237201 -48.992532) (xy 401.23313 -48.93691)
			(xy 399.062558 -48.93691) (xy 399.059793 -48.956131) (xy 399.044435 -49.008424) (xy 399.021792 -49.058)
			(xy 398.992325 -49.103849) (xy 398.956634 -49.145038) (xy 398.915444 -49.180729) (xy 398.869595 -49.210195)
			(xy 398.820019 -49.232838) (xy 398.767725 -49.248195) (xy 398.713779 -49.255954) (xy 398.686528 -49.256442)
			(xy 398.659083 -49.255979) (xy 398.60476 -49.248103) (xy 398.552131 -49.232511) (xy 398.502286 -49.209524)
			(xy 398.47901 -49.194974) (xy 398.468954 -49.18909) (xy 398.445841 -49.186317) (xy 398.423856 -49.193969)
			(xy 398.415256 -49.201832) (xy 398.310354 -49.306734) (xy 398.286811 -49.329656) (xy 398.235432 -49.370622)
			(xy 398.179788 -49.405577) (xy 398.120581 -49.434082) (xy 398.058555 -49.455778) (xy 397.994489 -49.470394)
			(xy 397.92919 -49.477744) (xy 397.896334 -49.478184) (xy 397.89608 -49.478184) (xy 397.860679 -49.47773)
			(xy 397.790394 -49.469193) (xy 397.721651 -49.452246) (xy 397.655452 -49.427137) (xy 397.592762 -49.394231)
			(xy 397.534495 -49.354008) (xy 397.481502 -49.307056) (xy 397.434554 -49.254058) (xy 397.394338 -49.195787)
			(xy 397.361438 -49.133094) (xy 397.336336 -49.066892) (xy 397.319396 -48.998147) (xy 397.310867 -48.927861)
			(xy 397.310356 -48.89246) (xy 396.205779 -48.89246) (xy 396.183503 -48.93998) (xy 396.15273 -48.986493)
			(xy 396.115513 -49.02803) (xy 396.072645 -49.063705) (xy 396.025039 -49.092759) (xy 395.97371 -49.114571)
			(xy 395.919753 -49.128677) (xy 395.864316 -49.134777) (xy 395.808582 -49.13274) (xy 395.753739 -49.12261)
			(xy 395.700955 -49.104603) (xy 395.651355 -49.079102) (xy 395.605997 -49.046651) (xy 395.565848 -49.007942)
			(xy 395.531762 -48.963799) (xy 395.504466 -48.915164) (xy 395.484543 -48.863073) (xy 395.472417 -48.808636)
			(xy 395.468346 -48.753014) (xy 387.078728 -48.753014) (xy 387.078728 -49.95291) (xy 401.23313 -49.95291)
			(xy 401.237201 -49.897288) (xy 401.249327 -49.842851) (xy 401.26925 -49.79076) (xy 401.296546 -49.742125)
			(xy 401.330632 -49.697982) (xy 401.370781 -49.659273) (xy 401.416139 -49.626822) (xy 401.465739 -49.601321)
			(xy 401.518523 -49.583314) (xy 401.573366 -49.573184) (xy 401.6291 -49.571147) (xy 401.684537 -49.577247)
			(xy 401.738494 -49.591353) (xy 401.763429 -49.601949) (xy 406.412982 -49.601949) (xy 406.412982 -49.547451)
			(xy 406.420737 -49.493508) (xy 406.43609 -49.441217) (xy 406.458727 -49.391644) (xy 406.488189 -49.345796)
			(xy 406.523875 -49.304608) (xy 406.565059 -49.268916) (xy 406.610903 -49.239449) (xy 406.660474 -49.216806)
			(xy 406.712763 -49.201447) (xy 406.766705 -49.193685) (xy 406.793954 -49.193196) (xy 406.821323 -49.19369)
			(xy 406.875501 -49.201501) (xy 406.928004 -49.216984) (xy 406.977751 -49.239819) (xy 407.023719 -49.269538)
			(xy 407.044652 -49.287176) (xy 407.044906 -49.28743) (xy 407.051984 -49.293029) (xy 407.068908 -49.299267)
			(xy 407.077926 -49.299622) (xy 407.144982 -49.299622) (xy 407.153997 -49.299252) (xy 407.170914 -49.293013)
			(xy 407.178002 -49.28743) (xy 407.178002 -49.287176) (xy 407.178256 -49.287176) (xy 407.199189 -49.269535)
			(xy 407.245157 -49.239811) (xy 407.294903 -49.216965) (xy 407.347405 -49.201469) (xy 407.401583 -49.19364)
			(xy 407.456325 -49.19364) (xy 407.510503 -49.201469) (xy 407.563005 -49.216965) (xy 407.612751 -49.239811)
			(xy 407.658719 -49.269535) (xy 407.679652 -49.287176) (xy 407.679906 -49.28743) (xy 407.686984 -49.293029)
			(xy 407.703908 -49.299267) (xy 407.712926 -49.299622) (xy 407.779982 -49.299622) (xy 407.788997 -49.299252)
			(xy 407.805914 -49.293013) (xy 407.813002 -49.28743) (xy 407.813002 -49.287176) (xy 407.813256 -49.287176)
			(xy 407.834189 -49.269535) (xy 407.880157 -49.239811) (xy 407.929903 -49.216965) (xy 407.982405 -49.201469)
			(xy 408.036583 -49.19364) (xy 408.091325 -49.19364) (xy 408.145503 -49.201469) (xy 408.198005 -49.216965)
			(xy 408.247751 -49.239811) (xy 408.293719 -49.269535) (xy 408.314652 -49.287176) (xy 408.314906 -49.28743)
			(xy 408.321984 -49.293029) (xy 408.338908 -49.299267) (xy 408.347926 -49.299622) (xy 408.414982 -49.299622)
			(xy 408.423997 -49.299252) (xy 408.440914 -49.293013) (xy 408.448002 -49.28743) (xy 408.448002 -49.287176)
			(xy 408.448256 -49.287176) (xy 408.469191 -49.26954) (xy 408.515163 -49.239829) (xy 408.56491 -49.216993)
			(xy 408.61741 -49.201501) (xy 408.671585 -49.193671) (xy 408.698954 -49.193196) (xy 408.726209 -49.193648)
			(xy 408.780166 -49.2014) (xy 408.83247 -49.216752) (xy 408.882056 -49.239392) (xy 408.927915 -49.268859)
			(xy 408.969114 -49.304553) (xy 409.004813 -49.345748) (xy 409.034286 -49.391603) (xy 409.056932 -49.441187)
			(xy 409.07229 -49.493489) (xy 409.080049 -49.547445) (xy 409.080049 -49.601955) (xy 409.07229 -49.655911)
			(xy 409.056932 -49.708213) (xy 409.034286 -49.757797) (xy 409.004813 -49.803652) (xy 408.969114 -49.844847)
			(xy 408.927915 -49.880541) (xy 408.882056 -49.910008) (xy 408.83247 -49.932648) (xy 408.780166 -49.948)
			(xy 408.726209 -49.955752) (xy 408.698954 -49.956212) (xy 408.671585 -49.955711) (xy 408.617408 -49.947901)
			(xy 408.564905 -49.93242) (xy 408.515158 -49.909586) (xy 408.469189 -49.87987) (xy 408.448256 -49.862232)
			(xy 408.448002 -49.861978) (xy 408.440921 -49.856384) (xy 408.424 -49.850142) (xy 408.414982 -49.849786)
			(xy 408.347926 -49.849786) (xy 408.338911 -49.850158) (xy 408.321994 -49.856396) (xy 408.314906 -49.861978)
			(xy 408.314652 -49.862232) (xy 408.293719 -49.879873) (xy 408.247751 -49.909597) (xy 408.198005 -49.932443)
			(xy 408.145503 -49.947939) (xy 408.091325 -49.955768) (xy 408.036583 -49.955768) (xy 407.982405 -49.947939)
			(xy 407.929903 -49.932443) (xy 407.880157 -49.909597) (xy 407.834189 -49.879873) (xy 407.813256 -49.862232)
			(xy 407.813002 -49.861978) (xy 407.805921 -49.856384) (xy 407.789 -49.850142) (xy 407.779982 -49.849786)
			(xy 407.712926 -49.849786) (xy 407.703911 -49.850158) (xy 407.686994 -49.856396) (xy 407.679906 -49.861978)
			(xy 407.679906 -49.862232) (xy 407.679652 -49.862232) (xy 407.658719 -49.879873) (xy 407.612751 -49.909597)
			(xy 407.563005 -49.932443) (xy 407.510503 -49.947939) (xy 407.456325 -49.955768) (xy 407.401583 -49.955768)
			(xy 407.347405 -49.947939) (xy 407.294903 -49.932443) (xy 407.245157 -49.909597) (xy 407.199189 -49.879873)
			(xy 407.178256 -49.862232) (xy 407.178002 -49.861978) (xy 407.170921 -49.856384) (xy 407.154 -49.850142)
			(xy 407.144982 -49.849786) (xy 407.077926 -49.849786) (xy 407.068911 -49.850158) (xy 407.051994 -49.856396)
			(xy 407.044906 -49.861978) (xy 407.044906 -49.862232) (xy 407.044652 -49.862232) (xy 407.023715 -49.879865)
			(xy 406.977743 -49.909577) (xy 406.927997 -49.932413) (xy 406.875497 -49.947906) (xy 406.821323 -49.955736)
			(xy 406.793954 -49.956212) (xy 406.766705 -49.955715) (xy 406.712763 -49.947953) (xy 406.660474 -49.932594)
			(xy 406.610903 -49.909951) (xy 406.565059 -49.880484) (xy 406.523875 -49.844792) (xy 406.488189 -49.803604)
			(xy 406.458727 -49.757756) (xy 406.43609 -49.708183) (xy 406.420737 -49.655892) (xy 406.412982 -49.601949)
			(xy 401.763429 -49.601949) (xy 401.789823 -49.613165) (xy 401.837429 -49.642219) (xy 401.880297 -49.677894)
			(xy 401.917514 -49.719431) (xy 401.948287 -49.765944) (xy 401.971959 -49.816441) (xy 401.988027 -49.869848)
			(xy 401.996147 -49.925024) (xy 401.996656 -49.95291) (xy 401.996147 -49.980796) (xy 401.988027 -50.035972)
			(xy 401.971959 -50.089379) (xy 401.948287 -50.139876) (xy 401.917514 -50.186389) (xy 401.880297 -50.227926)
			(xy 401.837429 -50.263601) (xy 401.789823 -50.292655) (xy 401.738494 -50.314467) (xy 401.684537 -50.328573)
			(xy 401.6291 -50.334673) (xy 401.573366 -50.332636) (xy 401.518523 -50.322506) (xy 401.465739 -50.304499)
			(xy 401.416139 -50.278998) (xy 401.370781 -50.246547) (xy 401.330632 -50.207838) (xy 401.296546 -50.163695)
			(xy 401.26925 -50.11506) (xy 401.249327 -50.062969) (xy 401.237201 -50.008532) (xy 401.23313 -49.95291)
			(xy 387.078728 -49.95291) (xy 387.078728 -51.019456) (xy 399.049492 -51.019456) (xy 399.053563 -50.963834)
			(xy 399.065689 -50.909397) (xy 399.085612 -50.857306) (xy 399.112908 -50.808671) (xy 399.146994 -50.764528)
			(xy 399.187143 -50.725819) (xy 399.232501 -50.693368) (xy 399.282101 -50.667867) (xy 399.334885 -50.64986)
			(xy 399.389728 -50.63973) (xy 399.445462 -50.637693) (xy 399.500899 -50.643793) (xy 399.554856 -50.657899)
			(xy 399.606185 -50.679711) (xy 399.653791 -50.708765) (xy 399.696659 -50.74444) (xy 399.733876 -50.785977)
			(xy 399.764649 -50.83249) (xy 399.788321 -50.882987) (xy 399.804389 -50.936394) (xy 399.812509 -50.99157)
			(xy 399.813018 -51.019456) (xy 399.812509 -51.047342) (xy 399.804389 -51.102518) (xy 399.788321 -51.155925)
			(xy 399.764649 -51.206422) (xy 399.739793 -51.243992) (xy 407.433018 -51.243992) (xy 407.433475 -51.216621)
			(xy 407.441294 -51.162442) (xy 407.456785 -51.109938) (xy 407.479629 -51.060192) (xy 407.509356 -51.014225)
			(xy 407.526998 -50.993294) (xy 407.527252 -50.99304) (xy 407.532834 -50.985951) (xy 407.539082 -50.969036)
			(xy 407.539444 -50.96002) (xy 407.539444 -50.892964) (xy 407.539117 -50.883944) (xy 407.53285 -50.867026)
			(xy 407.527252 -50.859944) (xy 407.526998 -50.859944) (xy 407.526998 -50.85969) (xy 407.50934 -50.838773)
			(xy 407.479631 -50.792796) (xy 407.456799 -50.743045) (xy 407.441312 -50.690541) (xy 407.433489 -50.636362)
			(xy 407.433018 -50.608992) (xy 407.433448 -50.581738) (xy 407.441207 -50.527784) (xy 407.456565 -50.475484)
			(xy 407.47921 -50.425902) (xy 407.508682 -50.380048) (xy 407.544379 -50.338855) (xy 407.585575 -50.303161)
			(xy 407.631432 -50.273694) (xy 407.681016 -50.251053) (xy 407.733318 -50.235699) (xy 407.787272 -50.227946)
			(xy 407.814526 -50.227484) (xy 407.843443 -50.228024) (xy 407.900614 -50.236744) (xy 407.955814 -50.253995)
			(xy 408.007776 -50.279383) (xy 408.055311 -50.312324) (xy 408.097326 -50.352065) (xy 408.115516 -50.37455)
			(xy 408.123117 -50.383363) (xy 408.144023 -50.393542) (xy 408.155648 -50.394108) (xy 408.235404 -50.394108)
			(xy 408.247034 -50.393554) (xy 408.267943 -50.383375) (xy 408.275536 -50.37455) (xy 408.293694 -50.352039)
			(xy 408.335722 -50.312308) (xy 408.383264 -50.279373) (xy 408.435232 -50.25399) (xy 408.490435 -50.236739)
			(xy 408.547608 -50.228016) (xy 408.576526 -50.227484) (xy 408.603778 -50.227954) (xy 408.657725 -50.235713)
			(xy 408.71002 -50.251071) (xy 408.759597 -50.273715) (xy 408.805447 -50.303183) (xy 408.846636 -50.338876)
			(xy 408.882328 -50.380068) (xy 408.911794 -50.425919) (xy 408.934435 -50.475497) (xy 408.94979 -50.527792)
			(xy 408.957548 -50.58174) (xy 408.958034 -50.608992) (xy 408.95755 -50.635305) (xy 408.950317 -50.687433)
			(xy 408.936001 -50.738075) (xy 408.914871 -50.786273) (xy 408.887329 -50.831117) (xy 408.853894 -50.871758)
			(xy 408.834844 -50.889916) (xy 408.82744 -50.897436) (xy 408.818916 -50.916717) (xy 408.818334 -50.927254)
			(xy 408.818334 -51.00193) (xy 408.818877 -51.012478) (xy 408.827401 -51.031774) (xy 408.834844 -51.039268)
			(xy 408.853934 -51.057389) (xy 408.887386 -51.098027) (xy 408.91494 -51.142875) (xy 408.936072 -51.191082)
			(xy 408.950382 -51.241735) (xy 408.957599 -51.293874) (xy 408.958034 -51.320192) (xy 408.957515 -51.347442)
			(xy 408.94976 -51.401387) (xy 408.934407 -51.45368) (xy 408.911769 -51.503255) (xy 408.882306 -51.549104)
			(xy 408.846618 -51.590294) (xy 408.805432 -51.625986) (xy 408.759585 -51.655453) (xy 408.710012 -51.678095)
			(xy 408.65772 -51.693453) (xy 408.603776 -51.701212) (xy 408.576526 -51.7017) (xy 408.548862 -51.701167)
			(xy 408.494113 -51.693172) (xy 408.441092 -51.677358) (xy 408.390908 -51.654059) (xy 408.344612 -51.623761)
			(xy 408.303174 -51.587098) (xy 408.26746 -51.54484) (xy 408.252422 -51.521614) (xy 408.245785 -51.511938)
			(xy 408.225924 -51.499495) (xy 408.214322 -51.497738) (xy 408.134312 -51.489864) (xy 408.122674 -51.489243)
			(xy 408.100837 -51.497315) (xy 408.092402 -51.505358) (xy 408.092148 -51.505612) (xy 408.074077 -51.524203)
			(xy 408.033742 -51.55678) (xy 407.989366 -51.583591) (xy 407.941766 -51.604142) (xy 407.89182 -51.618054)
			(xy 407.84045 -51.625069) (xy 407.814526 -51.6255) (xy 407.787273 -51.62502) (xy 407.733323 -51.617267)
			(xy 407.681025 -51.601914) (xy 407.631444 -51.579274) (xy 407.58559 -51.549808) (xy 407.544397 -51.514116)
			(xy 407.508703 -51.472924) (xy 407.479235 -51.427072) (xy 407.456593 -51.377492) (xy 407.441237 -51.325195)
			(xy 407.433481 -51.271245) (xy 407.433018 -51.243992) (xy 399.739793 -51.243992) (xy 399.733876 -51.252935)
			(xy 399.696659 -51.294472) (xy 399.653791 -51.330147) (xy 399.606185 -51.359201) (xy 399.554856 -51.381013)
			(xy 399.500899 -51.395119) (xy 399.445462 -51.401219) (xy 399.389728 -51.399182) (xy 399.334885 -51.389052)
			(xy 399.282101 -51.371045) (xy 399.232501 -51.345544) (xy 399.187143 -51.313093) (xy 399.146994 -51.274384)
			(xy 399.112908 -51.230241) (xy 399.085612 -51.181606) (xy 399.065689 -51.129515) (xy 399.053563 -51.075078)
			(xy 399.049492 -51.019456) (xy 387.078728 -51.019456) (xy 387.078728 -52.035456) (xy 401.241258 -52.035456)
			(xy 401.245329 -51.979834) (xy 401.257455 -51.925397) (xy 401.277378 -51.873306) (xy 401.304674 -51.824671)
			(xy 401.33876 -51.780528) (xy 401.378909 -51.741819) (xy 401.424267 -51.709368) (xy 401.473867 -51.683867)
			(xy 401.526651 -51.66586) (xy 401.581494 -51.65573) (xy 401.637228 -51.653693) (xy 401.692665 -51.659793)
			(xy 401.746622 -51.673899) (xy 401.797951 -51.695711) (xy 401.845557 -51.724765) (xy 401.888425 -51.76044)
			(xy 401.925642 -51.801977) (xy 401.956415 -51.84849) (xy 401.980087 -51.898987) (xy 401.996155 -51.952394)
			(xy 402.004275 -52.00757) (xy 402.004784 -52.035456) (xy 402.004275 -52.063342) (xy 401.996155 -52.118518)
			(xy 401.980087 -52.171925) (xy 401.956415 -52.222422) (xy 401.925642 -52.268935) (xy 401.888425 -52.310472)
			(xy 401.845557 -52.346147) (xy 401.797951 -52.375201) (xy 401.746622 -52.397013) (xy 401.692665 -52.411119)
			(xy 401.637228 -52.417219) (xy 401.581494 -52.415182) (xy 401.526651 -52.405052) (xy 401.473867 -52.387045)
			(xy 401.424267 -52.361544) (xy 401.378909 -52.329093) (xy 401.33876 -52.290384) (xy 401.304674 -52.246241)
			(xy 401.277378 -52.197606) (xy 401.257455 -52.145515) (xy 401.245329 -52.091078) (xy 401.241258 -52.035456)
			(xy 387.078728 -52.035456) (xy 387.078728 -54.731412) (xy 387.820662 -54.731412) (xy 387.82112 -54.704041)
			(xy 387.828937 -54.649861) (xy 387.844428 -54.597357) (xy 387.867272 -54.547611) (xy 387.896999 -54.501645)
			(xy 387.914642 -54.480714) (xy 387.914896 -54.48046) (xy 387.920463 -54.47336) (xy 387.926722 -54.456454)
			(xy 387.927088 -54.44744) (xy 387.927088 -54.380384) (xy 387.926741 -54.371366) (xy 387.920487 -54.354449)
			(xy 387.914896 -54.347364) (xy 387.914642 -54.347364) (xy 387.914642 -54.34711) (xy 387.897012 -54.326168)
			(xy 387.867286 -54.280202) (xy 387.844439 -54.230458) (xy 387.828941 -54.177957) (xy 387.821111 -54.123779)
			(xy 387.82111 -54.069039) (xy 387.828937 -54.014861) (xy 387.844433 -53.962359) (xy 387.867277 -53.912614)
			(xy 387.897002 -53.866646) (xy 387.914642 -53.845714) (xy 387.914896 -53.84546) (xy 387.920463 -53.83836)
			(xy 387.926722 -53.821454) (xy 387.927088 -53.81244) (xy 387.927088 -53.745384) (xy 387.926741 -53.736366)
			(xy 387.920487 -53.719449) (xy 387.914896 -53.712364) (xy 387.914642 -53.712364) (xy 387.914642 -53.71211)
			(xy 387.897012 -53.691168) (xy 387.867286 -53.645202) (xy 387.844439 -53.595458) (xy 387.828941 -53.542957)
			(xy 387.821111 -53.488779) (xy 387.82111 -53.434039) (xy 387.828937 -53.379861) (xy 387.844433 -53.327359)
			(xy 387.867277 -53.277614) (xy 387.897002 -53.231646) (xy 387.914642 -53.210714) (xy 387.914896 -53.21046)
			(xy 387.920463 -53.20336) (xy 387.926722 -53.186454) (xy 387.927088 -53.17744) (xy 387.927088 -53.110384)
			(xy 387.926741 -53.101366) (xy 387.920487 -53.084449) (xy 387.914896 -53.077364) (xy 387.914642 -53.077364)
			(xy 387.914642 -53.07711) (xy 387.897001 -53.05618) (xy 387.867288 -53.010207) (xy 387.844452 -52.960459)
			(xy 387.828961 -52.907958) (xy 387.821135 -52.853781) (xy 387.820662 -52.826412) (xy 387.821148 -52.799161)
			(xy 387.828904 -52.745213) (xy 387.844259 -52.692918) (xy 387.866901 -52.643341) (xy 387.896367 -52.597491)
			(xy 387.932058 -52.5563) (xy 387.973249 -52.520609) (xy 388.019099 -52.491143) (xy 388.068676 -52.468501)
			(xy 388.120971 -52.453146) (xy 388.174919 -52.44539) (xy 388.229421 -52.44539) (xy 388.283369 -52.453146)
			(xy 388.335664 -52.468501) (xy 388.385241 -52.491143) (xy 388.431091 -52.520609) (xy 388.472282 -52.5563)
			(xy 388.507973 -52.597491) (xy 388.537439 -52.643341) (xy 388.560081 -52.692918) (xy 388.575436 -52.745213)
			(xy 388.583192 -52.799161) (xy 388.583678 -52.826412) (xy 388.583224 -52.853783) (xy 388.575404 -52.907963)
			(xy 388.559913 -52.960466) (xy 388.537068 -53.010213) (xy 388.507341 -53.056179) (xy 388.489698 -53.07711)
			(xy 388.489444 -53.077364) (xy 388.48386 -53.084452) (xy 388.477613 -53.101368) (xy 388.477252 -53.110384)
			(xy 388.477252 -53.17744) (xy 388.477578 -53.18646) (xy 388.483846 -53.203378) (xy 388.489444 -53.21046)
			(xy 388.489698 -53.21046) (xy 388.489698 -53.210714) (xy 388.507349 -53.231638) (xy 388.537072 -53.277608)
			(xy 388.559915 -53.327356) (xy 388.575409 -53.379859) (xy 388.583236 -53.434038) (xy 388.583235 -53.48878)
			(xy 388.575405 -53.542959) (xy 388.559909 -53.595461) (xy 388.537063 -53.645208) (xy 388.507338 -53.691177)
			(xy 388.489698 -53.71211) (xy 388.489444 -53.712364) (xy 388.48386 -53.719452) (xy 388.477613 -53.736368)
			(xy 388.477252 -53.745384) (xy 388.477252 -53.81244) (xy 388.477578 -53.82146) (xy 388.483846 -53.838378)
			(xy 388.489444 -53.84546) (xy 388.489698 -53.84546) (xy 388.489698 -53.845714) (xy 388.507349 -53.866638)
			(xy 388.537072 -53.912608) (xy 388.559915 -53.962356) (xy 388.575409 -54.014859) (xy 388.583236 -54.069038)
			(xy 388.583235 -54.12378) (xy 388.575405 -54.177959) (xy 388.559909 -54.230461) (xy 388.537063 -54.280208)
			(xy 388.507338 -54.326177) (xy 388.489698 -54.34711) (xy 388.489444 -54.347364) (xy 388.48386 -54.354452)
			(xy 388.477613 -54.371368) (xy 388.477252 -54.380384) (xy 388.477252 -54.44744) (xy 388.477578 -54.45646)
			(xy 388.483846 -54.473378) (xy 388.489444 -54.48046) (xy 388.489698 -54.48046) (xy 388.489698 -54.480714)
			(xy 388.50731 -54.501668) (xy 388.537026 -54.547635) (xy 388.559867 -54.597377) (xy 388.575365 -54.649872)
			(xy 388.5832 -54.704044) (xy 388.583678 -54.731412) (xy 388.583192 -54.758663) (xy 388.578528 -54.791102)
			(xy 390.476486 -54.791102) (xy 390.476957 -54.763732) (xy 390.484774 -54.709553) (xy 390.500262 -54.65705)
			(xy 390.523103 -54.607303) (xy 390.552826 -54.561336) (xy 390.570466 -54.540404) (xy 390.57072 -54.54015)
			(xy 390.576294 -54.533055) (xy 390.582548 -54.516145) (xy 390.582912 -54.50713) (xy 390.582912 -54.440074)
			(xy 390.582565 -54.431056) (xy 390.57631 -54.41414) (xy 390.57072 -54.407054) (xy 390.570466 -54.407054)
			(xy 390.570466 -54.4068) (xy 390.552826 -54.385866) (xy 390.523098 -54.3399) (xy 390.50025 -54.290154)
			(xy 390.484752 -54.237652) (xy 390.476922 -54.183472) (xy 390.476922 -54.128731) (xy 390.484751 -54.074551)
			(xy 390.500249 -54.022049) (xy 390.523096 -53.972303) (xy 390.552824 -53.926336) (xy 390.570466 -53.905404)
			(xy 390.57072 -53.90515) (xy 390.576294 -53.898055) (xy 390.582548 -53.881145) (xy 390.582912 -53.87213)
			(xy 390.582912 -53.805074) (xy 390.582565 -53.796056) (xy 390.57631 -53.77914) (xy 390.57072 -53.772054)
			(xy 390.570466 -53.772054) (xy 390.570466 -53.7718) (xy 390.552826 -53.750866) (xy 390.523098 -53.7049)
			(xy 390.50025 -53.655154) (xy 390.484752 -53.602652) (xy 390.476922 -53.548472) (xy 390.476922 -53.493731)
			(xy 390.484751 -53.439551) (xy 390.500249 -53.387049) (xy 390.523096 -53.337303) (xy 390.552824 -53.291336)
			(xy 390.570466 -53.270404) (xy 390.57072 -53.27015) (xy 390.576294 -53.263055) (xy 390.582548 -53.246145)
			(xy 390.582912 -53.23713) (xy 390.582912 -53.170074) (xy 390.582565 -53.161056) (xy 390.57631 -53.14414)
			(xy 390.57072 -53.137054) (xy 390.570466 -53.137054) (xy 390.570466 -53.1368) (xy 390.552808 -53.115883)
			(xy 390.5231 -53.069906) (xy 390.500269 -53.020154) (xy 390.484782 -52.96765) (xy 390.476958 -52.913472)
			(xy 390.476486 -52.886102) (xy 390.476972 -52.858851) (xy 390.484728 -52.804903) (xy 390.500083 -52.752608)
			(xy 390.522725 -52.703031) (xy 390.552191 -52.657181) (xy 390.587882 -52.61599) (xy 390.629073 -52.580299)
			(xy 390.674923 -52.550833) (xy 390.7245 -52.528191) (xy 390.776795 -52.512836) (xy 390.830743 -52.50508)
			(xy 390.885245 -52.50508) (xy 390.939193 -52.512836) (xy 390.991488 -52.528191) (xy 391.030588 -52.546048)
			(xy 395.979696 -52.546048) (xy 395.979696 -52.491552) (xy 395.987451 -52.437612) (xy 396.002803 -52.385323)
			(xy 396.025439 -52.335752) (xy 396.054899 -52.289906) (xy 396.090584 -52.248719) (xy 396.131766 -52.213029)
			(xy 396.177608 -52.183563) (xy 396.227176 -52.16092) (xy 396.279463 -52.145562) (xy 396.333402 -52.1378)
			(xy 396.36065 -52.13731) (xy 396.388019 -52.137803) (xy 396.442197 -52.145614) (xy 396.4947 -52.161097)
			(xy 396.544448 -52.183932) (xy 396.590415 -52.213651) (xy 396.611348 -52.23129) (xy 396.611602 -52.231544)
			(xy 396.61868 -52.237143) (xy 396.635604 -52.243381) (xy 396.644622 -52.243736) (xy 396.711678 -52.243736)
			(xy 396.720693 -52.243361) (xy 396.737609 -52.237125) (xy 396.744698 -52.231544) (xy 396.744698 -52.23129)
			(xy 396.744952 -52.23129) (xy 396.765885 -52.213649) (xy 396.811853 -52.183925) (xy 396.861599 -52.161079)
			(xy 396.914101 -52.145583) (xy 396.968279 -52.137754) (xy 397.023021 -52.137754) (xy 397.077199 -52.145583)
			(xy 397.129701 -52.161079) (xy 397.179447 -52.183925) (xy 397.225415 -52.213649) (xy 397.246348 -52.23129)
			(xy 397.246602 -52.231544) (xy 397.25368 -52.237143) (xy 397.270604 -52.243381) (xy 397.279622 -52.243736)
			(xy 397.346678 -52.243736) (xy 397.355693 -52.243361) (xy 397.372609 -52.237125) (xy 397.379698 -52.231544)
			(xy 397.379698 -52.23129) (xy 397.379952 -52.23129) (xy 397.40089 -52.213658) (xy 397.446861 -52.183946)
			(xy 397.496607 -52.161109) (xy 397.549107 -52.145616) (xy 397.603281 -52.137785) (xy 397.63065 -52.13731)
			(xy 397.657906 -52.137733) (xy 397.711865 -52.145485) (xy 397.764172 -52.160837) (xy 397.813761 -52.183478)
			(xy 397.859622 -52.212946) (xy 397.900823 -52.248642) (xy 397.936524 -52.289838) (xy 397.965998 -52.335695)
			(xy 397.988645 -52.385281) (xy 398.004004 -52.437586) (xy 398.011763 -52.491544) (xy 398.011763 -52.546056)
			(xy 398.005818 -52.587398) (xy 399.055334 -52.587398) (xy 399.059405 -52.531776) (xy 399.071531 -52.477339)
			(xy 399.091454 -52.425248) (xy 399.11875 -52.376613) (xy 399.152836 -52.33247) (xy 399.192985 -52.293761)
			(xy 399.238343 -52.26131) (xy 399.287943 -52.235809) (xy 399.340727 -52.217802) (xy 399.39557 -52.207672)
			(xy 399.451304 -52.205635) (xy 399.506741 -52.211735) (xy 399.560698 -52.225841) (xy 399.612027 -52.247653)
			(xy 399.659633 -52.276707) (xy 399.702501 -52.312382) (xy 399.739718 -52.353919) (xy 399.770491 -52.400432)
			(xy 399.794163 -52.450929) (xy 399.810231 -52.504336) (xy 399.817827 -52.555948) (xy 406.883902 -52.555948)
			(xy 406.883902 -52.501452) (xy 406.891657 -52.44751) (xy 406.90701 -52.395221) (xy 406.929647 -52.345649)
			(xy 406.959109 -52.299803) (xy 406.994795 -52.258616) (xy 407.035979 -52.222927) (xy 407.081823 -52.193462)
			(xy 407.131393 -52.17082) (xy 407.183681 -52.155464) (xy 407.237622 -52.147704) (xy 407.26487 -52.147216)
			(xy 407.29224 -52.147696) (xy 407.346418 -52.15551) (xy 407.398922 -52.170995) (xy 407.448669 -52.193834)
			(xy 407.494636 -52.223556) (xy 407.515568 -52.241196) (xy 407.515822 -52.24145) (xy 407.522894 -52.247058)
			(xy 407.539822 -52.253291) (xy 407.548842 -52.253642) (xy 407.615898 -52.253642) (xy 407.624916 -52.253296)
			(xy 407.641834 -52.247042) (xy 407.648918 -52.24145) (xy 407.648918 -52.241196) (xy 407.649172 -52.241196)
			(xy 407.670103 -52.223556) (xy 407.716076 -52.193844) (xy 407.765824 -52.171009) (xy 407.818325 -52.155518)
			(xy 407.872501 -52.14769) (xy 407.89987 -52.147216) (xy 407.927126 -52.147629) (xy 407.981084 -52.155383)
			(xy 408.033388 -52.170737) (xy 408.082976 -52.19338) (xy 408.128835 -52.222849) (xy 408.170034 -52.258545)
			(xy 408.205733 -52.299741) (xy 408.235206 -52.345598) (xy 408.257852 -52.395183) (xy 408.273211 -52.447487)
			(xy 408.280969 -52.501444) (xy 408.280969 -52.555956) (xy 408.273211 -52.609913) (xy 408.257852 -52.662217)
			(xy 408.235206 -52.711802) (xy 408.205733 -52.757659) (xy 408.170034 -52.798855) (xy 408.128835 -52.834551)
			(xy 408.082976 -52.86402) (xy 408.033388 -52.886663) (xy 407.981084 -52.902017) (xy 407.927126 -52.909771)
			(xy 407.89987 -52.910232) (xy 407.872498 -52.9098) (xy 407.818317 -52.901977) (xy 407.765813 -52.88648)
			(xy 407.716067 -52.863631) (xy 407.670102 -52.833898) (xy 407.649172 -52.816252) (xy 407.648918 -52.815998)
			(xy 407.641831 -52.810413) (xy 407.624914 -52.804165) (xy 407.615898 -52.803806) (xy 407.548842 -52.803806)
			(xy 407.539827 -52.804182) (xy 407.52291 -52.810416) (xy 407.515822 -52.815998) (xy 407.515822 -52.816252)
			(xy 407.515568 -52.816252) (xy 407.494615 -52.833865) (xy 407.448649 -52.863583) (xy 407.398907 -52.886424)
			(xy 407.34641 -52.901921) (xy 407.292238 -52.909755) (xy 407.26487 -52.910232) (xy 407.237622 -52.909696)
			(xy 407.183681 -52.901936) (xy 407.131393 -52.88658) (xy 407.081823 -52.863938) (xy 407.035979 -52.834473)
			(xy 406.994795 -52.798784) (xy 406.959109 -52.757597) (xy 406.929647 -52.711751) (xy 406.90701 -52.662179)
			(xy 406.891657 -52.60989) (xy 406.883902 -52.555948) (xy 399.817827 -52.555948) (xy 399.818351 -52.559512)
			(xy 399.81886 -52.587398) (xy 399.818351 -52.615284) (xy 399.810231 -52.67046) (xy 399.794163 -52.723867)
			(xy 399.770491 -52.774364) (xy 399.739718 -52.820877) (xy 399.702501 -52.862414) (xy 399.659633 -52.898089)
			(xy 399.612027 -52.927143) (xy 399.560698 -52.948955) (xy 399.506741 -52.963061) (xy 399.451304 -52.969161)
			(xy 399.39557 -52.967124) (xy 399.340727 -52.956994) (xy 399.287943 -52.938987) (xy 399.238343 -52.913486)
			(xy 399.192985 -52.881035) (xy 399.152836 -52.842326) (xy 399.11875 -52.798183) (xy 399.091454 -52.749548)
			(xy 399.071531 -52.697457) (xy 399.059405 -52.64302) (xy 399.055334 -52.587398) (xy 398.005818 -52.587398)
			(xy 398.004004 -52.600014) (xy 397.988645 -52.652319) (xy 397.965998 -52.701905) (xy 397.936524 -52.747762)
			(xy 397.900823 -52.788958) (xy 397.859622 -52.824654) (xy 397.813761 -52.854122) (xy 397.764172 -52.876763)
			(xy 397.711865 -52.892115) (xy 397.657907 -52.899867) (xy 397.63065 -52.900326) (xy 397.60328 -52.899849)
			(xy 397.549101 -52.892036) (xy 397.496597 -52.876551) (xy 397.44685 -52.853711) (xy 397.400883 -52.823987)
			(xy 397.379952 -52.806346) (xy 397.379698 -52.806092) (xy 397.372617 -52.800498) (xy 397.355696 -52.794256)
			(xy 397.346678 -52.7939) (xy 397.279622 -52.7939) (xy 397.270606 -52.794267) (xy 397.253689 -52.800508)
			(xy 397.246602 -52.806092) (xy 397.246348 -52.806346) (xy 397.225415 -52.823987) (xy 397.179447 -52.853711)
			(xy 397.129701 -52.876557) (xy 397.077199 -52.892053) (xy 397.023021 -52.899882) (xy 396.968279 -52.899882)
			(xy 396.914101 -52.892053) (xy 396.861599 -52.876557) (xy 396.811853 -52.853711) (xy 396.765885 -52.823987)
			(xy 396.744952 -52.806346) (xy 396.744698 -52.806092) (xy 396.737617 -52.800498) (xy 396.720696 -52.794256)
			(xy 396.711678 -52.7939) (xy 396.644622 -52.7939) (xy 396.635606 -52.794267) (xy 396.618689 -52.800508)
			(xy 396.611602 -52.806092) (xy 396.611602 -52.806346) (xy 396.611348 -52.806346) (xy 396.590402 -52.823968)
			(xy 396.544434 -52.853684) (xy 396.49469 -52.876524) (xy 396.442192 -52.892019) (xy 396.388018 -52.899851)
			(xy 396.36065 -52.900326) (xy 396.333402 -52.8998) (xy 396.279463 -52.892038) (xy 396.227176 -52.87668)
			(xy 396.177608 -52.854037) (xy 396.131766 -52.824571) (xy 396.090584 -52.788881) (xy 396.054899 -52.747694)
			(xy 396.025439 -52.701848) (xy 396.002803 -52.652277) (xy 395.987451 -52.599988) (xy 395.979696 -52.546048)
			(xy 391.030588 -52.546048) (xy 391.041065 -52.550833) (xy 391.086915 -52.580299) (xy 391.128106 -52.61599)
			(xy 391.163797 -52.657181) (xy 391.193263 -52.703031) (xy 391.215905 -52.752608) (xy 391.23126 -52.804903)
			(xy 391.239016 -52.858851) (xy 391.239502 -52.886102) (xy 391.239037 -52.913472) (xy 391.231219 -52.967651)
			(xy 391.215729 -53.020154) (xy 391.192887 -53.069901) (xy 391.163163 -53.115868) (xy 391.145522 -53.1368)
			(xy 391.145268 -53.137054) (xy 391.139691 -53.144147) (xy 391.13344 -53.161059) (xy 391.133076 -53.170074)
			(xy 391.133076 -53.23713) (xy 391.133424 -53.246148) (xy 391.139678 -53.263064) (xy 391.145268 -53.27015)
			(xy 391.145522 -53.27015) (xy 391.145522 -53.270404) (xy 391.163163 -53.291336) (xy 391.192884 -53.337305)
			(xy 391.215726 -53.387052) (xy 391.23122 -53.439554) (xy 391.239047 -53.493731) (xy 391.239047 -53.548472)
			(xy 391.231219 -53.602649) (xy 391.215725 -53.655151) (xy 391.192882 -53.704897) (xy 391.163161 -53.750866)
			(xy 391.146592 -53.77053) (xy 391.510774 -53.77053) (xy 391.511286 -53.741612) (xy 391.520012 -53.68444)
			(xy 391.537269 -53.62924) (xy 391.562662 -53.577277) (xy 391.595608 -53.529744) (xy 391.635353 -53.487729)
			(xy 391.65784 -53.46954) (xy 391.666626 -53.461912) (xy 391.676819 -53.441027) (xy 391.677398 -53.429408)
			(xy 391.677398 -53.349652) (xy 391.676873 -53.338018) (xy 391.666674 -53.317109) (xy 391.65784 -53.30952)
			(xy 391.635374 -53.291308) (xy 391.595636 -53.249293) (xy 391.562694 -53.201763) (xy 391.537302 -53.149806)
			(xy 391.520043 -53.094612) (xy 391.51131 -53.037445) (xy 391.510774 -53.00853) (xy 391.511283 -52.981279)
			(xy 391.519036 -52.92733) (xy 391.534387 -52.875034) (xy 391.557025 -52.825456) (xy 391.586488 -52.779603)
			(xy 391.622177 -52.738411) (xy 391.663365 -52.702717) (xy 391.709213 -52.673248) (xy 391.758789 -52.650604)
			(xy 391.811083 -52.635246) (xy 391.865031 -52.627487) (xy 391.892282 -52.627022) (xy 391.918596 -52.627494)
			(xy 391.970724 -52.634727) (xy 392.021367 -52.649045) (xy 392.069567 -52.670176) (xy 392.11441 -52.697722)
			(xy 392.15505 -52.73116) (xy 392.173206 -52.750212) (xy 392.180722 -52.75762) (xy 392.200006 -52.766141)
			(xy 392.210544 -52.766722) (xy 392.28522 -52.766722) (xy 392.295765 -52.766157) (xy 392.315061 -52.757646)
			(xy 392.322558 -52.750212) (xy 392.340695 -52.731138) (xy 392.381328 -52.697682) (xy 392.426172 -52.670125)
			(xy 392.474377 -52.64899) (xy 392.525028 -52.634677) (xy 392.577165 -52.627457) (xy 392.603482 -52.627022)
			(xy 392.630736 -52.627472) (xy 392.684689 -52.635227) (xy 392.736989 -52.650583) (xy 392.786571 -52.673225)
			(xy 392.832425 -52.702694) (xy 392.873619 -52.738389) (xy 392.909313 -52.779584) (xy 392.93878 -52.82544)
			(xy 392.961421 -52.875023) (xy 392.976775 -52.927323) (xy 392.984529 -52.981276) (xy 392.98499 -53.00853)
			(xy 392.984506 -53.036196) (xy 392.976502 -53.090947) (xy 392.960681 -53.143969) (xy 392.937373 -53.194154)
			(xy 392.907068 -53.240449) (xy 392.870398 -53.281886) (xy 392.828133 -53.317598) (xy 392.804904 -53.332634)
			(xy 392.795223 -53.339267) (xy 392.782779 -53.35913) (xy 392.781028 -53.370734) (xy 392.773154 -53.450744)
			(xy 392.772501 -53.462383) (xy 392.780596 -53.484222) (xy 392.788648 -53.492654) (xy 392.788902 -53.492908)
			(xy 392.80747 -53.511002) (xy 392.840049 -53.551331) (xy 392.866864 -53.595703) (xy 392.887419 -53.643299)
			(xy 392.901335 -53.693241) (xy 392.908356 -53.744608) (xy 392.90879 -53.77053) (xy 392.90835 -53.797783)
			(xy 392.900589 -53.851733) (xy 392.885229 -53.90403) (xy 392.862583 -53.953608) (xy 392.833112 -53.999459)
			(xy 392.797416 -54.04065) (xy 392.756221 -54.076341) (xy 392.710366 -54.105806) (xy 392.660785 -54.128446)
			(xy 392.608486 -54.143799) (xy 392.554535 -54.151553) (xy 392.527282 -54.152038) (xy 392.499911 -54.151598)
			(xy 392.44573 -54.143776) (xy 392.393226 -54.128282) (xy 392.343479 -54.105434) (xy 392.297514 -54.075703)
			(xy 392.276584 -54.058058) (xy 392.27633 -54.057804) (xy 392.269239 -54.052224) (xy 392.252326 -54.045973)
			(xy 392.24331 -54.045612) (xy 392.176254 -54.045612) (xy 392.167239 -54.045992) (xy 392.150322 -54.052224)
			(xy 392.143234 -54.057804) (xy 392.143234 -54.058058) (xy 392.14298 -54.058058) (xy 392.122023 -54.075667)
			(xy 392.076058 -54.105384) (xy 392.026317 -54.128227) (xy 391.973821 -54.143725) (xy 391.91965 -54.15156)
			(xy 391.892282 -54.152038) (xy 391.865032 -54.151539) (xy 391.811086 -54.143781) (xy 391.758793 -54.128425)
			(xy 391.709218 -54.105784) (xy 391.663369 -54.076319) (xy 391.62218 -54.040629) (xy 391.586489 -53.99944)
			(xy 391.557022 -53.953593) (xy 391.534379 -53.904018) (xy 391.519022 -53.851726) (xy 391.511262 -53.79778)
			(xy 391.510774 -53.77053) (xy 391.146592 -53.77053) (xy 391.145522 -53.7718) (xy 391.145268 -53.772054)
			(xy 391.139691 -53.779147) (xy 391.13344 -53.796059) (xy 391.133076 -53.805074) (xy 391.133076 -53.87213)
			(xy 391.133424 -53.881148) (xy 391.139678 -53.898064) (xy 391.145268 -53.90515) (xy 391.145522 -53.90515)
			(xy 391.145522 -53.905404) (xy 391.163163 -53.926336) (xy 391.192884 -53.972305) (xy 391.215726 -54.022052)
			(xy 391.23122 -54.074554) (xy 391.239047 -54.128731) (xy 391.239047 -54.183472) (xy 391.231219 -54.237649)
			(xy 391.215725 -54.290151) (xy 391.201933 -54.320186) (xy 393.430506 -54.320186) (xy 393.430962 -54.292815)
			(xy 393.438782 -54.238636) (xy 393.454274 -54.186133) (xy 393.477117 -54.136386) (xy 393.506844 -54.090419)
			(xy 393.524486 -54.069488) (xy 393.52474 -54.069234) (xy 393.530323 -54.062145) (xy 393.536571 -54.04523)
			(xy 393.536932 -54.036214) (xy 393.536932 -53.969158) (xy 393.53654 -53.960145) (xy 393.530316 -53.943228)
			(xy 393.52474 -53.936138) (xy 393.524486 -53.936138) (xy 393.524486 -53.935884) (xy 393.506871 -53.914933)
			(xy 393.477156 -53.868965) (xy 393.454315 -53.819222) (xy 393.438819 -53.766726) (xy 393.430984 -53.712554)
			(xy 393.430506 -53.685186) (xy 393.430992 -53.657935) (xy 393.438748 -53.603987) (xy 393.454103 -53.551692)
			(xy 393.476745 -53.502115) (xy 393.506211 -53.456265) (xy 393.541902 -53.415074) (xy 393.583093 -53.379383)
			(xy 393.628943 -53.349917) (xy 393.67852 -53.327275) (xy 393.730815 -53.31192) (xy 393.784763 -53.304164)
			(xy 393.839265 -53.304164) (xy 393.893213 -53.31192) (xy 393.945508 -53.327275) (xy 393.995085 -53.349917)
			(xy 394.040935 -53.379383) (xy 394.082126 -53.415074) (xy 394.117817 -53.456265) (xy 394.147283 -53.502115)
			(xy 394.169925 -53.551692) (xy 394.18528 -53.603987) (xy 394.193036 -53.657935) (xy 394.193522 -53.685186)
			(xy 394.193067 -53.712557) (xy 394.185249 -53.766737) (xy 394.169759 -53.819241) (xy 394.146914 -53.868988)
			(xy 394.117186 -53.914953) (xy 394.099542 -53.935884) (xy 394.099288 -53.936138) (xy 394.09372 -53.943237)
			(xy 394.087462 -53.960144) (xy 394.087096 -53.969158) (xy 394.087096 -54.036214) (xy 394.087447 -54.045231)
			(xy 394.093699 -54.062148) (xy 394.099288 -54.069234) (xy 394.099542 -54.069234) (xy 394.099542 -54.069488)
			(xy 394.117196 -54.090408) (xy 394.146904 -54.136385) (xy 394.169737 -54.186135) (xy 394.185225 -54.238639)
			(xy 394.19305 -54.292816) (xy 394.193522 -54.320186) (xy 394.193036 -54.347437) (xy 394.18528 -54.401385)
			(xy 394.169925 -54.45368) (xy 394.147283 -54.503257) (xy 394.117817 -54.549107) (xy 394.082126 -54.590298)
			(xy 394.040935 -54.625989) (xy 393.995085 -54.655455) (xy 393.945508 -54.678097) (xy 393.893213 -54.693452)
			(xy 393.839265 -54.701208) (xy 393.784763 -54.701208) (xy 393.730815 -54.693452) (xy 393.67852 -54.678097)
			(xy 393.628943 -54.655455) (xy 393.583093 -54.625989) (xy 393.541902 -54.590298) (xy 393.506211 -54.549107)
			(xy 393.476745 -54.503257) (xy 393.454103 -54.45368) (xy 393.438748 -54.401385) (xy 393.430992 -54.347437)
			(xy 393.430506 -54.320186) (xy 391.201933 -54.320186) (xy 391.192882 -54.339897) (xy 391.163161 -54.385866)
			(xy 391.145522 -54.4068) (xy 391.145268 -54.407054) (xy 391.139691 -54.414147) (xy 391.13344 -54.431059)
			(xy 391.133076 -54.440074) (xy 391.133076 -54.50713) (xy 391.133424 -54.516148) (xy 391.139678 -54.533064)
			(xy 391.145268 -54.54015) (xy 391.145522 -54.54015) (xy 391.145522 -54.540404) (xy 391.16318 -54.561321)
			(xy 391.192888 -54.607298) (xy 391.21572 -54.65705) (xy 391.231207 -54.709554) (xy 391.23903 -54.763732)
			(xy 391.239147 -54.770528) (xy 394.371068 -54.770528) (xy 394.371534 -54.743158) (xy 394.379349 -54.688978)
			(xy 394.394837 -54.636474) (xy 394.41768 -54.586727) (xy 394.447406 -54.540761) (xy 394.465048 -54.51983)
			(xy 394.465302 -54.519576) (xy 394.470905 -54.512501) (xy 394.477142 -54.495575) (xy 394.477494 -54.486556)
			(xy 394.477494 -54.4195) (xy 394.477138 -54.410483) (xy 394.47089 -54.393566) (xy 394.465302 -54.38648)
			(xy 394.465048 -54.38648) (xy 394.465048 -54.386226) (xy 394.447415 -54.365289) (xy 394.417701 -54.319318)
			(xy 394.394863 -54.269572) (xy 394.37937 -54.217072) (xy 394.371542 -54.162897) (xy 394.371068 -54.135528)
			(xy 394.371554 -54.108277) (xy 394.37931 -54.054329) (xy 394.394665 -54.002034) (xy 394.417307 -53.952457)
			(xy 394.446773 -53.906607) (xy 394.482464 -53.865416) (xy 394.523655 -53.829725) (xy 394.569505 -53.800259)
			(xy 394.619082 -53.777617) (xy 394.671377 -53.762262) (xy 394.725325 -53.754506) (xy 394.779827 -53.754506)
			(xy 394.833775 -53.762262) (xy 394.88607 -53.777617) (xy 394.935647 -53.800259) (xy 394.981497 -53.829725)
			(xy 395.022688 -53.865416) (xy 395.058379 -53.906607) (xy 395.087845 -53.952457) (xy 395.09292 -53.96357)
			(xy 399.072098 -53.96357) (xy 399.076169 -53.907948) (xy 399.088295 -53.853511) (xy 399.108218 -53.80142)
			(xy 399.135514 -53.752785) (xy 399.1696 -53.708642) (xy 399.209749 -53.669933) (xy 399.255107 -53.637482)
			(xy 399.304707 -53.611981) (xy 399.357491 -53.593974) (xy 399.412334 -53.583844) (xy 399.468068 -53.581807)
			(xy 399.523505 -53.587907) (xy 399.577462 -53.602013) (xy 399.628791 -53.623825) (xy 399.676397 -53.652879)
			(xy 399.719265 -53.688554) (xy 399.756482 -53.730091) (xy 399.787255 -53.776604) (xy 399.810927 -53.827101)
			(xy 399.826995 -53.880508) (xy 399.835115 -53.935684) (xy 399.835624 -53.96357) (xy 399.835115 -53.991456)
			(xy 399.826995 -54.046632) (xy 399.810927 -54.100039) (xy 399.787255 -54.150536) (xy 399.756482 -54.197049)
			(xy 399.719265 -54.238586) (xy 399.676397 -54.274261) (xy 399.628791 -54.303315) (xy 399.577462 -54.325127)
			(xy 399.523505 -54.339233) (xy 399.468068 -54.345333) (xy 399.412334 -54.343296) (xy 399.357491 -54.333166)
			(xy 399.304707 -54.315159) (xy 399.255107 -54.289658) (xy 399.209749 -54.257207) (xy 399.1696 -54.218498)
			(xy 399.135514 -54.174355) (xy 399.108218 -54.12572) (xy 399.088295 -54.073629) (xy 399.076169 -54.019192)
			(xy 399.072098 -53.96357) (xy 395.09292 -53.96357) (xy 395.110487 -54.002034) (xy 395.125842 -54.054329)
			(xy 395.133598 -54.108277) (xy 395.134084 -54.135528) (xy 395.133638 -54.162899) (xy 395.125816 -54.217079)
			(xy 395.110322 -54.269583) (xy 395.087476 -54.319329) (xy 395.057747 -54.365295) (xy 395.040104 -54.386226)
			(xy 395.03985 -54.38648) (xy 395.03426 -54.393564) (xy 395.028016 -54.410483) (xy 395.027658 -54.4195)
			(xy 395.027658 -54.486556) (xy 395.028023 -54.495572) (xy 395.034264 -54.51249) (xy 395.03985 -54.519576)
			(xy 395.040104 -54.519576) (xy 395.040104 -54.51983) (xy 395.057724 -54.540777) (xy 395.087439 -54.586746)
			(xy 395.110278 -54.63649) (xy 395.125774 -54.688987) (xy 395.133607 -54.74316) (xy 395.134084 -54.770528)
			(xy 395.133598 -54.797779) (xy 395.125842 -54.851727) (xy 395.110487 -54.904022) (xy 395.087845 -54.953599)
			(xy 395.058379 -54.999449) (xy 395.022688 -55.04064) (xy 394.981497 -55.076331) (xy 394.935647 -55.105797)
			(xy 394.88607 -55.128439) (xy 394.833775 -55.143794) (xy 394.779827 -55.15155) (xy 394.725325 -55.15155)
			(xy 394.671377 -55.143794) (xy 394.619082 -55.128439) (xy 394.569505 -55.105797) (xy 394.523655 -55.076331)
			(xy 394.482464 -55.04064) (xy 394.446773 -54.999449) (xy 394.417307 -54.953599) (xy 394.394665 -54.904022)
			(xy 394.37931 -54.851727) (xy 394.371554 -54.797779) (xy 394.371068 -54.770528) (xy 391.239147 -54.770528)
			(xy 391.239502 -54.791102) (xy 391.239016 -54.818353) (xy 391.23126 -54.872301) (xy 391.215905 -54.924596)
			(xy 391.193263 -54.974173) (xy 391.163797 -55.020023) (xy 391.128106 -55.061214) (xy 391.086915 -55.096905)
			(xy 391.041065 -55.126371) (xy 390.991488 -55.149013) (xy 390.939193 -55.164368) (xy 390.885245 -55.172124)
			(xy 390.830743 -55.172124) (xy 390.776795 -55.164368) (xy 390.7245 -55.149013) (xy 390.674923 -55.126371)
			(xy 390.629073 -55.096905) (xy 390.587882 -55.061214) (xy 390.552191 -55.020023) (xy 390.522725 -54.974173)
			(xy 390.500083 -54.924596) (xy 390.484728 -54.872301) (xy 390.476972 -54.818353) (xy 390.476486 -54.791102)
			(xy 388.578528 -54.791102) (xy 388.575436 -54.812611) (xy 388.560081 -54.864906) (xy 388.537439 -54.914483)
			(xy 388.507973 -54.960333) (xy 388.472282 -55.001524) (xy 388.431091 -55.037215) (xy 388.385241 -55.066681)
			(xy 388.335664 -55.089323) (xy 388.283369 -55.104678) (xy 388.229421 -55.112434) (xy 388.174919 -55.112434)
			(xy 388.120971 -55.104678) (xy 388.068676 -55.089323) (xy 388.019099 -55.066681) (xy 387.973249 -55.037215)
			(xy 387.932058 -55.001524) (xy 387.896367 -54.960333) (xy 387.866901 -54.914483) (xy 387.844259 -54.864906)
			(xy 387.828904 -54.812611) (xy 387.821148 -54.758663) (xy 387.820662 -54.731412) (xy 387.078728 -54.731412)
			(xy 387.078728 -57.002934) (xy 395.863572 -57.002934) (xy 395.864098 -56.974844) (xy 395.872321 -56.919268)
			(xy 395.888607 -56.8655) (xy 395.912604 -56.814703) (xy 395.943794 -56.767976) (xy 395.981501 -56.72633)
			(xy 396.02491 -56.690666) (xy 396.048738 -56.675782) (xy 396.057628 -56.670448) (xy 396.06982 -56.65343)
			(xy 396.09014 -56.560212) (xy 396.085822 -56.539638) (xy 396.07998 -56.531002) (xy 396.063976 -56.506941)
			(xy 396.038635 -56.455008) (xy 396.021411 -56.399849) (xy 396.012696 -56.342725) (xy 396.012162 -56.313832)
			(xy 396.012685 -56.286581) (xy 396.020437 -56.232634) (xy 396.035787 -56.180339) (xy 396.058424 -56.130761)
			(xy 396.087886 -56.084909) (xy 396.123573 -56.043717) (xy 396.16476 -56.008023) (xy 396.210607 -55.978554)
			(xy 396.260181 -55.955909) (xy 396.312473 -55.94055) (xy 396.366419 -55.932789) (xy 396.39367 -55.932324)
			(xy 396.42104 -55.932802) (xy 396.475219 -55.940616) (xy 396.527722 -55.956102) (xy 396.577469 -55.978941)
			(xy 396.623436 -56.008664) (xy 396.644368 -56.026304) (xy 396.644622 -56.026558) (xy 396.651693 -56.032167)
			(xy 396.668622 -56.038399) (xy 396.677642 -56.03875) (xy 396.744698 -56.03875) (xy 396.753716 -56.038403)
			(xy 396.770633 -56.032149) (xy 396.777718 -56.026558) (xy 396.777718 -56.026304) (xy 396.777972 -56.026304)
			(xy 396.798905 -56.008663) (xy 396.844873 -55.978939) (xy 396.894619 -55.956093) (xy 396.947121 -55.940597)
			(xy 397.001299 -55.932768) (xy 397.056041 -55.932768) (xy 397.110219 -55.940597) (xy 397.162721 -55.956093)
			(xy 397.212467 -55.978939) (xy 397.258435 -56.008663) (xy 397.279368 -56.026304) (xy 397.279622 -56.026558)
			(xy 397.286693 -56.032167) (xy 397.303622 -56.038399) (xy 397.312642 -56.03875) (xy 397.379698 -56.03875)
			(xy 397.388716 -56.038403) (xy 397.405633 -56.032149) (xy 397.412718 -56.026558) (xy 397.412718 -56.026304)
			(xy 397.412972 -56.026304) (xy 397.433904 -56.008665) (xy 397.479877 -55.978953) (xy 397.529624 -55.956117)
			(xy 397.582125 -55.940626) (xy 397.636301 -55.932798) (xy 397.66367 -55.932324) (xy 397.690927 -55.932721)
			(xy 397.744885 -55.940475) (xy 397.797191 -55.95583) (xy 397.846779 -55.978472) (xy 397.89264 -56.007942)
			(xy 397.93384 -56.043639) (xy 397.96954 -56.084836) (xy 397.999013 -56.130694) (xy 398.02166 -56.180281)
			(xy 398.037019 -56.232585) (xy 398.044777 -56.286543) (xy 398.044777 -56.341057) (xy 398.037019 -56.395015)
			(xy 398.02166 -56.447319) (xy 397.999013 -56.496906) (xy 397.96954 -56.542764) (xy 397.93384 -56.583961)
			(xy 397.89264 -56.619658) (xy 397.846779 -56.649128) (xy 397.797191 -56.67177) (xy 397.744885 -56.687125)
			(xy 397.690927 -56.694879) (xy 397.66367 -56.69534) (xy 397.636298 -56.694906) (xy 397.582117 -56.687083)
			(xy 397.529613 -56.671587) (xy 397.479867 -56.648738) (xy 397.433902 -56.619005) (xy 397.412972 -56.60136)
			(xy 397.412718 -56.601106) (xy 397.40563 -56.595521) (xy 397.388714 -56.589273) (xy 397.379698 -56.588914)
			(xy 397.312642 -56.588914) (xy 397.303627 -56.589288) (xy 397.28671 -56.595524) (xy 397.279622 -56.601106)
			(xy 397.279622 -56.60136) (xy 397.279368 -56.60136) (xy 397.258435 -56.619001) (xy 397.212467 -56.648725)
			(xy 397.162721 -56.671571) (xy 397.110219 -56.687067) (xy 397.056041 -56.694896) (xy 397.001299 -56.694896)
			(xy 396.947121 -56.687067) (xy 396.894619 -56.671571) (xy 396.844873 -56.648725) (xy 396.798905 -56.619001)
			(xy 396.777972 -56.60136) (xy 396.777718 -56.601106) (xy 396.77063 -56.595521) (xy 396.753714 -56.589273)
			(xy 396.744698 -56.588914) (xy 396.677642 -56.588914) (xy 396.668627 -56.589288) (xy 396.65171 -56.595524)
			(xy 396.644622 -56.601106) (xy 396.644114 -56.60136) (xy 396.631383 -56.612308) (xy 396.604289 -56.632147)
			(xy 396.590012 -56.640984) (xy 396.581122 -56.646318) (xy 396.56893 -56.663336) (xy 396.54861 -56.756554)
			(xy 396.552928 -56.777128) (xy 396.55877 -56.785764) (xy 396.574753 -56.809838) (xy 396.600101 -56.861766)
			(xy 396.617331 -56.916921) (xy 396.626051 -56.974042) (xy 396.626588 -57.002934) (xy 396.626102 -57.030185)
			(xy 396.618346 -57.084133) (xy 396.602991 -57.136428) (xy 396.580349 -57.186005) (xy 396.550883 -57.231855)
			(xy 396.515192 -57.273046) (xy 396.474001 -57.308737) (xy 396.428151 -57.338203) (xy 396.378574 -57.360845)
			(xy 396.326279 -57.3762) (xy 396.272331 -57.383956) (xy 396.217829 -57.383956) (xy 396.163881 -57.3762)
			(xy 396.111586 -57.360845) (xy 396.062009 -57.338203) (xy 396.016159 -57.308737) (xy 395.974968 -57.273046)
			(xy 395.939277 -57.231855) (xy 395.909811 -57.186005) (xy 395.887169 -57.136428) (xy 395.871814 -57.084133)
			(xy 395.864058 -57.030185) (xy 395.863572 -57.002934) (xy 387.078728 -57.002934) (xy 387.078728 -58.679334)
			(xy 396.295372 -58.679334) (xy 396.295804 -58.653019) (xy 396.303048 -58.600889) (xy 396.317374 -58.550246)
			(xy 396.338513 -58.502048) (xy 396.366065 -58.457205) (xy 396.399508 -58.416566) (xy 396.418562 -58.39841)
			(xy 396.425955 -58.390881) (xy 396.434486 -58.371607) (xy 396.435072 -58.361072) (xy 396.435072 -58.286396)
			(xy 396.434567 -58.275843) (xy 396.426016 -58.256548) (xy 396.418562 -58.249058) (xy 396.399486 -58.230923)
			(xy 396.366032 -58.190288) (xy 396.338477 -58.145443) (xy 396.317342 -58.097239) (xy 396.303029 -58.046588)
			(xy 396.295808 -57.994451) (xy 396.295372 -57.968134) (xy 396.295858 -57.940883) (xy 396.303614 -57.886935)
			(xy 396.318969 -57.83464) (xy 396.341611 -57.785063) (xy 396.371077 -57.739213) (xy 396.406768 -57.698022)
			(xy 396.447959 -57.662331) (xy 396.493809 -57.632865) (xy 396.543386 -57.610223) (xy 396.595681 -57.594868)
			(xy 396.649629 -57.587112) (xy 396.704131 -57.587112) (xy 396.758079 -57.594868) (xy 396.810374 -57.610223)
			(xy 396.859951 -57.632865) (xy 396.905801 -57.662331) (xy 396.946992 -57.698022) (xy 396.982683 -57.739213)
			(xy 397.012149 -57.785063) (xy 397.034791 -57.83464) (xy 397.050146 -57.886935) (xy 397.057902 -57.940883)
			(xy 397.058388 -57.968134) (xy 397.057947 -57.994449) (xy 397.050707 -58.046579) (xy 397.036383 -58.097222)
			(xy 397.015246 -58.145421) (xy 396.987695 -58.190264) (xy 396.954252 -58.230902) (xy 396.935198 -58.249058)
			(xy 396.927813 -58.256593) (xy 396.919279 -58.275863) (xy 396.918688 -58.286396) (xy 396.918688 -58.361072)
			(xy 396.919222 -58.371621) (xy 396.927754 -58.390916) (xy 396.935198 -58.39841) (xy 396.954251 -58.416568)
			(xy 396.987708 -58.457197) (xy 397.015268 -58.502037) (xy 397.036407 -58.550237) (xy 397.050724 -58.600884)
			(xy 397.057949 -58.653018) (xy 397.058388 -58.679334) (xy 397.057902 -58.706585) (xy 397.050146 -58.760533)
			(xy 397.034791 -58.812828) (xy 397.012149 -58.862405) (xy 396.982683 -58.908255) (xy 396.946992 -58.949446)
			(xy 396.905801 -58.985137) (xy 396.859951 -59.014603) (xy 396.810374 -59.037245) (xy 396.758079 -59.0526)
			(xy 396.704131 -59.060356) (xy 396.649629 -59.060356) (xy 396.595681 -59.0526) (xy 396.543386 -59.037245)
			(xy 396.493809 -59.014603) (xy 396.447959 -58.985137) (xy 396.406768 -58.949446) (xy 396.371077 -58.908255)
			(xy 396.341611 -58.862405) (xy 396.318969 -58.812828) (xy 396.303614 -58.760533) (xy 396.295858 -58.706585)
			(xy 396.295372 -58.679334) (xy 387.078728 -58.679334) (xy 387.078728 -60.019254) (xy 396.435761 -60.019254)
			(xy 396.435761 -59.964746) (xy 396.443519 -59.910793) (xy 396.458877 -59.858493) (xy 396.481521 -59.808912)
			(xy 396.510992 -59.763058) (xy 396.546689 -59.721865) (xy 396.587885 -59.686172) (xy 396.633742 -59.656705)
			(xy 396.683325 -59.634065) (xy 396.735626 -59.618712) (xy 396.78958 -59.610959) (xy 396.816834 -59.610498)
			(xy 396.844205 -59.610945) (xy 396.898385 -59.618767) (xy 396.950888 -59.634261) (xy 397.000635 -59.657107)
			(xy 397.046601 -59.686835) (xy 397.067532 -59.704478) (xy 397.067786 -59.704732) (xy 397.07487 -59.710322)
			(xy 397.091789 -59.716566) (xy 397.100806 -59.716924) (xy 397.167862 -59.716924) (xy 397.176876 -59.716544)
			(xy 397.193793 -59.710312) (xy 397.200882 -59.704732) (xy 397.200882 -59.704478) (xy 397.201136 -59.704478)
			(xy 397.222069 -59.686837) (xy 397.268037 -59.657113) (xy 397.317783 -59.634267) (xy 397.370285 -59.618771)
			(xy 397.424463 -59.610942) (xy 397.479205 -59.610942) (xy 397.533383 -59.618771) (xy 397.585885 -59.634267)
			(xy 397.635631 -59.657113) (xy 397.681599 -59.686837) (xy 397.702532 -59.704478) (xy 397.702786 -59.704732)
			(xy 397.70987 -59.710322) (xy 397.726789 -59.716566) (xy 397.735806 -59.716924) (xy 397.802862 -59.716924)
			(xy 397.811876 -59.716544) (xy 397.828793 -59.710312) (xy 397.835882 -59.704732) (xy 397.835882 -59.704478)
			(xy 397.836136 -59.704478) (xy 397.857079 -59.686852) (xy 397.903049 -59.657139) (xy 397.952794 -59.634301)
			(xy 398.005292 -59.618807) (xy 398.059466 -59.610974) (xy 398.086834 -59.610498) (xy 398.114084 -59.610974)
			(xy 398.168029 -59.618735) (xy 398.22032 -59.634093) (xy 398.269894 -59.656736) (xy 398.315741 -59.686204)
			(xy 398.356928 -59.721896) (xy 398.392616 -59.763086) (xy 398.42208 -59.808936) (xy 398.444719 -59.858511)
			(xy 398.460073 -59.910804) (xy 398.467828 -59.96475) (xy 398.467828 -60.01925) (xy 398.460073 -60.073196)
			(xy 398.444719 -60.125489) (xy 398.42208 -60.175064) (xy 398.392616 -60.220914) (xy 398.356928 -60.262104)
			(xy 398.315741 -60.297796) (xy 398.269894 -60.327264) (xy 398.22032 -60.349907) (xy 398.168029 -60.365265)
			(xy 398.114084 -60.373026) (xy 398.086834 -60.373514) (xy 398.059465 -60.373025) (xy 398.005287 -60.365212)
			(xy 397.952784 -60.349728) (xy 397.903037 -60.326892) (xy 397.857069 -60.297173) (xy 397.836136 -60.279534)
			(xy 397.835882 -60.27928) (xy 397.828806 -60.273678) (xy 397.811881 -60.267441) (xy 397.802862 -60.267088)
			(xy 397.735806 -60.267088) (xy 397.72679 -60.267451) (xy 397.709873 -60.273695) (xy 397.702786 -60.27928)
			(xy 397.702532 -60.279534) (xy 397.681599 -60.297175) (xy 397.635631 -60.326899) (xy 397.585885 -60.349745)
			(xy 397.533383 -60.365241) (xy 397.479205 -60.37307) (xy 397.424463 -60.37307) (xy 397.370285 -60.365241)
			(xy 397.317783 -60.349745) (xy 397.268037 -60.326899) (xy 397.222069 -60.297175) (xy 397.201136 -60.279534)
			(xy 397.200882 -60.27928) (xy 397.193806 -60.273678) (xy 397.176881 -60.267441) (xy 397.167862 -60.267088)
			(xy 397.100806 -60.267088) (xy 397.09179 -60.267451) (xy 397.074873 -60.273695) (xy 397.067786 -60.27928)
			(xy 397.067786 -60.279534) (xy 397.067532 -60.279534) (xy 397.046603 -60.297177) (xy 397.000629 -60.326887)
			(xy 396.95088 -60.349722) (xy 396.898379 -60.365212) (xy 396.844203 -60.37304) (xy 396.816834 -60.373514)
			(xy 396.78958 -60.373041) (xy 396.735626 -60.365288) (xy 396.683325 -60.349935) (xy 396.633742 -60.327295)
			(xy 396.587885 -60.297828) (xy 396.546689 -60.262135) (xy 396.510992 -60.220942) (xy 396.481521 -60.175088)
			(xy 396.458877 -60.125507) (xy 396.443519 -60.073207) (xy 396.435761 -60.019254) (xy 387.078728 -60.019254)
			(xy 387.078728 -65.06972) (xy 387.078982 -65.07099) (xy 387.079321 -65.074704) (xy 387.080977 -65.081975)
			(xy 387.082284 -65.085468) (xy 387.084308 -65.090397) (xy 387.090074 -65.099356) (xy 387.093714 -65.103248)
			(xy 387.409436 -65.41897) (xy 387.415024 -65.423796) (xy 388.839964 -65.423796) (xy 388.842758 -65.422272)
			(xy 388.867242 -65.409192) (xy 388.919128 -65.389468) (xy 388.973324 -65.377465) (xy 389.028686 -65.373436)
			(xy 389.084048 -65.377465) (xy 389.138244 -65.389468) (xy 389.19013 -65.409192) (xy 389.214614 -65.422272)
			(xy 389.217408 -65.423796) (xy 392.32967 -65.423796) (xy 392.340592 -65.422526) (xy 392.347563 -65.420772)
			(xy 392.3602 -65.413937) (xy 392.365484 -65.409064) (xy 394.045948 -63.728346) (xy 394.064727 -63.710231)
			(xy 394.106923 -63.679543) (xy 394.153404 -63.655841) (xy 394.203023 -63.639709) (xy 394.254556 -63.631546)
			(xy 394.280644 -63.631064) (xy 396.490444 -63.631064) (xy 396.497579 -63.627007) (xy 396.508986 -63.615219)
			(xy 396.512796 -63.60795) (xy 396.52575 -63.576962) (xy 396.52575 -63.576454) (xy 396.5321 -63.56096)
			(xy 396.5321 -63.560706) (xy 396.536418 -63.552324) (xy 396.537688 -63.550292) (xy 396.539725 -63.546526)
			(xy 396.542658 -63.538482) (xy 396.54353 -63.53429) (xy 396.543784 -63.532766) (xy 396.547848 -63.506858)
			(xy 396.548859 -63.499649) (xy 396.547189 -63.485193) (xy 396.544546 -63.47841) (xy 396.53718 -63.461392)
			(xy 396.530322 -63.454534) (xy 396.510406 -63.433628) (xy 396.476474 -63.386914) (xy 396.449973 -63.335619)
			(xy 396.431508 -63.280913) (xy 396.421503 -63.22405) (xy 396.42034 -63.1952) (xy 396.42034 -63.180468)
			(xy 396.421322 -63.151502) (xy 396.430962 -63.094355) (xy 396.449136 -63.039323) (xy 396.475424 -62.987673)
			(xy 396.509221 -62.940593) (xy 396.549751 -62.899167) (xy 396.59608 -62.864347) (xy 396.647142 -62.836936)
			(xy 396.701764 -62.817563) (xy 396.758687 -62.806674) (xy 396.787624 -62.805056) (xy 396.787878 -62.805056)
			(xy 396.801848 -62.804802) (xy 396.802356 -62.804802) (xy 396.827983 -62.80523) (xy 396.878771 -62.812124)
			(xy 396.928176 -62.825766) (xy 396.975306 -62.84591) (xy 397.019308 -62.872193) (xy 397.039592 -62.88786)
			(xy 397.046196 -62.89294) (xy 397.057372 -62.89675) (xy 397.070834 -62.898782) (xy 397.092678 -62.898782)
			(xy 397.098119 -62.898919) (xy 397.108756 -62.901216) (xy 397.11376 -62.903354) (xy 397.127476 -62.909704)
			(xy 397.13218 -62.911769) (xy 397.142161 -62.914201) (xy 397.147288 -62.91453) (xy 397.155924 -62.914022)
			(xy 397.163207 -62.912734) (xy 397.176625 -62.906527) (xy 397.18234 -62.90183) (xy 397.182594 -62.901576)
			(xy 397.202481 -62.884469) (xy 397.246069 -62.855281) (xy 397.269462 -62.84341) (xy 397.284194 -62.836552)
			(xy 397.288766 -62.83452) (xy 397.312102 -62.825167) (xy 397.360616 -62.811973) (xy 397.410441 -62.805258)
			(xy 397.435578 -62.804802) (xy 397.442182 -62.804802) (xy 397.471945 -62.805789) (xy 397.530635 -62.815867)
			(xy 397.559022 -62.824868) (xy 397.590009 -62.836091) (xy 397.647871 -62.86763) (xy 397.674084 -62.887606)
			(xy 397.674338 -62.88786) (xy 397.677386 -62.8904) (xy 397.683496 -62.894131) (xy 397.697162 -62.898381)
			(xy 397.70431 -62.898782) (xy 397.727678 -62.898782) (xy 397.733119 -62.898919) (xy 397.743756 -62.901216)
			(xy 397.74876 -62.903354) (xy 397.762476 -62.909704) (xy 397.76718 -62.911769) (xy 397.777161 -62.914201)
			(xy 397.782288 -62.91453) (xy 397.790924 -62.914022) (xy 397.798207 -62.912734) (xy 397.811625 -62.906527)
			(xy 397.81734 -62.90183) (xy 397.817594 -62.901576) (xy 397.838664 -62.883469) (xy 397.885058 -62.852909)
			(xy 397.935391 -62.829396) (xy 397.988601 -62.813426) (xy 398.043563 -62.805337) (xy 398.07134 -62.804802)
			(xy 398.071848 -62.804802) (xy 398.099097 -62.805292) (xy 398.153039 -62.813054) (xy 398.205327 -62.828413)
			(xy 398.254897 -62.851057) (xy 398.300741 -62.880525) (xy 398.341925 -62.916216) (xy 398.37761 -62.957405)
			(xy 398.407071 -63.003253) (xy 398.429707 -63.052827) (xy 398.445059 -63.105118) (xy 398.452813 -63.159061)
			(xy 398.453356 -63.18631) (xy 398.452786 -63.216036) (xy 398.443558 -63.274769) (xy 398.425328 -63.331358)
			(xy 398.398536 -63.384432) (xy 398.363833 -63.432706) (xy 398.343374 -63.45428) (xy 398.34312 -63.454534)
			(xy 398.33677 -63.461138) (xy 398.330674 -63.4746) (xy 398.328642 -63.479172) (xy 398.327372 -63.482982)
			(xy 398.323816 -63.500508) (xy 398.323322 -63.506029) (xy 398.324484 -63.51705) (xy 398.326102 -63.522352)
			(xy 398.347946 -63.576454) (xy 398.347946 -63.576962) (xy 398.359376 -63.604902) (xy 398.363157 -63.613213)
			(xy 398.375529 -63.626621) (xy 398.383506 -63.631064) (xy 398.799812 -63.631064) (xy 398.803274 -63.629281)
			(xy 398.809651 -63.624815) (xy 398.812512 -63.622174) (xy 399.224754 -63.209932) (xy 399.22958 -63.204344)
			(xy 399.22958 -56.577992) (xy 399.224964 -56.572303) (xy 399.213224 -56.563551) (xy 399.206466 -56.56072)
			(xy 399.163032 -56.544718) (xy 399.116804 -56.5277) (xy 399.109184 -56.525668) (xy 399.103425 -56.524693)
			(xy 399.091755 -56.525086) (xy 399.08607 -56.52643) (xy 399.078704 -56.528462) (xy 399.065496 -56.536844)
			(xy 399.060416 -56.54294) (xy 399.042184 -56.563797) (xy 399.000729 -56.600542) (xy 398.954398 -56.630908)
			(xy 398.904164 -56.654258) (xy 398.851082 -56.670101) (xy 398.796268 -56.678104) (xy 398.76857 -56.678576)
			(xy 398.741322 -56.678088) (xy 398.687383 -56.670328) (xy 398.635096 -56.654972) (xy 398.585527 -56.632331)
			(xy 398.539684 -56.602866) (xy 398.498501 -56.567178) (xy 398.462816 -56.525992) (xy 398.433355 -56.480147)
			(xy 398.410717 -56.430576) (xy 398.395365 -56.378288) (xy 398.38761 -56.324348) (xy 398.38761 -56.269852)
			(xy 398.395365 -56.215912) (xy 398.410717 -56.163624) (xy 398.433355 -56.114053) (xy 398.462816 -56.068208)
			(xy 398.498501 -56.027022) (xy 398.539684 -55.991334) (xy 398.585527 -55.961869) (xy 398.635096 -55.939228)
			(xy 398.687383 -55.923872) (xy 398.741322 -55.916112) (xy 398.76857 -55.91556) (xy 398.795548 -55.916022)
			(xy 398.848967 -55.92361) (xy 398.900788 -55.938638) (xy 398.949979 -55.960807) (xy 398.995561 -55.989677)
			(xy 399.036628 -56.024673) (xy 399.054828 -56.044592) (xy 399.06067 -56.051196) (xy 399.073878 -56.060086)
			(xy 399.080482 -56.063388) (xy 399.08099 -56.063896) (xy 399.089917 -56.067456) (xy 399.1091 -56.068361)
			(xy 399.118328 -56.065674) (xy 399.11909 -56.06542) (xy 399.206466 -56.033416) (xy 399.213246 -56.030718)
			(xy 399.224994 -56.022074) (xy 399.22958 -56.016398) (xy 399.22958 -55.11292) (xy 399.23011 -55.086897)
			(xy 399.238281 -55.035497) (xy 399.25438 -54.986004) (xy 399.278011 -54.939632) (xy 399.308593 -54.897519)
			(xy 399.326608 -54.878732) (xy 401.250658 -52.954682) (xy 401.257008 -52.944014) (xy 401.258786 -52.938172)
			(xy 401.267233 -52.912604) (xy 401.29031 -52.863952) (xy 401.319995 -52.819026) (xy 401.355697 -52.778716)
			(xy 401.39671 -52.743823) (xy 401.442218 -52.715039) (xy 401.491319 -52.692935) (xy 401.54304 -52.677949)
			(xy 401.596352 -52.670379) (xy 401.623276 -52.669948) (xy 401.65053 -52.670432) (xy 401.704482 -52.678186)
			(xy 401.756782 -52.693538) (xy 401.806365 -52.716177) (xy 401.852222 -52.745642) (xy 401.893419 -52.781333)
			(xy 401.929117 -52.822524) (xy 401.95859 -52.868375) (xy 401.981238 -52.917954) (xy 401.9966 -52.970251)
			(xy 402.004363 -53.024203) (xy 402.004784 -53.051456) (xy 402.005038 -53.051456) (xy 402.004578 -53.07839)
			(xy 401.997007 -53.131723) (xy 401.982011 -53.183461) (xy 401.959886 -53.232575) (xy 401.931073 -53.278089)
			(xy 401.896144 -53.319098) (xy 401.855795 -53.354786) (xy 401.810827 -53.384445) (xy 401.762135 -53.407483)
			(xy 401.73656 -53.415946) (xy 401.736306 -53.415946) (xy 401.730473 -53.417959) (xy 401.719942 -53.424385)
			(xy 401.715478 -53.428646) (xy 401.647569 -53.496555) (xy 406.433441 -53.496555) (xy 406.433441 -53.442045)
			(xy 406.441199 -53.388089) (xy 406.456557 -53.335787) (xy 406.479202 -53.286203) (xy 406.508674 -53.240347)
			(xy 406.544372 -53.199152) (xy 406.58557 -53.163457) (xy 406.631428 -53.133989) (xy 406.681014 -53.111347)
			(xy 406.733317 -53.095993) (xy 406.787273 -53.088239) (xy 406.814528 -53.087778) (xy 406.8419 -53.088209)
			(xy 406.896081 -53.096032) (xy 406.948585 -53.111528) (xy 406.998332 -53.134379) (xy 407.044296 -53.164112)
			(xy 407.065226 -53.181758) (xy 407.06548 -53.182012) (xy 407.072567 -53.187598) (xy 407.089484 -53.193845)
			(xy 407.0985 -53.194204) (xy 407.165556 -53.194204) (xy 407.174571 -53.193825) (xy 407.191488 -53.187593)
			(xy 407.198576 -53.182012) (xy 407.198576 -53.181758) (xy 407.19883 -53.181758) (xy 407.219772 -53.164131)
			(xy 407.265743 -53.134419) (xy 407.315488 -53.111581) (xy 407.367986 -53.096087) (xy 407.42216 -53.088254)
			(xy 407.449528 -53.087778) (xy 407.476777 -53.088294) (xy 407.53072 -53.096054) (xy 407.583009 -53.111411)
			(xy 407.632581 -53.134052) (xy 407.678426 -53.163518) (xy 407.719611 -53.199209) (xy 407.755298 -53.240396)
			(xy 407.784761 -53.286244) (xy 407.807399 -53.335817) (xy 407.822752 -53.388108) (xy 407.830508 -53.442051)
			(xy 407.830508 -53.496549) (xy 407.822752 -53.550492) (xy 407.807399 -53.602783) (xy 407.784761 -53.652356)
			(xy 407.755298 -53.698204) (xy 407.719611 -53.739391) (xy 407.678426 -53.775082) (xy 407.632581 -53.804548)
			(xy 407.583009 -53.827189) (xy 407.53072 -53.842546) (xy 407.476777 -53.850306) (xy 407.449528 -53.850794)
			(xy 407.422158 -53.850313) (xy 407.36798 -53.842499) (xy 407.315477 -53.827013) (xy 407.26573 -53.804175)
			(xy 407.219762 -53.774454) (xy 407.19883 -53.756814) (xy 407.198576 -53.75656) (xy 407.191504 -53.750952)
			(xy 407.174576 -53.744719) (xy 407.165556 -53.744368) (xy 407.0985 -53.744368) (xy 407.089484 -53.744732)
			(xy 407.072567 -53.750976) (xy 407.06548 -53.75656) (xy 407.06548 -53.756814) (xy 407.065226 -53.756814)
			(xy 407.044297 -53.774457) (xy 406.998323 -53.804167) (xy 406.948575 -53.827002) (xy 406.896073 -53.842493)
			(xy 406.841897 -53.85032) (xy 406.814528 -53.850794) (xy 406.787273 -53.850361) (xy 406.733317 -53.842607)
			(xy 406.681014 -53.827253) (xy 406.631428 -53.804611) (xy 406.58557 -53.775143) (xy 406.544372 -53.739448)
			(xy 406.508674 -53.698253) (xy 406.479202 -53.652397) (xy 406.456557 -53.602813) (xy 406.441199 -53.550511)
			(xy 406.433441 -53.496555) (xy 401.647569 -53.496555) (xy 400.155069 -54.989055) (xy 404.201045 -54.989055)
			(xy 404.201045 -54.934545) (xy 404.208803 -54.880591) (xy 404.22416 -54.82829) (xy 404.246805 -54.778707)
			(xy 404.276276 -54.732852) (xy 404.311973 -54.691657) (xy 404.353169 -54.655963) (xy 404.399026 -54.626494)
			(xy 404.448611 -54.603853) (xy 404.500913 -54.588498) (xy 404.554867 -54.580743) (xy 404.582122 -54.580282)
			(xy 404.610214 -54.580759) (xy 404.665792 -54.58899) (xy 404.719562 -54.605284) (xy 404.770359 -54.629289)
			(xy 404.817086 -54.660487) (xy 404.85873 -54.698201) (xy 404.894392 -54.741616) (xy 404.909274 -54.765448)
			(xy 404.914608 -54.774338) (xy 404.931626 -54.78653) (xy 405.024844 -54.80685) (xy 405.045418 -54.802532)
			(xy 405.054054 -54.79669) (xy 405.078128 -54.780706) (xy 405.130056 -54.75536) (xy 405.185211 -54.73813)
			(xy 405.242332 -54.72941) (xy 405.271224 -54.728872) (xy 405.298475 -54.729355) (xy 405.352422 -54.737115)
			(xy 405.404715 -54.752472) (xy 405.454291 -54.775114) (xy 405.500141 -54.804581) (xy 405.54133 -54.840273)
			(xy 405.577021 -54.881463) (xy 405.606488 -54.927312) (xy 405.62913 -54.976888) (xy 405.644486 -55.029182)
			(xy 405.652245 -55.083129) (xy 405.652732 -55.11038) (xy 405.652271 -55.137751) (xy 405.644454 -55.191931)
			(xy 405.628965 -55.244434) (xy 405.606122 -55.294181) (xy 405.576395 -55.340147) (xy 405.558752 -55.361078)
			(xy 405.558498 -55.361332) (xy 405.552934 -55.368434) (xy 405.546674 -55.385339) (xy 405.546306 -55.394352)
			(xy 405.546306 -55.461408) (xy 405.546658 -55.470425) (xy 405.552909 -55.487342) (xy 405.558498 -55.494428)
			(xy 405.558752 -55.494428) (xy 405.558752 -55.494682) (xy 405.576374 -55.51563) (xy 405.606101 -55.561595)
			(xy 405.628949 -55.611338) (xy 405.644448 -55.663838) (xy 405.652279 -55.718015) (xy 405.652281 -55.772755)
			(xy 405.644454 -55.826932) (xy 405.62896 -55.879433) (xy 405.606116 -55.929179) (xy 405.576392 -55.975146)
			(xy 405.558752 -55.996078) (xy 405.558498 -55.996332) (xy 405.552934 -56.003434) (xy 405.546674 -56.020339)
			(xy 405.546306 -56.029352) (xy 405.546306 -56.096408) (xy 405.546658 -56.105425) (xy 405.552909 -56.122342)
			(xy 405.558498 -56.129428) (xy 405.558752 -56.129428) (xy 405.558752 -56.129682) (xy 405.576389 -56.150616)
			(xy 405.606103 -56.196588) (xy 405.62894 -56.246335) (xy 405.644431 -56.298835) (xy 405.652259 -56.353011)
			(xy 405.652732 -56.38038) (xy 405.652246 -56.407631) (xy 405.64449 -56.461579) (xy 405.629135 -56.513874)
			(xy 405.606493 -56.563451) (xy 405.577027 -56.609301) (xy 405.541336 -56.650492) (xy 405.500145 -56.686183)
			(xy 405.454295 -56.715649) (xy 405.404718 -56.738291) (xy 405.352423 -56.753646) (xy 405.298475 -56.761402)
			(xy 405.243973 -56.761402) (xy 405.190025 -56.753646) (xy 405.13773 -56.738291) (xy 405.088153 -56.715649)
			(xy 405.042303 -56.686183) (xy 405.001112 -56.650492) (xy 404.965421 -56.609301) (xy 404.935955 -56.563451)
			(xy 404.913313 -56.513874) (xy 404.897958 -56.461579) (xy 404.890202 -56.407631) (xy 404.889716 -56.38038)
			(xy 404.890166 -56.353009) (xy 404.897987 -56.298829) (xy 404.91348 -56.246326) (xy 404.936325 -56.196579)
			(xy 404.966053 -56.150613) (xy 404.983696 -56.129682) (xy 404.98395 -56.129428) (xy 404.989537 -56.122342)
			(xy 404.995782 -56.105425) (xy 404.996142 -56.096408) (xy 404.996142 -56.029352) (xy 404.995773 -56.020336)
			(xy 404.989535 -56.003418) (xy 404.98395 -55.996332) (xy 404.983696 -55.996332) (xy 404.983696 -55.996078)
			(xy 404.966037 -55.975161) (xy 404.936315 -55.929189) (xy 404.913473 -55.87944) (xy 404.89798 -55.826936)
			(xy 404.890154 -55.772756) (xy 404.890156 -55.718014) (xy 404.897986 -55.663834) (xy 404.913484 -55.611331)
			(xy 404.93633 -55.561584) (xy 404.966055 -55.515615) (xy 404.983696 -55.494682) (xy 404.98395 -55.494428)
			(xy 404.989537 -55.487342) (xy 404.995782 -55.470425) (xy 404.996142 -55.461408) (xy 404.996142 -55.394352)
			(xy 404.995773 -55.385336) (xy 404.989535 -55.368418) (xy 404.98395 -55.361332) (xy 404.983696 -55.360824)
			(xy 404.972752 -55.348089) (xy 404.952911 -55.320998) (xy 404.944072 -55.306722) (xy 404.938738 -55.297832)
			(xy 404.92172 -55.28564) (xy 404.828502 -55.26532) (xy 404.807928 -55.269638) (xy 404.799292 -55.27548)
			(xy 404.77523 -55.291483) (xy 404.723298 -55.316826) (xy 404.66814 -55.334051) (xy 404.611015 -55.342764)
			(xy 404.582122 -55.343298) (xy 404.554867 -55.342857) (xy 404.500913 -55.335102) (xy 404.448611 -55.319747)
			(xy 404.399026 -55.297106) (xy 404.353169 -55.267637) (xy 404.311973 -55.231943) (xy 404.276276 -55.190748)
			(xy 404.246805 -55.144893) (xy 404.22416 -55.09531) (xy 404.208803 -55.043009) (xy 404.201045 -54.989055)
			(xy 400.155069 -54.989055) (xy 399.925032 -55.219092) (xy 399.924524 -55.226458) (xy 399.924524 -55.722266)
			(xy 400.134072 -55.722266) (xy 400.138143 -55.666644) (xy 400.150269 -55.612207) (xy 400.170192 -55.560116)
			(xy 400.197488 -55.511481) (xy 400.231574 -55.467338) (xy 400.271723 -55.428629) (xy 400.317081 -55.396178)
			(xy 400.366681 -55.370677) (xy 400.419465 -55.35267) (xy 400.474308 -55.34254) (xy 400.530042 -55.340503)
			(xy 400.585479 -55.346603) (xy 400.639436 -55.360709) (xy 400.690765 -55.382521) (xy 400.738371 -55.411575)
			(xy 400.749522 -55.420855) (xy 402.524645 -55.420855) (xy 402.524645 -55.366345) (xy 402.532403 -55.312391)
			(xy 402.54776 -55.26009) (xy 402.570405 -55.210507) (xy 402.599876 -55.164652) (xy 402.635573 -55.123457)
			(xy 402.676769 -55.087763) (xy 402.722626 -55.058294) (xy 402.772211 -55.035653) (xy 402.824513 -55.020298)
			(xy 402.878467 -55.012543) (xy 402.905722 -55.012082) (xy 402.932036 -55.012541) (xy 402.984165 -55.019778)
			(xy 403.034808 -55.034099) (xy 403.083006 -55.055233) (xy 403.12785 -55.082781) (xy 403.168489 -55.11622)
			(xy 403.186646 -55.135272) (xy 403.194152 -55.142692) (xy 403.213444 -55.151207) (xy 403.223984 -55.151782)
			(xy 403.29866 -55.151782) (xy 403.30921 -55.15125) (xy 403.328505 -55.142718) (xy 403.335998 -55.135272)
			(xy 403.354156 -55.116219) (xy 403.394786 -55.082763) (xy 403.439626 -55.055204) (xy 403.487826 -55.034065)
			(xy 403.538473 -55.019747) (xy 403.590606 -55.012521) (xy 403.616922 -55.012082) (xy 403.644171 -55.01259)
			(xy 403.698115 -55.020349) (xy 403.750406 -55.035705) (xy 403.799979 -55.058347) (xy 403.845825 -55.087813)
			(xy 403.887012 -55.123504) (xy 403.9227 -55.164692) (xy 403.952164 -55.21054) (xy 403.974802 -55.260115)
			(xy 403.990156 -55.312406) (xy 403.997912 -55.366351) (xy 403.997912 -55.420849) (xy 403.990156 -55.474794)
			(xy 403.974802 -55.527085) (xy 403.952164 -55.57666) (xy 403.9227 -55.622508) (xy 403.887012 -55.663696)
			(xy 403.845826 -55.699387) (xy 403.799979 -55.728853) (xy 403.750406 -55.751495) (xy 403.698115 -55.766851)
			(xy 403.644171 -55.77461) (xy 403.616922 -55.775098) (xy 403.590609 -55.774617) (xy 403.538481 -55.767385)
			(xy 403.487838 -55.753068) (xy 403.439639 -55.731939) (xy 403.394795 -55.704395) (xy 403.354155 -55.670959)
			(xy 403.335998 -55.651908) (xy 403.328478 -55.644505) (xy 403.309197 -55.635981) (xy 403.29866 -55.635398)
			(xy 403.223984 -55.635398) (xy 403.213432 -55.635905) (xy 403.194137 -55.644456) (xy 403.186646 -55.651908)
			(xy 403.168511 -55.670984) (xy 403.127877 -55.704439) (xy 403.083032 -55.731995) (xy 403.034827 -55.75313)
			(xy 402.984176 -55.767443) (xy 402.932039 -55.774662) (xy 402.905722 -55.775098) (xy 402.878467 -55.774657)
			(xy 402.824513 -55.766902) (xy 402.772211 -55.751547) (xy 402.722626 -55.728906) (xy 402.676769 -55.699437)
			(xy 402.635573 -55.663743) (xy 402.599876 -55.622548) (xy 402.570405 -55.576693) (xy 402.54776 -55.52711)
			(xy 402.532403 -55.474809) (xy 402.524645 -55.420855) (xy 400.749522 -55.420855) (xy 400.781239 -55.44725)
			(xy 400.818456 -55.488787) (xy 400.849229 -55.5353) (xy 400.872901 -55.585797) (xy 400.888969 -55.639204)
			(xy 400.897089 -55.69438) (xy 400.897598 -55.722266) (xy 400.897089 -55.750152) (xy 400.888969 -55.805328)
			(xy 400.872901 -55.858735) (xy 400.849229 -55.909232) (xy 400.818456 -55.955745) (xy 400.781239 -55.997282)
			(xy 400.738371 -56.032957) (xy 400.690765 -56.062011) (xy 400.639436 -56.083823) (xy 400.585479 -56.097929)
			(xy 400.530042 -56.104029) (xy 400.474308 -56.101992) (xy 400.419465 -56.091862) (xy 400.366681 -56.073855)
			(xy 400.317081 -56.048354) (xy 400.271723 -56.015903) (xy 400.231574 -55.977194) (xy 400.197488 -55.933051)
			(xy 400.170192 -55.884416) (xy 400.150269 -55.832325) (xy 400.138143 -55.777888) (xy 400.134072 -55.722266)
			(xy 399.924524 -55.722266) (xy 399.924524 -56.570626) (xy 399.925213 -56.582496) (xy 399.935939 -56.603685)
			(xy 399.945098 -56.611266) (xy 400.009868 -56.659272) (xy 400.01847 -56.665116) (xy 400.038668 -56.669976)
			(xy 400.048984 -56.66867) (xy 400.055842 -56.6674) (xy 400.059144 -56.666384) (xy 400.085652 -56.659023)
			(xy 400.140095 -56.651113) (xy 400.167602 -56.650636) (xy 400.167856 -56.650636) (xy 400.171666 -56.650636)
			(xy 400.173952 -56.650636) (xy 400.183858 -56.65089) (xy 400.188684 -56.651144) (xy 400.188938 -56.651144)
			(xy 400.200367 -56.651877) (xy 400.223115 -56.654547) (xy 400.234404 -56.656478) (xy 400.261122 -56.661709)
			(xy 400.312833 -56.67874) (xy 400.361601 -56.702943) (xy 400.406435 -56.733829) (xy 400.446428 -56.77077)
			(xy 400.480767 -56.813018) (xy 400.508756 -56.859715) (xy 400.529828 -56.909915) (xy 400.537172 -56.936132)
			(xy 400.53895 -56.943498) (xy 400.542252 -56.949086) (xy 400.549872 -56.959246) (xy 400.753834 -57.162954)
			(xy 400.760679 -57.170352) (xy 400.768404 -57.188951) (xy 400.76882 -57.199022) (xy 400.76882 -57.48528)
			(xy 404.90597 -57.48528) (xy 404.910041 -57.429658) (xy 404.922167 -57.375221) (xy 404.94209 -57.32313)
			(xy 404.969386 -57.274495) (xy 405.003472 -57.230352) (xy 405.043621 -57.191643) (xy 405.088979 -57.159192)
			(xy 405.138579 -57.133691) (xy 405.191363 -57.115684) (xy 405.246206 -57.105554) (xy 405.30194 -57.103517)
			(xy 405.357377 -57.109617) (xy 405.411334 -57.123723) (xy 405.462663 -57.145535) (xy 405.510269 -57.174589)
			(xy 405.553137 -57.210264) (xy 405.590354 -57.251801) (xy 405.621127 -57.298314) (xy 405.644799 -57.348811)
			(xy 405.660867 -57.402218) (xy 405.668987 -57.457394) (xy 405.669496 -57.48528) (xy 405.668987 -57.513166)
			(xy 405.660867 -57.568342) (xy 405.644799 -57.621749) (xy 405.621127 -57.672246) (xy 405.590354 -57.718759)
			(xy 405.553137 -57.760296) (xy 405.510269 -57.795971) (xy 405.462663 -57.825025) (xy 405.411334 -57.846837)
			(xy 405.357377 -57.860943) (xy 405.30194 -57.867043) (xy 405.246206 -57.865006) (xy 405.191363 -57.854876)
			(xy 405.138579 -57.836869) (xy 405.088979 -57.811368) (xy 405.043621 -57.778917) (xy 405.003472 -57.740208)
			(xy 404.969386 -57.696065) (xy 404.94209 -57.64743) (xy 404.922167 -57.595339) (xy 404.910041 -57.540902)
			(xy 404.90597 -57.48528) (xy 400.76882 -57.48528) (xy 400.76882 -57.664858) (xy 400.769119 -57.672729)
			(xy 400.773911 -57.687726) (xy 400.778218 -57.694322) (xy 400.782536 -57.700672) (xy 400.794728 -57.709816)
			(xy 400.802602 -57.71261) (xy 400.830425 -57.723036) (xy 400.882704 -57.751264) (xy 400.929979 -57.787251)
			(xy 400.971106 -57.830129) (xy 401.005092 -57.878862) (xy 401.031116 -57.932273) (xy 401.040346 -57.960514)
			(xy 401.043648 -57.970928) (xy 401.338542 -58.265822) (xy 401.356654 -58.284603) (xy 401.387338 -58.326801)
			(xy 401.411037 -58.373282) (xy 401.427168 -58.4229) (xy 401.435333 -58.474431) (xy 401.435824 -58.500518)
			(xy 401.435824 -58.561224) (xy 406.862278 -58.561224) (xy 406.866349 -58.505602) (xy 406.878475 -58.451165)
			(xy 406.898398 -58.399074) (xy 406.925694 -58.350439) (xy 406.95978 -58.306296) (xy 406.999929 -58.267587)
			(xy 407.045287 -58.235136) (xy 407.094887 -58.209635) (xy 407.147671 -58.191628) (xy 407.202514 -58.181498)
			(xy 407.258248 -58.179461) (xy 407.313685 -58.185561) (xy 407.367642 -58.199667) (xy 407.418971 -58.221479)
			(xy 407.466577 -58.250533) (xy 407.509445 -58.286208) (xy 407.546662 -58.327745) (xy 407.577435 -58.374258)
			(xy 407.601107 -58.424755) (xy 407.617175 -58.478162) (xy 407.625295 -58.533338) (xy 407.625804 -58.561224)
			(xy 407.625295 -58.58911) (xy 407.617175 -58.644286) (xy 407.601107 -58.697693) (xy 407.577435 -58.74819)
			(xy 407.546662 -58.794703) (xy 407.509445 -58.83624) (xy 407.466577 -58.871915) (xy 407.418971 -58.900969)
			(xy 407.367642 -58.922781) (xy 407.313685 -58.936887) (xy 407.258248 -58.942987) (xy 407.202514 -58.94095)
			(xy 407.147671 -58.93082) (xy 407.094887 -58.912813) (xy 407.045287 -58.887312) (xy 406.999929 -58.854861)
			(xy 406.95978 -58.816152) (xy 406.925694 -58.772009) (xy 406.898398 -58.723374) (xy 406.878475 -58.671283)
			(xy 406.866349 -58.616846) (xy 406.862278 -58.561224) (xy 401.435824 -58.561224) (xy 401.435824 -59.174634)
			(xy 405.393142 -59.174634) (xy 405.397213 -59.119012) (xy 405.409339 -59.064575) (xy 405.429262 -59.012484)
			(xy 405.456558 -58.963849) (xy 405.490644 -58.919706) (xy 405.530793 -58.880997) (xy 405.576151 -58.848546)
			(xy 405.625751 -58.823045) (xy 405.678535 -58.805038) (xy 405.733378 -58.794908) (xy 405.789112 -58.792871)
			(xy 405.844549 -58.798971) (xy 405.898506 -58.813077) (xy 405.949835 -58.834889) (xy 405.997441 -58.863943)
			(xy 406.040309 -58.899618) (xy 406.077526 -58.941155) (xy 406.108299 -58.987668) (xy 406.131971 -59.038165)
			(xy 406.148039 -59.091572) (xy 406.156159 -59.146748) (xy 406.156668 -59.174634) (xy 406.156159 -59.20252)
			(xy 406.148039 -59.257696) (xy 406.131971 -59.311103) (xy 406.108299 -59.3616) (xy 406.077526 -59.408113)
			(xy 406.040309 -59.44965) (xy 405.997441 -59.485325) (xy 405.949835 -59.514379) (xy 405.898506 -59.536191)
			(xy 405.844549 -59.550297) (xy 405.789112 -59.556397) (xy 405.733378 -59.55436) (xy 405.678535 -59.54423)
			(xy 405.625751 -59.526223) (xy 405.576151 -59.500722) (xy 405.530793 -59.468271) (xy 405.490644 -59.429562)
			(xy 405.456558 -59.385419) (xy 405.429262 -59.336784) (xy 405.409339 -59.284693) (xy 405.397213 -59.230256)
			(xy 405.393142 -59.174634) (xy 401.435824 -59.174634) (xy 401.435824 -60.633356) (xy 408.096972 -60.633356)
			(xy 408.101043 -60.577734) (xy 408.113169 -60.523297) (xy 408.133092 -60.471206) (xy 408.160388 -60.422571)
			(xy 408.194474 -60.378428) (xy 408.234623 -60.339719) (xy 408.279981 -60.307268) (xy 408.329581 -60.281767)
			(xy 408.382365 -60.26376) (xy 408.437208 -60.25363) (xy 408.492942 -60.251593) (xy 408.548379 -60.257693)
			(xy 408.602336 -60.271799) (xy 408.653665 -60.293611) (xy 408.701271 -60.322665) (xy 408.744139 -60.35834)
			(xy 408.781356 -60.399877) (xy 408.812129 -60.44639) (xy 408.835801 -60.496887) (xy 408.851869 -60.550294)
			(xy 408.859989 -60.60547) (xy 408.860498 -60.633356) (xy 408.859989 -60.661242) (xy 408.851869 -60.716418)
			(xy 408.835801 -60.769825) (xy 408.812129 -60.820322) (xy 408.781356 -60.866835) (xy 408.744139 -60.908372)
			(xy 408.701271 -60.944047) (xy 408.653665 -60.973101) (xy 408.602336 -60.994913) (xy 408.548379 -61.009019)
			(xy 408.492942 -61.015119) (xy 408.437208 -61.013082) (xy 408.382365 -61.002952) (xy 408.329581 -60.984945)
			(xy 408.279981 -60.959444) (xy 408.234623 -60.926993) (xy 408.194474 -60.888284) (xy 408.160388 -60.844141)
			(xy 408.133092 -60.795506) (xy 408.113169 -60.743415) (xy 408.101043 -60.688978) (xy 408.096972 -60.633356)
			(xy 401.435824 -60.633356) (xy 401.435824 -61.487812) (xy 406.604468 -61.487812) (xy 406.608539 -61.43219)
			(xy 406.620665 -61.377753) (xy 406.640588 -61.325662) (xy 406.667884 -61.277027) (xy 406.70197 -61.232884)
			(xy 406.742119 -61.194175) (xy 406.787477 -61.161724) (xy 406.837077 -61.136223) (xy 406.889861 -61.118216)
			(xy 406.944704 -61.108086) (xy 407.000438 -61.106049) (xy 407.055875 -61.112149) (xy 407.109832 -61.126255)
			(xy 407.161161 -61.148067) (xy 407.208767 -61.177121) (xy 407.251635 -61.212796) (xy 407.288852 -61.254333)
			(xy 407.319625 -61.300846) (xy 407.343297 -61.351343) (xy 407.359365 -61.40475) (xy 407.367485 -61.459926)
			(xy 407.367994 -61.487812) (xy 407.367485 -61.515698) (xy 407.359365 -61.570874) (xy 407.343297 -61.624281)
			(xy 407.319625 -61.674778) (xy 407.288852 -61.721291) (xy 407.251635 -61.762828) (xy 407.208767 -61.798503)
			(xy 407.161161 -61.827557) (xy 407.109832 -61.849369) (xy 407.055875 -61.863475) (xy 407.000438 -61.869575)
			(xy 406.944704 -61.867538) (xy 406.889861 -61.857408) (xy 406.837077 -61.839401) (xy 406.787477 -61.8139)
			(xy 406.742119 -61.781449) (xy 406.70197 -61.74274) (xy 406.667884 -61.698597) (xy 406.640588 -61.649962)
			(xy 406.620665 -61.597871) (xy 406.608539 -61.543434) (xy 406.604468 -61.487812) (xy 401.435824 -61.487812)
			(xy 401.435824 -62.121034) (xy 404.542242 -62.121034) (xy 404.546313 -62.065412) (xy 404.558439 -62.010975)
			(xy 404.578362 -61.958884) (xy 404.605658 -61.910249) (xy 404.639744 -61.866106) (xy 404.679893 -61.827397)
			(xy 404.725251 -61.794946) (xy 404.774851 -61.769445) (xy 404.827635 -61.751438) (xy 404.882478 -61.741308)
			(xy 404.938212 -61.739271) (xy 404.993649 -61.745371) (xy 405.047606 -61.759477) (xy 405.098935 -61.781289)
			(xy 405.146541 -61.810343) (xy 405.189409 -61.846018) (xy 405.226626 -61.887555) (xy 405.257399 -61.934068)
			(xy 405.281071 -61.984565) (xy 405.297139 -62.037972) (xy 405.305259 -62.093148) (xy 405.305768 -62.121034)
			(xy 405.305259 -62.14892) (xy 405.297139 -62.204096) (xy 405.281071 -62.257503) (xy 405.257399 -62.308)
			(xy 405.226626 -62.354513) (xy 405.189409 -62.39605) (xy 405.146541 -62.431725) (xy 405.098935 -62.460779)
			(xy 405.047606 -62.482591) (xy 404.993649 -62.496697) (xy 404.938212 -62.502797) (xy 404.882478 -62.50076)
			(xy 404.827635 -62.49063) (xy 404.774851 -62.472623) (xy 404.725251 -62.447122) (xy 404.679893 -62.414671)
			(xy 404.639744 -62.375962) (xy 404.605658 -62.331819) (xy 404.578362 -62.283184) (xy 404.558439 -62.231093)
			(xy 404.546313 -62.176656) (xy 404.542242 -62.121034) (xy 401.435824 -62.121034) (xy 401.435824 -63.086234)
			(xy 401.687536 -63.086234) (xy 401.691607 -63.030612) (xy 401.703733 -62.976175) (xy 401.723656 -62.924084)
			(xy 401.750952 -62.875449) (xy 401.785038 -62.831306) (xy 401.825187 -62.792597) (xy 401.870545 -62.760146)
			(xy 401.920145 -62.734645) (xy 401.972929 -62.716638) (xy 402.027772 -62.706508) (xy 402.083506 -62.704471)
			(xy 402.138943 -62.710571) (xy 402.1929 -62.724677) (xy 402.244229 -62.746489) (xy 402.291835 -62.775543)
			(xy 402.334703 -62.811218) (xy 402.37192 -62.852755) (xy 402.402693 -62.899268) (xy 402.426365 -62.949765)
			(xy 402.442433 -63.003172) (xy 402.450553 -63.058348) (xy 402.451062 -63.086234) (xy 402.450553 -63.11412)
			(xy 402.442433 -63.169296) (xy 402.426365 -63.222703) (xy 402.402693 -63.2732) (xy 402.40254 -63.273432)
			(xy 403.876762 -63.273432) (xy 403.880833 -63.21781) (xy 403.892959 -63.163373) (xy 403.912882 -63.111282)
			(xy 403.940178 -63.062647) (xy 403.974264 -63.018504) (xy 404.014413 -62.979795) (xy 404.059771 -62.947344)
			(xy 404.109371 -62.921843) (xy 404.162155 -62.903836) (xy 404.216998 -62.893706) (xy 404.272732 -62.891669)
			(xy 404.328169 -62.897769) (xy 404.382126 -62.911875) (xy 404.433455 -62.933687) (xy 404.481061 -62.962741)
			(xy 404.523929 -62.998416) (xy 404.561146 -63.039953) (xy 404.591919 -63.086466) (xy 404.615591 -63.136963)
			(xy 404.631659 -63.19037) (xy 404.639779 -63.245546) (xy 404.640288 -63.273432) (xy 404.639779 -63.301318)
			(xy 404.631659 -63.356494) (xy 404.615591 -63.409901) (xy 404.591919 -63.460398) (xy 404.561146 -63.506911)
			(xy 404.523929 -63.548448) (xy 404.481061 -63.584123) (xy 404.433455 -63.613177) (xy 404.382126 -63.634989)
			(xy 404.328169 -63.649095) (xy 404.272732 -63.655195) (xy 404.216998 -63.653158) (xy 404.162155 -63.643028)
			(xy 404.109371 -63.625021) (xy 404.059771 -63.59952) (xy 404.014413 -63.567069) (xy 403.974264 -63.52836)
			(xy 403.940178 -63.484217) (xy 403.912882 -63.435582) (xy 403.892959 -63.383491) (xy 403.880833 -63.329054)
			(xy 403.876762 -63.273432) (xy 402.40254 -63.273432) (xy 402.37192 -63.319713) (xy 402.334703 -63.36125)
			(xy 402.291835 -63.396925) (xy 402.244229 -63.425979) (xy 402.1929 -63.447791) (xy 402.138943 -63.461897)
			(xy 402.083506 -63.467997) (xy 402.027772 -63.46596) (xy 401.972929 -63.45583) (xy 401.920145 -63.437823)
			(xy 401.870545 -63.412322) (xy 401.825187 -63.379871) (xy 401.785038 -63.341162) (xy 401.750952 -63.297019)
			(xy 401.723656 -63.248384) (xy 401.703733 -63.196293) (xy 401.691607 -63.141856) (xy 401.687536 -63.086234)
			(xy 401.435824 -63.086234) (xy 401.435824 -63.569088) (xy 401.435339 -63.595175) (xy 401.427173 -63.646707)
			(xy 401.411041 -63.696325) (xy 401.38734 -63.742806) (xy 401.356656 -63.785004) (xy 401.338542 -63.803784)
			(xy 400.058382 -65.083944) (xy 400.039611 -65.101976) (xy 399.997494 -65.132554) (xy 399.951118 -65.156178)
			(xy 399.90162 -65.172268) (xy 399.850217 -65.180428) (xy 399.824194 -65.180972) (xy 397.21282 -65.180972)
			(xy 397.204438 -65.181734) (xy 397.196745 -65.183273) (xy 397.182773 -65.190386) (xy 397.177006 -65.195704)
			(xy 396.289276 -66.083688) (xy 396.270504 -66.101717) (xy 396.228386 -66.132291) (xy 396.182009 -66.155911)
			(xy 396.132512 -66.171998) (xy 396.08111 -66.180156) (xy 396.055088 -66.180716) (xy 395.30528 -66.180716)
			(xy 395.298676 -66.181224) (xy 395.290491 -66.182584) (xy 395.275585 -66.189844) (xy 395.269466 -66.195448)
			(xy 394.775944 -66.689224) (xy 394.757175 -66.70726) (xy 394.71506 -66.737849) (xy 394.668685 -66.761483)
			(xy 394.619187 -66.777583) (xy 394.567781 -66.785753) (xy 394.541756 -66.786252) (xy 390.0805 -66.786252)
			(xy 390.076701 -66.789254) (xy 390.07019 -66.796419) (xy 390.067546 -66.800476) (xy 390.04494 -66.83756)
			(xy 390.04494 -66.838068) (xy 390.026906 -66.868294) (xy 390.024084 -66.873923) (xy 390.021005 -66.88613)
			(xy 390.02081 -66.892424) (xy 390.02081 -66.918586) (xy 390.02335 -66.929762) (xy 390.02589 -66.934842)
			(xy 390.037709 -66.960271) (xy 390.054582 -67.013746) (xy 390.063427 -67.069118) (xy 390.064244 -67.097148)
			(xy 390.064244 -67.102736) (xy 390.063688 -67.12994) (xy 390.055812 -67.183777) (xy 390.040368 -67.23595)
			(xy 390.017668 -67.285399) (xy 389.988174 -67.331122) (xy 389.952484 -67.372192) (xy 389.911321 -67.407774)
			(xy 389.865521 -67.437149) (xy 389.816012 -67.459718) (xy 389.763799 -67.475026) (xy 389.709941 -67.48276)
			(xy 389.682736 -67.483228) (xy 389.65712 -67.482814) (xy 389.606349 -67.475954) (xy 389.556956 -67.462353)
			(xy 389.50983 -67.442255) (xy 389.465822 -67.416024) (xy 389.4455 -67.400424) (xy 389.445246 -67.40017)
			(xy 389.442198 -67.39763) (xy 389.436088 -67.393899) (xy 389.422422 -67.38965) (xy 389.415274 -67.389248)
			(xy 389.391906 -67.389248) (xy 389.386466 -67.389108) (xy 389.375832 -67.386806) (xy 389.370824 -67.384676)
			(xy 389.357108 -67.378326) (xy 389.352403 -67.376265) (xy 389.342422 -67.373839) (xy 389.337296 -67.3735)
			(xy 389.32866 -67.374008) (xy 389.321372 -67.375286) (xy 389.307941 -67.381479) (xy 389.302244 -67.3862)
			(xy 389.30199 -67.386454) (xy 389.280921 -67.404565) (xy 389.234528 -67.435133) (xy 389.184196 -67.458655)
			(xy 389.130986 -67.474635) (xy 389.076022 -67.482736) (xy 389.048244 -67.483228) (xy 389.047736 -67.483228)
			(xy 389.020796 -67.48276) (xy 388.967453 -67.475173) (xy 388.915707 -67.460158) (xy 388.866587 -67.438014)
			(xy 388.821071 -67.409181) (xy 388.780062 -67.374233) (xy 388.744377 -67.333864) (xy 388.714724 -67.288878)
			(xy 388.691694 -67.240167) (xy 388.675744 -67.188702) (xy 388.667192 -67.135505) (xy 388.666228 -67.108578)
			(xy 388.666228 -67.10807) (xy 388.665974 -67.101466) (xy 388.665974 -67.101212) (xy 388.666541 -67.072079)
			(xy 388.675436 -67.014495) (xy 388.69299 -66.958935) (xy 388.718794 -66.906693) (xy 388.735062 -66.882518)
			(xy 388.735316 -66.88201) (xy 388.738964 -66.876515) (xy 388.743582 -66.864164) (xy 388.74446 -66.857626)
			(xy 388.74573 -66.845434) (xy 388.74192 -66.836798) (xy 388.740904 -66.834512) (xy 388.739888 -66.83248)
			(xy 388.72795 -66.806064) (xy 388.725153 -66.8003) (xy 388.717193 -66.790268) (xy 388.712202 -66.786252)
			(xy 388.601966 -66.786252) (xy 388.59714 -66.791332) (xy 388.595362 -66.792856) (xy 388.593076 -66.794634)
			(xy 388.242048 -67.145662) (xy 388.234648 -67.152504) (xy 388.21605 -67.160226) (xy 388.20598 -67.160648)
			(xy 386.865622 -67.160648) (xy 386.859613 -67.160818) (xy 386.847932 -67.163645) (xy 386.842508 -67.166236)
			(xy 386.839034 -67.168075) (xy 386.832655 -67.172669) (xy 386.829808 -67.17538) (xy 386.517134 -67.488054)
			(xy 393.079222 -67.488054) (xy 393.083293 -67.432432) (xy 393.095419 -67.377995) (xy 393.115342 -67.325904)
			(xy 393.142638 -67.277269) (xy 393.176724 -67.233126) (xy 393.216873 -67.194417) (xy 393.262231 -67.161966)
			(xy 393.311831 -67.136465) (xy 393.364615 -67.118458) (xy 393.419458 -67.108328) (xy 393.475192 -67.106291)
			(xy 393.530629 -67.112391) (xy 393.584586 -67.126497) (xy 393.635915 -67.148309) (xy 393.683521 -67.177363)
			(xy 393.726389 -67.213038) (xy 393.763606 -67.254575) (xy 393.794379 -67.301088) (xy 393.818051 -67.351585)
			(xy 393.834119 -67.404992) (xy 393.842239 -67.460168) (xy 393.842748 -67.488054) (xy 393.842239 -67.51594)
			(xy 393.839054 -67.537584) (xy 394.37132 -67.537584) (xy 394.375391 -67.481962) (xy 394.387517 -67.427525)
			(xy 394.40744 -67.375434) (xy 394.434736 -67.326799) (xy 394.468822 -67.282656) (xy 394.508971 -67.243947)
			(xy 394.554329 -67.211496) (xy 394.603929 -67.185995) (xy 394.656713 -67.167988) (xy 394.711556 -67.157858)
			(xy 394.76729 -67.155821) (xy 394.822727 -67.161921) (xy 394.876684 -67.176027) (xy 394.928013 -67.197839)
			(xy 394.975619 -67.226893) (xy 395.018487 -67.262568) (xy 395.055704 -67.304105) (xy 395.086477 -67.350618)
			(xy 395.110149 -67.401115) (xy 395.126217 -67.454522) (xy 395.134337 -67.509698) (xy 395.134846 -67.537584)
			(xy 395.134337 -67.56547) (xy 395.130292 -67.592956) (xy 395.645384 -67.592956) (xy 395.649455 -67.537334)
			(xy 395.661581 -67.482897) (xy 395.681504 -67.430806) (xy 395.7088 -67.382171) (xy 395.742886 -67.338028)
			(xy 395.783035 -67.299319) (xy 395.828393 -67.266868) (xy 395.877993 -67.241367) (xy 395.930777 -67.22336)
			(xy 395.98562 -67.21323) (xy 396.041354 -67.211193) (xy 396.096791 -67.217293) (xy 396.150748 -67.231399)
			(xy 396.202077 -67.253211) (xy 396.249683 -67.282265) (xy 396.292551 -67.31794) (xy 396.329768 -67.359477)
			(xy 396.360541 -67.40599) (xy 396.384213 -67.456487) (xy 396.400281 -67.509894) (xy 396.408398 -67.565051)
			(xy 398.746693 -67.565051) (xy 398.746693 -67.510549) (xy 398.75445 -67.456601) (xy 398.769806 -67.404306)
			(xy 398.792448 -67.354729) (xy 398.821916 -67.308879) (xy 398.857609 -67.26769) (xy 398.8988 -67.232)
			(xy 398.944652 -67.202536) (xy 398.994231 -67.179897) (xy 399.046526 -67.164545) (xy 399.100475 -67.156791)
			(xy 399.127726 -67.15633) (xy 399.155097 -67.156774) (xy 399.209277 -67.164596) (xy 399.261781 -67.18009)
			(xy 399.311528 -67.202937) (xy 399.357493 -67.232666) (xy 399.378424 -67.25031) (xy 399.378678 -67.250564)
			(xy 399.385761 -67.256155) (xy 399.402681 -67.262397) (xy 399.411698 -67.262756) (xy 399.478754 -67.262756)
			(xy 399.48777 -67.262387) (xy 399.504687 -67.256149) (xy 399.511774 -67.250564) (xy 399.511774 -67.25031)
			(xy 399.512028 -67.25031) (xy 399.532978 -67.232693) (xy 399.578945 -67.202977) (xy 399.628689 -67.180137)
			(xy 399.681185 -67.164641) (xy 399.735358 -67.156807) (xy 399.762726 -67.15633) (xy 399.789979 -67.156742)
			(xy 399.843929 -67.164502) (xy 399.896226 -67.179861) (xy 399.945805 -67.202506) (xy 399.991656 -67.231976)
			(xy 400.032848 -67.267671) (xy 400.06854 -67.308864) (xy 400.098007 -67.354718) (xy 400.120648 -67.404299)
			(xy 400.136004 -67.456596) (xy 400.14376 -67.510547) (xy 400.14376 -67.565053) (xy 400.136004 -67.619004)
			(xy 400.120648 -67.671301) (xy 400.098007 -67.720882) (xy 400.06854 -67.766736) (xy 400.032848 -67.807929)
			(xy 399.991656 -67.843624) (xy 399.945805 -67.873094) (xy 399.896226 -67.895739) (xy 399.843929 -67.911098)
			(xy 399.789979 -67.918858) (xy 399.762726 -67.919346) (xy 399.735356 -67.918878) (xy 399.681176 -67.911063)
			(xy 399.628673 -67.895575) (xy 399.578926 -67.872733) (xy 399.532959 -67.843008) (xy 399.512028 -67.825366)
			(xy 399.511774 -67.825112) (xy 399.504669 -67.819552) (xy 399.487767 -67.813289) (xy 399.478754 -67.81292)
			(xy 399.411698 -67.81292) (xy 399.40268 -67.813272) (xy 399.385763 -67.819522) (xy 399.378678 -67.825112)
			(xy 399.378678 -67.825366) (xy 399.378424 -67.825366) (xy 399.357489 -67.843002) (xy 399.311518 -67.872715)
			(xy 399.261771 -67.895553) (xy 399.209271 -67.911044) (xy 399.155095 -67.918872) (xy 399.127726 -67.919346)
			(xy 399.100475 -67.918809) (xy 399.046526 -67.911055) (xy 398.994231 -67.895703) (xy 398.944652 -67.873064)
			(xy 398.8988 -67.8436) (xy 398.857609 -67.80791) (xy 398.821916 -67.766721) (xy 398.792448 -67.720871)
			(xy 398.769806 -67.671294) (xy 398.75445 -67.618999) (xy 398.746693 -67.565051) (xy 396.408398 -67.565051)
			(xy 396.408401 -67.56507) (xy 396.40891 -67.592956) (xy 396.408401 -67.620842) (xy 396.400281 -67.676018)
			(xy 396.384213 -67.729425) (xy 396.360541 -67.779922) (xy 396.329768 -67.826435) (xy 396.292551 -67.867972)
			(xy 396.249683 -67.903647) (xy 396.202077 -67.932701) (xy 396.150748 -67.954513) (xy 396.096791 -67.968619)
			(xy 396.041354 -67.974719) (xy 395.98562 -67.972682) (xy 395.930777 -67.962552) (xy 395.877993 -67.944545)
			(xy 395.828393 -67.919044) (xy 395.783035 -67.886593) (xy 395.742886 -67.847884) (xy 395.7088 -67.803741)
			(xy 395.681504 -67.755106) (xy 395.661581 -67.703015) (xy 395.649455 -67.648578) (xy 395.645384 -67.592956)
			(xy 395.130292 -67.592956) (xy 395.126217 -67.620646) (xy 395.110149 -67.674053) (xy 395.086477 -67.72455)
			(xy 395.055704 -67.771063) (xy 395.018487 -67.8126) (xy 394.975619 -67.848275) (xy 394.928013 -67.877329)
			(xy 394.876684 -67.899141) (xy 394.822727 -67.913247) (xy 394.76729 -67.919347) (xy 394.711556 -67.91731)
			(xy 394.656713 -67.90718) (xy 394.603929 -67.889173) (xy 394.554329 -67.863672) (xy 394.508971 -67.831221)
			(xy 394.468822 -67.792512) (xy 394.434736 -67.748369) (xy 394.40744 -67.699734) (xy 394.387517 -67.647643)
			(xy 394.375391 -67.593206) (xy 394.37132 -67.537584) (xy 393.839054 -67.537584) (xy 393.834119 -67.571116)
			(xy 393.818051 -67.624523) (xy 393.794379 -67.67502) (xy 393.763606 -67.721533) (xy 393.726389 -67.76307)
			(xy 393.683521 -67.798745) (xy 393.635915 -67.827799) (xy 393.584586 -67.849611) (xy 393.530629 -67.863717)
			(xy 393.475192 -67.869817) (xy 393.419458 -67.86778) (xy 393.364615 -67.85765) (xy 393.311831 -67.839643)
			(xy 393.262231 -67.814142) (xy 393.216873 -67.781691) (xy 393.176724 -67.742982) (xy 393.142638 -67.698839)
			(xy 393.115342 -67.650204) (xy 393.095419 -67.598113) (xy 393.083293 -67.543676) (xy 393.079222 -67.488054)
			(xy 386.517134 -67.488054) (xy 385.418584 -68.586604) (xy 390.925304 -68.586604) (xy 390.925771 -68.559234)
			(xy 390.933589 -68.505055) (xy 390.949077 -68.452552) (xy 390.971919 -68.402805) (xy 391.001643 -68.356838)
			(xy 391.019284 -68.335906) (xy 391.019538 -68.335652) (xy 391.025113 -68.328558) (xy 391.031366 -68.311647)
			(xy 391.03173 -68.302632) (xy 391.03173 -68.235576) (xy 391.031378 -68.226559) (xy 391.025126 -68.209642)
			(xy 391.019538 -68.202556) (xy 391.019284 -68.202556) (xy 391.019284 -68.202302) (xy 391.00163 -68.181382)
			(xy 390.971921 -68.135406) (xy 390.949088 -68.085655) (xy 390.9336 -68.033152) (xy 390.925776 -67.978974)
			(xy 390.925304 -67.951604) (xy 390.925759 -67.924351) (xy 390.933516 -67.870399) (xy 390.948872 -67.8181)
			(xy 390.971515 -67.768519) (xy 391.000984 -67.722666) (xy 391.036678 -67.681472) (xy 391.077872 -67.645779)
			(xy 391.123726 -67.616311) (xy 391.173308 -67.593669) (xy 391.225607 -67.578314) (xy 391.279559 -67.570559)
			(xy 391.306812 -67.570096) (xy 391.333126 -67.570557) (xy 391.385255 -67.577793) (xy 391.435898 -67.592114)
			(xy 391.484097 -67.613247) (xy 391.52894 -67.640795) (xy 391.569579 -67.674234) (xy 391.587736 -67.693286)
			(xy 391.595244 -67.700703) (xy 391.614534 -67.709219) (xy 391.625074 -67.709796) (xy 391.69975 -67.709796)
			(xy 391.710298 -67.709255) (xy 391.729594 -67.700728) (xy 391.737088 -67.693286) (xy 391.755254 -67.674241)
			(xy 391.795882 -67.640783) (xy 391.84072 -67.613223) (xy 391.888919 -67.592083) (xy 391.939564 -67.577763)
			(xy 391.991696 -67.570536) (xy 392.018012 -67.570096) (xy 392.045382 -67.570556) (xy 392.099562 -67.578375)
			(xy 392.152065 -67.593866) (xy 392.201812 -67.616709) (xy 392.247778 -67.646434) (xy 392.26871 -67.664076)
			(xy 392.268964 -67.66433) (xy 392.276054 -67.669911) (xy 392.292968 -67.67616) (xy 392.301984 -67.676522)
			(xy 392.36904 -67.676522) (xy 392.378058 -67.676179) (xy 392.394975 -67.669921) (xy 392.40206 -67.66433)
			(xy 392.40206 -67.664076) (xy 392.402314 -67.664076) (xy 392.423265 -67.64646) (xy 392.469233 -67.616746)
			(xy 392.518976 -67.593906) (xy 392.571472 -67.578409) (xy 392.625644 -67.570574) (xy 392.653012 -67.570096)
			(xy 392.680264 -67.570567) (xy 392.734212 -67.578325) (xy 392.786507 -67.593682) (xy 392.836085 -67.616325)
			(xy 392.881936 -67.645792) (xy 392.923126 -67.681486) (xy 392.958817 -67.722677) (xy 392.988283 -67.768529)
			(xy 393.010924 -67.818108) (xy 393.026279 -67.870403) (xy 393.034035 -67.924352) (xy 393.03452 -67.951604)
			(xy 393.034076 -67.978975) (xy 393.026256 -68.033156) (xy 393.010763 -68.08566) (xy 392.987915 -68.135407)
			(xy 392.958185 -68.181372) (xy 392.94054 -68.202302) (xy 392.940286 -68.202556) (xy 392.93471 -68.20965)
			(xy 392.928457 -68.226561) (xy 392.928094 -68.235576) (xy 392.928094 -68.302632) (xy 392.928437 -68.31165)
			(xy 392.934695 -68.328567) (xy 392.940286 -68.335652) (xy 392.94054 -68.335652) (xy 392.94054 -68.335906)
			(xy 392.958202 -68.35682) (xy 392.987909 -68.402798) (xy 393.01074 -68.45255) (xy 393.026226 -68.505055)
			(xy 393.034049 -68.559234) (xy 393.03452 -68.586604) (xy 393.034026 -68.613855) (xy 393.026269 -68.667802)
			(xy 393.010914 -68.720095) (xy 392.994275 -68.75653) (xy 396.470378 -68.75653) (xy 396.470843 -68.729159)
			(xy 396.478658 -68.67498) (xy 396.494146 -68.622476) (xy 396.516989 -68.572729) (xy 396.546715 -68.526763)
			(xy 396.564358 -68.505832) (xy 396.564612 -68.505578) (xy 396.570215 -68.498503) (xy 396.576452 -68.481577)
			(xy 396.576804 -68.472558) (xy 396.576804 -68.405502) (xy 396.576445 -68.396485) (xy 396.570199 -68.379568)
			(xy 396.564612 -68.372482) (xy 396.564358 -68.372482) (xy 396.564358 -68.372228) (xy 396.546712 -68.351302)
			(xy 396.517002 -68.305327) (xy 396.494168 -68.255578) (xy 396.478679 -68.203076) (xy 396.470851 -68.148899)
			(xy 396.470378 -68.12153) (xy 396.470883 -68.094279) (xy 396.478636 -68.04033) (xy 396.493987 -67.988034)
			(xy 396.516625 -67.938455) (xy 396.546089 -67.892602) (xy 396.581778 -67.851409) (xy 396.622967 -67.815715)
			(xy 396.668816 -67.786246) (xy 396.718392 -67.763603) (xy 396.770687 -67.748245) (xy 396.824635 -67.740486)
			(xy 396.851886 -67.740022) (xy 396.879256 -67.740491) (xy 396.933435 -67.748307) (xy 396.985939 -67.763795)
			(xy 397.035686 -67.786637) (xy 397.081652 -67.816361) (xy 397.102584 -67.834002) (xy 397.102838 -67.834256)
			(xy 397.109933 -67.839829) (xy 397.126844 -67.846083) (xy 397.135858 -67.846448) (xy 397.202914 -67.846448)
			(xy 397.211933 -67.846109) (xy 397.22885 -67.83985) (xy 397.235934 -67.834256) (xy 397.235934 -67.834002)
			(xy 397.236188 -67.834002) (xy 397.257114 -67.816355) (xy 397.303088 -67.786645) (xy 397.352837 -67.76381)
			(xy 397.40534 -67.748321) (xy 397.459516 -67.740495) (xy 397.486886 -67.740022) (xy 397.5132 -67.740492)
			(xy 397.565329 -67.747725) (xy 397.615972 -67.762043) (xy 397.664171 -67.783175) (xy 397.709014 -67.810721)
			(xy 397.749654 -67.84416) (xy 397.76781 -67.863212) (xy 397.775324 -67.870622) (xy 397.79461 -67.879141)
			(xy 397.805148 -67.879722) (xy 397.879824 -67.879722) (xy 397.89037 -67.879159) (xy 397.909665 -67.870647)
			(xy 397.917162 -67.863212) (xy 397.935297 -67.844136) (xy 397.975931 -67.81068) (xy 398.020775 -67.783123)
			(xy 398.06898 -67.761988) (xy 398.119631 -67.747676) (xy 398.171769 -67.740457) (xy 398.198086 -67.740022)
			(xy 398.22534 -67.740468) (xy 398.279293 -67.748224) (xy 398.331593 -67.76358) (xy 398.381175 -67.786223)
			(xy 398.42703 -67.815692) (xy 398.468223 -67.851388) (xy 398.503917 -67.892583) (xy 398.533385 -67.938439)
			(xy 398.556026 -67.988022) (xy 398.571379 -68.040323) (xy 398.579133 -68.094276) (xy 398.579594 -68.12153)
			(xy 398.579147 -68.148901) (xy 398.571325 -68.203081) (xy 398.555831 -68.255584) (xy 398.532985 -68.305331)
			(xy 398.503257 -68.351297) (xy 398.485614 -68.372228) (xy 398.48536 -68.372482) (xy 398.47977 -68.379566)
			(xy 398.473526 -68.396485) (xy 398.473168 -68.405502) (xy 398.473168 -68.472558) (xy 398.473552 -68.481572)
			(xy 398.479782 -68.498489) (xy 398.48536 -68.505578) (xy 398.485614 -68.505578) (xy 398.485614 -68.505832)
			(xy 398.503237 -68.526777) (xy 398.532951 -68.572747) (xy 398.555789 -68.622491) (xy 398.571284 -68.674988)
			(xy 398.579117 -68.729162) (xy 398.579594 -68.75653) (xy 398.57915 -68.783783) (xy 398.571389 -68.837733)
			(xy 398.556029 -68.890029) (xy 398.533384 -68.939607) (xy 398.503913 -68.985458) (xy 398.468217 -69.026648)
			(xy 398.427023 -69.062339) (xy 398.381169 -69.091805) (xy 398.331588 -69.114445) (xy 398.27929 -69.129798)
			(xy 398.225339 -69.137553) (xy 398.198086 -69.138038) (xy 398.171771 -69.1376) (xy 398.11964 -69.130362)
			(xy 398.068996 -69.116038) (xy 398.020797 -69.0949) (xy 397.975954 -69.067348) (xy 397.935317 -69.033903)
			(xy 397.917162 -69.014848) (xy 397.90965 -69.007435) (xy 397.890363 -68.998916) (xy 397.879824 -68.998338)
			(xy 397.805148 -68.998338) (xy 397.794598 -68.998868) (xy 397.775302 -69.007402) (xy 397.76781 -69.014848)
			(xy 397.749652 -69.033901) (xy 397.709022 -69.067356) (xy 397.664182 -69.094915) (xy 397.615982 -69.116053)
			(xy 397.565335 -69.130371) (xy 397.513202 -69.137598) (xy 397.486886 -69.138038) (xy 397.459515 -69.137595)
			(xy 397.405334 -69.129774) (xy 397.35283 -69.11428) (xy 397.303084 -69.091433) (xy 397.257118 -69.061702)
			(xy 397.236188 -69.044058) (xy 397.235934 -69.043804) (xy 397.228842 -69.038226) (xy 397.211929 -69.031974)
			(xy 397.202914 -69.031612) (xy 397.135858 -69.031612) (xy 397.126844 -69.031994) (xy 397.109926 -69.038224)
			(xy 397.102838 -69.043804) (xy 397.102838 -69.044058) (xy 397.102584 -69.044058) (xy 397.081626 -69.061665)
			(xy 397.035661 -69.091383) (xy 396.98592 -69.114226) (xy 396.933425 -69.129724) (xy 396.879253 -69.13756)
			(xy 396.851886 -69.138038) (xy 396.824636 -69.137535) (xy 396.77069 -69.129778) (xy 396.718398 -69.114422)
			(xy 396.668822 -69.091782) (xy 396.622973 -69.062317) (xy 396.581784 -69.026627) (xy 396.546093 -68.985439)
			(xy 396.516626 -68.939592) (xy 396.493983 -68.890017) (xy 396.478626 -68.837725) (xy 396.470866 -68.78378)
			(xy 396.470378 -68.75653) (xy 392.994275 -68.75653) (xy 392.988273 -68.769672) (xy 392.958808 -68.815522)
			(xy 392.923117 -68.856712) (xy 392.881928 -68.892403) (xy 392.836079 -68.92187) (xy 392.786503 -68.944511)
			(xy 392.734209 -68.959868) (xy 392.680263 -68.967625) (xy 392.653012 -68.968112) (xy 392.625642 -68.967636)
			(xy 392.571464 -68.95982) (xy 392.518961 -68.944333) (xy 392.469214 -68.921494) (xy 392.423246 -68.891772)
			(xy 392.402314 -68.874132) (xy 392.40206 -68.873878) (xy 392.394962 -68.868308) (xy 392.378054 -68.862052)
			(xy 392.36904 -68.861686) (xy 392.301984 -68.861686) (xy 392.292967 -68.862039) (xy 392.27605 -68.86829)
			(xy 392.268964 -68.873878) (xy 392.268964 -68.874132) (xy 392.26871 -68.874132) (xy 392.247789 -68.891785)
			(xy 392.201813 -68.921494) (xy 392.152062 -68.944326) (xy 392.099559 -68.959814) (xy 392.045382 -68.967639)
			(xy 392.018012 -68.968112) (xy 391.991698 -68.967633) (xy 391.939571 -68.9604) (xy 391.888928 -68.946083)
			(xy 391.840729 -68.924952) (xy 391.795886 -68.897409) (xy 391.755245 -68.863972) (xy 391.737088 -68.844922)
			(xy 391.72957 -68.837516) (xy 391.710287 -68.828993) (xy 391.69975 -68.828412) (xy 391.625074 -68.828412)
			(xy 391.614527 -68.828964) (xy 391.595231 -68.837483) (xy 391.587736 -68.844922) (xy 391.569609 -68.864006)
			(xy 391.528973 -68.89746) (xy 391.484126 -68.925014) (xy 391.43592 -68.946148) (xy 391.385268 -68.960459)
			(xy 391.33313 -68.967677) (xy 391.306812 -68.968112) (xy 391.27956 -68.967634) (xy 391.225609 -68.959878)
			(xy 391.173312 -68.944524) (xy 391.123732 -68.921883) (xy 391.077879 -68.892417) (xy 391.036687 -68.856725)
			(xy 391.000993 -68.815533) (xy 390.971525 -68.769682) (xy 390.948882 -68.720103) (xy 390.933525 -68.667806)
			(xy 390.925768 -68.613856) (xy 390.925304 -68.586604) (xy 385.418584 -68.586604) (xy 384.811524 -69.193664)
			(xy 384.811016 -69.200776) (xy 384.811016 -71.555864) (xy 393.494512 -71.555864) (xy 393.498583 -71.500242)
			(xy 393.510709 -71.445805) (xy 393.530632 -71.393714) (xy 393.557928 -71.345079) (xy 393.592014 -71.300936)
			(xy 393.632163 -71.262227) (xy 393.677521 -71.229776) (xy 393.727121 -71.204275) (xy 393.779905 -71.186268)
			(xy 393.834748 -71.176138) (xy 393.890482 -71.174101) (xy 393.945919 -71.180201) (xy 393.999876 -71.194307)
			(xy 394.051205 -71.216119) (xy 394.098811 -71.245173) (xy 394.141679 -71.280848) (xy 394.178896 -71.322385)
			(xy 394.209669 -71.368898) (xy 394.233341 -71.419395) (xy 394.249409 -71.472802) (xy 394.257529 -71.527978)
			(xy 394.258038 -71.555864) (xy 394.257529 -71.58375) (xy 394.25169 -71.623428) (xy 395.003526 -71.623428)
			(xy 395.007597 -71.567806) (xy 395.019723 -71.513369) (xy 395.039646 -71.461278) (xy 395.066942 -71.412643)
			(xy 395.101028 -71.3685) (xy 395.141177 -71.329791) (xy 395.186535 -71.29734) (xy 395.236135 -71.271839)
			(xy 395.288919 -71.253832) (xy 395.343762 -71.243702) (xy 395.399496 -71.241665) (xy 395.454933 -71.247765)
			(xy 395.50889 -71.261871) (xy 395.560219 -71.283683) (xy 395.607825 -71.312737) (xy 395.650693 -71.348412)
			(xy 395.68791 -71.389949) (xy 395.718683 -71.436462) (xy 395.742355 -71.486959) (xy 395.758423 -71.540366)
			(xy 395.766543 -71.595542) (xy 395.767052 -71.623428) (xy 395.766543 -71.651314) (xy 395.758423 -71.70649)
			(xy 395.742355 -71.759897) (xy 395.718683 -71.810394) (xy 395.68791 -71.856907) (xy 395.650693 -71.898444)
			(xy 395.607825 -71.934119) (xy 395.560219 -71.963173) (xy 395.50889 -71.984985) (xy 395.454933 -71.999091)
			(xy 395.399496 -72.005191) (xy 395.343762 -72.003154) (xy 395.288919 -71.993024) (xy 395.236135 -71.975017)
			(xy 395.186535 -71.949516) (xy 395.141177 -71.917065) (xy 395.101028 -71.878356) (xy 395.066942 -71.834213)
			(xy 395.039646 -71.785578) (xy 395.019723 -71.733487) (xy 395.007597 -71.67905) (xy 395.003526 -71.623428)
			(xy 394.25169 -71.623428) (xy 394.249409 -71.638926) (xy 394.233341 -71.692333) (xy 394.209669 -71.74283)
			(xy 394.178896 -71.789343) (xy 394.141679 -71.83088) (xy 394.098811 -71.866555) (xy 394.051205 -71.895609)
			(xy 393.999876 -71.917421) (xy 393.945919 -71.931527) (xy 393.890482 -71.937627) (xy 393.834748 -71.93559)
			(xy 393.779905 -71.92546) (xy 393.727121 -71.907453) (xy 393.677521 -71.881952) (xy 393.632163 -71.849501)
			(xy 393.592014 -71.810792) (xy 393.557928 -71.766649) (xy 393.530632 -71.718014) (xy 393.510709 -71.665923)
			(xy 393.498583 -71.611486) (xy 393.494512 -71.555864) (xy 384.811016 -71.555864) (xy 384.811016 -78.628494)
			(xy 391.77722 -78.628494) (xy 391.77722 -77.509624) (xy 391.777712 -77.474224) (xy 391.786244 -77.40394)
			(xy 391.803185 -77.335197) (xy 391.82829 -77.268998) (xy 391.861192 -77.206308) (xy 391.901412 -77.148041)
			(xy 391.948361 -77.095047) (xy 392.001357 -77.048099) (xy 392.059625 -77.007882) (xy 392.122316 -76.974982)
			(xy 392.188516 -76.949879) (xy 392.25726 -76.93294) (xy 392.327544 -76.924411) (xy 392.362944 -76.9239)
			(xy 392.397718 -76.924396) (xy 392.466777 -76.932619) (xy 392.534376 -76.948969) (xy 392.59956 -76.973214)
			(xy 392.661412 -77.005013) (xy 392.719059 -77.043918) (xy 392.77169 -77.089381) (xy 392.818562 -77.14076)
			(xy 392.839194 -77.168756) (xy 392.846088 -77.177413) (xy 392.865357 -77.188255) (xy 392.887394 -77.19006)
			(xy 392.908171 -77.182497) (xy 392.91641 -77.175106) (xy 392.937994 -77.154553) (xy 392.986333 -77.119695)
			(xy 393.039506 -77.09278) (xy 393.096219 -77.074464) (xy 393.15509 -77.065192) (xy 393.184888 -77.064616)
			(xy 393.215713 -77.065211) (xy 393.276558 -77.075135) (xy 393.335012 -77.094727) (xy 393.389548 -77.123475)
			(xy 393.414504 -77.141578) (xy 393.422006 -77.146773) (xy 393.439499 -77.151932) (xy 393.457694 -77.150675)
			(xy 393.474312 -77.143159) (xy 393.481052 -77.137006) (xy 393.5222 -77.095858) (xy 393.545774 -77.072969)
			(xy 393.597148 -77.032003) (xy 393.652786 -76.997047) (xy 393.711988 -76.96854) (xy 393.77401 -76.946841)
			(xy 393.838071 -76.932222) (xy 393.903366 -76.924867) (xy 393.93622 -76.924408) (xy 393.936474 -76.924408)
			(xy 393.971876 -76.92498) (xy 394.042164 -76.933509) (xy 394.110913 -76.950446) (xy 394.177119 -76.975545)
			(xy 394.239818 -77.008438) (xy 394.298097 -77.048647) (xy 394.351105 -77.095587) (xy 394.398071 -77.148572)
			(xy 394.43831 -77.20683) (xy 394.471235 -77.269513) (xy 394.496366 -77.335707) (xy 394.513337 -77.404446)
			(xy 394.521902 -77.47473) (xy 394.522452 -77.510132) (xy 394.521981 -77.543012) (xy 394.514621 -77.60836)
			(xy 394.499985 -77.672471) (xy 394.478259 -77.734538) (xy 394.449714 -77.793781) (xy 394.414712 -77.849452)
			(xy 394.373693 -77.900851) (xy 394.350748 -77.924406) (xy 394.08227 -78.192884) (xy 394.07544 -78.200292)
			(xy 394.067715 -78.218885) (xy 394.067284 -78.228952) (xy 394.067284 -78.722728) (xy 394.067596 -78.730746)
			(xy 394.072505 -78.746011) (xy 394.076936 -78.7527) (xy 394.09816 -78.782819) (xy 394.133711 -78.847357)
			(xy 394.160896 -78.915841) (xy 394.179286 -78.987191) (xy 394.18859 -79.060283) (xy 394.189204 -79.097124)
			(xy 394.189204 -80.356202) (xy 394.436344 -80.356202) (xy 394.440415 -80.30058) (xy 394.452541 -80.246143)
			(xy 394.472464 -80.194052) (xy 394.49976 -80.145417) (xy 394.533846 -80.101274) (xy 394.573995 -80.062565)
			(xy 394.619353 -80.030114) (xy 394.668953 -80.004613) (xy 394.721737 -79.986606) (xy 394.77658 -79.976476)
			(xy 394.832314 -79.974439) (xy 394.887751 -79.980539) (xy 394.941708 -79.994645) (xy 394.993037 -80.016457)
			(xy 395.040643 -80.045511) (xy 395.083511 -80.081186) (xy 395.120728 -80.122723) (xy 395.151501 -80.169236)
			(xy 395.175173 -80.219733) (xy 395.191241 -80.27314) (xy 395.199361 -80.328316) (xy 395.19987 -80.356202)
			(xy 396.84274 -80.356202) (xy 396.846811 -80.30058) (xy 396.858937 -80.246143) (xy 396.87886 -80.194052)
			(xy 396.906156 -80.145417) (xy 396.940242 -80.101274) (xy 396.980391 -80.062565) (xy 397.025749 -80.030114)
			(xy 397.075349 -80.004613) (xy 397.128133 -79.986606) (xy 397.182976 -79.976476) (xy 397.23871 -79.974439)
			(xy 397.294147 -79.980539) (xy 397.348104 -79.994645) (xy 397.399433 -80.016457) (xy 397.447039 -80.045511)
			(xy 397.489907 -80.081186) (xy 397.527124 -80.122723) (xy 397.557897 -80.169236) (xy 397.581569 -80.219733)
			(xy 397.597637 -80.27314) (xy 397.605757 -80.328316) (xy 397.606266 -80.356202) (xy 397.605757 -80.384088)
			(xy 397.597637 -80.439264) (xy 397.581569 -80.492671) (xy 397.557897 -80.543168) (xy 397.527124 -80.589681)
			(xy 397.489907 -80.631218) (xy 397.447039 -80.666893) (xy 397.399433 -80.695947) (xy 397.348104 -80.717759)
			(xy 397.294147 -80.731865) (xy 397.23871 -80.737965) (xy 397.182976 -80.735928) (xy 397.128133 -80.725798)
			(xy 397.075349 -80.707791) (xy 397.025749 -80.68229) (xy 396.980391 -80.649839) (xy 396.940242 -80.61113)
			(xy 396.906156 -80.566987) (xy 396.87886 -80.518352) (xy 396.858937 -80.466261) (xy 396.846811 -80.411824)
			(xy 396.84274 -80.356202) (xy 395.19987 -80.356202) (xy 395.199361 -80.384088) (xy 395.191241 -80.439264)
			(xy 395.175173 -80.492671) (xy 395.151501 -80.543168) (xy 395.120728 -80.589681) (xy 395.083511 -80.631218)
			(xy 395.040643 -80.666893) (xy 394.993037 -80.695947) (xy 394.941708 -80.717759) (xy 394.887751 -80.731865)
			(xy 394.832314 -80.737965) (xy 394.77658 -80.735928) (xy 394.721737 -80.725798) (xy 394.668953 -80.707791)
			(xy 394.619353 -80.68229) (xy 394.573995 -80.649839) (xy 394.533846 -80.61113) (xy 394.49976 -80.566987)
			(xy 394.472464 -80.518352) (xy 394.452541 -80.466261) (xy 394.440415 -80.411824) (xy 394.436344 -80.356202)
			(xy 394.189204 -80.356202) (xy 394.189204 -82.642202) (xy 396.84274 -82.642202) (xy 396.846811 -82.58658)
			(xy 396.858937 -82.532143) (xy 396.87886 -82.480052) (xy 396.906156 -82.431417) (xy 396.940242 -82.387274)
			(xy 396.980391 -82.348565) (xy 397.025749 -82.316114) (xy 397.075349 -82.290613) (xy 397.128133 -82.272606)
			(xy 397.182976 -82.262476) (xy 397.23871 -82.260439) (xy 397.294147 -82.266539) (xy 397.348104 -82.280645)
			(xy 397.399433 -82.302457) (xy 397.447039 -82.331511) (xy 397.489907 -82.367186) (xy 397.527124 -82.408723)
			(xy 397.557897 -82.455236) (xy 397.581569 -82.505733) (xy 397.597637 -82.55914) (xy 397.605757 -82.614316)
			(xy 397.606266 -82.642202) (xy 397.605757 -82.670088) (xy 397.597637 -82.725264) (xy 397.581569 -82.778671)
			(xy 397.557897 -82.829168) (xy 397.527124 -82.875681) (xy 397.489907 -82.917218) (xy 397.447039 -82.952893)
			(xy 397.399433 -82.981947) (xy 397.348104 -83.003759) (xy 397.294147 -83.017865) (xy 397.23871 -83.023965)
			(xy 397.182976 -83.021928) (xy 397.128133 -83.011798) (xy 397.075349 -82.993791) (xy 397.025749 -82.96829)
			(xy 396.980391 -82.935839) (xy 396.940242 -82.89713) (xy 396.906156 -82.852987) (xy 396.87886 -82.804352)
			(xy 396.858937 -82.752261) (xy 396.846811 -82.697824) (xy 396.84274 -82.642202) (xy 394.189204 -82.642202)
			(xy 394.189204 -82.770218) (xy 394.18961 -82.779837) (xy 394.196702 -82.797719) (xy 394.209882 -82.811732)
			(xy 394.218414 -82.816192) (xy 394.315188 -82.861912) (xy 394.34389 -82.858356) (xy 394.35532 -82.848958)
			(xy 394.375882 -82.832605) (xy 394.42065 -82.805108) (xy 394.468768 -82.784019) (xy 394.519327 -82.769735)
			(xy 394.571367 -82.762527) (xy 394.597636 -82.76209) (xy 394.624885 -82.762582) (xy 394.678829 -82.770343)
			(xy 394.731119 -82.785701) (xy 394.780692 -82.808344) (xy 394.826537 -82.837811) (xy 394.867723 -82.873503)
			(xy 394.90341 -82.914692) (xy 394.932873 -82.96054) (xy 394.955512 -83.010115) (xy 394.970865 -83.062406)
			(xy 394.97862 -83.116351) (xy 394.97862 -83.170849) (xy 394.970865 -83.224794) (xy 394.955512 -83.277085)
			(xy 394.932873 -83.32666) (xy 394.90341 -83.372508) (xy 394.867723 -83.413697) (xy 394.826537 -83.449389)
			(xy 394.780692 -83.478856) (xy 394.731119 -83.501499) (xy 394.678829 -83.516857) (xy 394.624885 -83.524618)
			(xy 394.597636 -83.525106) (xy 394.571369 -83.524635) (xy 394.519334 -83.517422) (xy 394.468779 -83.50314)
			(xy 394.420661 -83.48206) (xy 394.375888 -83.45458) (xy 394.35532 -83.438238) (xy 394.34389 -83.42884)
			(xy 394.315188 -83.425284) (xy 394.218414 -83.471004) (xy 394.209889 -83.475475) (xy 394.196712 -83.489484)
			(xy 394.18962 -83.507362) (xy 394.189204 -83.516978) (xy 394.189204 -83.785202) (xy 396.84274 -83.785202)
			(xy 396.846811 -83.72958) (xy 396.858937 -83.675143) (xy 396.87886 -83.623052) (xy 396.906156 -83.574417)
			(xy 396.940242 -83.530274) (xy 396.980391 -83.491565) (xy 397.025749 -83.459114) (xy 397.075349 -83.433613)
			(xy 397.128133 -83.415606) (xy 397.182976 -83.405476) (xy 397.23871 -83.403439) (xy 397.294147 -83.409539)
			(xy 397.348104 -83.423645) (xy 397.399433 -83.445457) (xy 397.447039 -83.474511) (xy 397.489907 -83.510186)
			(xy 397.527124 -83.551723) (xy 397.557897 -83.598236) (xy 397.581569 -83.648733) (xy 397.597637 -83.70214)
			(xy 397.605757 -83.757316) (xy 397.606266 -83.785202) (xy 397.605757 -83.813088) (xy 397.597637 -83.868264)
			(xy 397.581569 -83.921671) (xy 397.557897 -83.972168) (xy 397.527124 -84.018681) (xy 397.489907 -84.060218)
			(xy 397.447039 -84.095893) (xy 397.399433 -84.124947) (xy 397.348104 -84.146759) (xy 397.294147 -84.160865)
			(xy 397.23871 -84.166965) (xy 397.182976 -84.164928) (xy 397.128133 -84.154798) (xy 397.075349 -84.136791)
			(xy 397.025749 -84.11129) (xy 396.980391 -84.078839) (xy 396.940242 -84.04013) (xy 396.906156 -83.995987)
			(xy 396.87886 -83.947352) (xy 396.858937 -83.895261) (xy 396.846811 -83.840824) (xy 396.84274 -83.785202)
			(xy 394.189204 -83.785202) (xy 394.189204 -84.276692) (xy 394.311122 -84.276692) (xy 394.315193 -84.22107)
			(xy 394.327319 -84.166633) (xy 394.347242 -84.114542) (xy 394.374538 -84.065907) (xy 394.408624 -84.021764)
			(xy 394.448773 -83.983055) (xy 394.494131 -83.950604) (xy 394.543731 -83.925103) (xy 394.596515 -83.907096)
			(xy 394.651358 -83.896966) (xy 394.707092 -83.894929) (xy 394.762529 -83.901029) (xy 394.816486 -83.915135)
			(xy 394.867815 -83.936947) (xy 394.915421 -83.966001) (xy 394.958289 -84.001676) (xy 394.995506 -84.043213)
			(xy 395.026279 -84.089726) (xy 395.049951 -84.140223) (xy 395.066019 -84.19363) (xy 395.074139 -84.248806)
			(xy 395.074648 -84.276692) (xy 395.074139 -84.304578) (xy 395.066019 -84.359754) (xy 395.049951 -84.413161)
			(xy 395.026279 -84.463658) (xy 394.995506 -84.510171) (xy 394.958289 -84.551708) (xy 394.915421 -84.587383)
			(xy 394.867815 -84.616437) (xy 394.816486 -84.638249) (xy 394.762529 -84.652355) (xy 394.707092 -84.658455)
			(xy 394.651358 -84.656418) (xy 394.596515 -84.646288) (xy 394.543731 -84.628281) (xy 394.494131 -84.60278)
			(xy 394.448773 -84.570329) (xy 394.408624 -84.53162) (xy 394.374538 -84.487477) (xy 394.347242 -84.438842)
			(xy 394.327319 -84.386751) (xy 394.315193 -84.332314) (xy 394.311122 -84.276692) (xy 394.189204 -84.276692)
			(xy 394.189204 -84.928202) (xy 396.84274 -84.928202) (xy 396.846811 -84.87258) (xy 396.858937 -84.818143)
			(xy 396.87886 -84.766052) (xy 396.906156 -84.717417) (xy 396.940242 -84.673274) (xy 396.980391 -84.634565)
			(xy 397.025749 -84.602114) (xy 397.075349 -84.576613) (xy 397.128133 -84.558606) (xy 397.182976 -84.548476)
			(xy 397.23871 -84.546439) (xy 397.294147 -84.552539) (xy 397.348104 -84.566645) (xy 397.399433 -84.588457)
			(xy 397.447039 -84.617511) (xy 397.489907 -84.653186) (xy 397.527124 -84.694723) (xy 397.544804 -84.721446)
			(xy 399.610832 -84.721446) (xy 399.614903 -84.665824) (xy 399.627029 -84.611387) (xy 399.646952 -84.559296)
			(xy 399.674248 -84.510661) (xy 399.708334 -84.466518) (xy 399.748483 -84.427809) (xy 399.793841 -84.395358)
			(xy 399.843441 -84.369857) (xy 399.896225 -84.35185) (xy 399.951068 -84.34172) (xy 400.006802 -84.339683)
			(xy 400.062239 -84.345783) (xy 400.116196 -84.359889) (xy 400.167525 -84.381701) (xy 400.215131 -84.410755)
			(xy 400.257999 -84.44643) (xy 400.295216 -84.487967) (xy 400.325989 -84.53448) (xy 400.349661 -84.584977)
			(xy 400.365729 -84.638384) (xy 400.373849 -84.69356) (xy 400.374358 -84.721446) (xy 400.373849 -84.749332)
			(xy 400.365729 -84.804508) (xy 400.349661 -84.857915) (xy 400.325989 -84.908412) (xy 400.295216 -84.954925)
			(xy 400.257999 -84.996462) (xy 400.215131 -85.032137) (xy 400.167525 -85.061191) (xy 400.116196 -85.083003)
			(xy 400.062239 -85.097109) (xy 400.006802 -85.103209) (xy 399.951068 -85.101172) (xy 399.896225 -85.091042)
			(xy 399.843441 -85.073035) (xy 399.793841 -85.047534) (xy 399.748483 -85.015083) (xy 399.708334 -84.976374)
			(xy 399.674248 -84.932231) (xy 399.646952 -84.883596) (xy 399.627029 -84.831505) (xy 399.614903 -84.777068)
			(xy 399.610832 -84.721446) (xy 397.544804 -84.721446) (xy 397.557897 -84.741236) (xy 397.581569 -84.791733)
			(xy 397.597637 -84.84514) (xy 397.605757 -84.900316) (xy 397.606266 -84.928202) (xy 397.605757 -84.956088)
			(xy 397.597637 -85.011264) (xy 397.581569 -85.064671) (xy 397.557897 -85.115168) (xy 397.527124 -85.161681)
			(xy 397.489907 -85.203218) (xy 397.447039 -85.238893) (xy 397.399433 -85.267947) (xy 397.348104 -85.289759)
			(xy 397.294147 -85.303865) (xy 397.23871 -85.309965) (xy 397.182976 -85.307928) (xy 397.128133 -85.297798)
			(xy 397.075349 -85.279791) (xy 397.025749 -85.25429) (xy 396.980391 -85.221839) (xy 396.940242 -85.18313)
			(xy 396.906156 -85.138987) (xy 396.87886 -85.090352) (xy 396.858937 -85.038261) (xy 396.846811 -84.983824)
			(xy 396.84274 -84.928202) (xy 394.189204 -84.928202) (xy 394.189204 -85.13699) (xy 394.189629 -85.146769)
			(xy 394.196917 -85.164919) (xy 394.210447 -85.179043) (xy 394.219176 -85.183472) (xy 394.304266 -85.221318)
			(xy 394.313372 -85.224921) (xy 394.332927 -85.225602) (xy 394.351311 -85.218902) (xy 394.358876 -85.212682)
			(xy 394.379965 -85.194391) (xy 394.426506 -85.163566) (xy 394.477044 -85.139854) (xy 394.530497 -85.12376)
			(xy 394.585726 -85.115629) (xy 394.613638 -85.115146) (xy 394.640884 -85.115727) (xy 394.694821 -85.123487)
			(xy 394.747105 -85.138843) (xy 394.796671 -85.161484) (xy 394.842511 -85.190948) (xy 394.883692 -85.226635)
			(xy 394.919375 -85.267819) (xy 394.948834 -85.313662) (xy 394.97147 -85.363231) (xy 394.986821 -85.415516)
			(xy 394.994576 -85.469454) (xy 394.994576 -85.523946) (xy 394.986821 -85.577884) (xy 394.97147 -85.630169)
			(xy 394.948834 -85.679738) (xy 394.919375 -85.725581) (xy 394.883692 -85.766765) (xy 394.842512 -85.802452)
			(xy 394.796671 -85.831916) (xy 394.747105 -85.854557) (xy 394.694821 -85.869913) (xy 394.640884 -85.877673)
			(xy 394.613638 -85.878162) (xy 394.585726 -85.877693) (xy 394.5305 -85.869551) (xy 394.47705 -85.853449)
			(xy 394.426515 -85.829731) (xy 394.379976 -85.798904) (xy 394.358876 -85.780626) (xy 394.351315 -85.774415)
			(xy 394.332927 -85.767764) (xy 394.313385 -85.768438) (xy 394.304266 -85.77199) (xy 394.219176 -85.809836)
			(xy 394.210427 -85.814248) (xy 394.196855 -85.828351) (xy 394.189596 -85.846529) (xy 394.189204 -85.856318)
			(xy 394.189204 -85.930486) (xy 400.536662 -85.930486) (xy 400.540733 -85.874864) (xy 400.552859 -85.820427)
			(xy 400.572782 -85.768336) (xy 400.600078 -85.719701) (xy 400.634164 -85.675558) (xy 400.674313 -85.636849)
			(xy 400.719671 -85.604398) (xy 400.769271 -85.578897) (xy 400.822055 -85.56089) (xy 400.876898 -85.55076)
			(xy 400.932632 -85.548723) (xy 400.988069 -85.554823) (xy 401.042026 -85.568929) (xy 401.093355 -85.590741)
			(xy 401.140961 -85.619795) (xy 401.183829 -85.65547) (xy 401.221046 -85.697007) (xy 401.251819 -85.74352)
			(xy 401.275491 -85.794017) (xy 401.291559 -85.847424) (xy 401.299679 -85.9026) (xy 401.300188 -85.930486)
			(xy 401.299679 -85.958372) (xy 401.291559 -86.013548) (xy 401.275491 -86.066955) (xy 401.251819 -86.117452)
			(xy 401.221046 -86.163965) (xy 401.183829 -86.205502) (xy 401.140961 -86.241177) (xy 401.093355 -86.270231)
			(xy 401.042026 -86.292043) (xy 400.988069 -86.306149) (xy 400.932632 -86.312249) (xy 400.876898 -86.310212)
			(xy 400.822055 -86.300082) (xy 400.769271 -86.282075) (xy 400.719671 -86.256574) (xy 400.674313 -86.224123)
			(xy 400.634164 -86.185414) (xy 400.600078 -86.141271) (xy 400.572782 -86.092636) (xy 400.552859 -86.040545)
			(xy 400.540733 -85.986108) (xy 400.536662 -85.930486) (xy 394.189204 -85.930486) (xy 394.189204 -86.615016)
			(xy 394.189593 -86.62509) (xy 394.197336 -86.643689) (xy 394.20419 -86.651084) (xy 394.367124 -86.813898)
			(xy 400.57908 -86.813898) (xy 400.583151 -86.758276) (xy 400.595277 -86.703839) (xy 400.6152 -86.651748)
			(xy 400.642496 -86.603113) (xy 400.676582 -86.55897) (xy 400.716731 -86.520261) (xy 400.762089 -86.48781)
			(xy 400.811689 -86.462309) (xy 400.864473 -86.444302) (xy 400.919316 -86.434172) (xy 400.97505 -86.432135)
			(xy 401.030487 -86.438235) (xy 401.084444 -86.452341) (xy 401.135773 -86.474153) (xy 401.183379 -86.503207)
			(xy 401.226247 -86.538882) (xy 401.263464 -86.580419) (xy 401.294237 -86.626932) (xy 401.317909 -86.677429)
			(xy 401.333977 -86.730836) (xy 401.342097 -86.786012) (xy 401.342606 -86.813898) (xy 401.342097 -86.841784)
			(xy 401.333977 -86.89696) (xy 401.317909 -86.950367) (xy 401.294237 -87.000864) (xy 401.263464 -87.047377)
			(xy 401.226247 -87.088914) (xy 401.183379 -87.124589) (xy 401.135773 -87.153643) (xy 401.084444 -87.175455)
			(xy 401.030487 -87.189561) (xy 400.97505 -87.195661) (xy 400.919316 -87.193624) (xy 400.864473 -87.183494)
			(xy 400.811689 -87.165487) (xy 400.762089 -87.139986) (xy 400.716731 -87.107535) (xy 400.676582 -87.068826)
			(xy 400.642496 -87.024683) (xy 400.6152 -86.976048) (xy 400.595277 -86.923957) (xy 400.583151 -86.86952)
			(xy 400.57908 -86.813898) (xy 394.367124 -86.813898) (xy 394.548614 -86.995254) (xy 394.556021 -87.002086)
			(xy 394.574615 -87.009812) (xy 394.584682 -87.01024) (xy 394.680948 -87.01024) (xy 394.715048 -87.010702)
			(xy 394.782785 -87.018625) (xy 394.849145 -87.034358) (xy 394.91323 -87.057687) (xy 394.974174 -87.088299)
			(xy 395.031152 -87.125778) (xy 395.083394 -87.169618) (xy 395.125453 -87.214202) (xy 396.84274 -87.214202)
			(xy 396.846811 -87.15858) (xy 396.858937 -87.104143) (xy 396.87886 -87.052052) (xy 396.906156 -87.003417)
			(xy 396.940242 -86.959274) (xy 396.980391 -86.920565) (xy 397.025749 -86.888114) (xy 397.075349 -86.862613)
			(xy 397.128133 -86.844606) (xy 397.182976 -86.834476) (xy 397.23871 -86.832439) (xy 397.294147 -86.838539)
			(xy 397.348104 -86.852645) (xy 397.399433 -86.874457) (xy 397.447039 -86.903511) (xy 397.489907 -86.939186)
			(xy 397.527124 -86.980723) (xy 397.557897 -87.027236) (xy 397.581569 -87.077733) (xy 397.597637 -87.13114)
			(xy 397.605757 -87.186316) (xy 397.606266 -87.214202) (xy 397.605757 -87.242088) (xy 397.597637 -87.297264)
			(xy 397.581569 -87.350671) (xy 397.557897 -87.401168) (xy 397.534488 -87.436551) (xy 398.811752 -87.436551)
			(xy 398.811752 -87.382049) (xy 398.819507 -87.328102) (xy 398.834861 -87.275808) (xy 398.8575 -87.226231)
			(xy 398.886964 -87.180379) (xy 398.922652 -87.139188) (xy 398.963839 -87.103494) (xy 399.009687 -87.074024)
			(xy 399.059261 -87.051379) (xy 399.111553 -87.036018) (xy 399.165499 -87.028255) (xy 399.19275 -87.027766)
			(xy 399.219314 -87.028244) (xy 399.271928 -87.035605) (xy 399.323014 -87.050191) (xy 399.371583 -87.07172)
			(xy 399.416698 -87.099777) (xy 399.457486 -87.133819) (xy 399.493159 -87.173188) (xy 399.508472 -87.194898)
			(xy 399.516806 -87.206378) (xy 399.53855 -87.224582) (xy 399.564463 -87.2361) (xy 399.592546 -87.24004)
			(xy 399.620629 -87.2361) (xy 399.646542 -87.224582) (xy 399.668286 -87.206378) (xy 399.67662 -87.194898)
			(xy 399.69188 -87.173054) (xy 399.727531 -87.133451) (xy 399.768349 -87.099197) (xy 399.813537 -87.070959)
			(xy 399.862216 -87.049286) (xy 399.913439 -87.034601) (xy 399.966207 -87.02719) (xy 399.99285 -87.02675)
			(xy 400.020102 -87.027294) (xy 400.074053 -87.035044) (xy 400.126351 -87.050394) (xy 400.175932 -87.073031)
			(xy 400.221786 -87.102495) (xy 400.26298 -87.138184) (xy 400.298675 -87.179374) (xy 400.328145 -87.225224)
			(xy 400.350788 -87.274802) (xy 400.366145 -87.327098) (xy 400.373903 -87.381048) (xy 400.373903 -87.435552)
			(xy 400.366145 -87.489502) (xy 400.350788 -87.541798) (xy 400.328145 -87.591376) (xy 400.298675 -87.637226)
			(xy 400.26298 -87.678416) (xy 400.221786 -87.714105) (xy 400.175932 -87.743569) (xy 400.126351 -87.766206)
			(xy 400.074053 -87.781556) (xy 400.020102 -87.789306) (xy 399.99285 -87.789766) (xy 399.966287 -87.789274)
			(xy 399.913673 -87.781914) (xy 399.862589 -87.767329) (xy 399.81402 -87.745802) (xy 399.768905 -87.717748)
			(xy 399.728117 -87.683709) (xy 399.692442 -87.644343) (xy 399.677128 -87.622634) (xy 399.668794 -87.611154)
			(xy 399.64705 -87.59295) (xy 399.621137 -87.581432) (xy 399.593054 -87.577492) (xy 399.564971 -87.581432)
			(xy 399.539058 -87.59295) (xy 399.517314 -87.611154) (xy 399.50898 -87.622634) (xy 399.49373 -87.644485)
			(xy 399.458076 -87.684086) (xy 399.417256 -87.718339) (xy 399.372066 -87.746576) (xy 399.323386 -87.768247)
			(xy 399.272162 -87.782931) (xy 399.219393 -87.790342) (xy 399.19275 -87.790782) (xy 399.165499 -87.790345)
			(xy 399.111553 -87.782582) (xy 399.059261 -87.767221) (xy 399.009687 -87.744576) (xy 398.963839 -87.715106)
			(xy 398.922652 -87.679412) (xy 398.886964 -87.638221) (xy 398.8575 -87.592369) (xy 398.834861 -87.542792)
			(xy 398.819507 -87.490498) (xy 398.811752 -87.436551) (xy 397.534488 -87.436551) (xy 397.527124 -87.447681)
			(xy 397.489907 -87.489218) (xy 397.447039 -87.524893) (xy 397.399433 -87.553947) (xy 397.348104 -87.575759)
			(xy 397.294147 -87.589865) (xy 397.23871 -87.595965) (xy 397.182976 -87.593928) (xy 397.128133 -87.583798)
			(xy 397.075349 -87.565791) (xy 397.025749 -87.54029) (xy 396.980391 -87.507839) (xy 396.940242 -87.46913)
			(xy 396.906156 -87.424987) (xy 396.87886 -87.376352) (xy 396.858937 -87.324261) (xy 396.846811 -87.269824)
			(xy 396.84274 -87.214202) (xy 395.125453 -87.214202) (xy 395.130193 -87.219226) (xy 395.170917 -87.273932)
			(xy 395.205015 -87.332995) (xy 395.232026 -87.395618) (xy 395.251585 -87.460952) (xy 395.263427 -87.528116)
			(xy 395.267393 -87.5962) (xy 395.263427 -87.664284) (xy 395.251585 -87.731448) (xy 395.232026 -87.796782)
			(xy 395.205015 -87.859405) (xy 395.170917 -87.918468) (xy 395.130193 -87.973174) (xy 395.083394 -88.022782)
			(xy 395.031152 -88.066622) (xy 394.974174 -88.104101) (xy 394.91323 -88.134713) (xy 394.849145 -88.158042)
			(xy 394.782785 -88.173775) (xy 394.715048 -88.181698) (xy 394.680948 -88.182196) (xy 394.614146 -88.182196)
			(xy 394.584682 -88.210644) (xy 394.58392 -88.230964) (xy 394.582232 -88.265525) (xy 394.571616 -88.333903)
			(xy 394.553021 -88.400556) (xy 394.526704 -88.464554) (xy 394.493032 -88.525007) (xy 394.452475 -88.581073)
			(xy 394.405596 -88.631972) (xy 394.353048 -88.676995) (xy 394.295564 -88.715516) (xy 394.233942 -88.746997)
			(xy 394.169041 -88.771002) (xy 394.101764 -88.787195) (xy 394.033049 -88.795351) (xy 393.99845 -88.79586)
			(xy 393.965569 -88.795399) (xy 393.900222 -88.788037) (xy 393.836111 -88.773399) (xy 393.774043 -88.751671)
			(xy 393.7148 -88.723126) (xy 393.659129 -88.688122) (xy 393.60773 -88.647102) (xy 393.584176 -88.624156)
			(xy 392.729466 -87.769446) (xy 392.707402 -87.746776) (xy 392.66776 -87.697472) (xy 392.633676 -87.644174)
			(xy 392.61923 -87.61603) (xy 392.614792 -87.60805) (xy 392.601381 -87.595679) (xy 392.593068 -87.5919)
			(xy 392.565128 -87.580216) (xy 392.556828 -87.577135) (xy 392.539159 -87.576233) (xy 392.530584 -87.578438)
			(xy 392.503022 -87.586487) (xy 392.446262 -87.595153) (xy 392.417554 -87.59571) (xy 392.390305 -87.595217)
			(xy 392.336363 -87.587455) (xy 392.284074 -87.572096) (xy 392.234502 -87.549453) (xy 392.188658 -87.519985)
			(xy 392.147474 -87.484294) (xy 392.111787 -87.443105) (xy 392.082325 -87.397257) (xy 392.059688 -87.347683)
			(xy 392.044335 -87.295392) (xy 392.03658 -87.241449) (xy 392.03658 -87.186951) (xy 392.044335 -87.133008)
			(xy 392.059688 -87.080717) (xy 392.082325 -87.031143) (xy 392.111787 -86.985295) (xy 392.147474 -86.944106)
			(xy 392.188658 -86.908415) (xy 392.234502 -86.878947) (xy 392.284074 -86.856304) (xy 392.336363 -86.840945)
			(xy 392.390305 -86.833183) (xy 392.417554 -86.832694) (xy 392.448034 -86.833964) (xy 392.448288 -86.833964)
			(xy 392.45877 -86.834275) (xy 392.478577 -86.827457) (xy 392.486642 -86.820756) (xy 392.54176 -86.769956)
			(xy 392.549085 -86.762399) (xy 392.557486 -86.743128) (xy 392.558016 -86.732618) (xy 392.558016 -85.321648)
			(xy 392.538712 -85.294978) (xy 392.523218 -85.289898) (xy 392.496857 -85.280493) (xy 392.446999 -85.255067)
			(xy 392.401388 -85.222633) (xy 392.361002 -85.183885) (xy 392.326708 -85.139655) (xy 392.299241 -85.090891)
			(xy 392.27919 -85.038638) (xy 392.266985 -84.984018) (xy 392.262887 -84.928201) (xy 392.266985 -84.872383)
			(xy 392.27919 -84.817763) (xy 392.299241 -84.76551) (xy 392.326708 -84.716746) (xy 392.361001 -84.672516)
			(xy 392.401387 -84.633768) (xy 392.446997 -84.601333) (xy 392.496856 -84.575907) (xy 392.523218 -84.566506)
			(xy 392.538712 -84.561426) (xy 392.558016 -84.534756) (xy 392.558016 -83.04784) (xy 392.535156 -83.0199)
			(xy 392.517122 -83.016344) (xy 392.490138 -83.010477) (xy 392.438097 -82.992014) (xy 392.389262 -82.96624)
			(xy 392.344653 -82.933694) (xy 392.305203 -82.895056) (xy 392.271736 -82.851134) (xy 392.244952 -82.802845)
			(xy 392.225411 -82.751199) (xy 392.21352 -82.697275) (xy 392.209529 -82.6422) (xy 392.21352 -82.587125)
			(xy 392.225411 -82.533201) (xy 392.244952 -82.481555) (xy 392.271736 -82.433267) (xy 392.305203 -82.389344)
			(xy 392.344652 -82.350707) (xy 392.389261 -82.31816) (xy 392.438096 -82.292386) (xy 392.490138 -82.273923)
			(xy 392.517122 -82.26806) (xy 392.535156 -82.264504) (xy 392.558016 -82.236564) (xy 392.558016 -80.763872)
			(xy 392.533886 -80.735678) (xy 392.515344 -80.73263) (xy 392.487578 -80.727466) (xy 392.433857 -80.710043)
			(xy 392.38329 -80.684894) (xy 392.336981 -80.652567) (xy 392.295941 -80.61377) (xy 392.261067 -80.569348)
			(xy 392.23312 -80.520272) (xy 392.21271 -80.467613) (xy 392.200283 -80.412522) (xy 392.196111 -80.3562)
			(xy 392.200283 -80.299879) (xy 392.21271 -80.244788) (xy 392.23312 -80.192129) (xy 392.261067 -80.143053)
			(xy 392.295941 -80.098631) (xy 392.33698 -80.059833) (xy 392.383289 -80.027507) (xy 392.433856 -80.002357)
			(xy 392.487577 -79.984935) (xy 392.515344 -79.979774) (xy 392.533886 -79.976726) (xy 392.558016 -79.948532)
			(xy 392.558016 -79.672688) (xy 392.557619 -79.662615) (xy 392.549881 -79.644016) (xy 392.54303 -79.63662)
			(xy 391.94867 -79.042514) (xy 391.92579 -79.018932) (xy 391.884823 -78.967559) (xy 391.849866 -78.911923)
			(xy 391.821357 -78.852722) (xy 391.799656 -78.790702) (xy 391.785036 -78.726642) (xy 391.77768 -78.661348)
			(xy 391.77722 -78.628494) (xy 384.811016 -78.628494) (xy 384.811016 -81.499202) (xy 390.559542 -81.499202)
			(xy 390.563613 -81.44358) (xy 390.575739 -81.389143) (xy 390.595662 -81.337052) (xy 390.622958 -81.288417)
			(xy 390.657044 -81.244274) (xy 390.697193 -81.205565) (xy 390.742551 -81.173114) (xy 390.792151 -81.147613)
			(xy 390.844935 -81.129606) (xy 390.899778 -81.119476) (xy 390.955512 -81.117439) (xy 391.010949 -81.123539)
			(xy 391.064906 -81.137645) (xy 391.116235 -81.159457) (xy 391.163841 -81.188511) (xy 391.206709 -81.224186)
			(xy 391.243926 -81.265723) (xy 391.274699 -81.312236) (xy 391.298371 -81.362733) (xy 391.314439 -81.41614)
			(xy 391.322559 -81.471316) (xy 391.323068 -81.499202) (xy 391.322559 -81.527088) (xy 391.314439 -81.582264)
			(xy 391.298371 -81.635671) (xy 391.274699 -81.686168) (xy 391.243926 -81.732681) (xy 391.206709 -81.774218)
			(xy 391.163841 -81.809893) (xy 391.116235 -81.838947) (xy 391.064906 -81.860759) (xy 391.010949 -81.874865)
			(xy 390.955512 -81.880965) (xy 390.899778 -81.878928) (xy 390.844935 -81.868798) (xy 390.792151 -81.850791)
			(xy 390.742551 -81.82529) (xy 390.697193 -81.792839) (xy 390.657044 -81.75413) (xy 390.622958 -81.709987)
			(xy 390.595662 -81.661352) (xy 390.575739 -81.609261) (xy 390.563613 -81.554824) (xy 390.559542 -81.499202)
			(xy 384.811016 -81.499202) (xy 384.811016 -83.785202) (xy 391.48842 -83.785202) (xy 391.492491 -83.72958)
			(xy 391.504617 -83.675143) (xy 391.52454 -83.623052) (xy 391.551836 -83.574417) (xy 391.585922 -83.530274)
			(xy 391.626071 -83.491565) (xy 391.671429 -83.459114) (xy 391.721029 -83.433613) (xy 391.773813 -83.415606)
			(xy 391.828656 -83.405476) (xy 391.88439 -83.403439) (xy 391.939827 -83.409539) (xy 391.993784 -83.423645)
			(xy 392.045113 -83.445457) (xy 392.092719 -83.474511) (xy 392.135587 -83.510186) (xy 392.172804 -83.551723)
			(xy 392.203577 -83.598236) (xy 392.227249 -83.648733) (xy 392.243317 -83.70214) (xy 392.251437 -83.757316)
			(xy 392.251946 -83.785202) (xy 392.251437 -83.813088) (xy 392.243317 -83.868264) (xy 392.227249 -83.921671)
			(xy 392.203577 -83.972168) (xy 392.172804 -84.018681) (xy 392.135587 -84.060218) (xy 392.092719 -84.095893)
			(xy 392.045113 -84.124947) (xy 391.993784 -84.146759) (xy 391.939827 -84.160865) (xy 391.88439 -84.166965)
			(xy 391.828656 -84.164928) (xy 391.773813 -84.154798) (xy 391.721029 -84.136791) (xy 391.671429 -84.11129)
			(xy 391.626071 -84.078839) (xy 391.585922 -84.04013) (xy 391.551836 -83.995987) (xy 391.52454 -83.947352)
			(xy 391.504617 -83.895261) (xy 391.492491 -83.840824) (xy 391.48842 -83.785202) (xy 384.811016 -83.785202)
			(xy 384.811016 -87.927942) (xy 384.811122 -87.932289) (xy 384.812647 -87.940849) (xy 384.814064 -87.94496)
			(xy 384.816055 -87.950021) (xy 384.821811 -87.959246) (xy 384.825494 -87.963248) (xy 384.828288 -87.966042)
			(xy 384.831008 -87.968439) (xy 384.836997 -87.972522) (xy 384.840226 -87.97417) (xy 384.888486 -87.992204)
			(xy 384.93319 -88.008714) (xy 384.94044 -88.011121) (xy 384.95568 -88.012031) (xy 384.963162 -88.010492)
			(xy 384.970528 -88.008714) (xy 384.983228 -88.00084) (xy 384.988816 -87.99449) (xy 385.007067 -87.974328)
			(xy 385.048287 -87.938856) (xy 385.094116 -87.909578) (xy 385.143629 -87.887086) (xy 385.195828 -87.871832)
			(xy 385.249661 -87.864124) (xy 385.276852 -87.86368) (xy 385.304107 -87.86414) (xy 385.358064 -87.871891)
			(xy 385.410369 -87.887243) (xy 385.459956 -87.909882) (xy 385.505816 -87.939349) (xy 385.547015 -87.975042)
			(xy 385.582715 -88.016236) (xy 385.612189 -88.062092) (xy 385.634836 -88.111675) (xy 385.650196 -88.163977)
			(xy 385.657956 -88.217933) (xy 385.65836 -88.245188) (xy 385.657856 -88.272924) (xy 385.649813 -88.32781)
			(xy 385.633909 -88.380953) (xy 385.610479 -88.431234) (xy 385.580017 -88.477594) (xy 385.543164 -88.519055)
			(xy 385.500697 -88.554744) (xy 385.453511 -88.58391) (xy 385.4026 -88.605937) (xy 385.349037 -88.620362)
			(xy 385.321556 -88.624156) (xy 385.306316 -88.625934) (xy 385.276852 -88.62695) (xy 385.276598 -88.62695)
			(xy 385.249561 -88.626481) (xy 385.196028 -88.618857) (xy 385.144105 -88.60376) (xy 385.094829 -88.581493)
			(xy 385.049185 -88.5525) (xy 385.008085 -88.517361) (xy 384.989832 -88.49741) (xy 384.988816 -88.49614)
			(xy 384.98399 -88.491314) (xy 384.979299 -88.487433) (xy 384.968512 -88.481797) (xy 384.962654 -88.480138)
			(xy 384.955542 -88.47836) (xy 384.948684 -88.478614) (xy 384.94478 -88.478926) (xy 384.937128 -88.480588)
			(xy 384.933444 -88.481916) (xy 384.868166 -88.506046) (xy 384.844036 -88.514936) (xy 384.834571 -88.519006)
			(xy 384.81969 -88.533229) (xy 384.811567 -88.552143) (xy 384.811016 -88.562434) (xy 384.811016 -89.500202)
			(xy 392.158218 -89.500202) (xy 392.162289 -89.44458) (xy 392.174415 -89.390143) (xy 392.194338 -89.338052)
			(xy 392.221634 -89.289417) (xy 392.25572 -89.245274) (xy 392.295869 -89.206565) (xy 392.341227 -89.174114)
			(xy 392.390827 -89.148613) (xy 392.443611 -89.130606) (xy 392.498454 -89.120476) (xy 392.554188 -89.118439)
			(xy 392.609625 -89.124539) (xy 392.663582 -89.138645) (xy 392.714911 -89.160457) (xy 392.762517 -89.189511)
			(xy 392.805385 -89.225186) (xy 392.842602 -89.266723) (xy 392.873375 -89.313236) (xy 392.897047 -89.363733)
			(xy 392.913115 -89.41714) (xy 392.921235 -89.472316) (xy 392.921744 -89.500202) (xy 396.84274 -89.500202)
			(xy 396.846811 -89.44458) (xy 396.858937 -89.390143) (xy 396.87886 -89.338052) (xy 396.906156 -89.289417)
			(xy 396.940242 -89.245274) (xy 396.980391 -89.206565) (xy 397.025749 -89.174114) (xy 397.075349 -89.148613)
			(xy 397.128133 -89.130606) (xy 397.182976 -89.120476) (xy 397.23871 -89.118439) (xy 397.294147 -89.124539)
			(xy 397.348104 -89.138645) (xy 397.399433 -89.160457) (xy 397.447039 -89.189511) (xy 397.489907 -89.225186)
			(xy 397.527124 -89.266723) (xy 397.557897 -89.313236) (xy 397.581569 -89.363733) (xy 397.597637 -89.41714)
			(xy 397.605757 -89.472316) (xy 397.606266 -89.500202) (xy 397.605757 -89.528088) (xy 397.597637 -89.583264)
			(xy 397.581569 -89.636671) (xy 397.557897 -89.687168) (xy 397.527124 -89.733681) (xy 397.489907 -89.775218)
			(xy 397.447039 -89.810893) (xy 397.399433 -89.839947) (xy 397.348104 -89.861759) (xy 397.294147 -89.875865)
			(xy 397.23871 -89.881965) (xy 397.182976 -89.879928) (xy 397.128133 -89.869798) (xy 397.075349 -89.851791)
			(xy 397.025749 -89.82629) (xy 396.980391 -89.793839) (xy 396.940242 -89.75513) (xy 396.906156 -89.710987)
			(xy 396.87886 -89.662352) (xy 396.858937 -89.610261) (xy 396.846811 -89.555824) (xy 396.84274 -89.500202)
			(xy 392.921744 -89.500202) (xy 392.921235 -89.528088) (xy 392.913115 -89.583264) (xy 392.897047 -89.636671)
			(xy 392.873375 -89.687168) (xy 392.842602 -89.733681) (xy 392.805385 -89.775218) (xy 392.762517 -89.810893)
			(xy 392.714911 -89.839947) (xy 392.663582 -89.861759) (xy 392.609625 -89.875865) (xy 392.554188 -89.881965)
			(xy 392.498454 -89.879928) (xy 392.443611 -89.869798) (xy 392.390827 -89.851791) (xy 392.341227 -89.82629)
			(xy 392.295869 -89.793839) (xy 392.25572 -89.75513) (xy 392.221634 -89.710987) (xy 392.194338 -89.662352)
			(xy 392.174415 -89.610261) (xy 392.162289 -89.555824) (xy 392.158218 -89.500202) (xy 384.811016 -89.500202)
			(xy 384.811016 -89.602818) (xy 384.811591 -89.614483) (xy 384.821918 -89.6354) (xy 384.830828 -89.64295)
			(xy 384.834892 -89.645998) (xy 384.896868 -89.693242) (xy 384.900717 -89.695825) (xy 384.909156 -89.699658)
			(xy 384.913632 -89.700862) (xy 384.918256 -89.701902) (xy 384.927719 -89.70242) (xy 384.932428 -89.701878)
			(xy 384.938016 -89.701116) (xy 384.94208 -89.7001) (xy 384.965711 -89.694179) (xy 385.013991 -89.68768)
			(xy 385.038346 -89.687146) (xy 385.041648 -89.687146) (xy 385.068866 -89.687683) (xy 385.122735 -89.695525)
			(xy 385.174942 -89.710945) (xy 385.224429 -89.733628) (xy 385.270188 -89.763114) (xy 385.311293 -89.798804)
			(xy 385.346908 -89.839974) (xy 385.37631 -89.885788) (xy 385.398901 -89.935316) (xy 385.414225 -89.987552)
			(xy 385.421968 -90.041436) (xy 385.422203 -90.056462) (xy 390.303764 -90.056462) (xy 390.307835 -90.00084)
			(xy 390.319961 -89.946403) (xy 390.339884 -89.894312) (xy 390.36718 -89.845677) (xy 390.401266 -89.801534)
			(xy 390.441415 -89.762825) (xy 390.486773 -89.730374) (xy 390.536373 -89.704873) (xy 390.589157 -89.686866)
			(xy 390.644 -89.676736) (xy 390.699734 -89.674699) (xy 390.755171 -89.680799) (xy 390.809128 -89.694905)
			(xy 390.860457 -89.716717) (xy 390.908063 -89.745771) (xy 390.950931 -89.781446) (xy 390.988148 -89.822983)
			(xy 391.018921 -89.869496) (xy 391.042593 -89.919993) (xy 391.058661 -89.9734) (xy 391.066781 -90.028576)
			(xy 391.06729 -90.056462) (xy 391.066781 -90.084348) (xy 391.058661 -90.139524) (xy 391.042593 -90.192931)
			(xy 391.018921 -90.243428) (xy 390.988148 -90.289941) (xy 390.950931 -90.331478) (xy 390.908063 -90.367153)
			(xy 390.860457 -90.396207) (xy 390.809128 -90.418019) (xy 390.755171 -90.432125) (xy 390.699734 -90.438225)
			(xy 390.644 -90.436188) (xy 390.589157 -90.426058) (xy 390.536373 -90.408051) (xy 390.486773 -90.38255)
			(xy 390.441415 -90.350099) (xy 390.401266 -90.31139) (xy 390.36718 -90.267247) (xy 390.339884 -90.218612)
			(xy 390.319961 -90.166521) (xy 390.307835 -90.112084) (xy 390.303764 -90.056462) (xy 385.422203 -90.056462)
			(xy 385.422394 -90.068654) (xy 385.421912 -90.095787) (xy 385.414215 -90.149505) (xy 385.398983 -90.201589)
			(xy 385.376524 -90.25099) (xy 385.347291 -90.296709) (xy 385.311875 -90.337825) (xy 385.270989 -90.373507)
			(xy 385.22546 -90.403035) (xy 385.176206 -90.425814) (xy 385.124221 -90.441383) (xy 385.070555 -90.449428)
			(xy 385.043426 -90.450162) (xy 385.040632 -90.450162) (xy 385.0159 -90.449787) (xy 384.966849 -90.443417)
			(xy 384.942842 -90.437462) (xy 384.942588 -90.437462) (xy 384.94208 -90.437208) (xy 384.938016 -90.436192)
			(xy 384.932682 -90.43543) (xy 384.932428 -90.43543) (xy 384.928293 -90.435037) (xy 384.919997 -90.435414)
			(xy 384.915918 -90.436192) (xy 384.911854 -90.437208) (xy 384.902202 -90.441018) (xy 384.901948 -90.441018)
			(xy 384.898392 -90.44305) (xy 384.858006 -90.473784) (xy 384.829558 -90.495374) (xy 384.821275 -90.502975)
			(xy 384.811656 -90.523266) (xy 384.811016 -90.53449) (xy 384.811016 -92.853764) (xy 384.810582 -92.863829)
			(xy 384.802853 -92.882419) (xy 384.79603 -92.889832) (xy 382.470986 -95.214948) (xy 395.574279 -95.214948)
			(xy 395.578234 -95.123111) (xy 395.590069 -95.031954) (xy 395.609696 -94.942151) (xy 395.63697 -94.854369)
			(xy 395.67169 -94.769255) (xy 395.713598 -94.687442) (xy 395.762384 -94.609534) (xy 395.817687 -94.536109)
			(xy 395.879097 -94.467709) (xy 395.946159 -94.404842) (xy 396.018378 -94.347972) (xy 396.095218 -94.297521)
			(xy 396.176111 -94.253862) (xy 396.260457 -94.217319) (xy 396.347633 -94.188162) (xy 396.436992 -94.166608)
			(xy 396.527873 -94.152814) (xy 396.619604 -94.146884) (xy 396.711505 -94.148862) (xy 396.802896 -94.158733)
			(xy 396.8931 -94.176423) (xy 396.981449 -94.201803) (xy 397.067289 -94.234683) (xy 397.149985 -94.274821)
			(xy 397.228925 -94.32192) (xy 397.303523 -94.37563) (xy 397.373229 -94.435554) (xy 397.437524 -94.501248)
			(xy 397.495935 -94.572226) (xy 397.548027 -94.647963) (xy 397.593416 -94.727898) (xy 397.631766 -94.811438)
			(xy 397.662791 -94.897966) (xy 397.686264 -94.986841) (xy 397.70201 -95.077405) (xy 397.709912 -95.168987)
			(xy 397.710406 -95.214948) (xy 397.709912 -95.260909) (xy 397.70201 -95.352491) (xy 397.686264 -95.443055)
			(xy 397.662791 -95.53193) (xy 397.631766 -95.618458) (xy 397.593416 -95.701998) (xy 397.548027 -95.781933)
			(xy 397.495935 -95.85767) (xy 397.437524 -95.928648) (xy 397.373229 -95.994342) (xy 397.303523 -96.054266)
			(xy 397.228925 -96.107976) (xy 397.149985 -96.155075) (xy 397.067289 -96.195213) (xy 396.981449 -96.228093)
			(xy 396.8931 -96.253473) (xy 396.802896 -96.271163) (xy 396.711505 -96.281034) (xy 396.619604 -96.283012)
			(xy 396.527873 -96.277082) (xy 396.436992 -96.263288) (xy 396.347633 -96.241734) (xy 396.260457 -96.212577)
			(xy 396.176111 -96.176034) (xy 396.095218 -96.132375) (xy 396.018378 -96.081924) (xy 395.946159 -96.025054)
			(xy 395.879097 -95.962187) (xy 395.817687 -95.893787) (xy 395.762384 -95.820362) (xy 395.713598 -95.742454)
			(xy 395.67169 -95.660641) (xy 395.63697 -95.575527) (xy 395.609696 -95.487745) (xy 395.590069 -95.397942)
			(xy 395.578234 -95.306785) (xy 395.574279 -95.214948) (xy 382.470986 -95.214948) (xy 381.521564 -96.1644)
			(xy 385.525516 -96.1644) (xy 385.529587 -96.108778) (xy 385.541713 -96.054341) (xy 385.561636 -96.00225)
			(xy 385.588932 -95.953615) (xy 385.623018 -95.909472) (xy 385.663167 -95.870763) (xy 385.708525 -95.838312)
			(xy 385.758125 -95.812811) (xy 385.810909 -95.794804) (xy 385.865752 -95.784674) (xy 385.921486 -95.782637)
			(xy 385.976923 -95.788737) (xy 386.03088 -95.802843) (xy 386.082209 -95.824655) (xy 386.129815 -95.853709)
			(xy 386.172683 -95.889384) (xy 386.2099 -95.930921) (xy 386.240673 -95.977434) (xy 386.264345 -96.027931)
			(xy 386.280413 -96.081338) (xy 386.288533 -96.136514) (xy 386.289042 -96.1644) (xy 386.288533 -96.192286)
			(xy 386.280413 -96.247462) (xy 386.264345 -96.300869) (xy 386.240673 -96.351366) (xy 386.2099 -96.397879)
			(xy 386.172683 -96.439416) (xy 386.129815 -96.475091) (xy 386.082209 -96.504145) (xy 386.03088 -96.525957)
			(xy 385.976923 -96.540063) (xy 385.921486 -96.546163) (xy 385.865752 -96.544126) (xy 385.810909 -96.533996)
			(xy 385.758125 -96.515989) (xy 385.708525 -96.490488) (xy 385.663167 -96.458037) (xy 385.623018 -96.419328)
			(xy 385.588932 -96.375185) (xy 385.561636 -96.32655) (xy 385.541713 -96.274459) (xy 385.529587 -96.220022)
			(xy 385.525516 -96.1644) (xy 381.521564 -96.1644) (xy 380.505596 -97.1804) (xy 385.525516 -97.1804)
			(xy 385.529587 -97.124778) (xy 385.541713 -97.070341) (xy 385.561636 -97.01825) (xy 385.588932 -96.969615)
			(xy 385.623018 -96.925472) (xy 385.663167 -96.886763) (xy 385.708525 -96.854312) (xy 385.758125 -96.828811)
			(xy 385.810909 -96.810804) (xy 385.865752 -96.800674) (xy 385.921486 -96.798637) (xy 385.976923 -96.804737)
			(xy 386.03088 -96.818843) (xy 386.082209 -96.840655) (xy 386.129815 -96.869709) (xy 386.172683 -96.905384)
			(xy 386.2099 -96.946921) (xy 386.240673 -96.993434) (xy 386.264345 -97.043931) (xy 386.267882 -97.055686)
			(xy 399.905472 -97.055686) (xy 399.909543 -97.000064) (xy 399.921669 -96.945627) (xy 399.941592 -96.893536)
			(xy 399.968888 -96.844901) (xy 400.002974 -96.800758) (xy 400.043123 -96.762049) (xy 400.088481 -96.729598)
			(xy 400.138081 -96.704097) (xy 400.190865 -96.68609) (xy 400.245708 -96.67596) (xy 400.301442 -96.673923)
			(xy 400.356879 -96.680023) (xy 400.410836 -96.694129) (xy 400.462165 -96.715941) (xy 400.509771 -96.744995)
			(xy 400.552639 -96.78067) (xy 400.589856 -96.822207) (xy 400.620629 -96.86872) (xy 400.644301 -96.919217)
			(xy 400.660369 -96.972624) (xy 400.668489 -97.0278) (xy 400.668998 -97.055686) (xy 400.668489 -97.083572)
			(xy 400.660369 -97.138748) (xy 400.644301 -97.192155) (xy 400.620629 -97.242652) (xy 400.589856 -97.289165)
			(xy 400.552639 -97.330702) (xy 400.509771 -97.366377) (xy 400.462165 -97.395431) (xy 400.410836 -97.417243)
			(xy 400.356879 -97.431349) (xy 400.301442 -97.437449) (xy 400.245708 -97.435412) (xy 400.190865 -97.425282)
			(xy 400.138081 -97.407275) (xy 400.088481 -97.381774) (xy 400.043123 -97.349323) (xy 400.002974 -97.310614)
			(xy 399.968888 -97.266471) (xy 399.941592 -97.217836) (xy 399.921669 -97.165745) (xy 399.909543 -97.111308)
			(xy 399.905472 -97.055686) (xy 386.267882 -97.055686) (xy 386.280413 -97.097338) (xy 386.288533 -97.152514)
			(xy 386.289042 -97.1804) (xy 386.288533 -97.208286) (xy 386.280413 -97.263462) (xy 386.264345 -97.316869)
			(xy 386.240673 -97.367366) (xy 386.2099 -97.413879) (xy 386.172683 -97.455416) (xy 386.129815 -97.491091)
			(xy 386.082209 -97.520145) (xy 386.03088 -97.541957) (xy 385.976923 -97.556063) (xy 385.921486 -97.562163)
			(xy 385.865752 -97.560126) (xy 385.810909 -97.549996) (xy 385.758125 -97.531989) (xy 385.708525 -97.506488)
			(xy 385.663167 -97.474037) (xy 385.623018 -97.435328) (xy 385.588932 -97.391185) (xy 385.561636 -97.34255)
			(xy 385.541713 -97.290459) (xy 385.529587 -97.236022) (xy 385.525516 -97.1804) (xy 380.505596 -97.1804)
			(xy 380.04587 -97.64014) (xy 422.218102 -97.64014) (xy 422.222173 -97.584518) (xy 422.234299 -97.530081)
			(xy 422.254222 -97.47799) (xy 422.281518 -97.429355) (xy 422.315604 -97.385212) (xy 422.355753 -97.346503)
			(xy 422.401111 -97.314052) (xy 422.450711 -97.288551) (xy 422.503495 -97.270544) (xy 422.558338 -97.260414)
			(xy 422.614072 -97.258377) (xy 422.669509 -97.264477) (xy 422.723466 -97.278583) (xy 422.774795 -97.300395)
			(xy 422.822401 -97.329449) (xy 422.865269 -97.365124) (xy 422.902486 -97.406661) (xy 422.933259 -97.453174)
			(xy 422.956931 -97.503671) (xy 422.972999 -97.557078) (xy 422.981119 -97.612254) (xy 422.981628 -97.64014)
			(xy 422.981119 -97.668026) (xy 422.972999 -97.723202) (xy 422.956931 -97.776609) (xy 422.933259 -97.827106)
			(xy 422.902486 -97.873619) (xy 422.865269 -97.915156) (xy 422.822401 -97.950831) (xy 422.774795 -97.979885)
			(xy 422.723466 -98.001697) (xy 422.669509 -98.015803) (xy 422.614072 -98.021903) (xy 422.558338 -98.019866)
			(xy 422.503495 -98.009736) (xy 422.450711 -97.991729) (xy 422.401111 -97.966228) (xy 422.355753 -97.933777)
			(xy 422.315604 -97.895068) (xy 422.281518 -97.850925) (xy 422.254222 -97.80229) (xy 422.234299 -97.750199)
			(xy 422.222173 -97.695762) (xy 422.218102 -97.64014) (xy 380.04587 -97.64014) (xy 379.515027 -98.171)
			(xy 423.864022 -98.171) (xy 423.868093 -98.115378) (xy 423.880219 -98.060941) (xy 423.900142 -98.00885)
			(xy 423.927438 -97.960215) (xy 423.961524 -97.916072) (xy 424.001673 -97.877363) (xy 424.047031 -97.844912)
			(xy 424.096631 -97.819411) (xy 424.149415 -97.801404) (xy 424.204258 -97.791274) (xy 424.259992 -97.789237)
			(xy 424.315429 -97.795337) (xy 424.369386 -97.809443) (xy 424.420715 -97.831255) (xy 424.468321 -97.860309)
			(xy 424.511189 -97.895984) (xy 424.548406 -97.937521) (xy 424.579179 -97.984034) (xy 424.602851 -98.034531)
			(xy 424.618919 -98.087938) (xy 424.627039 -98.143114) (xy 424.627548 -98.171) (xy 424.627039 -98.198886)
			(xy 424.618919 -98.254062) (xy 424.602851 -98.307469) (xy 424.579179 -98.357966) (xy 424.548406 -98.404479)
			(xy 424.511189 -98.446016) (xy 424.468321 -98.481691) (xy 424.420715 -98.510745) (xy 424.369386 -98.532557)
			(xy 424.315429 -98.546663) (xy 424.259992 -98.552763) (xy 424.204258 -98.550726) (xy 424.149415 -98.540596)
			(xy 424.096631 -98.522589) (xy 424.047031 -98.497088) (xy 424.001673 -98.464637) (xy 423.961524 -98.425928)
			(xy 423.927438 -98.381785) (xy 423.900142 -98.33315) (xy 423.880219 -98.281059) (xy 423.868093 -98.226622)
			(xy 423.864022 -98.171) (xy 379.515027 -98.171) (xy 377.508236 -100.177854) (xy 385.6101 -100.177854)
			(xy 385.6101 -99.314254) (xy 385.61059 -99.284286) (xy 385.618413 -99.224864) (xy 385.633926 -99.166971)
			(xy 385.656862 -99.111598) (xy 385.686829 -99.059692) (xy 385.723316 -99.012142) (xy 385.765696 -98.969762)
			(xy 385.813246 -98.933275) (xy 385.865152 -98.903308) (xy 385.920525 -98.880372) (xy 385.978418 -98.864859)
			(xy 386.03784 -98.857036) (xy 386.097776 -98.857036) (xy 386.157198 -98.864859) (xy 386.215091 -98.880372)
			(xy 386.270464 -98.903308) (xy 386.32237 -98.933275) (xy 386.36992 -98.969762) (xy 386.4123 -99.012142)
			(xy 386.448787 -99.059692) (xy 386.478754 -99.111598) (xy 386.50169 -99.166971) (xy 386.517203 -99.224864)
			(xy 386.525026 -99.284286) (xy 386.525516 -99.314254) (xy 386.525516 -100.177854) (xy 386.525026 -100.207822)
			(xy 386.517203 -100.267244) (xy 386.50169 -100.325137) (xy 386.478754 -100.38051) (xy 386.448787 -100.432416)
			(xy 386.4123 -100.479966) (xy 386.36992 -100.522346) (xy 386.32237 -100.558833) (xy 386.270464 -100.5888)
			(xy 386.215091 -100.611736) (xy 386.157198 -100.627249) (xy 386.097776 -100.635072) (xy 386.03784 -100.635072)
			(xy 385.978418 -100.627249) (xy 385.920525 -100.611736) (xy 385.865152 -100.5888) (xy 385.813246 -100.558833)
			(xy 385.765696 -100.522346) (xy 385.723316 -100.479966) (xy 385.686829 -100.432416) (xy 385.656862 -100.38051)
			(xy 385.633926 -100.325137) (xy 385.618413 -100.267244) (xy 385.61059 -100.207822) (xy 385.6101 -100.177854)
			(xy 377.508236 -100.177854) (xy 376.690382 -100.995734) (xy 376.68581 -101.001068) (xy 376.682956 -101.005115)
			(xy 376.678739 -101.014073) (xy 376.677428 -101.018848) (xy 376.675904 -101.031294) (xy 376.675904 -101.984302)
			(xy 383.577592 -101.984302) (xy 383.577592 -101.120702) (xy 383.578082 -101.090734) (xy 383.585905 -101.031312)
			(xy 383.601418 -100.973419) (xy 383.624354 -100.918046) (xy 383.654321 -100.86614) (xy 383.690808 -100.81859)
			(xy 383.733188 -100.77621) (xy 383.780738 -100.739723) (xy 383.832644 -100.709756) (xy 383.888017 -100.68682)
			(xy 383.94591 -100.671307) (xy 384.005332 -100.663484) (xy 384.065268 -100.663484) (xy 384.12469 -100.671307)
			(xy 384.182583 -100.68682) (xy 384.237956 -100.709756) (xy 384.289862 -100.739723) (xy 384.337412 -100.77621)
			(xy 384.379792 -100.81859) (xy 384.416279 -100.86614) (xy 384.446246 -100.918046) (xy 384.469182 -100.973419)
			(xy 384.484695 -101.031312) (xy 384.492518 -101.090734) (xy 384.493008 -101.120702) (xy 384.493008 -101.984302)
			(xy 384.492518 -102.01427) (xy 384.484695 -102.073692) (xy 384.469182 -102.131585) (xy 384.446246 -102.186958)
			(xy 384.416279 -102.238864) (xy 384.379792 -102.286414) (xy 384.337412 -102.328794) (xy 384.289862 -102.365281)
			(xy 384.237956 -102.395248) (xy 384.182583 -102.418184) (xy 384.12469 -102.433697) (xy 384.065268 -102.44152)
			(xy 384.005332 -102.44152) (xy 383.94591 -102.433697) (xy 383.888017 -102.418184) (xy 383.832644 -102.395248)
			(xy 383.780738 -102.365281) (xy 383.733188 -102.328794) (xy 383.690808 -102.286414) (xy 383.654321 -102.238864)
			(xy 383.624354 -102.186958) (xy 383.601418 -102.131585) (xy 383.585905 -102.073692) (xy 383.578082 -102.01427)
			(xy 383.577592 -101.984302) (xy 376.675904 -101.984302) (xy 376.675904 -103.777796) (xy 385.6101 -103.777796)
			(xy 385.6101 -102.914196) (xy 385.61059 -102.884228) (xy 385.618413 -102.824806) (xy 385.633926 -102.766913)
			(xy 385.656862 -102.71154) (xy 385.686829 -102.659634) (xy 385.723316 -102.612084) (xy 385.765696 -102.569704)
			(xy 385.813246 -102.533217) (xy 385.865152 -102.50325) (xy 385.920525 -102.480314) (xy 385.978418 -102.464801)
			(xy 386.03784 -102.456978) (xy 386.097776 -102.456978) (xy 386.157198 -102.464801) (xy 386.215091 -102.480314)
			(xy 386.270464 -102.50325) (xy 386.32237 -102.533217) (xy 386.36992 -102.569704) (xy 386.4123 -102.612084)
			(xy 386.448787 -102.659634) (xy 386.478754 -102.71154) (xy 386.50169 -102.766913) (xy 386.517203 -102.824806)
			(xy 386.525026 -102.884228) (xy 386.525516 -102.914196) (xy 386.525516 -103.777796) (xy 386.525026 -103.807764)
			(xy 386.517203 -103.867186) (xy 386.50169 -103.925079) (xy 386.478754 -103.980452) (xy 386.448787 -104.032358)
			(xy 386.4123 -104.079908) (xy 386.36992 -104.122288) (xy 386.32237 -104.158775) (xy 386.270464 -104.188742)
			(xy 386.215091 -104.211678) (xy 386.157198 -104.227191) (xy 386.097776 -104.235014) (xy 386.03784 -104.235014)
			(xy 385.978418 -104.227191) (xy 385.920525 -104.211678) (xy 385.865152 -104.188742) (xy 385.813246 -104.158775)
			(xy 385.765696 -104.122288) (xy 385.723316 -104.079908) (xy 385.686829 -104.032358) (xy 385.656862 -103.980452)
			(xy 385.633926 -103.925079) (xy 385.618413 -103.867186) (xy 385.61059 -103.807764) (xy 385.6101 -103.777796)
			(xy 376.675904 -103.777796) (xy 376.675904 -105.584498) (xy 382.967992 -105.584498) (xy 382.967992 -104.720898)
			(xy 382.968482 -104.69093) (xy 382.976305 -104.631508) (xy 382.991818 -104.573615) (xy 383.014754 -104.518242)
			(xy 383.044721 -104.466336) (xy 383.081208 -104.418786) (xy 383.123588 -104.376406) (xy 383.171138 -104.339919)
			(xy 383.223044 -104.309952) (xy 383.278417 -104.287016) (xy 383.33631 -104.271503) (xy 383.395732 -104.26368)
			(xy 383.455668 -104.26368) (xy 383.51509 -104.271503) (xy 383.572983 -104.287016) (xy 383.628356 -104.309952)
			(xy 383.680262 -104.339919) (xy 383.727812 -104.376406) (xy 383.770192 -104.418786) (xy 383.806679 -104.466336)
			(xy 383.836646 -104.518242) (xy 383.859582 -104.573615) (xy 383.875095 -104.631508) (xy 383.882918 -104.69093)
			(xy 383.883408 -104.720898) (xy 383.883408 -105.584498) (xy 383.882918 -105.614466) (xy 383.875095 -105.673888)
			(xy 383.859582 -105.731781) (xy 383.836646 -105.787154) (xy 383.806679 -105.83906) (xy 383.770192 -105.88661)
			(xy 383.727812 -105.92899) (xy 383.680262 -105.965477) (xy 383.628356 -105.995444) (xy 383.572983 -106.01838)
			(xy 383.51509 -106.033893) (xy 383.455668 -106.041716) (xy 383.395732 -106.041716) (xy 383.33631 -106.033893)
			(xy 383.278417 -106.01838) (xy 383.223044 -105.995444) (xy 383.171138 -105.965477) (xy 383.123588 -105.92899)
			(xy 383.081208 -105.88661) (xy 383.044721 -105.83906) (xy 383.014754 -105.787154) (xy 382.991818 -105.731781)
			(xy 382.976305 -105.673888) (xy 382.968482 -105.614466) (xy 382.967992 -105.584498) (xy 376.675904 -105.584498)
			(xy 376.675904 -106.777282) (xy 376.675466 -106.787346) (xy 376.667731 -106.805929) (xy 376.660918 -106.81335)
			(xy 375.81459 -107.659678) (xy 375.811885 -107.66253) (xy 375.807293 -107.668909) (xy 375.805446 -107.672378)
			(xy 375.802864 -107.677805) (xy 375.800046 -107.689485) (xy 375.799858 -107.695492) (xy 375.799858 -111.825278)
			(xy 375.800874 -111.834676) (xy 375.800874 -111.835184) (xy 375.802578 -111.842344) (xy 375.809408 -111.855372)
			(xy 375.814336 -111.860838) (xy 376.257566 -112.304068) (xy 376.263 -112.309042) (xy 376.276042 -112.315874)
			(xy 376.28322 -112.31753) (xy 376.283728 -112.31753) (xy 376.293126 -112.318546) (xy 377.331224 -112.318546)
			(xy 377.337235 -112.318709) (xy 377.348921 -112.321525) (xy 377.354338 -112.324134) (xy 377.37034 -112.332262)
			(xy 377.380754 -112.332262) (xy 377.388882 -112.333024) (xy 380.539498 -112.333024) (xy 380.550314 -112.332525)
			(xy 380.570028 -112.323622) (xy 380.584331 -112.307394) (xy 380.588012 -112.29721) (xy 380.692914 -111.95685)
			(xy 380.703235 -111.924324) (xy 380.727766 -111.860639) (xy 380.741936 -111.829596) (xy 381.074422 -111.117126)
			(xy 381.07493 -111.11611) (xy 381.129794 -110.948724) (xy 381.174244 -110.81385) (xy 381.188936 -110.770808)
			(xy 381.225106 -110.687353) (xy 381.268718 -110.607534) (xy 381.319408 -110.532013) (xy 381.376759 -110.461415)
			(xy 381.408178 -110.428532) (xy 381.881634 -109.9439) (xy 381.890016 -109.935518) (xy 381.925674 -109.900757)
			(xy 382.00277 -109.837718) (xy 382.085757 -109.782666) (xy 382.173812 -109.736147) (xy 382.219708 -109.716824)
			(xy 383.00914 -109.395768) (xy 383.009648 -109.383068) (xy 383.00914 -109.377226) (xy 382.99771 -109.347)
			(xy 382.988566 -109.320584) (xy 382.986026 -109.31271) (xy 382.986026 -109.311694) (xy 382.985264 -109.309408)
			(xy 382.984248 -109.30636) (xy 382.97993 -109.289088) (xy 382.974303 -109.263294) (xy 382.968322 -109.210838)
			(xy 382.967992 -109.18444) (xy 382.967992 -108.32084) (xy 382.968482 -108.290872) (xy 382.976305 -108.23145)
			(xy 382.991818 -108.173557) (xy 383.014754 -108.118184) (xy 383.044721 -108.066278) (xy 383.081208 -108.018728)
			(xy 383.123588 -107.976348) (xy 383.171138 -107.939861) (xy 383.223044 -107.909894) (xy 383.278417 -107.886958)
			(xy 383.33631 -107.871445) (xy 383.395732 -107.863622) (xy 383.455668 -107.863622) (xy 383.51509 -107.871445)
			(xy 383.572983 -107.886958) (xy 383.628356 -107.909894) (xy 383.680262 -107.939861) (xy 383.727812 -107.976348)
			(xy 383.770192 -108.018728) (xy 383.806679 -108.066278) (xy 383.836646 -108.118184) (xy 383.859582 -108.173557)
			(xy 383.875095 -108.23145) (xy 383.882918 -108.290872) (xy 383.883408 -108.32084) (xy 383.883408 -108.81868)
			(xy 383.88395 -108.828628) (xy 383.891621 -108.846994) (xy 383.905674 -108.86109) (xy 383.91465 -108.865416)
			(xy 383.938272 -108.865416) (xy 383.9464 -108.864654) (xy 383.946908 -108.864654) (xy 383.95443 -108.863058)
			(xy 383.968127 -108.856092) (xy 383.973832 -108.850938) (xy 384.093466 -108.731304) (xy 384.128201 -108.697326)
			(xy 384.203268 -108.635618) (xy 384.243326 -108.608114) (xy 385.635246 -107.677966) (xy 385.643374 -107.672378)
			(xy 385.648708 -107.664758) (xy 385.651493 -107.660628) (xy 385.655581 -107.651545) (xy 385.656836 -107.646724)
			(xy 385.658614 -107.63885) (xy 385.658614 -107.638342) (xy 385.663948 -107.616498) (xy 385.663948 -107.604306)
			(xy 385.662424 -107.59821) (xy 385.661916 -107.595924) (xy 385.658614 -107.583732) (xy 385.656582 -107.579414)
			(xy 385.655566 -107.576874) (xy 385.651756 -107.569) (xy 385.651502 -107.568746) (xy 385.64947 -107.56392)
			(xy 385.648962 -107.563158) (xy 385.6482 -107.56138) (xy 385.64566 -107.555284) (xy 385.645406 -107.554776)
			(xy 385.643882 -107.550966) (xy 385.642358 -107.546902) (xy 385.642104 -107.546394) (xy 385.631934 -107.519455)
			(xy 385.617671 -107.463667) (xy 385.610518 -107.40653) (xy 385.6101 -107.377738) (xy 385.6101 -106.514138)
			(xy 385.61059 -106.48417) (xy 385.618413 -106.424748) (xy 385.633926 -106.366855) (xy 385.656862 -106.311482)
			(xy 385.686829 -106.259576) (xy 385.723316 -106.212026) (xy 385.765696 -106.169646) (xy 385.813246 -106.133159)
			(xy 385.865152 -106.103192) (xy 385.920525 -106.080256) (xy 385.978418 -106.064743) (xy 386.03784 -106.05692)
			(xy 386.097776 -106.05692) (xy 386.157198 -106.064743) (xy 386.215091 -106.080256) (xy 386.270464 -106.103192)
			(xy 386.32237 -106.133159) (xy 386.36992 -106.169646) (xy 386.4123 -106.212026) (xy 386.448787 -106.259576)
			(xy 386.478754 -106.311482) (xy 386.50169 -106.366855) (xy 386.517203 -106.424748) (xy 386.525026 -106.48417)
			(xy 386.525516 -106.514138) (xy 386.525516 -106.986578) (xy 386.526146 -106.997997) (xy 386.536041 -107.018578)
			(xy 386.544566 -107.026202) (xy 386.553456 -107.032298) (xy 386.561721 -107.036364) (xy 386.579951 -107.038886)
			(xy 386.597888 -107.034764) (xy 386.60578 -107.030012) (xy 386.61721 -107.022392) (xy 386.71881 -106.954828)
			(xy 386.720842 -106.953558) (xy 392.473942 -102.37089) (xy 392.47445 -102.370382) (xy 392.503835 -102.346485)
			(xy 392.565684 -102.302756) (xy 392.630701 -102.263891) (xy 392.664442 -102.246684) (xy 393.19708 -101.981254)
			(xy 393.203938 -101.975666) (xy 393.206224 -101.97338) (xy 395.643354 -99.53625) (xy 395.650753 -99.529407)
			(xy 395.669352 -99.521684) (xy 395.679422 -99.521264) (xy 398.11579 -99.521264) (xy 398.119798 -99.521195)
			(xy 398.127711 -99.519917) (xy 398.131538 -99.518724) (xy 399.53565 -98.816668) (xy 399.539731 -98.81398)
			(xy 399.546887 -98.807328) (xy 399.549874 -98.80346) (xy 399.554192 -98.797364) (xy 399.556224 -98.785172)
			(xy 399.560896 -98.758601) (xy 399.576744 -98.707031) (xy 399.599701 -98.65821) (xy 399.62931 -98.613111)
			(xy 399.66498 -98.572636) (xy 399.705998 -98.537592) (xy 399.751545 -98.508678) (xy 399.800713 -98.486473)
			(xy 399.85252 -98.471418) (xy 399.905931 -98.463816) (xy 399.932906 -98.463354) (xy 399.933414 -98.463354)
			(xy 399.96745 -98.465132) (xy 399.978118 -98.466148) (xy 400.005814 -98.469914) (xy 400.05977 -98.484502)
			(xy 400.111021 -98.506802) (xy 400.158473 -98.536339) (xy 400.201109 -98.57248) (xy 400.219926 -98.593148)
			(xy 400.22365 -98.597196) (xy 400.232485 -98.603742) (xy 400.237452 -98.606102) (xy 400.23796 -98.606356)
			(xy 401.48256 -98.606356) (xy 401.486615 -98.604401) (xy 401.494026 -98.599293) (xy 401.497292 -98.596196)
			(xy 401.49907 -98.594418) (xy 401.500086 -98.593148) (xy 401.51832 -98.573095) (xy 401.559472 -98.537826)
			(xy 401.605194 -98.508724) (xy 401.654568 -98.486374) (xy 401.706605 -98.471222) (xy 401.760261 -98.463574)
			(xy 401.78736 -98.4631) (xy 401.817586 -98.46437) (xy 401.832064 -98.465894) (xy 401.85213 -98.468942)
			(xy 401.862544 -98.47072) (xy 401.902523 -98.445978) (xy 401.98629 -98.403269) (xy 402.073703 -98.36863)
			(xy 402.163987 -98.342367) (xy 402.256342 -98.324714) (xy 402.349947 -98.315828) (xy 402.39696 -98.315272)
			(xy 402.40458 -98.315272) (xy 402.450954 -98.316165) (xy 402.543241 -98.325504) (xy 402.634262 -98.343379)
			(xy 402.723227 -98.369633) (xy 402.809369 -98.404041) (xy 402.89194 -98.446303) (xy 402.931376 -98.47072)
			(xy 402.941028 -98.468942) (xy 402.957157 -98.466327) (xy 402.989714 -98.463525) (xy 403.006052 -98.463354)
			(xy 403.00656 -98.463354) (xy 403.033816 -98.463814) (xy 403.087773 -98.471566) (xy 403.140078 -98.486918)
			(xy 403.189666 -98.509558) (xy 403.235527 -98.539025) (xy 403.276727 -98.574718) (xy 403.312429 -98.615911)
			(xy 403.341904 -98.661766) (xy 403.364554 -98.711349) (xy 403.379917 -98.763651) (xy 403.38768 -98.817606)
			(xy 403.388068 -98.844862) (xy 403.388068 -98.845624) (xy 403.387572 -98.87395) (xy 403.379237 -98.929985)
			(xy 403.362708 -98.984171) (xy 403.350984 -99.009962) (xy 403.34946 -99.017074) (xy 403.36364 -99.064886)
			(xy 403.383508 -99.16262) (xy 403.385971 -99.187) (xy 418.422072 -99.187) (xy 418.426143 -99.131378)
			(xy 418.438269 -99.076941) (xy 418.458192 -99.02485) (xy 418.485488 -98.976215) (xy 418.519574 -98.932072)
			(xy 418.559723 -98.893363) (xy 418.605081 -98.860912) (xy 418.654681 -98.835411) (xy 418.707465 -98.817404)
			(xy 418.762308 -98.807274) (xy 418.818042 -98.805237) (xy 418.873479 -98.811337) (xy 418.927436 -98.825443)
			(xy 418.978765 -98.847255) (xy 419.026371 -98.876309) (xy 419.069239 -98.911984) (xy 419.106456 -98.953521)
			(xy 419.137229 -99.000034) (xy 419.160901 -99.050531) (xy 419.176969 -99.103938) (xy 419.185089 -99.159114)
			(xy 419.185598 -99.187) (xy 419.185089 -99.214886) (xy 419.176969 -99.270062) (xy 419.160901 -99.323469)
			(xy 419.137229 -99.373966) (xy 419.106456 -99.420479) (xy 419.08898 -99.439984) (xy 423.610022 -99.439984)
			(xy 423.614093 -99.384362) (xy 423.626219 -99.329925) (xy 423.646142 -99.277834) (xy 423.673438 -99.229199)
			(xy 423.707524 -99.185056) (xy 423.747673 -99.146347) (xy 423.793031 -99.113896) (xy 423.842631 -99.088395)
			(xy 423.895415 -99.070388) (xy 423.950258 -99.060258) (xy 424.005992 -99.058221) (xy 424.061429 -99.064321)
			(xy 424.115386 -99.078427) (xy 424.166715 -99.100239) (xy 424.214321 -99.129293) (xy 424.257189 -99.164968)
			(xy 424.294406 -99.206505) (xy 424.325179 -99.253018) (xy 424.348851 -99.303515) (xy 424.364919 -99.356922)
			(xy 424.373039 -99.412098) (xy 424.373548 -99.439984) (xy 424.373039 -99.46787) (xy 424.364919 -99.523046)
			(xy 424.348851 -99.576453) (xy 424.325179 -99.62695) (xy 424.294406 -99.673463) (xy 424.257189 -99.715)
			(xy 424.214321 -99.750675) (xy 424.166715 -99.779729) (xy 424.115386 -99.801541) (xy 424.061429 -99.815647)
			(xy 424.005992 -99.821747) (xy 423.950258 -99.81971) (xy 423.895415 -99.80958) (xy 423.842631 -99.791573)
			(xy 423.793031 -99.766072) (xy 423.747673 -99.733621) (xy 423.707524 -99.694912) (xy 423.673438 -99.650769)
			(xy 423.646142 -99.602134) (xy 423.626219 -99.550043) (xy 423.614093 -99.495606) (xy 423.610022 -99.439984)
			(xy 419.08898 -99.439984) (xy 419.069239 -99.462016) (xy 419.026371 -99.497691) (xy 418.978765 -99.526745)
			(xy 418.927436 -99.548557) (xy 418.873479 -99.562663) (xy 418.818042 -99.568763) (xy 418.762308 -99.566726)
			(xy 418.707465 -99.556596) (xy 418.654681 -99.538589) (xy 418.605081 -99.513088) (xy 418.559723 -99.480637)
			(xy 418.519574 -99.441928) (xy 418.485488 -99.397785) (xy 418.458192 -99.34915) (xy 418.438269 -99.297059)
			(xy 418.426143 -99.242622) (xy 418.422072 -99.187) (xy 403.385971 -99.187) (xy 403.393532 -99.261848)
			(xy 403.394164 -99.311714) (xy 403.394164 -99.31273) (xy 403.393728 -99.355316) (xy 403.386486 -99.44018)
			(xy 403.372032 -99.524117) (xy 403.350471 -99.606516) (xy 403.32196 -99.686775) (xy 403.304756 -99.725734)
			(xy 403.301579 -99.734867) (xy 403.30159 -99.754188) (xy 403.304756 -99.763326) (xy 403.321967 -99.802282)
			(xy 403.350467 -99.882545) (xy 403.372025 -99.964944) (xy 403.384942 -100.039932) (xy 422.176954 -100.039932)
			(xy 422.181025 -99.98431) (xy 422.193151 -99.929873) (xy 422.213074 -99.877782) (xy 422.24037 -99.829147)
			(xy 422.274456 -99.785004) (xy 422.314605 -99.746295) (xy 422.359963 -99.713844) (xy 422.409563 -99.688343)
			(xy 422.462347 -99.670336) (xy 422.51719 -99.660206) (xy 422.572924 -99.658169) (xy 422.628361 -99.664269)
			(xy 422.682318 -99.678375) (xy 422.733647 -99.700187) (xy 422.781253 -99.729241) (xy 422.824121 -99.764916)
			(xy 422.861338 -99.806453) (xy 422.892111 -99.852966) (xy 422.915783 -99.903463) (xy 422.931851 -99.95687)
			(xy 422.939971 -100.012046) (xy 422.94048 -100.039932) (xy 422.939971 -100.067818) (xy 422.931851 -100.122994)
			(xy 422.915783 -100.176401) (xy 422.892111 -100.226898) (xy 422.861338 -100.273411) (xy 422.824121 -100.314948)
			(xy 422.781253 -100.350623) (xy 422.733647 -100.379677) (xy 422.682318 -100.401489) (xy 422.628361 -100.415595)
			(xy 422.572924 -100.421695) (xy 422.51719 -100.419658) (xy 422.462347 -100.409528) (xy 422.409563 -100.391521)
			(xy 422.359963 -100.36602) (xy 422.314605 -100.333569) (xy 422.274456 -100.29486) (xy 422.24037 -100.250717)
			(xy 422.213074 -100.202082) (xy 422.193151 -100.149991) (xy 422.181025 -100.095554) (xy 422.176954 -100.039932)
			(xy 403.384942 -100.039932) (xy 403.386483 -100.048881) (xy 403.393737 -100.133744) (xy 403.394164 -100.17633)
			(xy 403.394164 -100.176838) (xy 403.393555 -100.22679) (xy 403.383561 -100.326191) (xy 403.363667 -100.424094)
			(xy 403.34946 -100.471986) (xy 403.349968 -100.47478) (xy 403.353524 -100.484178) (xy 403.354286 -100.486464)
			(xy 403.354794 -100.487226) (xy 403.355048 -100.487734) (xy 403.365586 -100.512495) (xy 403.380371 -100.564236)
			(xy 403.38772 -100.617544) (xy 403.388068 -100.644452) (xy 403.387592 -100.672347) (xy 403.379537 -100.72755)
			(xy 403.367911 -100.766372) (xy 405.89784 -100.766372) (xy 405.901911 -100.71075) (xy 405.914037 -100.656313)
			(xy 405.93396 -100.604222) (xy 405.961256 -100.555587) (xy 405.995342 -100.511444) (xy 406.035491 -100.472735)
			(xy 406.080849 -100.440284) (xy 406.130449 -100.414783) (xy 406.183233 -100.396776) (xy 406.238076 -100.386646)
			(xy 406.29381 -100.384609) (xy 406.349247 -100.390709) (xy 406.403204 -100.404815) (xy 406.454533 -100.426627)
			(xy 406.502139 -100.455681) (xy 406.545007 -100.491356) (xy 406.582224 -100.532893) (xy 406.612997 -100.579406)
			(xy 406.636669 -100.629903) (xy 406.652737 -100.68331) (xy 406.660857 -100.738486) (xy 406.661366 -100.766372)
			(xy 406.660857 -100.794258) (xy 406.652737 -100.849434) (xy 406.636669 -100.902841) (xy 406.612997 -100.953338)
			(xy 406.582224 -100.999851) (xy 406.545007 -101.041388) (xy 406.502139 -101.077063) (xy 406.454533 -101.106117)
			(xy 406.403204 -101.127929) (xy 406.349247 -101.142035) (xy 406.29381 -101.148135) (xy 406.238076 -101.146098)
			(xy 406.183233 -101.135968) (xy 406.130449 -101.117961) (xy 406.080849 -101.09246) (xy 406.035491 -101.060009)
			(xy 405.995342 -101.0213) (xy 405.961256 -100.977157) (xy 405.93396 -100.928522) (xy 405.914037 -100.876431)
			(xy 405.901911 -100.821994) (xy 405.89784 -100.766372) (xy 403.367911 -100.766372) (xy 403.363533 -100.780993)
			(xy 403.339921 -100.831538) (xy 403.309204 -100.878108) (xy 403.272036 -100.919712) (xy 403.229208 -100.955462)
			(xy 403.181633 -100.984599) (xy 403.156166 -100.995988) (xy 403.149562 -100.998782) (xy 403.136608 -101.00945)
			(xy 403.128288 -101.017023) (xy 403.11867 -101.03733) (xy 403.118066 -101.048566) (xy 403.118066 -101.240082)
			(xy 422.594022 -101.240082) (xy 422.598093 -101.18446) (xy 422.610219 -101.130023) (xy 422.630142 -101.077932)
			(xy 422.657438 -101.029297) (xy 422.691524 -100.985154) (xy 422.731673 -100.946445) (xy 422.777031 -100.913994)
			(xy 422.826631 -100.888493) (xy 422.879415 -100.870486) (xy 422.934258 -100.860356) (xy 422.989992 -100.858319)
			(xy 423.045429 -100.864419) (xy 423.099386 -100.878525) (xy 423.150715 -100.900337) (xy 423.198321 -100.929391)
			(xy 423.241189 -100.965066) (xy 423.278406 -101.006603) (xy 423.309179 -101.053116) (xy 423.316929 -101.069648)
			(xy 423.886374 -101.069648) (xy 423.890445 -101.014026) (xy 423.902571 -100.959589) (xy 423.922494 -100.907498)
			(xy 423.94979 -100.858863) (xy 423.983876 -100.81472) (xy 424.024025 -100.776011) (xy 424.069383 -100.74356)
			(xy 424.118983 -100.718059) (xy 424.171767 -100.700052) (xy 424.22661 -100.689922) (xy 424.282344 -100.687885)
			(xy 424.337781 -100.693985) (xy 424.391738 -100.708091) (xy 424.443067 -100.729903) (xy 424.490673 -100.758957)
			(xy 424.533541 -100.794632) (xy 424.570758 -100.836169) (xy 424.601531 -100.882682) (xy 424.625203 -100.933179)
			(xy 424.641271 -100.986586) (xy 424.649391 -101.041762) (xy 424.6499 -101.069648) (xy 424.649391 -101.097534)
			(xy 424.641271 -101.15271) (xy 424.625203 -101.206117) (xy 424.601531 -101.256614) (xy 424.570758 -101.303127)
			(xy 424.533541 -101.344664) (xy 424.490673 -101.380339) (xy 424.443067 -101.409393) (xy 424.391738 -101.431205)
			(xy 424.337781 -101.445311) (xy 424.282344 -101.451411) (xy 424.22661 -101.449374) (xy 424.171767 -101.439244)
			(xy 424.118983 -101.421237) (xy 424.069383 -101.395736) (xy 424.024025 -101.363285) (xy 423.983876 -101.324576)
			(xy 423.94979 -101.280433) (xy 423.922494 -101.231798) (xy 423.902571 -101.179707) (xy 423.890445 -101.12527)
			(xy 423.886374 -101.069648) (xy 423.316929 -101.069648) (xy 423.332851 -101.103613) (xy 423.348919 -101.15702)
			(xy 423.357039 -101.212196) (xy 423.357548 -101.240082) (xy 423.357039 -101.267968) (xy 423.348919 -101.323144)
			(xy 423.332851 -101.376551) (xy 423.309179 -101.427048) (xy 423.278406 -101.473561) (xy 423.241189 -101.515098)
			(xy 423.198321 -101.550773) (xy 423.150715 -101.579827) (xy 423.099386 -101.601639) (xy 423.045429 -101.615745)
			(xy 422.989992 -101.621845) (xy 422.934258 -101.619808) (xy 422.879415 -101.609678) (xy 422.826631 -101.591671)
			(xy 422.777031 -101.56617) (xy 422.731673 -101.533719) (xy 422.691524 -101.49501) (xy 422.657438 -101.450867)
			(xy 422.630142 -101.402232) (xy 422.610219 -101.350141) (xy 422.598093 -101.295704) (xy 422.594022 -101.240082)
			(xy 403.118066 -101.240082) (xy 403.118066 -102.00386) (xy 403.118636 -102.011354) (xy 403.123539 -102.025553)
			(xy 403.127718 -102.0318) (xy 403.138386 -102.044246) (xy 403.139402 -102.045516) (xy 403.140164 -102.046278)
			(xy 403.143466 -102.050342) (xy 403.148038 -102.0572) (xy 403.151086 -102.069646) (xy 403.15388 -102.081584)
			(xy 403.160484 -102.089966) (xy 403.163944 -102.094078) (xy 403.172264 -102.100877) (xy 403.176994 -102.103428)
			(xy 403.177756 -102.103936) (xy 403.179534 -102.104698) (xy 403.179788 -102.104952) (xy 403.18309 -102.106476)
			(xy 403.205928 -102.118908) (xy 403.248316 -102.149026) (xy 403.286225 -102.184616) (xy 403.318954 -102.225021)
			(xy 403.345897 -102.269494) (xy 403.366557 -102.317211) (xy 403.380551 -102.36729) (xy 403.387619 -102.418805)
			(xy 403.388068 -102.444804) (xy 403.388068 -102.445566) (xy 403.387569 -102.473891) (xy 403.38532 -102.489)
			(xy 423.102022 -102.489) (xy 423.106093 -102.433378) (xy 423.118219 -102.378941) (xy 423.138142 -102.32685)
			(xy 423.165438 -102.278215) (xy 423.199524 -102.234072) (xy 423.239673 -102.195363) (xy 423.285031 -102.162912)
			(xy 423.334631 -102.137411) (xy 423.387415 -102.119404) (xy 423.442258 -102.109274) (xy 423.497992 -102.107237)
			(xy 423.553429 -102.113337) (xy 423.607386 -102.127443) (xy 423.658715 -102.149255) (xy 423.706321 -102.178309)
			(xy 423.749189 -102.213984) (xy 423.786406 -102.255521) (xy 423.817179 -102.302034) (xy 423.840851 -102.352531)
			(xy 423.856919 -102.405938) (xy 423.865039 -102.461114) (xy 423.865548 -102.489) (xy 423.865039 -102.516886)
			(xy 423.856919 -102.572062) (xy 423.840851 -102.625469) (xy 423.817179 -102.675966) (xy 423.786406 -102.722479)
			(xy 423.749189 -102.764016) (xy 423.706321 -102.799691) (xy 423.658715 -102.828745) (xy 423.607386 -102.850557)
			(xy 423.553429 -102.864663) (xy 423.497992 -102.870763) (xy 423.442258 -102.868726) (xy 423.387415 -102.858596)
			(xy 423.334631 -102.840589) (xy 423.285031 -102.815088) (xy 423.239673 -102.782637) (xy 423.199524 -102.743928)
			(xy 423.165438 -102.699785) (xy 423.138142 -102.65115) (xy 423.118219 -102.599059) (xy 423.106093 -102.544622)
			(xy 423.102022 -102.489) (xy 403.38532 -102.489) (xy 403.379228 -102.529924) (xy 403.362694 -102.584107)
			(xy 403.350984 -102.609904) (xy 403.34946 -102.617016) (xy 403.363638 -102.664828) (xy 403.383502 -102.762562)
			(xy 403.393521 -102.86179) (xy 403.394164 -102.911656) (xy 403.394164 -102.912672) (xy 403.393731 -102.955259)
			(xy 403.386493 -103.040124) (xy 403.372044 -103.124063) (xy 403.350487 -103.206464) (xy 403.32198 -103.286725)
			(xy 403.304756 -103.325676) (xy 403.301569 -103.33481) (xy 403.301559 -103.354139) (xy 403.304756 -103.363268)
			(xy 403.321966 -103.402224) (xy 403.350462 -103.482488) (xy 403.372016 -103.564887) (xy 403.386471 -103.648823)
			(xy 403.393722 -103.733686) (xy 403.394164 -103.776272) (xy 403.394164 -103.77678) (xy 403.393558 -103.826732)
			(xy 403.387602 -103.886) (xy 423.610022 -103.886) (xy 423.614093 -103.830378) (xy 423.626219 -103.775941)
			(xy 423.646142 -103.72385) (xy 423.673438 -103.675215) (xy 423.707524 -103.631072) (xy 423.747673 -103.592363)
			(xy 423.793031 -103.559912) (xy 423.842631 -103.534411) (xy 423.895415 -103.516404) (xy 423.950258 -103.506274)
			(xy 424.005992 -103.504237) (xy 424.061429 -103.510337) (xy 424.115386 -103.524443) (xy 424.166715 -103.546255)
			(xy 424.214321 -103.575309) (xy 424.257189 -103.610984) (xy 424.294406 -103.652521) (xy 424.325179 -103.699034)
			(xy 424.348851 -103.749531) (xy 424.364919 -103.802938) (xy 424.373039 -103.858114) (xy 424.373548 -103.886)
			(xy 424.373039 -103.913886) (xy 424.364919 -103.969062) (xy 424.348851 -104.022469) (xy 424.325179 -104.072966)
			(xy 424.294406 -104.119479) (xy 424.257189 -104.161016) (xy 424.214321 -104.196691) (xy 424.166715 -104.225745)
			(xy 424.115386 -104.247557) (xy 424.061429 -104.261663) (xy 424.005992 -104.267763) (xy 423.950258 -104.265726)
			(xy 423.895415 -104.255596) (xy 423.842631 -104.237589) (xy 423.793031 -104.212088) (xy 423.747673 -104.179637)
			(xy 423.707524 -104.140928) (xy 423.673438 -104.096785) (xy 423.646142 -104.04815) (xy 423.626219 -103.996059)
			(xy 423.614093 -103.941622) (xy 423.610022 -103.886) (xy 403.387602 -103.886) (xy 403.383569 -103.926135)
			(xy 403.363681 -104.024039) (xy 403.34946 -104.071928) (xy 403.349968 -104.074722) (xy 403.353524 -104.08412)
			(xy 403.354286 -104.086406) (xy 403.354794 -104.087168) (xy 403.355048 -104.087676) (xy 403.365584 -104.112437)
			(xy 403.380363 -104.164179) (xy 403.387706 -104.217487) (xy 403.388068 -104.244394) (xy 403.387589 -104.272287)
			(xy 403.379529 -104.327487) (xy 403.363521 -104.380925) (xy 403.339906 -104.431465) (xy 403.309187 -104.47803)
			(xy 403.272018 -104.519629) (xy 403.229191 -104.555375) (xy 403.181617 -104.584507) (xy 403.156166 -104.59593)
			(xy 403.149562 -104.598724) (xy 403.136608 -104.609392) (xy 403.128295 -104.616968) (xy 403.118694 -104.637275)
			(xy 403.118066 -104.648508) (xy 403.118066 -105.603802) (xy 403.118641 -105.611294) (xy 403.123554 -105.625486)
			(xy 403.127718 -105.631742) (xy 403.138386 -105.644188) (xy 403.139402 -105.645458) (xy 403.140164 -105.64622)
			(xy 403.143466 -105.650284) (xy 403.148038 -105.657142) (xy 403.151086 -105.669588) (xy 403.15388 -105.681526)
			(xy 403.160484 -105.689908) (xy 403.163946 -105.694017) (xy 403.172269 -105.700811) (xy 403.176994 -105.70337)
			(xy 403.177756 -105.703878) (xy 403.179534 -105.70464) (xy 403.179788 -105.704894) (xy 403.18309 -105.706418)
			(xy 403.205926 -105.718851) (xy 403.24831 -105.748969) (xy 403.286216 -105.784561) (xy 403.31894 -105.824966)
			(xy 403.345879 -105.869439) (xy 403.366534 -105.917156) (xy 403.380522 -105.967235) (xy 403.387585 -106.018748)
			(xy 403.388068 -106.044746) (xy 403.388068 -106.045508) (xy 403.387573 -106.073834) (xy 403.37924 -106.12987)
			(xy 403.362713 -106.184058) (xy 403.350984 -106.209846) (xy 403.34946 -106.216958) (xy 403.363636 -106.26477)
			(xy 403.383496 -106.362505) (xy 403.393511 -106.461733) (xy 403.394164 -106.511598) (xy 403.394164 -106.512614)
			(xy 403.393729 -106.555201) (xy 403.386488 -106.640065) (xy 403.372035 -106.724003) (xy 403.350475 -106.806401)
			(xy 403.321965 -106.886661) (xy 403.304756 -106.925618) (xy 403.301576 -106.934751) (xy 403.301581 -106.954075)
			(xy 403.304756 -106.96321) (xy 403.321964 -107.002167) (xy 403.350457 -107.08243) (xy 403.372008 -107.16483)
			(xy 403.379845 -107.210352) (xy 413.291526 -107.210352) (xy 413.295597 -107.15473) (xy 413.307723 -107.100293)
			(xy 413.327646 -107.048202) (xy 413.354942 -106.999567) (xy 413.389028 -106.955424) (xy 413.429177 -106.916715)
			(xy 413.474535 -106.884264) (xy 413.524135 -106.858763) (xy 413.576919 -106.840756) (xy 413.631762 -106.830626)
			(xy 413.687496 -106.828589) (xy 413.742933 -106.834689) (xy 413.79689 -106.848795) (xy 413.848219 -106.870607)
			(xy 413.895825 -106.899661) (xy 413.938693 -106.935336) (xy 413.97591 -106.976873) (xy 414.006683 -107.023386)
			(xy 414.030355 -107.073883) (xy 414.046423 -107.12729) (xy 414.054543 -107.182466) (xy 414.055052 -107.210352)
			(xy 414.054543 -107.238238) (xy 414.046423 -107.293414) (xy 414.030355 -107.346821) (xy 414.006683 -107.397318)
			(xy 413.97591 -107.443831) (xy 413.938693 -107.485368) (xy 413.895825 -107.521043) (xy 413.848219 -107.550097)
			(xy 413.79689 -107.571909) (xy 413.742933 -107.586015) (xy 413.687496 -107.592115) (xy 413.631762 -107.590078)
			(xy 413.576919 -107.579948) (xy 413.524135 -107.561941) (xy 413.474535 -107.53644) (xy 413.429177 -107.503989)
			(xy 413.389028 -107.46528) (xy 413.354942 -107.421137) (xy 413.327646 -107.372502) (xy 413.307723 -107.320411)
			(xy 413.295597 -107.265974) (xy 413.291526 -107.210352) (xy 403.379845 -107.210352) (xy 403.386459 -107.248766)
			(xy 403.393706 -107.333628) (xy 403.394164 -107.376214) (xy 403.394164 -107.376722) (xy 403.393556 -107.426674)
			(xy 403.383563 -107.526076) (xy 403.363671 -107.623979) (xy 403.34946 -107.67187) (xy 403.349968 -107.674664)
			(xy 403.353524 -107.684062) (xy 403.354286 -107.686348) (xy 403.354794 -107.68711) (xy 403.355048 -107.687618)
			(xy 403.365587 -107.712379) (xy 403.380374 -107.76412) (xy 403.387726 -107.817428) (xy 403.388068 -107.844336)
			(xy 403.387593 -107.872231) (xy 403.37954 -107.927436) (xy 403.363538 -107.980881) (xy 403.339927 -108.031428)
			(xy 403.309211 -108.078) (xy 403.272043 -108.119605) (xy 403.229215 -108.155358) (xy 403.18164 -108.184496)
			(xy 403.156166 -108.195872) (xy 403.149562 -108.198666) (xy 403.136608 -108.209334) (xy 403.128285 -108.216906)
			(xy 403.118661 -108.237213) (xy 403.118066 -108.24845) (xy 403.118066 -109.203998) (xy 403.118641 -109.21149)
			(xy 403.123553 -109.225683) (xy 403.127718 -109.231938) (xy 403.138386 -109.244384) (xy 403.139402 -109.245654)
			(xy 403.140164 -109.246416) (xy 403.143466 -109.25048) (xy 403.148038 -109.257338) (xy 403.151086 -109.269784)
			(xy 403.15388 -109.281722) (xy 403.160484 -109.290104) (xy 403.163946 -109.294214) (xy 403.172269 -109.301008)
			(xy 403.176994 -109.303566) (xy 403.177756 -109.304074) (xy 403.179534 -109.304836) (xy 403.179788 -109.30509)
			(xy 403.18309 -109.306614) (xy 403.205926 -109.319047) (xy 403.248311 -109.349165) (xy 403.286216 -109.384756)
			(xy 403.318941 -109.425162) (xy 403.345881 -109.469635) (xy 403.366536 -109.517352) (xy 403.380525 -109.567431)
			(xy 403.387588 -109.618944) (xy 403.388068 -109.644942) (xy 403.388068 -109.645704) (xy 403.387574 -109.67403)
			(xy 403.379241 -109.730066) (xy 403.362714 -109.784254) (xy 403.350984 -109.810042) (xy 403.34946 -109.817154)
			(xy 403.363637 -109.864966) (xy 403.383497 -109.962701) (xy 403.393512 -110.061928) (xy 403.394164 -110.111794)
			(xy 403.394164 -110.11281) (xy 403.393729 -110.155397) (xy 403.386489 -110.240261) (xy 403.372036 -110.324199)
			(xy 403.350476 -110.406598) (xy 403.321967 -110.486857) (xy 403.304756 -110.525814) (xy 403.303253 -110.530132)
			(xy 418.729158 -110.530132) (xy 418.733229 -110.47451) (xy 418.745355 -110.420073) (xy 418.765278 -110.367982)
			(xy 418.792574 -110.319347) (xy 418.82666 -110.275204) (xy 418.866809 -110.236495) (xy 418.912167 -110.204044)
			(xy 418.961767 -110.178543) (xy 419.014551 -110.160536) (xy 419.069394 -110.150406) (xy 419.125128 -110.148369)
			(xy 419.180565 -110.154469) (xy 419.234522 -110.168575) (xy 419.285851 -110.190387) (xy 419.333457 -110.219441)
			(xy 419.376325 -110.255116) (xy 419.413542 -110.296653) (xy 419.444315 -110.343166) (xy 419.467987 -110.393663)
			(xy 419.484055 -110.44707) (xy 419.492175 -110.502246) (xy 419.492684 -110.530132) (xy 419.492175 -110.558018)
			(xy 419.484055 -110.613194) (xy 419.467987 -110.666601) (xy 419.444315 -110.717098) (xy 419.413542 -110.763611)
			(xy 419.376325 -110.805148) (xy 419.333457 -110.840823) (xy 419.285851 -110.869877) (xy 419.234522 -110.891689)
			(xy 419.180565 -110.905795) (xy 419.125128 -110.911895) (xy 419.069394 -110.909858) (xy 419.014551 -110.899728)
			(xy 418.961767 -110.881721) (xy 418.912167 -110.85622) (xy 418.866809 -110.823769) (xy 418.82666 -110.78506)
			(xy 418.792574 -110.740917) (xy 418.765278 -110.692282) (xy 418.745355 -110.640191) (xy 418.733229 -110.585754)
			(xy 418.729158 -110.530132) (xy 403.303253 -110.530132) (xy 403.301576 -110.534947) (xy 403.301579 -110.554271)
			(xy 403.304756 -110.563406) (xy 403.321964 -110.602362) (xy 403.350457 -110.682626) (xy 403.372008 -110.765026)
			(xy 403.38646 -110.848962) (xy 403.393708 -110.933824) (xy 403.394164 -110.97641) (xy 403.394164 -110.976918)
			(xy 403.393556 -111.02687) (xy 403.383564 -111.126272) (xy 403.363672 -111.224175) (xy 403.34946 -111.272066)
			(xy 403.349968 -111.27486) (xy 403.353524 -111.284258) (xy 403.354286 -111.286544) (xy 403.354794 -111.287306)
			(xy 403.355048 -111.287814) (xy 403.365588 -111.312575) (xy 403.371723 -111.334042) (xy 412.56407 -111.334042)
			(xy 412.568141 -111.27842) (xy 412.580267 -111.223983) (xy 412.60019 -111.171892) (xy 412.627486 -111.123257)
			(xy 412.661572 -111.079114) (xy 412.701721 -111.040405) (xy 412.747079 -111.007954) (xy 412.796679 -110.982453)
			(xy 412.849463 -110.964446) (xy 412.904306 -110.954316) (xy 412.96004 -110.952279) (xy 413.015477 -110.958379)
			(xy 413.069434 -110.972485) (xy 413.120763 -110.994297) (xy 413.168369 -111.023351) (xy 413.211237 -111.059026)
			(xy 413.248454 -111.100563) (xy 413.279227 -111.147076) (xy 413.302899 -111.197573) (xy 413.318967 -111.25098)
			(xy 413.327087 -111.306156) (xy 413.327596 -111.334042) (xy 413.327087 -111.361928) (xy 413.318967 -111.417104)
			(xy 413.302899 -111.470511) (xy 413.279227 -111.521008) (xy 413.248454 -111.567521) (xy 413.211237 -111.609058)
			(xy 413.168369 -111.644733) (xy 413.120763 -111.673787) (xy 413.069434 -111.695599) (xy 413.015477 -111.709705)
			(xy 412.96004 -111.715805) (xy 412.904306 -111.713768) (xy 412.849463 -111.703638) (xy 412.796679 -111.685631)
			(xy 412.747079 -111.66013) (xy 412.701721 -111.627679) (xy 412.661572 -111.58897) (xy 412.627486 -111.544827)
			(xy 412.60019 -111.496192) (xy 412.580267 -111.444101) (xy 412.568141 -111.389664) (xy 412.56407 -111.334042)
			(xy 403.371723 -111.334042) (xy 403.380375 -111.364316) (xy 403.387727 -111.417624) (xy 403.388068 -111.444532)
			(xy 403.387594 -111.472427) (xy 403.379541 -111.527633) (xy 403.363539 -111.581078) (xy 403.339929 -111.631625)
			(xy 403.309212 -111.678198) (xy 403.272044 -111.719804) (xy 403.229217 -111.755556) (xy 403.181641 -111.784695)
			(xy 403.156166 -111.796068) (xy 403.149562 -111.798862) (xy 403.136608 -111.80953) (xy 403.128284 -111.817102)
			(xy 403.118659 -111.837409) (xy 403.118066 -111.848646) (xy 403.118066 -111.884206) (xy 418.664388 -111.884206)
			(xy 418.668459 -111.828584) (xy 418.680585 -111.774147) (xy 418.700508 -111.722056) (xy 418.727804 -111.673421)
			(xy 418.76189 -111.629278) (xy 418.802039 -111.590569) (xy 418.847397 -111.558118) (xy 418.896997 -111.532617)
			(xy 418.949781 -111.51461) (xy 419.004624 -111.50448) (xy 419.060358 -111.502443) (xy 419.115795 -111.508543)
			(xy 419.169752 -111.522649) (xy 419.221081 -111.544461) (xy 419.268687 -111.573515) (xy 419.311555 -111.60919)
			(xy 419.348772 -111.650727) (xy 419.379545 -111.69724) (xy 419.403217 -111.747737) (xy 419.419285 -111.801144)
			(xy 419.427405 -111.85632) (xy 419.427914 -111.884206) (xy 419.427405 -111.912092) (xy 419.419285 -111.967268)
			(xy 419.415236 -111.980726) (xy 422.201594 -111.980726) (xy 422.202135 -111.951988) (xy 422.210754 -111.895161)
			(xy 422.2278 -111.840271) (xy 422.252887 -111.788559) (xy 422.285449 -111.741195) (xy 422.304718 -111.719868)
			(xy 422.311322 -111.71301) (xy 422.318434 -111.694976) (xy 422.318434 -111.606076) (xy 422.311322 -111.588042)
			(xy 422.304718 -111.581184) (xy 422.285473 -111.559835) (xy 422.252908 -111.512476) (xy 422.227815 -111.460768)
			(xy 422.210763 -111.405881) (xy 422.202139 -111.349056) (xy 422.202136 -111.291581) (xy 422.210755 -111.234756)
			(xy 422.227801 -111.179868) (xy 422.252889 -111.128157) (xy 422.285449 -111.080795) (xy 422.304718 -111.059468)
			(xy 422.311322 -111.05261) (xy 422.318434 -111.034576) (xy 422.318434 -110.945676) (xy 422.311322 -110.927642)
			(xy 422.304718 -110.920784) (xy 422.285473 -110.899435) (xy 422.252908 -110.852076) (xy 422.227815 -110.800368)
			(xy 422.210763 -110.745481) (xy 422.202139 -110.688656) (xy 422.202136 -110.631181) (xy 422.210755 -110.574356)
			(xy 422.227801 -110.519468) (xy 422.252889 -110.467757) (xy 422.285449 -110.420395) (xy 422.304718 -110.399068)
			(xy 422.311322 -110.39221) (xy 422.318434 -110.374176) (xy 422.318434 -110.285276) (xy 422.311322 -110.267242)
			(xy 422.304718 -110.260384) (xy 422.285473 -110.239035) (xy 422.252908 -110.191676) (xy 422.227815 -110.139968)
			(xy 422.210763 -110.085081) (xy 422.202139 -110.028256) (xy 422.202136 -109.970781) (xy 422.210755 -109.913956)
			(xy 422.227801 -109.859068) (xy 422.252889 -109.807357) (xy 422.285449 -109.759995) (xy 422.304718 -109.738668)
			(xy 422.311322 -109.73181) (xy 422.318434 -109.713776) (xy 422.318434 -109.624876) (xy 422.311322 -109.606842)
			(xy 422.304718 -109.599984) (xy 422.285456 -109.578649) (xy 422.252889 -109.531289) (xy 422.227796 -109.479579)
			(xy 422.210743 -109.42469) (xy 422.202117 -109.367864) (xy 422.201594 -109.339126) (xy 422.20208 -109.311874)
			(xy 422.209833 -109.257923) (xy 422.225186 -109.205626) (xy 422.247825 -109.156046) (xy 422.277291 -109.110192)
			(xy 422.312982 -109.068999) (xy 422.354173 -109.033305) (xy 422.400025 -109.003837) (xy 422.449603 -108.981194)
			(xy 422.5019 -108.965838) (xy 422.55585 -108.958081) (xy 422.583102 -108.957618) (xy 422.609416 -108.958078)
			(xy 422.661545 -108.965314) (xy 422.712188 -108.979634) (xy 422.760388 -109.000768) (xy 422.805231 -109.028315)
			(xy 422.84587 -109.061756) (xy 422.864026 -109.080808) (xy 422.871535 -109.088224) (xy 422.890825 -109.09674)
			(xy 422.901364 -109.097318) (xy 422.97604 -109.097318) (xy 422.986587 -109.096765) (xy 423.005882 -109.088246)
			(xy 423.013378 -109.080808) (xy 423.031553 -109.061772) (xy 423.072178 -109.028312) (xy 423.117014 -109.000751)
			(xy 423.165211 -108.979609) (xy 423.215856 -108.965288) (xy 423.267987 -108.958059) (xy 423.294302 -108.957618)
			(xy 423.321556 -108.958054) (xy 423.375509 -108.965811) (xy 423.427809 -108.981169) (xy 423.477391 -109.003814)
			(xy 423.523246 -109.033284) (xy 423.564439 -109.068981) (xy 423.600132 -109.110177) (xy 423.6296 -109.156033)
			(xy 423.652241 -109.205617) (xy 423.667594 -109.257918) (xy 423.675348 -109.311872) (xy 423.67581 -109.339126)
			(xy 423.675299 -109.367865) (xy 423.666673 -109.424693) (xy 423.64962 -109.479584) (xy 423.624526 -109.531295)
			(xy 423.591958 -109.578657) (xy 423.572686 -109.599984) (xy 423.566082 -109.606842) (xy 423.55897 -109.624876)
			(xy 423.55897 -109.713776) (xy 423.566082 -109.73181) (xy 423.572686 -109.738668) (xy 423.591982 -109.759973)
			(xy 423.624546 -109.807339) (xy 423.649635 -109.859055) (xy 423.666683 -109.913949) (xy 423.675303 -109.970779)
			(xy 423.6753 -110.028259) (xy 423.666674 -110.085088) (xy 423.649621 -110.139981) (xy 423.624527 -110.191694)
			(xy 423.591958 -110.239057) (xy 423.572686 -110.260384) (xy 423.566082 -110.267242) (xy 423.55897 -110.285276)
			(xy 423.55897 -110.374176) (xy 423.566082 -110.39221) (xy 423.572686 -110.399068) (xy 423.591982 -110.420373)
			(xy 423.624546 -110.467739) (xy 423.649635 -110.519455) (xy 423.666683 -110.574349) (xy 423.675303 -110.631179)
			(xy 423.6753 -110.688659) (xy 423.666674 -110.745488) (xy 423.649621 -110.800381) (xy 423.624527 -110.852094)
			(xy 423.591958 -110.899457) (xy 423.572686 -110.920784) (xy 423.566082 -110.927642) (xy 423.55897 -110.945676)
			(xy 423.55897 -111.034576) (xy 423.566082 -111.05261) (xy 423.572686 -111.059468) (xy 423.591982 -111.080773)
			(xy 423.624546 -111.128139) (xy 423.649635 -111.179855) (xy 423.666683 -111.234749) (xy 423.675303 -111.291579)
			(xy 423.6753 -111.349059) (xy 423.666674 -111.405888) (xy 423.649621 -111.460781) (xy 423.624527 -111.512494)
			(xy 423.591958 -111.559857) (xy 423.572686 -111.581184) (xy 423.566082 -111.588042) (xy 423.55897 -111.606076)
			(xy 423.55897 -111.694976) (xy 423.566082 -111.71301) (xy 423.572686 -111.719868) (xy 423.591973 -111.741181)
			(xy 423.624536 -111.788547) (xy 423.649625 -111.840262) (xy 423.666672 -111.895156) (xy 423.675291 -111.951986)
			(xy 423.67581 -111.980726) (xy 423.675346 -112.007978) (xy 423.667586 -112.061926) (xy 423.652228 -112.114221)
			(xy 423.629584 -112.163798) (xy 423.600115 -112.209649) (xy 423.564421 -112.250838) (xy 423.523229 -112.28653)
			(xy 423.477377 -112.315996) (xy 423.427799 -112.338636) (xy 423.375503 -112.353991) (xy 423.321554 -112.361748)
			(xy 423.294302 -112.362234) (xy 423.267989 -112.361754) (xy 423.215861 -112.35452) (xy 423.165219 -112.340203)
			(xy 423.11702 -112.319073) (xy 423.072176 -112.291529) (xy 423.031536 -112.258094) (xy 423.013378 -112.239044)
			(xy 423.005861 -112.231637) (xy 422.986578 -112.223114) (xy 422.97604 -112.222534) (xy 422.901364 -112.222534)
			(xy 422.890815 -112.223074) (xy 422.871519 -112.2316) (xy 422.864026 -112.239044) (xy 422.845859 -112.258088)
			(xy 422.805231 -112.291545) (xy 422.760393 -112.319104) (xy 422.712194 -112.340244) (xy 422.661549 -112.354564)
			(xy 422.609417 -112.361793) (xy 422.583102 -112.362234) (xy 422.555852 -112.36172) (xy 422.501907 -112.353965)
			(xy 422.449614 -112.338611) (xy 422.400038 -112.315972) (xy 422.354189 -112.286509) (xy 422.313 -112.25082)
			(xy 422.277308 -112.209633) (xy 422.247841 -112.163786) (xy 422.225198 -112.114212) (xy 422.209841 -112.061921)
			(xy 422.202082 -112.007976) (xy 422.201594 -111.980726) (xy 419.415236 -111.980726) (xy 419.403217 -112.020675)
			(xy 419.379545 -112.071172) (xy 419.348772 -112.117685) (xy 419.311555 -112.159222) (xy 419.268687 -112.194897)
			(xy 419.221081 -112.223951) (xy 419.169752 -112.245763) (xy 419.115795 -112.259869) (xy 419.060358 -112.265969)
			(xy 419.004624 -112.263932) (xy 418.949781 -112.253802) (xy 418.896997 -112.235795) (xy 418.847397 -112.210294)
			(xy 418.802039 -112.177843) (xy 418.76189 -112.139134) (xy 418.727804 -112.094991) (xy 418.700508 -112.046356)
			(xy 418.680585 -111.994265) (xy 418.668459 -111.939828) (xy 418.664388 -111.884206) (xy 403.118066 -111.884206)
			(xy 403.118066 -115.801394) (xy 404.147272 -115.801394) (xy 404.151343 -115.745772) (xy 404.163469 -115.691335)
			(xy 404.183392 -115.639244) (xy 404.210688 -115.590609) (xy 404.244774 -115.546466) (xy 404.284923 -115.507757)
			(xy 404.330281 -115.475306) (xy 404.379881 -115.449805) (xy 404.432665 -115.431798) (xy 404.487508 -115.421668)
			(xy 404.543242 -115.419631) (xy 404.598679 -115.425731) (xy 404.652636 -115.439837) (xy 404.703965 -115.461649)
			(xy 404.751571 -115.490703) (xy 404.794439 -115.526378) (xy 404.831656 -115.567915) (xy 404.862429 -115.614428)
			(xy 404.886101 -115.664925) (xy 404.902169 -115.718332) (xy 404.910289 -115.773508) (xy 404.910798 -115.801394)
			(xy 404.910289 -115.82928) (xy 404.902169 -115.884456) (xy 404.886101 -115.937863) (xy 404.862429 -115.98836)
			(xy 404.831656 -116.034873) (xy 404.794439 -116.07641) (xy 404.751571 -116.112085) (xy 404.703965 -116.141139)
			(xy 404.652636 -116.162951) (xy 404.598679 -116.177057) (xy 404.543242 -116.183157) (xy 404.487508 -116.18112)
			(xy 404.432665 -116.17099) (xy 404.379881 -116.152983) (xy 404.330281 -116.127482) (xy 404.284923 -116.095031)
			(xy 404.244774 -116.056322) (xy 404.210688 -116.012179) (xy 404.183392 -115.963544) (xy 404.163469 -115.911453)
			(xy 404.151343 -115.857016) (xy 404.147272 -115.801394) (xy 403.118066 -115.801394) (xy 403.118066 -118.194328)
			(xy 403.844504 -118.194328) (xy 403.848575 -118.138706) (xy 403.860701 -118.084269) (xy 403.880624 -118.032178)
			(xy 403.90792 -117.983543) (xy 403.942006 -117.9394) (xy 403.982155 -117.900691) (xy 404.027513 -117.86824)
			(xy 404.077113 -117.842739) (xy 404.129897 -117.824732) (xy 404.18474 -117.814602) (xy 404.240474 -117.812565)
			(xy 404.295911 -117.818665) (xy 404.349868 -117.832771) (xy 404.401197 -117.854583) (xy 404.448803 -117.883637)
			(xy 404.491671 -117.919312) (xy 404.528888 -117.960849) (xy 404.559661 -118.007362) (xy 404.583333 -118.057859)
			(xy 404.599401 -118.111266) (xy 404.607521 -118.166442) (xy 404.60803 -118.194328) (xy 404.607521 -118.222214)
			(xy 404.599401 -118.27739) (xy 404.583333 -118.330797) (xy 404.559661 -118.381294) (xy 404.528888 -118.427807)
			(xy 404.491671 -118.469344) (xy 404.448803 -118.505019) (xy 404.401197 -118.534073) (xy 404.349868 -118.555885)
			(xy 404.295911 -118.569991) (xy 404.240474 -118.576091) (xy 404.18474 -118.574054) (xy 404.129897 -118.563924)
			(xy 404.077113 -118.545917) (xy 404.027513 -118.520416) (xy 403.982155 -118.487965) (xy 403.942006 -118.449256)
			(xy 403.90792 -118.405113) (xy 403.880624 -118.356478) (xy 403.860701 -118.304387) (xy 403.848575 -118.24995)
			(xy 403.844504 -118.194328) (xy 403.118066 -118.194328) (xy 403.118066 -118.313962) (xy 403.118636 -118.321456)
			(xy 403.12354 -118.335655) (xy 403.127718 -118.341902) (xy 403.138386 -118.354348) (xy 403.139402 -118.355618)
			(xy 403.140164 -118.35638) (xy 403.143466 -118.360444) (xy 403.148038 -118.367302) (xy 403.151594 -118.382288)
			(xy 403.15642 -118.393718) (xy 403.160364 -118.400037) (xy 403.1712 -118.410249) (xy 403.177756 -118.413784)
			(xy 403.183344 -118.416578) (xy 403.209329 -118.430785) (xy 403.25695 -118.465986) (xy 403.298567 -118.508117)
			(xy 403.33318 -118.556167) (xy 403.35996 -118.608985) (xy 403.378265 -118.665305) (xy 403.387656 -118.723775)
			(xy 403.388322 -118.753382) (xy 403.388068 -118.766336) (xy 403.386873 -118.792864) (xy 403.378043 -118.845227)
			(xy 403.362024 -118.895855) (xy 403.350984 -118.920006) (xy 403.34946 -118.927118) (xy 403.363638 -118.97493)
			(xy 403.383502 -119.072664) (xy 403.393521 -119.171892) (xy 403.394164 -119.221758) (xy 403.394164 -119.222774)
			(xy 403.393731 -119.265361) (xy 403.386493 -119.350226) (xy 403.372043 -119.434165) (xy 403.350486 -119.516566)
			(xy 403.321979 -119.596827) (xy 403.304756 -119.635778) (xy 403.301569 -119.644912) (xy 403.30156 -119.664241)
			(xy 403.304756 -119.67337) (xy 403.321966 -119.712326) (xy 403.350462 -119.79259) (xy 403.372016 -119.874989)
			(xy 403.38647 -119.958925) (xy 403.393721 -120.043788) (xy 403.394164 -120.086374) (xy 403.394164 -120.086882)
			(xy 403.393558 -120.136834) (xy 403.383569 -120.236237) (xy 403.363681 -120.334141) (xy 403.34946 -120.38203)
			(xy 403.349968 -120.384824) (xy 403.353524 -120.394222) (xy 403.354286 -120.396508) (xy 403.354794 -120.39727)
			(xy 403.355048 -120.397778) (xy 403.36559 -120.422538) (xy 403.380382 -120.474279) (xy 403.387739 -120.527587)
			(xy 403.388068 -120.554496) (xy 403.387589 -120.582389) (xy 403.379529 -120.637588) (xy 403.363521 -120.691027)
			(xy 403.339905 -120.741567) (xy 403.309186 -120.788131) (xy 403.272017 -120.829729) (xy 403.22919 -120.865475)
			(xy 403.181617 -120.894607) (xy 403.156166 -120.906032) (xy 403.149562 -120.908826) (xy 403.136608 -120.919494)
			(xy 403.128295 -120.92707) (xy 403.118695 -120.947377) (xy 403.118066 -120.95861) (xy 403.118066 -121.913904)
			(xy 403.118642 -121.921396) (xy 403.123555 -121.935588) (xy 403.127718 -121.941844) (xy 403.138386 -121.95429)
			(xy 403.139402 -121.95556) (xy 403.140164 -121.956322) (xy 403.143466 -121.960386) (xy 403.148038 -121.967244)
			(xy 403.151086 -121.97969) (xy 403.15388 -121.991628) (xy 403.160484 -122.00001) (xy 403.163946 -122.004119)
			(xy 403.172269 -122.010913) (xy 403.176994 -122.013472) (xy 403.177756 -122.01398) (xy 403.179534 -122.014742)
			(xy 403.179788 -122.014996) (xy 403.18309 -122.01652) (xy 403.205926 -122.028953) (xy 403.24831 -122.059071)
			(xy 403.286215 -122.094663) (xy 403.31894 -122.135069) (xy 403.345878 -122.179541) (xy 403.366533 -122.227258)
			(xy 403.380521 -122.277337) (xy 403.387583 -122.32885) (xy 403.388068 -122.354848) (xy 403.388068 -122.35561)
			(xy 403.387573 -122.383936) (xy 403.379239 -122.439972) (xy 403.362712 -122.494159) (xy 403.350984 -122.519948)
			(xy 403.34946 -122.52706) (xy 403.363636 -122.574872) (xy 403.383496 -122.672607) (xy 403.39351 -122.771835)
			(xy 403.394164 -122.8217) (xy 403.394164 -122.822716) (xy 403.393729 -122.865303) (xy 403.386488 -122.950167)
			(xy 403.372035 -123.034104) (xy 403.350474 -123.116503) (xy 403.321964 -123.196763) (xy 403.304756 -123.23572)
			(xy 403.301577 -123.244853) (xy 403.301582 -123.264176) (xy 403.304756 -123.273312) (xy 403.321964 -123.312269)
			(xy 403.350457 -123.392532) (xy 403.372007 -123.474932) (xy 403.386458 -123.558868) (xy 403.393705 -123.64373)
			(xy 403.394164 -123.686316) (xy 403.394164 -123.686824) (xy 403.393555 -123.736776) (xy 403.383563 -123.836178)
			(xy 403.363671 -123.934081) (xy 403.34946 -123.981972) (xy 403.349968 -123.984766) (xy 403.353524 -123.994164)
			(xy 403.354286 -123.99645) (xy 403.354794 -123.997212) (xy 403.355048 -123.99772) (xy 403.365587 -124.022481)
			(xy 403.380374 -124.074222) (xy 403.387725 -124.12753) (xy 403.388068 -124.154438) (xy 403.387593 -124.182333)
			(xy 403.37954 -124.237538) (xy 403.363537 -124.290983) (xy 403.339926 -124.341529) (xy 403.30921 -124.388101)
			(xy 403.272042 -124.429706) (xy 403.229214 -124.465458) (xy 403.181639 -124.494596) (xy 403.156166 -124.505974)
			(xy 403.149562 -124.508768) (xy 403.136608 -124.519436) (xy 403.128285 -124.527009) (xy 403.118662 -124.547315)
			(xy 403.118066 -124.558552) (xy 403.118066 -129.523998) (xy 403.118641 -129.53149) (xy 403.123553 -129.545683)
			(xy 403.127718 -129.551938) (xy 403.138386 -129.564384) (xy 403.139402 -129.565654) (xy 403.140164 -129.566416)
			(xy 403.143466 -129.57048) (xy 403.148038 -129.577338) (xy 403.151086 -129.589784) (xy 403.15388 -129.601722)
			(xy 403.160484 -129.610104) (xy 403.163946 -129.614214) (xy 403.172269 -129.621008) (xy 403.176994 -129.623566)
			(xy 403.177756 -129.624074) (xy 403.179534 -129.624836) (xy 403.179788 -129.62509) (xy 403.18309 -129.626614)
			(xy 403.205926 -129.639047) (xy 403.248311 -129.669165) (xy 403.286216 -129.704756) (xy 403.318941 -129.745162)
			(xy 403.345881 -129.789635) (xy 403.366536 -129.837352) (xy 403.380525 -129.887431) (xy 403.387588 -129.938944)
			(xy 403.388068 -129.964942) (xy 403.388068 -129.965704) (xy 403.387574 -129.99403) (xy 403.379241 -130.050066)
			(xy 403.362714 -130.104254) (xy 403.350984 -130.130042) (xy 403.34946 -130.137154) (xy 403.363637 -130.184966)
			(xy 403.383497 -130.282701) (xy 403.393512 -130.381928) (xy 403.394164 -130.431794) (xy 403.394164 -130.43281)
			(xy 403.393729 -130.475397) (xy 403.386489 -130.560261) (xy 403.372036 -130.644199) (xy 403.350476 -130.726598)
			(xy 403.321967 -130.806857) (xy 403.304756 -130.845814) (xy 403.301576 -130.854947) (xy 403.301579 -130.874271)
			(xy 403.304756 -130.883406) (xy 403.321964 -130.922362) (xy 403.350457 -131.002626) (xy 403.372008 -131.085026)
			(xy 403.38646 -131.168962) (xy 403.393708 -131.253824) (xy 403.394164 -131.29641) (xy 403.394164 -131.296918)
			(xy 403.393556 -131.34687) (xy 403.383564 -131.446272) (xy 403.363672 -131.544175) (xy 403.34946 -131.592066)
			(xy 403.349968 -131.59486) (xy 403.353524 -131.604258) (xy 403.354286 -131.606544) (xy 403.354794 -131.607306)
			(xy 403.355048 -131.607814) (xy 403.365588 -131.632575) (xy 403.380375 -131.684316) (xy 403.387727 -131.737624)
			(xy 403.388068 -131.764532) (xy 403.387594 -131.792427) (xy 403.379541 -131.847633) (xy 403.363539 -131.901078)
			(xy 403.339929 -131.951625) (xy 403.309212 -131.998198) (xy 403.272044 -132.039804) (xy 403.229217 -132.075556)
			(xy 403.181641 -132.104695) (xy 403.156166 -132.116068) (xy 403.149562 -132.118862) (xy 403.136608 -132.12953)
			(xy 403.128284 -132.137102) (xy 403.118659 -132.157409) (xy 403.118066 -132.168646) (xy 403.118066 -133.12394)
			(xy 403.118633 -133.131435) (xy 403.123532 -133.145638) (xy 403.127718 -133.15188) (xy 403.138386 -133.164326)
			(xy 403.139402 -133.165596) (xy 403.140164 -133.166358) (xy 403.143466 -133.170422) (xy 403.148038 -133.17728)
			(xy 403.151594 -133.192266) (xy 403.15642 -133.203696) (xy 403.16037 -133.210009) (xy 403.171213 -133.220207)
			(xy 403.177756 -133.223762) (xy 403.183344 -133.226556) (xy 403.20933 -133.240763) (xy 403.256954 -133.275963)
			(xy 403.298573 -133.318093) (xy 403.333189 -133.366143) (xy 403.359972 -133.418961) (xy 403.37828 -133.475281)
			(xy 403.387673 -133.533752) (xy 403.388322 -133.56336) (xy 403.388068 -133.576314) (xy 403.386875 -133.602842)
			(xy 403.378047 -133.655206) (xy 403.362031 -133.705836) (xy 403.350984 -133.729984) (xy 403.34946 -133.737096)
			(xy 403.363639 -133.784908) (xy 403.383505 -133.882642) (xy 403.393526 -133.98187) (xy 403.394164 -134.031736)
			(xy 403.394164 -134.032752) (xy 403.393731 -134.075339) (xy 403.386496 -134.160205) (xy 403.372048 -134.244145)
			(xy 403.350492 -134.326546) (xy 403.321987 -134.406808) (xy 403.304756 -134.445756) (xy 403.301565 -134.45489)
			(xy 403.301548 -134.474222) (xy 403.304756 -134.483348) (xy 403.321967 -134.522304) (xy 403.350464 -134.602567)
			(xy 403.355025 -134.62) (xy 405.195022 -134.62) (xy 405.199093 -134.564378) (xy 405.211219 -134.509941)
			(xy 405.231142 -134.45785) (xy 405.258438 -134.409215) (xy 405.292524 -134.365072) (xy 405.332673 -134.326363)
			(xy 405.378031 -134.293912) (xy 405.427631 -134.268411) (xy 405.480415 -134.250404) (xy 405.535258 -134.240274)
			(xy 405.590992 -134.238237) (xy 405.646429 -134.244337) (xy 405.700386 -134.258443) (xy 405.751715 -134.280255)
			(xy 405.799321 -134.309309) (xy 405.842189 -134.344984) (xy 405.879406 -134.386521) (xy 405.910179 -134.433034)
			(xy 405.933851 -134.483531) (xy 405.949919 -134.536938) (xy 405.958039 -134.592114) (xy 405.958548 -134.62)
			(xy 405.958039 -134.647886) (xy 405.949919 -134.703062) (xy 405.933851 -134.756469) (xy 405.910179 -134.806966)
			(xy 405.879406 -134.853479) (xy 405.842189 -134.895016) (xy 405.799321 -134.930691) (xy 405.751715 -134.959745)
			(xy 405.700386 -134.981557) (xy 405.646429 -134.995663) (xy 405.590992 -135.001763) (xy 405.535258 -134.999726)
			(xy 405.480415 -134.989596) (xy 405.427631 -134.971589) (xy 405.378031 -134.946088) (xy 405.332673 -134.913637)
			(xy 405.292524 -134.874928) (xy 405.258438 -134.830785) (xy 405.231142 -134.78215) (xy 405.211219 -134.730059)
			(xy 405.199093 -134.675622) (xy 405.195022 -134.62) (xy 403.355025 -134.62) (xy 403.37202 -134.684967)
			(xy 403.386477 -134.768903) (xy 403.393729 -134.853766) (xy 403.394164 -134.896352) (xy 403.394164 -134.89686)
			(xy 403.393554 -134.946811) (xy 403.383558 -135.046213) (xy 403.363662 -135.144114) (xy 403.34946 -135.192008)
			(xy 403.349968 -135.194802) (xy 403.353524 -135.2042) (xy 403.354286 -135.206486) (xy 403.354794 -135.207248)
			(xy 403.355048 -135.207756) (xy 403.365585 -135.232517) (xy 403.380367 -135.284259) (xy 403.387713 -135.337566)
			(xy 403.388068 -135.364474) (xy 403.387591 -135.392368) (xy 403.379533 -135.447569) (xy 403.363527 -135.50101)
			(xy 403.339913 -135.551552) (xy 403.309195 -135.59812) (xy 403.272027 -135.639721) (xy 403.229199 -135.675469)
			(xy 403.181625 -135.704603) (xy 403.156166 -135.71601) (xy 403.149562 -135.718804) (xy 403.136608 -135.729472)
			(xy 403.128292 -135.737047) (xy 403.118682 -135.757354) (xy 403.118066 -135.768588) (xy 403.118066 -137.287)
			(xy 405.068022 -137.287) (xy 405.072093 -137.231378) (xy 405.084219 -137.176941) (xy 405.104142 -137.12485)
			(xy 405.131438 -137.076215) (xy 405.165524 -137.032072) (xy 405.205673 -136.993363) (xy 405.251031 -136.960912)
			(xy 405.300631 -136.935411) (xy 405.353415 -136.917404) (xy 405.408258 -136.907274) (xy 405.463992 -136.905237)
			(xy 405.519429 -136.911337) (xy 405.573386 -136.925443) (xy 405.624715 -136.947255) (xy 405.672321 -136.976309)
			(xy 405.715189 -137.011984) (xy 405.752406 -137.053521) (xy 405.783179 -137.100034) (xy 405.806851 -137.150531)
			(xy 405.822919 -137.203938) (xy 405.831039 -137.259114) (xy 405.831548 -137.287) (xy 405.831039 -137.314886)
			(xy 405.822919 -137.370062) (xy 405.806851 -137.423469) (xy 405.783179 -137.473966) (xy 405.752406 -137.520479)
			(xy 405.715189 -137.562016) (xy 405.672321 -137.597691) (xy 405.624715 -137.626745) (xy 405.573386 -137.648557)
			(xy 405.519429 -137.662663) (xy 405.463992 -137.668763) (xy 405.408258 -137.666726) (xy 405.353415 -137.656596)
			(xy 405.300631 -137.638589) (xy 405.251031 -137.613088) (xy 405.205673 -137.580637) (xy 405.165524 -137.541928)
			(xy 405.131438 -137.497785) (xy 405.104142 -137.44915) (xy 405.084219 -137.397059) (xy 405.072093 -137.342622)
			(xy 405.068022 -137.287) (xy 403.118066 -137.287) (xy 403.118066 -138.95705) (xy 404.814532 -138.95705)
			(xy 404.815018 -138.929799) (xy 404.822774 -138.875851) (xy 404.838129 -138.823556) (xy 404.860771 -138.773979)
			(xy 404.890237 -138.728129) (xy 404.925928 -138.686938) (xy 404.967119 -138.651247) (xy 405.012969 -138.621781)
			(xy 405.062546 -138.599139) (xy 405.114841 -138.583784) (xy 405.168789 -138.576028) (xy 405.223291 -138.576028)
			(xy 405.277239 -138.583784) (xy 405.329534 -138.599139) (xy 405.379111 -138.621781) (xy 405.424961 -138.651247)
			(xy 405.466152 -138.686938) (xy 405.501843 -138.728129) (xy 405.531309 -138.773979) (xy 405.553951 -138.823556)
			(xy 405.569306 -138.875851) (xy 405.577062 -138.929799) (xy 405.577548 -138.95705) (xy 405.577051 -138.98483)
			(xy 405.568978 -139.039801) (xy 405.553008 -139.093017) (xy 405.529482 -139.143351) (xy 405.498897 -139.189735)
			(xy 405.480774 -139.210796) (xy 405.48052 -139.21105) (xy 405.474217 -139.218931) (xy 405.467799 -139.238047)
			(xy 405.468074 -139.248134) (xy 405.473408 -139.321286) (xy 405.474577 -139.331363) (xy 405.48375 -139.349439)
			(xy 405.491188 -139.356338) (xy 405.491442 -139.356592) (xy 405.512467 -139.374801) (xy 405.549506 -139.416293)
			(xy 405.580134 -139.462721) (xy 405.603702 -139.5131) (xy 405.619711 -139.566366) (xy 405.627824 -139.621391)
			(xy 405.628348 -139.6492) (xy 405.627862 -139.676451) (xy 405.620106 -139.730399) (xy 405.604751 -139.782694)
			(xy 405.582109 -139.832271) (xy 405.552643 -139.878121) (xy 405.516952 -139.919312) (xy 405.475761 -139.955003)
			(xy 405.429911 -139.984469) (xy 405.380334 -140.007111) (xy 405.328039 -140.022466) (xy 405.274091 -140.030222)
			(xy 405.219589 -140.030222) (xy 405.165641 -140.022466) (xy 405.113346 -140.007111) (xy 405.063769 -139.984469)
			(xy 405.017919 -139.955003) (xy 404.976728 -139.919312) (xy 404.941037 -139.878121) (xy 404.911571 -139.832271)
			(xy 404.888929 -139.782694) (xy 404.873574 -139.730399) (xy 404.865818 -139.676451) (xy 404.865332 -139.6492)
			(xy 404.865864 -139.621421) (xy 404.87393 -139.566452) (xy 404.889891 -139.513237) (xy 404.91341 -139.462903)
			(xy 404.943987 -139.416516) (xy 404.962106 -139.395454) (xy 404.96236 -139.3952) (xy 404.968685 -139.387334)
			(xy 404.97509 -139.368207) (xy 404.974806 -139.358116) (xy 404.969472 -139.284964) (xy 404.968333 -139.274881)
			(xy 404.95914 -139.256806) (xy 404.951692 -139.249912) (xy 404.951438 -139.249658) (xy 404.930433 -139.231427)
			(xy 404.893393 -139.189939) (xy 404.862764 -139.143516) (xy 404.839192 -139.093141) (xy 404.823178 -139.039879)
			(xy 404.81506 -138.984858) (xy 404.814532 -138.95705) (xy 403.118066 -138.95705) (xy 403.118066 -140.353542)
			(xy 403.117635 -140.363608) (xy 403.109906 -140.382198) (xy 403.10308 -140.38961) (xy 402.8313 -140.66139)
			(xy 408.872944 -140.66139) (xy 408.872944 -114.864642) (xy 408.873491 -114.831357) (xy 408.882233 -114.765361)
			(xy 408.899508 -114.70107) (xy 408.925021 -114.639581) (xy 408.958335 -114.581945) (xy 408.998882 -114.529146)
			(xy 409.022042 -114.505232) (xy 410.634942 -112.892332) (xy 410.658872 -112.869201) (xy 410.711677 -112.828692)
			(xy 410.769317 -112.795419) (xy 410.830805 -112.769951) (xy 410.895091 -112.752725) (xy 410.961075 -112.744035)
			(xy 410.994352 -112.743488) (xy 412.019496 -112.743488) (xy 412.031309 -112.742905) (xy 412.052492 -112.732448)
			(xy 412.060136 -112.723422) (xy 412.108904 -112.658652) (xy 412.115492 -112.648864) (xy 412.119876 -112.625711)
			(xy 412.117286 -112.614202) (xy 412.110616 -112.588946) (xy 412.103486 -112.537197) (xy 412.103062 -112.511078)
			(xy 412.103062 -112.510824) (xy 412.103548 -112.483573) (xy 412.111304 -112.429625) (xy 412.126659 -112.37733)
			(xy 412.149301 -112.327753) (xy 412.178767 -112.281903) (xy 412.214458 -112.240712) (xy 412.255649 -112.205021)
			(xy 412.301499 -112.175555) (xy 412.351076 -112.152913) (xy 412.403371 -112.137558) (xy 412.457319 -112.129802)
			(xy 412.511821 -112.129802) (xy 412.565769 -112.137558) (xy 412.618064 -112.152913) (xy 412.667641 -112.175555)
			(xy 412.713491 -112.205021) (xy 412.754682 -112.240712) (xy 412.790373 -112.281903) (xy 412.819839 -112.327753)
			(xy 412.842481 -112.37733) (xy 412.857836 -112.429625) (xy 412.865592 -112.483573) (xy 412.865625 -112.485424)
			(xy 414.951162 -112.485424) (xy 414.955233 -112.429802) (xy 414.967359 -112.375365) (xy 414.987282 -112.323274)
			(xy 415.014578 -112.274639) (xy 415.048664 -112.230496) (xy 415.088813 -112.191787) (xy 415.134171 -112.159336)
			(xy 415.183771 -112.133835) (xy 415.236555 -112.115828) (xy 415.291398 -112.105698) (xy 415.347132 -112.103661)
			(xy 415.402569 -112.109761) (xy 415.456526 -112.123867) (xy 415.507855 -112.145679) (xy 415.555461 -112.174733)
			(xy 415.598329 -112.210408) (xy 415.635546 -112.251945) (xy 415.666319 -112.298458) (xy 415.689991 -112.348955)
			(xy 415.706059 -112.402362) (xy 415.708938 -112.421924) (xy 417.755068 -112.421924) (xy 417.759139 -112.366302)
			(xy 417.771265 -112.311865) (xy 417.791188 -112.259774) (xy 417.818484 -112.211139) (xy 417.85257 -112.166996)
			(xy 417.892719 -112.128287) (xy 417.938077 -112.095836) (xy 417.987677 -112.070335) (xy 418.040461 -112.052328)
			(xy 418.095304 -112.042198) (xy 418.151038 -112.040161) (xy 418.206475 -112.046261) (xy 418.260432 -112.060367)
			(xy 418.311761 -112.082179) (xy 418.359367 -112.111233) (xy 418.402235 -112.146908) (xy 418.439452 -112.188445)
			(xy 418.470225 -112.234958) (xy 418.493897 -112.285455) (xy 418.509965 -112.338862) (xy 418.518085 -112.394038)
			(xy 418.518594 -112.421924) (xy 418.518085 -112.44981) (xy 418.509965 -112.504986) (xy 418.493897 -112.558393)
			(xy 418.470225 -112.60889) (xy 418.439452 -112.655403) (xy 418.402235 -112.69694) (xy 418.359367 -112.732615)
			(xy 418.311761 -112.761669) (xy 418.260432 -112.783481) (xy 418.206475 -112.797587) (xy 418.151038 -112.803687)
			(xy 418.095304 -112.80165) (xy 418.040461 -112.79152) (xy 417.987677 -112.773513) (xy 417.938077 -112.748012)
			(xy 417.892719 -112.715561) (xy 417.85257 -112.676852) (xy 417.818484 -112.632709) (xy 417.791188 -112.584074)
			(xy 417.771265 -112.531983) (xy 417.759139 -112.477546) (xy 417.755068 -112.421924) (xy 415.708938 -112.421924)
			(xy 415.714179 -112.457538) (xy 415.714688 -112.485424) (xy 415.714179 -112.51331) (xy 415.706059 -112.568486)
			(xy 415.689991 -112.621893) (xy 415.666319 -112.67239) (xy 415.635546 -112.718903) (xy 415.598329 -112.76044)
			(xy 415.555461 -112.796115) (xy 415.507855 -112.825169) (xy 415.456526 -112.846981) (xy 415.402569 -112.861087)
			(xy 415.347132 -112.867187) (xy 415.291398 -112.86515) (xy 415.236555 -112.85502) (xy 415.183771 -112.837013)
			(xy 415.134171 -112.811512) (xy 415.088813 -112.779061) (xy 415.048664 -112.740352) (xy 415.014578 -112.696209)
			(xy 414.987282 -112.647574) (xy 414.967359 -112.595483) (xy 414.955233 -112.541046) (xy 414.951162 -112.485424)
			(xy 412.865625 -112.485424) (xy 412.866078 -112.510824) (xy 412.866078 -112.511078) (xy 412.865625 -112.537194)
			(xy 412.858483 -112.588937) (xy 412.851854 -112.614202) (xy 412.849199 -112.625713) (xy 412.853571 -112.648898)
			(xy 412.860236 -112.658652) (xy 412.909004 -112.723422) (xy 412.916608 -112.732494) (xy 412.937817 -112.742946)
			(xy 412.949644 -112.743488) (xy 412.988252 -112.743488) (xy 413.020203 -112.743882) (xy 413.083602 -112.751886)
			(xy 413.145497 -112.767772) (xy 413.204913 -112.791292) (xy 413.260913 -112.822073) (xy 413.312613 -112.859631)
			(xy 413.359197 -112.903373) (xy 413.399932 -112.952608) (xy 413.423418 -112.989614) (xy 418.74008 -112.989614)
			(xy 418.744151 -112.933992) (xy 418.756277 -112.879555) (xy 418.7762 -112.827464) (xy 418.803496 -112.778829)
			(xy 418.837582 -112.734686) (xy 418.877731 -112.695977) (xy 418.923089 -112.663526) (xy 418.972689 -112.638025)
			(xy 419.025473 -112.620018) (xy 419.080316 -112.609888) (xy 419.13605 -112.607851) (xy 419.191487 -112.613951)
			(xy 419.245444 -112.628057) (xy 419.296773 -112.649869) (xy 419.344379 -112.678923) (xy 419.387247 -112.714598)
			(xy 419.424464 -112.756135) (xy 419.455237 -112.802648) (xy 419.478909 -112.853145) (xy 419.494977 -112.906552)
			(xy 419.503097 -112.961728) (xy 419.503606 -112.989614) (xy 419.503097 -113.0175) (xy 419.494977 -113.072676)
			(xy 419.478909 -113.126083) (xy 419.455237 -113.17658) (xy 419.424464 -113.223093) (xy 419.387247 -113.26463)
			(xy 419.344379 -113.300305) (xy 419.296773 -113.329359) (xy 419.245444 -113.351171) (xy 419.191487 -113.365277)
			(xy 419.13605 -113.371377) (xy 419.080316 -113.36934) (xy 419.025473 -113.35921) (xy 418.972689 -113.341203)
			(xy 418.923089 -113.315702) (xy 418.877731 -113.283251) (xy 418.837582 -113.244542) (xy 418.803496 -113.200399)
			(xy 418.7762 -113.151764) (xy 418.756277 -113.099673) (xy 418.744151 -113.045236) (xy 418.74008 -112.989614)
			(xy 413.423418 -112.989614) (xy 413.434174 -113.006561) (xy 413.461384 -113.064381) (xy 413.481132 -113.125154)
			(xy 413.493106 -113.187924) (xy 413.497119 -113.2517) (xy 413.493106 -113.315476) (xy 413.481132 -113.378246)
			(xy 413.462648 -113.43513) (xy 414.954972 -113.43513) (xy 414.959043 -113.379508) (xy 414.971169 -113.325071)
			(xy 414.991092 -113.27298) (xy 415.018388 -113.224345) (xy 415.052474 -113.180202) (xy 415.092623 -113.141493)
			(xy 415.137981 -113.109042) (xy 415.187581 -113.083541) (xy 415.240365 -113.065534) (xy 415.295208 -113.055404)
			(xy 415.350942 -113.053367) (xy 415.406379 -113.059467) (xy 415.460336 -113.073573) (xy 415.511665 -113.095385)
			(xy 415.559271 -113.124439) (xy 415.602139 -113.160114) (xy 415.639356 -113.201651) (xy 415.670129 -113.248164)
			(xy 415.693801 -113.298661) (xy 415.709869 -113.352068) (xy 415.717989 -113.407244) (xy 415.718498 -113.43513)
			(xy 415.718447 -113.437924) (xy 417.657786 -113.437924) (xy 417.661857 -113.382302) (xy 417.673983 -113.327865)
			(xy 417.693906 -113.275774) (xy 417.721202 -113.227139) (xy 417.755288 -113.182996) (xy 417.795437 -113.144287)
			(xy 417.840795 -113.111836) (xy 417.890395 -113.086335) (xy 417.943179 -113.068328) (xy 417.998022 -113.058198)
			(xy 418.053756 -113.056161) (xy 418.109193 -113.062261) (xy 418.16315 -113.076367) (xy 418.214479 -113.098179)
			(xy 418.262085 -113.127233) (xy 418.304953 -113.162908) (xy 418.34217 -113.204445) (xy 418.372943 -113.250958)
			(xy 418.396615 -113.301455) (xy 418.412683 -113.354862) (xy 418.420803 -113.410038) (xy 418.421312 -113.437924)
			(xy 418.420803 -113.46581) (xy 418.412683 -113.520986) (xy 418.396615 -113.574393) (xy 418.372943 -113.62489)
			(xy 418.34217 -113.671403) (xy 418.304953 -113.71294) (xy 418.262085 -113.748615) (xy 418.214479 -113.777669)
			(xy 418.16315 -113.799481) (xy 418.109193 -113.813587) (xy 418.053756 -113.819687) (xy 417.998022 -113.81765)
			(xy 417.943179 -113.80752) (xy 417.890395 -113.789513) (xy 417.840795 -113.764012) (xy 417.795437 -113.731561)
			(xy 417.755288 -113.692852) (xy 417.721202 -113.648709) (xy 417.693906 -113.600074) (xy 417.673983 -113.547983)
			(xy 417.661857 -113.493546) (xy 417.657786 -113.437924) (xy 415.718447 -113.437924) (xy 415.717989 -113.463016)
			(xy 415.709869 -113.518192) (xy 415.693801 -113.571599) (xy 415.670129 -113.622096) (xy 415.639356 -113.668609)
			(xy 415.602139 -113.710146) (xy 415.559271 -113.745821) (xy 415.511665 -113.774875) (xy 415.460336 -113.796687)
			(xy 415.406379 -113.810793) (xy 415.350942 -113.816893) (xy 415.295208 -113.814856) (xy 415.240365 -113.804726)
			(xy 415.187581 -113.786719) (xy 415.137981 -113.761218) (xy 415.092623 -113.728767) (xy 415.052474 -113.690058)
			(xy 415.018388 -113.645915) (xy 414.991092 -113.59728) (xy 414.971169 -113.545189) (xy 414.959043 -113.490752)
			(xy 414.954972 -113.43513) (xy 413.462648 -113.43513) (xy 413.461384 -113.439019) (xy 413.434174 -113.496839)
			(xy 413.399932 -113.550792) (xy 413.359197 -113.600027) (xy 413.312613 -113.643769) (xy 413.260913 -113.681327)
			(xy 413.204913 -113.712108) (xy 413.145497 -113.735628) (xy 413.083602 -113.751514) (xy 413.020203 -113.759518)
			(xy 412.988252 -113.759996) (xy 411.226 -113.759996) (xy 411.215927 -113.760396) (xy 411.197328 -113.768132)
			(xy 411.189932 -113.774982) (xy 410.674922 -114.290094) (xy 418.660324 -114.290094) (xy 418.664395 -114.234472)
			(xy 418.676521 -114.180035) (xy 418.696444 -114.127944) (xy 418.72374 -114.079309) (xy 418.757826 -114.035166)
			(xy 418.797975 -113.996457) (xy 418.843333 -113.964006) (xy 418.892933 -113.938505) (xy 418.945717 -113.920498)
			(xy 419.00056 -113.910368) (xy 419.056294 -113.908331) (xy 419.111731 -113.914431) (xy 419.165688 -113.928537)
			(xy 419.217017 -113.950349) (xy 419.264623 -113.979403) (xy 419.307491 -114.015078) (xy 419.344708 -114.056615)
			(xy 419.375481 -114.103128) (xy 419.399153 -114.153625) (xy 419.415221 -114.207032) (xy 419.423341 -114.262208)
			(xy 419.42385 -114.290094) (xy 419.423341 -114.31798) (xy 419.415221 -114.373156) (xy 419.399153 -114.426563)
			(xy 419.375481 -114.47706) (xy 419.344708 -114.523573) (xy 419.307491 -114.56511) (xy 419.264623 -114.600785)
			(xy 419.217017 -114.629839) (xy 419.165688 -114.651651) (xy 419.111731 -114.665757) (xy 419.056294 -114.671857)
			(xy 419.00056 -114.66982) (xy 418.945717 -114.65969) (xy 418.892933 -114.641683) (xy 418.843333 -114.616182)
			(xy 418.797975 -114.583731) (xy 418.757826 -114.545022) (xy 418.72374 -114.500879) (xy 418.696444 -114.452244)
			(xy 418.676521 -114.400153) (xy 418.664395 -114.345716) (xy 418.660324 -114.290094) (xy 410.674922 -114.290094)
			(xy 410.089821 -114.87531) (xy 414.257488 -114.87531) (xy 414.261559 -114.819688) (xy 414.273685 -114.765251)
			(xy 414.293608 -114.71316) (xy 414.320904 -114.664525) (xy 414.35499 -114.620382) (xy 414.395139 -114.581673)
			(xy 414.440497 -114.549222) (xy 414.490097 -114.523721) (xy 414.542881 -114.505714) (xy 414.597724 -114.495584)
			(xy 414.653458 -114.493547) (xy 414.708895 -114.499647) (xy 414.762852 -114.513753) (xy 414.814181 -114.535565)
			(xy 414.861787 -114.564619) (xy 414.904655 -114.600294) (xy 414.941872 -114.641831) (xy 414.972645 -114.688344)
			(xy 414.996317 -114.738841) (xy 415.012385 -114.792248) (xy 415.020505 -114.847424) (xy 415.021014 -114.87531)
			(xy 415.020505 -114.903196) (xy 415.012385 -114.958372) (xy 414.996317 -115.011779) (xy 414.972645 -115.062276)
			(xy 414.941872 -115.108789) (xy 414.904655 -115.150326) (xy 414.861787 -115.186001) (xy 414.814181 -115.215055)
			(xy 414.762852 -115.236867) (xy 414.708895 -115.250973) (xy 414.653458 -115.257073) (xy 414.597724 -115.255036)
			(xy 414.542881 -115.244906) (xy 414.490097 -115.226899) (xy 414.440497 -115.201398) (xy 414.395139 -115.168947)
			(xy 414.35499 -115.130238) (xy 414.320904 -115.086095) (xy 414.293608 -115.03746) (xy 414.273685 -114.985369)
			(xy 414.261559 -114.930932) (xy 414.257488 -114.87531) (xy 410.089821 -114.87531) (xy 409.904946 -115.060222)
			(xy 409.89811 -115.067626) (xy 409.890387 -115.086222) (xy 409.88996 -115.09629) (xy 409.88996 -115.285774)
			(xy 415.230816 -115.285774) (xy 415.234887 -115.230152) (xy 415.247013 -115.175715) (xy 415.266936 -115.123624)
			(xy 415.294232 -115.074989) (xy 415.328318 -115.030846) (xy 415.368467 -114.992137) (xy 415.413825 -114.959686)
			(xy 415.463425 -114.934185) (xy 415.516209 -114.916178) (xy 415.571052 -114.906048) (xy 415.626786 -114.904011)
			(xy 415.682223 -114.910111) (xy 415.73618 -114.924217) (xy 415.787509 -114.946029) (xy 415.835115 -114.975083)
			(xy 415.877983 -115.010758) (xy 415.9152 -115.052295) (xy 415.945973 -115.098808) (xy 415.969645 -115.149305)
			(xy 415.985713 -115.202712) (xy 415.993833 -115.257888) (xy 415.994342 -115.285774) (xy 415.993833 -115.31366)
			(xy 415.986872 -115.360958) (xy 422.41851 -115.360958) (xy 422.419008 -115.333589) (xy 422.426817 -115.279411)
			(xy 422.442299 -115.226908) (xy 422.465134 -115.177161) (xy 422.494852 -115.131193) (xy 422.51249 -115.11026)
			(xy 422.512744 -115.110006) (xy 422.51834 -115.102926) (xy 422.52458 -115.086004) (xy 422.524936 -115.076986)
			(xy 422.524936 -115.00993) (xy 422.524557 -115.000916) (xy 422.518324 -114.983999) (xy 422.512744 -114.97691)
			(xy 422.51249 -114.97691) (xy 422.51249 -114.976656) (xy 422.494862 -114.955715) (xy 422.465149 -114.909744)
			(xy 422.442311 -114.859999) (xy 422.426817 -114.807501) (xy 422.418986 -114.753327) (xy 422.41851 -114.725958)
			(xy 422.418939 -114.698705) (xy 422.426701 -114.644754) (xy 422.442063 -114.592457) (xy 422.46471 -114.542879)
			(xy 422.494183 -114.497028) (xy 422.52988 -114.455837) (xy 422.571076 -114.420147) (xy 422.616931 -114.390681)
			(xy 422.666514 -114.368042) (xy 422.718813 -114.352689) (xy 422.772765 -114.344935) (xy 422.800018 -114.34445)
			(xy 422.827389 -114.344893) (xy 422.88157 -114.352715) (xy 422.934074 -114.368208) (xy 422.98382 -114.391056)
			(xy 423.029786 -114.420786) (xy 423.050716 -114.43843) (xy 423.05097 -114.438684) (xy 423.058062 -114.444262)
			(xy 423.074975 -114.450514) (xy 423.08399 -114.450876) (xy 423.151046 -114.450876) (xy 423.160061 -114.450498)
			(xy 423.176978 -114.444266) (xy 423.184066 -114.438684) (xy 423.184066 -114.43843) (xy 423.18432 -114.43843)
			(xy 423.205275 -114.42082) (xy 423.251241 -114.391102) (xy 423.300983 -114.36826) (xy 423.353478 -114.352763)
			(xy 423.40765 -114.344928) (xy 423.435018 -114.34445) (xy 423.462268 -114.344961) (xy 423.516212 -114.352719)
			(xy 423.568504 -114.368074) (xy 423.618079 -114.390714) (xy 423.663927 -114.420179) (xy 423.705116 -114.455867)
			(xy 423.740807 -114.497054) (xy 423.770274 -114.5429) (xy 423.792918 -114.592473) (xy 423.808276 -114.644764)
			(xy 423.816037 -114.698708) (xy 423.816526 -114.725958) (xy 423.816053 -114.753328) (xy 423.80824 -114.807508)
			(xy 423.792753 -114.860011) (xy 423.769913 -114.909759) (xy 423.740188 -114.955725) (xy 423.722546 -114.976656)
			(xy 423.722292 -114.97691) (xy 423.716694 -114.983989) (xy 423.710455 -115.000912) (xy 423.7101 -115.00993)
			(xy 423.7101 -115.076986) (xy 423.710464 -115.086002) (xy 423.716707 -115.102919) (xy 423.722292 -115.110006)
			(xy 423.722546 -115.110006) (xy 423.722546 -115.11026) (xy 423.740171 -115.131203) (xy 423.769887 -115.177172)
			(xy 423.792727 -115.226917) (xy 423.808221 -115.279415) (xy 423.816051 -115.333589) (xy 423.816526 -115.360958)
			(xy 423.816006 -115.388209) (xy 423.808255 -115.442157) (xy 423.792905 -115.494453) (xy 423.770269 -115.544031)
			(xy 423.740807 -115.589884) (xy 423.705119 -115.631077) (xy 423.663932 -115.666771) (xy 423.618084 -115.69624)
			(xy 423.568509 -115.718884) (xy 423.516216 -115.734242) (xy 423.462269 -115.742001) (xy 423.435018 -115.742466)
			(xy 423.407648 -115.741998) (xy 423.353468 -115.734182) (xy 423.300965 -115.718694) (xy 423.251218 -115.695852)
			(xy 423.205251 -115.666127) (xy 423.18432 -115.648486) (xy 423.184066 -115.648232) (xy 423.176971 -115.642659)
			(xy 423.16006 -115.636406) (xy 423.151046 -115.63604) (xy 423.08399 -115.63604) (xy 423.074972 -115.636383)
			(xy 423.058054 -115.642639) (xy 423.05097 -115.648232) (xy 423.05097 -115.648486) (xy 423.050716 -115.648486)
			(xy 423.029787 -115.666129) (xy 422.983814 -115.695841) (xy 422.934065 -115.718676) (xy 422.881564 -115.734166)
			(xy 422.827387 -115.741993) (xy 422.800018 -115.742466) (xy 422.772764 -115.742028) (xy 422.71881 -115.734272)
			(xy 422.666509 -115.718916) (xy 422.616926 -115.696273) (xy 422.571071 -115.666803) (xy 422.529877 -115.631106)
			(xy 422.494183 -115.58991) (xy 422.464716 -115.544053) (xy 422.442075 -115.494469) (xy 422.426723 -115.442167)
			(xy 422.41897 -115.388212) (xy 422.41851 -115.360958) (xy 415.986872 -115.360958) (xy 415.985713 -115.368836)
			(xy 415.969645 -115.422243) (xy 415.945973 -115.47274) (xy 415.9152 -115.519253) (xy 415.877983 -115.56079)
			(xy 415.835115 -115.596465) (xy 415.787509 -115.625519) (xy 415.73618 -115.647331) (xy 415.682223 -115.661437)
			(xy 415.626786 -115.667537) (xy 415.571052 -115.6655) (xy 415.516209 -115.65537) (xy 415.463425 -115.637363)
			(xy 415.413825 -115.611862) (xy 415.368467 -115.579411) (xy 415.328318 -115.540702) (xy 415.294232 -115.496559)
			(xy 415.266936 -115.447924) (xy 415.247013 -115.395833) (xy 415.234887 -115.341396) (xy 415.230816 -115.285774)
			(xy 409.88996 -115.285774) (xy 409.88996 -115.922044) (xy 411.503366 -115.922044) (xy 411.507437 -115.866422)
			(xy 411.519563 -115.811985) (xy 411.539486 -115.759894) (xy 411.566782 -115.711259) (xy 411.600868 -115.667116)
			(xy 411.641017 -115.628407) (xy 411.686375 -115.595956) (xy 411.735975 -115.570455) (xy 411.788759 -115.552448)
			(xy 411.843602 -115.542318) (xy 411.899336 -115.540281) (xy 411.954773 -115.546381) (xy 412.00873 -115.560487)
			(xy 412.060059 -115.582299) (xy 412.107665 -115.611353) (xy 412.150533 -115.647028) (xy 412.18775 -115.688565)
			(xy 412.218523 -115.735078) (xy 412.242195 -115.785575) (xy 412.258263 -115.838982) (xy 412.266383 -115.894158)
			(xy 412.266892 -115.922044) (xy 412.266383 -115.94993) (xy 412.258263 -116.005106) (xy 412.242195 -116.058513)
			(xy 412.218523 -116.10901) (xy 412.18775 -116.155523) (xy 412.150533 -116.19706) (xy 412.107665 -116.232735)
			(xy 412.060059 -116.261789) (xy 412.00873 -116.283601) (xy 411.954773 -116.297707) (xy 411.899336 -116.303807)
			(xy 411.843602 -116.30177) (xy 411.788759 -116.29164) (xy 411.735975 -116.273633) (xy 411.686375 -116.248132)
			(xy 411.641017 -116.215681) (xy 411.600868 -116.176972) (xy 411.566782 -116.132829) (xy 411.539486 -116.084194)
			(xy 411.519563 -116.032103) (xy 411.507437 -115.977666) (xy 411.503366 -115.922044) (xy 409.88996 -115.922044)
			(xy 409.88996 -116.44757) (xy 414.457132 -116.44757) (xy 414.461203 -116.391948) (xy 414.473329 -116.337511)
			(xy 414.493252 -116.28542) (xy 414.520548 -116.236785) (xy 414.554634 -116.192642) (xy 414.594783 -116.153933)
			(xy 414.640141 -116.121482) (xy 414.689741 -116.095981) (xy 414.742525 -116.077974) (xy 414.797368 -116.067844)
			(xy 414.853102 -116.065807) (xy 414.908539 -116.071907) (xy 414.962496 -116.086013) (xy 415.013825 -116.107825)
			(xy 415.061431 -116.136879) (xy 415.104299 -116.172554) (xy 415.141516 -116.214091) (xy 415.172289 -116.260604)
			(xy 415.195961 -116.311101) (xy 415.212029 -116.364508) (xy 415.220149 -116.419684) (xy 415.220658 -116.44757)
			(xy 415.220149 -116.475456) (xy 415.219879 -116.477288) (xy 419.604442 -116.477288) (xy 419.608513 -116.421666)
			(xy 419.620639 -116.367229) (xy 419.640562 -116.315138) (xy 419.667858 -116.266503) (xy 419.701944 -116.22236)
			(xy 419.742093 -116.183651) (xy 419.787451 -116.1512) (xy 419.837051 -116.125699) (xy 419.889835 -116.107692)
			(xy 419.944678 -116.097562) (xy 420.000412 -116.095525) (xy 420.055849 -116.101625) (xy 420.109806 -116.115731)
			(xy 420.161135 -116.137543) (xy 420.208741 -116.166597) (xy 420.251609 -116.202272) (xy 420.288826 -116.243809)
			(xy 420.319599 -116.290322) (xy 420.343271 -116.340819) (xy 420.359339 -116.394226) (xy 420.367459 -116.449402)
			(xy 420.367968 -116.477288) (xy 420.367459 -116.505174) (xy 420.359339 -116.56035) (xy 420.343271 -116.613757)
			(xy 420.319599 -116.664254) (xy 420.288826 -116.710767) (xy 420.251609 -116.752304) (xy 420.208741 -116.787979)
			(xy 420.161135 -116.817033) (xy 420.109806 -116.838845) (xy 420.055849 -116.852951) (xy 420.000412 -116.859051)
			(xy 419.944678 -116.857014) (xy 419.889835 -116.846884) (xy 419.837051 -116.828877) (xy 419.787451 -116.803376)
			(xy 419.742093 -116.770925) (xy 419.701944 -116.732216) (xy 419.667858 -116.688073) (xy 419.640562 -116.639438)
			(xy 419.620639 -116.587347) (xy 419.608513 -116.53291) (xy 419.604442 -116.477288) (xy 415.219879 -116.477288)
			(xy 415.212029 -116.530632) (xy 415.195961 -116.584039) (xy 415.172289 -116.634536) (xy 415.141516 -116.681049)
			(xy 415.104299 -116.722586) (xy 415.061431 -116.758261) (xy 415.013825 -116.787315) (xy 414.962496 -116.809127)
			(xy 414.908539 -116.823233) (xy 414.853102 -116.829333) (xy 414.797368 -116.827296) (xy 414.742525 -116.817166)
			(xy 414.689741 -116.799159) (xy 414.640141 -116.773658) (xy 414.594783 -116.741207) (xy 414.554634 -116.702498)
			(xy 414.520548 -116.658355) (xy 414.493252 -116.60972) (xy 414.473329 -116.557629) (xy 414.461203 -116.503192)
			(xy 414.457132 -116.44757) (xy 409.88996 -116.44757) (xy 409.88996 -118.331996) (xy 411.195772 -118.331996)
			(xy 411.199843 -118.276374) (xy 411.211969 -118.221937) (xy 411.231892 -118.169846) (xy 411.259188 -118.121211)
			(xy 411.293274 -118.077068) (xy 411.333423 -118.038359) (xy 411.378781 -118.005908) (xy 411.428381 -117.980407)
			(xy 411.481165 -117.9624) (xy 411.536008 -117.95227) (xy 411.591742 -117.950233) (xy 411.647179 -117.956333)
			(xy 411.701136 -117.970439) (xy 411.752465 -117.992251) (xy 411.800071 -118.021305) (xy 411.842939 -118.05698)
			(xy 411.880156 -118.098517) (xy 411.910929 -118.14503) (xy 411.934601 -118.195527) (xy 411.950669 -118.248934)
			(xy 411.958789 -118.30411) (xy 411.959298 -118.331996) (xy 411.958789 -118.359882) (xy 411.950669 -118.415058)
			(xy 411.934601 -118.468465) (xy 411.910929 -118.518962) (xy 411.880156 -118.565475) (xy 411.842939 -118.607012)
			(xy 411.800071 -118.642687) (xy 411.752465 -118.671741) (xy 411.701136 -118.693553) (xy 411.647179 -118.707659)
			(xy 411.591742 -118.713759) (xy 411.536008 -118.711722) (xy 411.481165 -118.701592) (xy 411.428381 -118.683585)
			(xy 411.378781 -118.658084) (xy 411.333423 -118.625633) (xy 411.293274 -118.586924) (xy 411.259188 -118.542781)
			(xy 411.231892 -118.494146) (xy 411.211969 -118.442055) (xy 411.199843 -118.387618) (xy 411.195772 -118.331996)
			(xy 409.88996 -118.331996) (xy 409.88996 -137.848848) (xy 410.23997 -137.848848) (xy 410.244041 -137.793226)
			(xy 410.256167 -137.738789) (xy 410.27609 -137.686698) (xy 410.303386 -137.638063) (xy 410.337472 -137.59392)
			(xy 410.377621 -137.555211) (xy 410.422979 -137.52276) (xy 410.472579 -137.497259) (xy 410.525363 -137.479252)
			(xy 410.580206 -137.469122) (xy 410.63594 -137.467085) (xy 410.691377 -137.473185) (xy 410.745334 -137.487291)
			(xy 410.796663 -137.509103) (xy 410.844269 -137.538157) (xy 410.887137 -137.573832) (xy 410.924354 -137.615369)
			(xy 410.955127 -137.661882) (xy 410.978799 -137.712379) (xy 410.994867 -137.765786) (xy 411.002987 -137.820962)
			(xy 411.003496 -137.848848) (xy 411.002987 -137.876734) (xy 410.994867 -137.93191) (xy 410.978799 -137.985317)
			(xy 410.955127 -138.035814) (xy 410.924354 -138.082327) (xy 410.887137 -138.123864) (xy 410.844269 -138.159539)
			(xy 410.796663 -138.188593) (xy 410.745334 -138.210405) (xy 410.691377 -138.224511) (xy 410.63594 -138.230611)
			(xy 410.580206 -138.228574) (xy 410.525363 -138.218444) (xy 410.472579 -138.200437) (xy 410.422979 -138.174936)
			(xy 410.377621 -138.142485) (xy 410.337472 -138.103776) (xy 410.303386 -138.059633) (xy 410.27609 -138.010998)
			(xy 410.256167 -137.958907) (xy 410.244041 -137.90447) (xy 410.23997 -137.848848) (xy 409.88996 -137.848848)
			(xy 409.88996 -138.864848) (xy 410.23997 -138.864848) (xy 410.244041 -138.809226) (xy 410.256167 -138.754789)
			(xy 410.27609 -138.702698) (xy 410.303386 -138.654063) (xy 410.337472 -138.60992) (xy 410.377621 -138.571211)
			(xy 410.422979 -138.53876) (xy 410.472579 -138.513259) (xy 410.525363 -138.495252) (xy 410.580206 -138.485122)
			(xy 410.63594 -138.483085) (xy 410.691377 -138.489185) (xy 410.745334 -138.503291) (xy 410.796663 -138.525103)
			(xy 410.844269 -138.554157) (xy 410.887137 -138.589832) (xy 410.924354 -138.631369) (xy 410.955127 -138.677882)
			(xy 410.978799 -138.728379) (xy 410.994867 -138.781786) (xy 411.002987 -138.836962) (xy 411.003496 -138.864848)
			(xy 411.002987 -138.892734) (xy 410.994867 -138.94791) (xy 410.978799 -139.001317) (xy 410.955127 -139.051814)
			(xy 410.924354 -139.098327) (xy 410.887137 -139.139864) (xy 410.844269 -139.175539) (xy 410.796663 -139.204593)
			(xy 410.745334 -139.226405) (xy 410.691377 -139.240511) (xy 410.63594 -139.246611) (xy 410.580206 -139.244574)
			(xy 410.525363 -139.234444) (xy 410.472579 -139.216437) (xy 410.422979 -139.190936) (xy 410.377621 -139.158485)
			(xy 410.337472 -139.119776) (xy 410.303386 -139.075633) (xy 410.27609 -139.026998) (xy 410.256167 -138.974907)
			(xy 410.244041 -138.92047) (xy 410.23997 -138.864848) (xy 409.88996 -138.864848) (xy 409.88996 -140.429742)
			(xy 409.890348 -140.439816) (xy 409.898093 -140.458414) (xy 409.904946 -140.46581) (xy 411.468062 -142.02918)
			(xy 411.491232 -142.053087) (xy 411.531798 -142.105876) (xy 411.565124 -142.16351) (xy 411.590638 -142.225003)
			(xy 411.607903 -142.289301) (xy 411.616625 -142.355302) (xy 411.61716 -142.38859) (xy 411.61716 -156.9339)
			(xy 411.617268 -156.938918) (xy 411.619177 -156.94877) (xy 411.62097 -156.953458) (xy 413.784542 -162.176968)
			(xy 413.796806 -162.207924) (xy 413.814078 -162.272231) (xy 413.822826 -162.33824) (xy 413.823404 -162.371532)
			(xy 413.823404 -163.386008) (xy 413.822902 -163.417969) (xy 413.814891 -163.481387) (xy 413.798994 -163.543301)
			(xy 413.775462 -163.602734) (xy 413.744668 -163.658749) (xy 413.707095 -163.710464) (xy 413.663338 -163.757061)
			(xy 413.614085 -163.797806) (xy 413.560114 -163.832057) (xy 413.502275 -163.859274) (xy 413.441482 -163.879027)
			(xy 413.378692 -163.891005) (xy 413.314896 -163.895019) (xy 413.2511 -163.891005) (xy 413.18831 -163.879027)
			(xy 413.127517 -163.859274) (xy 413.069678 -163.832057) (xy 413.015707 -163.797806) (xy 412.966454 -163.757061)
			(xy 412.922697 -163.710464) (xy 412.885124 -163.658749) (xy 412.85433 -163.602734) (xy 412.830798 -163.543301)
			(xy 412.814901 -163.481387) (xy 412.80689 -163.417969) (xy 412.806388 -163.386008) (xy 412.806388 -162.482784)
			(xy 412.806288 -162.477765) (xy 412.804375 -162.467913) (xy 412.802578 -162.463226) (xy 410.639006 -157.239716)
			(xy 410.626765 -157.208751) (xy 410.609485 -157.144449) (xy 410.600728 -157.078443) (xy 410.600144 -157.045152)
			(xy 410.600144 -142.620238) (xy 410.599714 -142.610169) (xy 410.591998 -142.59157) (xy 410.585158 -142.58417)
			(xy 409.022042 -141.0208) (xy 408.998845 -140.996919) (xy 408.958284 -140.944123) (xy 408.924965 -140.886482)
			(xy 408.899456 -140.824985) (xy 408.882195 -140.760683) (xy 408.873478 -140.694679) (xy 408.872944 -140.66139)
			(xy 402.8313 -140.66139) (xy 401.55749 -141.9352) (xy 404.824182 -141.9352) (xy 404.828253 -141.879578)
			(xy 404.840379 -141.825141) (xy 404.860302 -141.77305) (xy 404.887598 -141.724415) (xy 404.921684 -141.680272)
			(xy 404.961833 -141.641563) (xy 405.007191 -141.609112) (xy 405.056791 -141.583611) (xy 405.109575 -141.565604)
			(xy 405.164418 -141.555474) (xy 405.220152 -141.553437) (xy 405.275589 -141.559537) (xy 405.329546 -141.573643)
			(xy 405.380875 -141.595455) (xy 405.428481 -141.624509) (xy 405.471349 -141.660184) (xy 405.508566 -141.701721)
			(xy 405.539339 -141.748234) (xy 405.563011 -141.798731) (xy 405.579079 -141.852138) (xy 405.587199 -141.907314)
			(xy 405.587708 -141.9352) (xy 405.587199 -141.963086) (xy 405.579079 -142.018262) (xy 405.563011 -142.071669)
			(xy 405.539339 -142.122166) (xy 405.508566 -142.168679) (xy 405.471349 -142.210216) (xy 405.428481 -142.245891)
			(xy 405.380875 -142.274945) (xy 405.329546 -142.296757) (xy 405.275589 -142.310863) (xy 405.220152 -142.316963)
			(xy 405.164418 -142.314926) (xy 405.109575 -142.304796) (xy 405.056791 -142.286789) (xy 405.007191 -142.261288)
			(xy 404.961833 -142.228837) (xy 404.921684 -142.190128) (xy 404.887598 -142.145985) (xy 404.860302 -142.09735)
			(xy 404.840379 -142.045259) (xy 404.828253 -141.990822) (xy 404.824182 -141.9352) (xy 401.55749 -141.9352)
			(xy 400.54149 -142.9512) (xy 404.840438 -142.9512) (xy 404.844509 -142.895578) (xy 404.856635 -142.841141)
			(xy 404.876558 -142.78905) (xy 404.903854 -142.740415) (xy 404.93794 -142.696272) (xy 404.978089 -142.657563)
			(xy 405.023447 -142.625112) (xy 405.073047 -142.599611) (xy 405.125831 -142.581604) (xy 405.180674 -142.571474)
			(xy 405.236408 -142.569437) (xy 405.291845 -142.575537) (xy 405.345802 -142.589643) (xy 405.397131 -142.611455)
			(xy 405.444737 -142.640509) (xy 405.487605 -142.676184) (xy 405.524822 -142.717721) (xy 405.555595 -142.764234)
			(xy 405.579267 -142.814731) (xy 405.595335 -142.868138) (xy 405.603455 -142.923314) (xy 405.603964 -142.9512)
			(xy 405.603455 -142.979086) (xy 405.595335 -143.034262) (xy 405.579267 -143.087669) (xy 405.555595 -143.138166)
			(xy 405.524822 -143.184679) (xy 405.487605 -143.226216) (xy 405.444737 -143.261891) (xy 405.397131 -143.290945)
			(xy 405.345802 -143.312757) (xy 405.291845 -143.326863) (xy 405.236408 -143.332963) (xy 405.180674 -143.330926)
			(xy 405.125831 -143.320796) (xy 405.073047 -143.302789) (xy 405.023447 -143.277288) (xy 404.978089 -143.244837)
			(xy 404.93794 -143.206128) (xy 404.903854 -143.161985) (xy 404.876558 -143.11335) (xy 404.856635 -143.061259)
			(xy 404.844509 -143.006822) (xy 404.840438 -142.9512) (xy 400.54149 -142.9512) (xy 399.626074 -143.866616)
			(xy 399.618454 -143.873982) (xy 399.609818 -143.895572) (xy 399.590856 -143.939888) (xy 399.545505 -144.024952)
			(xy 399.492084 -144.105194) (xy 399.431102 -144.179852) (xy 399.363138 -144.248215) (xy 399.335052 -144.272)
			(xy 404.687022 -144.272) (xy 404.691093 -144.216378) (xy 404.703219 -144.161941) (xy 404.723142 -144.10985)
			(xy 404.750438 -144.061215) (xy 404.784524 -144.017072) (xy 404.824673 -143.978363) (xy 404.870031 -143.945912)
			(xy 404.919631 -143.920411) (xy 404.972415 -143.902404) (xy 405.027258 -143.892274) (xy 405.082992 -143.890237)
			(xy 405.138429 -143.896337) (xy 405.192386 -143.910443) (xy 405.243715 -143.932255) (xy 405.291321 -143.961309)
			(xy 405.334189 -143.996984) (xy 405.371406 -144.038521) (xy 405.402179 -144.085034) (xy 405.425851 -144.135531)
			(xy 405.441919 -144.188938) (xy 405.450039 -144.244114) (xy 405.450548 -144.272) (xy 405.450039 -144.299886)
			(xy 405.441919 -144.355062) (xy 405.425851 -144.408469) (xy 405.402179 -144.458966) (xy 405.371406 -144.505479)
			(xy 405.334189 -144.547016) (xy 405.291321 -144.582691) (xy 405.243715 -144.611745) (xy 405.192386 -144.633557)
			(xy 405.138429 -144.647663) (xy 405.082992 -144.653763) (xy 405.027258 -144.651726) (xy 404.972415 -144.641596)
			(xy 404.919631 -144.623589) (xy 404.870031 -144.598088) (xy 404.824673 -144.565637) (xy 404.784524 -144.526928)
			(xy 404.750438 -144.482785) (xy 404.723142 -144.43415) (xy 404.703219 -144.382059) (xy 404.691093 -144.327622)
			(xy 404.687022 -144.272) (xy 399.335052 -144.272) (xy 399.326354 -144.279366) (xy 399.320258 -144.284446)
			(xy 399.128234 -144.753838) (xy 399.112556 -144.791082) (xy 399.075998 -144.863157) (xy 399.033735 -144.932041)
			(xy 398.986044 -144.997284) (xy 398.933235 -145.05846) (xy 398.904714 -145.087086) (xy 398.844262 -145.146522)
			(xy 398.840452 -145.157444) (xy 398.826489 -145.195107) (xy 398.793274 -145.26825) (xy 398.754228 -145.338454)
			(xy 398.732248 -145.372074) (xy 398.716763 -145.394907) (xy 398.683597 -145.439002) (xy 398.665954 -145.460212)
			(xy 398.663922 -145.462752) (xy 398.65173 -145.480024) (xy 398.650206 -145.482056) (xy 398.641062 -145.49374)
			(xy 398.640554 -145.494248) (xy 398.619561 -145.521043) (xy 398.574438 -145.572017) (xy 398.550384 -145.596102)
			(xy 398.197324 -145.943574) (xy 398.168458 -145.971415) (xy 398.106954 -146.022896) (xy 398.041514 -146.069268)
			(xy 397.972559 -146.110233) (xy 397.93672 -146.128232) (xy 397.933672 -146.129756) (xy 397.929354 -146.131788)
			(xy 397.911828 -146.148806) (xy 397.908956 -146.151747) (xy 397.904107 -146.158385) (xy 397.902176 -146.162014)
			(xy 397.882872 -146.197828) (xy 397.852392 -146.247866) (xy 397.843502 -146.261328) (xy 397.841978 -146.263614)
			(xy 397.840454 -146.2659) (xy 397.8402 -146.266154) (xy 397.825468 -146.287744) (xy 397.822674 -146.290538)
			(xy 397.820134 -146.294094) (xy 397.813784 -146.302984) (xy 397.81353 -146.303238) (xy 397.81353 -146.303492)
			(xy 397.813276 -146.303746) (xy 397.808213 -146.311679) (xy 397.803658 -146.329922) (xy 397.804386 -146.339306)
			(xy 397.813276 -146.41195) (xy 397.819118 -146.42084) (xy 397.826484 -146.434048) (xy 397.828494 -146.437618)
			(xy 397.833472 -146.444126) (xy 397.83639 -146.447002) (xy 397.838168 -146.448526) (xy 397.85898 -146.466733)
			(xy 397.895647 -146.508124) (xy 397.925952 -146.554376) (xy 397.94926 -146.604519) (xy 397.965082 -146.657503)
			(xy 397.973087 -146.712216) (xy 397.97355 -146.739864) (xy 397.973067 -146.767118) (xy 397.968918 -146.795998)
			(xy 398.843752 -146.795998) (xy 398.847823 -146.740376) (xy 398.859949 -146.685939) (xy 398.879872 -146.633848)
			(xy 398.907168 -146.585213) (xy 398.941254 -146.54107) (xy 398.981403 -146.502361) (xy 399.026761 -146.46991)
			(xy 399.076361 -146.444409) (xy 399.129145 -146.426402) (xy 399.183988 -146.416272) (xy 399.239722 -146.414235)
			(xy 399.295159 -146.420335) (xy 399.349116 -146.434441) (xy 399.400445 -146.456253) (xy 399.448051 -146.485307)
			(xy 399.490919 -146.520982) (xy 399.528136 -146.562519) (xy 399.558909 -146.609032) (xy 399.582581 -146.659529)
			(xy 399.598649 -146.712936) (xy 399.606769 -146.768112) (xy 399.607278 -146.795998) (xy 399.606769 -146.823884)
			(xy 399.598649 -146.87906) (xy 399.582581 -146.932467) (xy 399.558909 -146.982964) (xy 399.528136 -147.029477)
			(xy 399.490919 -147.071014) (xy 399.448051 -147.106689) (xy 399.400445 -147.135743) (xy 399.349116 -147.157555)
			(xy 399.295159 -147.171661) (xy 399.239722 -147.177761) (xy 399.183988 -147.175724) (xy 399.129145 -147.165594)
			(xy 399.076361 -147.147587) (xy 399.026761 -147.122086) (xy 398.981403 -147.089635) (xy 398.941254 -147.050926)
			(xy 398.907168 -147.006783) (xy 398.879872 -146.958148) (xy 398.859949 -146.906057) (xy 398.847823 -146.85162)
			(xy 398.843752 -146.795998) (xy 397.968918 -146.795998) (xy 397.965315 -146.821072) (xy 397.949963 -146.873373)
			(xy 397.927324 -146.922958) (xy 397.89786 -146.968816) (xy 397.862169 -147.010014) (xy 397.820978 -147.045713)
			(xy 397.775126 -147.075187) (xy 397.725547 -147.097836) (xy 397.673248 -147.113198) (xy 397.619296 -147.120961)
			(xy 397.592042 -147.121372) (xy 397.56486 -147.120896) (xy 397.511044 -147.113194) (xy 397.458863 -147.097939)
			(xy 397.409373 -147.07544) (xy 397.363572 -147.046151) (xy 397.322387 -147.010665) (xy 397.28665 -146.969697)
			(xy 397.271494 -146.947128) (xy 397.266414 -146.939254) (xy 397.259048 -146.93392) (xy 397.255541 -146.931461)
			(xy 397.247879 -146.927633) (xy 397.243808 -146.9263) (xy 397.194532 -146.91233) (xy 397.190976 -146.911822)
			(xy 397.172434 -146.924014) (xy 397.171926 -146.924014) (xy 397.155924 -146.934682) (xy 397.155416 -146.934682)
			(xy 397.124039 -146.953843) (xy 397.058948 -146.98804) (xy 397.025368 -147.003008) (xy 397.021254 -147.00488)
			(xy 397.013716 -147.009863) (xy 397.010382 -147.012914) (xy 397.007731 -147.015531) (xy 397.003141 -147.021396)
			(xy 397.001238 -147.024598) (xy 396.97871 -147.063533) (xy 396.927573 -147.137546) (xy 396.869915 -147.206599)
			(xy 396.838424 -147.23872) (xy 396.526004 -147.55114) (xy 396.496596 -147.579946) (xy 396.43374 -147.633115)
			(xy 396.366682 -147.680876) (xy 396.295888 -147.722899) (xy 396.221846 -147.758894) (xy 396.183612 -147.774152)
			(xy 396.173452 -147.777962) (xy 395.418056 -148.533358) (xy 395.414027 -148.537564) (xy 395.407871 -148.547448)
			(xy 395.405864 -148.552916) (xy 395.403578 -148.562568) (xy 395.378432 -148.869654) (xy 395.381988 -148.879814)
			(xy 395.39545 -148.920962) (xy 395.401425 -148.941334) (xy 395.411844 -148.982496) (xy 395.416278 -149.003258)
			(xy 395.425918 -149.052862) (xy 395.436229 -149.15339) (xy 395.436852 -149.203918) (xy 395.436852 -149.204934)
			(xy 395.436795 -149.224957) (xy 395.435271 -149.264974) (xy 395.433804 -149.284944) (xy 395.39799 -149.725634)
			(xy 395.394238 -149.766716) (xy 395.380754 -149.848107) (xy 395.360533 -149.928091) (xy 395.333717 -150.006112)
			(xy 395.300492 -150.081627) (xy 395.28115 -150.118064) (xy 395.280896 -150.118318) (xy 395.275816 -150.12797)
			(xy 395.2748 -150.140416) (xy 395.272768 -150.166578) (xy 395.267434 -150.236936) (xy 395.267434 -150.23719)
			(xy 395.26718 -150.239476) (xy 395.26718 -151.063706) (xy 395.267688 -151.067516) (xy 395.273159 -151.105378)
			(xy 395.279005 -151.181662) (xy 395.279372 -151.219916) (xy 395.279277 -151.240259) (xy 395.278598 -151.257)
			(xy 400.877022 -151.257) (xy 400.881093 -151.201378) (xy 400.893219 -151.146941) (xy 400.913142 -151.09485)
			(xy 400.940438 -151.046215) (xy 400.974524 -151.002072) (xy 401.014673 -150.963363) (xy 401.060031 -150.930912)
			(xy 401.109631 -150.905411) (xy 401.162415 -150.887404) (xy 401.217258 -150.877274) (xy 401.272992 -150.875237)
			(xy 401.328429 -150.881337) (xy 401.382386 -150.895443) (xy 401.433715 -150.917255) (xy 401.481321 -150.946309)
			(xy 401.524189 -150.981984) (xy 401.561406 -151.023521) (xy 401.592179 -151.070034) (xy 401.615851 -151.120531)
			(xy 401.631919 -151.173938) (xy 401.640039 -151.229114) (xy 401.640548 -151.257) (xy 401.640039 -151.284886)
			(xy 401.631919 -151.340062) (xy 401.615851 -151.393469) (xy 401.592179 -151.443966) (xy 401.561406 -151.490479)
			(xy 401.524189 -151.532016) (xy 401.481321 -151.567691) (xy 401.433715 -151.596745) (xy 401.382386 -151.618557)
			(xy 401.328429 -151.632663) (xy 401.272992 -151.638763) (xy 401.217258 -151.636726) (xy 401.162415 -151.626596)
			(xy 401.109631 -151.608589) (xy 401.060031 -151.583088) (xy 401.014673 -151.550637) (xy 400.974524 -151.511928)
			(xy 400.940438 -151.467785) (xy 400.913142 -151.41915) (xy 400.893219 -151.367059) (xy 400.881093 -151.312622)
			(xy 400.877022 -151.257) (xy 395.278598 -151.257) (xy 395.277627 -151.280912) (xy 395.27607 -151.301196)
			(xy 395.267688 -151.407368) (xy 395.26718 -151.41194) (xy 395.26718 -153.560018) (xy 400.750022 -153.560018)
			(xy 400.754093 -153.504396) (xy 400.766219 -153.449959) (xy 400.786142 -153.397868) (xy 400.813438 -153.349233)
			(xy 400.847524 -153.30509) (xy 400.887673 -153.266381) (xy 400.933031 -153.23393) (xy 400.982631 -153.208429)
			(xy 401.035415 -153.190422) (xy 401.090258 -153.180292) (xy 401.145992 -153.178255) (xy 401.201429 -153.184355)
			(xy 401.255386 -153.198461) (xy 401.306715 -153.220273) (xy 401.354321 -153.249327) (xy 401.397189 -153.285002)
			(xy 401.434406 -153.326539) (xy 401.465179 -153.373052) (xy 401.488851 -153.423549) (xy 401.504919 -153.476956)
			(xy 401.513039 -153.532132) (xy 401.513548 -153.560018) (xy 401.513039 -153.587904) (xy 401.504919 -153.64308)
			(xy 401.488851 -153.696487) (xy 401.465179 -153.746984) (xy 401.434406 -153.793497) (xy 401.397189 -153.835034)
			(xy 401.354321 -153.870709) (xy 401.306715 -153.899763) (xy 401.255386 -153.921575) (xy 401.201429 -153.935681)
			(xy 401.145992 -153.941781) (xy 401.090258 -153.939744) (xy 401.035415 -153.929614) (xy 400.982631 -153.911607)
			(xy 400.933031 -153.886106) (xy 400.887673 -153.853655) (xy 400.847524 -153.814946) (xy 400.813438 -153.770803)
			(xy 400.786142 -153.722168) (xy 400.766219 -153.670077) (xy 400.754093 -153.61564) (xy 400.750022 -153.560018)
			(xy 395.26718 -153.560018) (xy 395.26718 -154.159966) (xy 399.607022 -154.159966) (xy 399.611093 -154.104344)
			(xy 399.623219 -154.049907) (xy 399.643142 -153.997816) (xy 399.670438 -153.949181) (xy 399.704524 -153.905038)
			(xy 399.744673 -153.866329) (xy 399.790031 -153.833878) (xy 399.839631 -153.808377) (xy 399.892415 -153.79037)
			(xy 399.947258 -153.78024) (xy 400.002992 -153.778203) (xy 400.058429 -153.784303) (xy 400.112386 -153.798409)
			(xy 400.163715 -153.820221) (xy 400.211321 -153.849275) (xy 400.254189 -153.88495) (xy 400.291406 -153.926487)
			(xy 400.322179 -153.973) (xy 400.345851 -154.023497) (xy 400.361919 -154.076904) (xy 400.370039 -154.13208)
			(xy 400.370548 -154.159966) (xy 400.370039 -154.187852) (xy 400.361919 -154.243028) (xy 400.345851 -154.296435)
			(xy 400.322179 -154.346932) (xy 400.291406 -154.393445) (xy 400.254189 -154.434982) (xy 400.211321 -154.470657)
			(xy 400.163715 -154.499711) (xy 400.112386 -154.521523) (xy 400.058429 -154.535629) (xy 400.002992 -154.541729)
			(xy 399.947258 -154.539692) (xy 399.892415 -154.529562) (xy 399.839631 -154.511555) (xy 399.790031 -154.486054)
			(xy 399.744673 -154.453603) (xy 399.704524 -154.414894) (xy 399.670438 -154.370751) (xy 399.643142 -154.322116)
			(xy 399.623219 -154.270025) (xy 399.611093 -154.215588) (xy 399.607022 -154.159966) (xy 395.26718 -154.159966)
			(xy 395.26718 -155.0416) (xy 396.337536 -155.0416) (xy 396.337956 -155.010877) (xy 396.34536 -154.949879)
			(xy 396.360061 -154.890218) (xy 396.381845 -154.832763) (xy 396.410393 -154.778352) (xy 396.44529 -154.727777)
			(xy 396.486028 -154.681776) (xy 396.532012 -154.64102) (xy 396.582572 -154.606102) (xy 396.636971 -154.577531)
			(xy 396.694417 -154.555724) (xy 396.754072 -154.540998) (xy 396.815067 -154.533568) (xy 396.84579 -154.533092)
			(xy 396.879073 -154.533698) (xy 396.945065 -154.54243) (xy 397.009355 -154.559695) (xy 397.070844 -154.585196)
			(xy 397.128482 -154.6185) (xy 397.181284 -154.659036) (xy 397.2052 -154.68219) (xy 397.481298 -154.958288)
			(xy 401.044154 -154.958288) (xy 401.048225 -154.902666) (xy 401.060351 -154.848229) (xy 401.080274 -154.796138)
			(xy 401.10757 -154.747503) (xy 401.141656 -154.70336) (xy 401.181805 -154.664651) (xy 401.227163 -154.6322)
			(xy 401.276763 -154.606699) (xy 401.329547 -154.588692) (xy 401.38439 -154.578562) (xy 401.440124 -154.576525)
			(xy 401.495561 -154.582625) (xy 401.549518 -154.596731) (xy 401.600847 -154.618543) (xy 401.648453 -154.647597)
			(xy 401.691321 -154.683272) (xy 401.728538 -154.724809) (xy 401.759311 -154.771322) (xy 401.782983 -154.821819)
			(xy 401.799051 -154.875226) (xy 401.807171 -154.930402) (xy 401.80768 -154.958288) (xy 401.807171 -154.986174)
			(xy 401.799051 -155.04135) (xy 401.782983 -155.094757) (xy 401.759311 -155.145254) (xy 401.728538 -155.191767)
			(xy 401.691321 -155.233304) (xy 401.648453 -155.268979) (xy 401.600847 -155.298033) (xy 401.549518 -155.319845)
			(xy 401.495561 -155.333951) (xy 401.440124 -155.340051) (xy 401.38439 -155.338014) (xy 401.329547 -155.327884)
			(xy 401.276763 -155.309877) (xy 401.227163 -155.284376) (xy 401.181805 -155.251925) (xy 401.141656 -155.213216)
			(xy 401.10757 -155.169073) (xy 401.080274 -155.120438) (xy 401.060351 -155.068347) (xy 401.048225 -155.01391)
			(xy 401.044154 -154.958288) (xy 397.481298 -154.958288) (xy 398.121378 -155.598368) (xy 399.668236 -155.598368)
			(xy 399.672307 -155.542746) (xy 399.684433 -155.488309) (xy 399.704356 -155.436218) (xy 399.731652 -155.387583)
			(xy 399.765738 -155.34344) (xy 399.805887 -155.304731) (xy 399.851245 -155.27228) (xy 399.900845 -155.246779)
			(xy 399.953629 -155.228772) (xy 400.008472 -155.218642) (xy 400.064206 -155.216605) (xy 400.119643 -155.222705)
			(xy 400.1736 -155.236811) (xy 400.224929 -155.258623) (xy 400.272535 -155.287677) (xy 400.315403 -155.323352)
			(xy 400.35262 -155.364889) (xy 400.383393 -155.411402) (xy 400.407065 -155.461899) (xy 400.423133 -155.515306)
			(xy 400.431253 -155.570482) (xy 400.431762 -155.598368) (xy 400.431253 -155.626254) (xy 400.423133 -155.68143)
			(xy 400.407065 -155.734837) (xy 400.383393 -155.785334) (xy 400.35262 -155.831847) (xy 400.315403 -155.873384)
			(xy 400.272535 -155.909059) (xy 400.224929 -155.938113) (xy 400.1736 -155.959925) (xy 400.119643 -155.974031)
			(xy 400.064206 -155.980131) (xy 400.008472 -155.978094) (xy 399.953629 -155.967964) (xy 399.900845 -155.949957)
			(xy 399.851245 -155.924456) (xy 399.805887 -155.892005) (xy 399.765738 -155.853296) (xy 399.731652 -155.809153)
			(xy 399.704356 -155.760518) (xy 399.684433 -155.708427) (xy 399.672307 -155.65399) (xy 399.668236 -155.598368)
			(xy 398.121378 -155.598368) (xy 398.438116 -155.915106) (xy 398.461274 -155.939008) (xy 398.501802 -155.991799)
			(xy 398.535101 -156.049423) (xy 398.548352 -156.079952) (xy 398.740774 -156.544518) (xy 401.027898 -156.544518)
			(xy 401.031969 -156.488896) (xy 401.044095 -156.434459) (xy 401.064018 -156.382368) (xy 401.091314 -156.333733)
			(xy 401.1254 -156.28959) (xy 401.165549 -156.250881) (xy 401.210907 -156.21843) (xy 401.260507 -156.192929)
			(xy 401.313291 -156.174922) (xy 401.368134 -156.164792) (xy 401.423868 -156.162755) (xy 401.479305 -156.168855)
			(xy 401.533262 -156.182961) (xy 401.584591 -156.204773) (xy 401.632197 -156.233827) (xy 401.675065 -156.269502)
			(xy 401.712282 -156.311039) (xy 401.743055 -156.357552) (xy 401.766727 -156.408049) (xy 401.782795 -156.461456)
			(xy 401.790915 -156.516632) (xy 401.791424 -156.544518) (xy 401.790915 -156.572404) (xy 401.782795 -156.62758)
			(xy 401.766727 -156.680987) (xy 401.743055 -156.731484) (xy 401.712282 -156.777997) (xy 401.675065 -156.819534)
			(xy 401.632197 -156.855209) (xy 401.584591 -156.884263) (xy 401.533262 -156.906075) (xy 401.479305 -156.920181)
			(xy 401.423868 -156.926281) (xy 401.368134 -156.924244) (xy 401.313291 -156.914114) (xy 401.260507 -156.896107)
			(xy 401.210907 -156.870606) (xy 401.165549 -156.838155) (xy 401.1254 -156.799446) (xy 401.091314 -156.755303)
			(xy 401.064018 -156.706668) (xy 401.044095 -156.654577) (xy 401.031969 -156.60014) (xy 401.027898 -156.544518)
			(xy 398.740774 -156.544518) (xy 398.959918 -157.0736) (xy 399.596862 -157.0736) (xy 399.600933 -157.017978)
			(xy 399.613059 -156.963541) (xy 399.632982 -156.91145) (xy 399.660278 -156.862815) (xy 399.694364 -156.818672)
			(xy 399.734513 -156.779963) (xy 399.779871 -156.747512) (xy 399.829471 -156.722011) (xy 399.882255 -156.704004)
			(xy 399.937098 -156.693874) (xy 399.992832 -156.691837) (xy 400.048269 -156.697937) (xy 400.102226 -156.712043)
			(xy 400.153555 -156.733855) (xy 400.201161 -156.762909) (xy 400.244029 -156.798584) (xy 400.281246 -156.840121)
			(xy 400.312019 -156.886634) (xy 400.335691 -156.937131) (xy 400.351759 -156.990538) (xy 400.359796 -157.045152)
			(xy 409.710634 -157.045152) (xy 409.714705 -156.98953) (xy 409.726831 -156.935093) (xy 409.746754 -156.883002)
			(xy 409.77405 -156.834367) (xy 409.808136 -156.790224) (xy 409.848285 -156.751515) (xy 409.893643 -156.719064)
			(xy 409.943243 -156.693563) (xy 409.996027 -156.675556) (xy 410.05087 -156.665426) (xy 410.106604 -156.663389)
			(xy 410.162041 -156.669489) (xy 410.215998 -156.683595) (xy 410.267327 -156.705407) (xy 410.314933 -156.734461)
			(xy 410.357801 -156.770136) (xy 410.395018 -156.811673) (xy 410.425791 -156.858186) (xy 410.449463 -156.908683)
			(xy 410.465531 -156.96209) (xy 410.473651 -157.017266) (xy 410.47416 -157.045152) (xy 410.473651 -157.073038)
			(xy 410.465531 -157.128214) (xy 410.449463 -157.181621) (xy 410.425791 -157.232118) (xy 410.395018 -157.278631)
			(xy 410.357801 -157.320168) (xy 410.314933 -157.355843) (xy 410.267327 -157.384897) (xy 410.215998 -157.406709)
			(xy 410.162041 -157.420815) (xy 410.106604 -157.426915) (xy 410.05087 -157.424878) (xy 409.996027 -157.414748)
			(xy 409.943243 -157.396741) (xy 409.893643 -157.37124) (xy 409.848285 -157.338789) (xy 409.808136 -157.30008)
			(xy 409.77405 -157.255937) (xy 409.746754 -157.207302) (xy 409.726831 -157.155211) (xy 409.714705 -157.100774)
			(xy 409.710634 -157.045152) (xy 400.359796 -157.045152) (xy 400.359879 -157.045714) (xy 400.360388 -157.0736)
			(xy 400.359879 -157.101486) (xy 400.351759 -157.156662) (xy 400.335691 -157.210069) (xy 400.312019 -157.260566)
			(xy 400.281246 -157.307079) (xy 400.244029 -157.348616) (xy 400.201161 -157.384291) (xy 400.153555 -157.413345)
			(xy 400.102226 -157.435157) (xy 400.048269 -157.449263) (xy 399.992832 -157.455363) (xy 399.937098 -157.453326)
			(xy 399.882255 -157.443196) (xy 399.829471 -157.425189) (xy 399.779871 -157.399688) (xy 399.734513 -157.367237)
			(xy 399.694364 -157.328528) (xy 399.660278 -157.284385) (xy 399.632982 -157.23575) (xy 399.613059 -157.183659)
			(xy 399.600933 -157.129222) (xy 399.596862 -157.0736) (xy 398.959918 -157.0736) (xy 399.59915 -158.616904)
			(xy 399.611395 -158.647867) (xy 399.628674 -158.71217) (xy 399.63743 -158.778177) (xy 399.638012 -158.811468)
			(xy 399.638012 -159.4104) (xy 399.99742 -159.4104) (xy 400.001491 -159.354778) (xy 400.013617 -159.300341)
			(xy 400.03354 -159.24825) (xy 400.060836 -159.199615) (xy 400.094922 -159.155472) (xy 400.135071 -159.116763)
			(xy 400.180429 -159.084312) (xy 400.230029 -159.058811) (xy 400.282813 -159.040804) (xy 400.337656 -159.030674)
			(xy 400.39339 -159.028637) (xy 400.448827 -159.034737) (xy 400.502784 -159.048843) (xy 400.554113 -159.070655)
			(xy 400.601719 -159.099709) (xy 400.644587 -159.135384) (xy 400.681804 -159.176921) (xy 400.712577 -159.223434)
			(xy 400.736249 -159.273931) (xy 400.752317 -159.327338) (xy 400.760437 -159.382514) (xy 400.760946 -159.4104)
			(xy 400.760437 -159.438286) (xy 400.752317 -159.493462) (xy 400.736249 -159.546869) (xy 400.712577 -159.597366)
			(xy 400.681804 -159.643879) (xy 400.644587 -159.685416) (xy 400.601719 -159.721091) (xy 400.554113 -159.750145)
			(xy 400.502784 -159.771957) (xy 400.448827 -159.786063) (xy 400.39339 -159.792163) (xy 400.337656 -159.790126)
			(xy 400.282813 -159.779996) (xy 400.230029 -159.761989) (xy 400.180429 -159.736488) (xy 400.135071 -159.704037)
			(xy 400.094922 -159.665328) (xy 400.060836 -159.621185) (xy 400.03354 -159.57255) (xy 400.013617 -159.520459)
			(xy 400.001491 -159.466022) (xy 399.99742 -159.4104) (xy 399.638012 -159.4104) (xy 399.638012 -160.454848)
			(xy 400.19554 -160.454848) (xy 400.199611 -160.399226) (xy 400.211737 -160.344789) (xy 400.23166 -160.292698)
			(xy 400.258956 -160.244063) (xy 400.293042 -160.19992) (xy 400.333191 -160.161211) (xy 400.378549 -160.12876)
			(xy 400.428149 -160.103259) (xy 400.480933 -160.085252) (xy 400.535776 -160.075122) (xy 400.59151 -160.073085)
			(xy 400.646947 -160.079185) (xy 400.700904 -160.093291) (xy 400.752233 -160.115103) (xy 400.799839 -160.144157)
			(xy 400.842707 -160.179832) (xy 400.879924 -160.221369) (xy 400.910697 -160.267882) (xy 400.934369 -160.318379)
			(xy 400.950437 -160.371786) (xy 400.958557 -160.426962) (xy 400.959066 -160.454848) (xy 400.958557 -160.482734)
			(xy 400.950437 -160.53791) (xy 400.934369 -160.591317) (xy 400.910697 -160.641814) (xy 400.879924 -160.688327)
			(xy 400.842707 -160.729864) (xy 400.799839 -160.765539) (xy 400.752233 -160.794593) (xy 400.700904 -160.816405)
			(xy 400.646947 -160.830511) (xy 400.59151 -160.836611) (xy 400.535776 -160.834574) (xy 400.480933 -160.824444)
			(xy 400.428149 -160.806437) (xy 400.378549 -160.780936) (xy 400.333191 -160.748485) (xy 400.293042 -160.709776)
			(xy 400.258956 -160.665633) (xy 400.23166 -160.616998) (xy 400.211737 -160.564907) (xy 400.199611 -160.51047)
			(xy 400.19554 -160.454848) (xy 399.638012 -160.454848) (xy 399.638012 -162.20694) (xy 399.637485 -162.240236)
			(xy 399.628745 -162.306251) (xy 399.611446 -162.370557) (xy 399.59915 -162.401504) (xy 398.913629 -164.056314)
			(xy 399.637502 -164.056314) (xy 399.641573 -164.000692) (xy 399.653699 -163.946255) (xy 399.673622 -163.894164)
			(xy 399.700918 -163.845529) (xy 399.735004 -163.801386) (xy 399.775153 -163.762677) (xy 399.820511 -163.730226)
			(xy 399.870111 -163.704725) (xy 399.922895 -163.686718) (xy 399.977738 -163.676588) (xy 400.033472 -163.674551)
			(xy 400.088909 -163.680651) (xy 400.142866 -163.694757) (xy 400.194195 -163.716569) (xy 400.241801 -163.745623)
			(xy 400.284669 -163.781298) (xy 400.321886 -163.822835) (xy 400.352659 -163.869348) (xy 400.376331 -163.919845)
			(xy 400.392399 -163.973252) (xy 400.400519 -164.028428) (xy 400.401028 -164.056314) (xy 400.400519 -164.0842)
			(xy 400.392399 -164.139376) (xy 400.376331 -164.192783) (xy 400.352659 -164.24328) (xy 400.321886 -164.289793)
			(xy 400.284669 -164.33133) (xy 400.241801 -164.367005) (xy 400.194195 -164.396059) (xy 400.142866 -164.417871)
			(xy 400.088909 -164.431977) (xy 400.033472 -164.438077) (xy 399.977738 -164.43604) (xy 399.922895 -164.42591)
			(xy 399.870111 -164.407903) (xy 399.820511 -164.382402) (xy 399.775153 -164.349951) (xy 399.735004 -164.311242)
			(xy 399.700918 -164.267099) (xy 399.673622 -164.218464) (xy 399.653699 -164.166373) (xy 399.641573 -164.111936)
			(xy 399.637502 -164.056314) (xy 398.913629 -164.056314) (xy 398.735804 -164.485574) (xy 398.722566 -164.51611)
			(xy 398.689272 -164.57374) (xy 398.648739 -164.626529) (xy 398.625568 -164.65042) (xy 398.333468 -164.94252)
			(xy 398.877534 -164.94252) (xy 398.881605 -164.886898) (xy 398.893731 -164.832461) (xy 398.913654 -164.78037)
			(xy 398.94095 -164.731735) (xy 398.975036 -164.687592) (xy 399.015185 -164.648883) (xy 399.060543 -164.616432)
			(xy 399.110143 -164.590931) (xy 399.162927 -164.572924) (xy 399.21777 -164.562794) (xy 399.273504 -164.560757)
			(xy 399.328941 -164.566857) (xy 399.382898 -164.580963) (xy 399.434227 -164.602775) (xy 399.481833 -164.631829)
			(xy 399.524701 -164.667504) (xy 399.561918 -164.709041) (xy 399.592691 -164.755554) (xy 399.616363 -164.806051)
			(xy 399.632431 -164.859458) (xy 399.640551 -164.914634) (xy 399.64106 -164.94252) (xy 399.640551 -164.970406)
			(xy 399.632431 -165.025582) (xy 399.616363 -165.078989) (xy 399.592691 -165.129486) (xy 399.561918 -165.175999)
			(xy 399.524701 -165.217536) (xy 399.481833 -165.253211) (xy 399.434227 -165.282265) (xy 399.382898 -165.304077)
			(xy 399.328941 -165.318183) (xy 399.273504 -165.324283) (xy 399.21777 -165.322246) (xy 399.162927 -165.312116)
			(xy 399.110143 -165.294109) (xy 399.060543 -165.268608) (xy 399.015185 -165.236157) (xy 398.975036 -165.197448)
			(xy 398.94095 -165.153305) (xy 398.913654 -165.10467) (xy 398.893731 -165.052579) (xy 398.881605 -164.998142)
			(xy 398.877534 -164.94252) (xy 398.333468 -164.94252) (xy 397.78559 -165.490398) (xy 397.761703 -165.513589)
			(xy 397.708909 -165.554152) (xy 397.65127 -165.587474) (xy 397.589774 -165.612984) (xy 397.525473 -165.630245)
			(xy 397.459469 -165.638962) (xy 397.42618 -165.639496) (xy 397.395448 -165.639063) (xy 397.334433 -165.631652)
			(xy 397.274756 -165.61694) (xy 397.217287 -165.595143) (xy 397.162864 -165.566577) (xy 397.112282 -165.53166)
			(xy 397.066277 -165.490901) (xy 397.02552 -165.444893) (xy 396.990606 -165.394308) (xy 396.962044 -165.339884)
			(xy 396.94025 -165.282414) (xy 396.925543 -165.222736) (xy 396.918135 -165.16172) (xy 396.917672 -165.130988)
			(xy 396.918241 -165.097703) (xy 396.926977 -165.031709) (xy 396.944247 -164.967417) (xy 396.969756 -164.905928)
			(xy 397.003067 -164.848291) (xy 397.043611 -164.795492) (xy 397.06677 -164.771578) (xy 397.828008 -164.010086)
			(xy 397.831416 -164.006447) (xy 397.83692 -163.998138) (xy 397.83893 -163.993576) (xy 398.617186 -162.115246)
			(xy 398.618973 -162.110555) (xy 398.6209 -162.100706) (xy 398.620996 -162.095688) (xy 398.620996 -158.92272)
			(xy 398.620914 -158.9177) (xy 398.618988 -158.907848) (xy 398.617186 -158.903162) (xy 397.651478 -156.57195)
			(xy 397.649501 -156.56737) (xy 397.643993 -156.559055) (xy 397.640556 -156.55544) (xy 396.48638 -155.40101)
			(xy 396.463217 -155.377111) (xy 396.422712 -155.324298) (xy 396.389445 -155.266651) (xy 396.363984 -155.205157)
			(xy 396.346764 -155.140866) (xy 396.33808 -155.074878) (xy 396.337536 -155.0416) (xy 395.26718 -155.0416)
			(xy 395.26718 -159.135572) (xy 395.26745 -159.142457) (xy 395.271193 -159.155713) (xy 395.274546 -159.161734)
			(xy 395.290294 -159.18561) (xy 395.299438 -159.19577) (xy 395.305026 -159.200342) (xy 395.30782 -159.201612)
			(xy 395.312138 -159.20339) (xy 395.354532 -159.222058) (xy 395.436233 -159.265723) (xy 395.513845 -159.316302)
			(xy 395.586783 -159.373415) (xy 395.654499 -159.436632) (xy 395.716484 -159.505478) (xy 395.772271 -159.579434)
			(xy 395.797278 -159.618426) (xy 395.822014 -159.65889) (xy 395.86503 -159.743422) (xy 395.900375 -159.831436)
			(xy 395.927772 -159.92224) (xy 395.947003 -160.015116) (xy 395.95298 -160.062164) (xy 395.955012 -160.081468)
			(xy 395.955266 -160.08477) (xy 395.955266 -160.085786) (xy 395.956282 -160.095438) (xy 395.956536 -160.098994)
			(xy 395.959691 -160.143644) (xy 395.959414 -160.233161) (xy 395.951642 -160.322341) (xy 395.936429 -160.410557)
			(xy 395.913883 -160.497189) (xy 395.884162 -160.581629) (xy 395.847475 -160.663284) (xy 395.804079 -160.74158)
			(xy 395.754279 -160.815967) (xy 395.698425 -160.885923) (xy 395.636909 -160.950955) (xy 395.570164 -161.010609)
			(xy 395.498657 -161.064463) (xy 395.422893 -161.112141) (xy 395.343402 -161.153307) (xy 395.302232 -161.170874)
			(xy 395.29639 -161.17316) (xy 395.287754 -161.17951) (xy 395.279372 -161.187384) (xy 395.275562 -161.192464)
			(xy 395.272245 -161.197917) (xy 395.268134 -161.209996) (xy 395.267434 -161.21634) (xy 395.267434 -161.217356)
			(xy 395.26718 -161.220404) (xy 395.26718 -163.002722) (xy 395.268958 -163.015676) (xy 395.944852 -165.555422)
			(xy 396.251114 -166.705534) (xy 409.41193 -166.705534) (xy 409.416001 -166.649912) (xy 409.428127 -166.595475)
			(xy 409.44805 -166.543384) (xy 409.475346 -166.494749) (xy 409.509432 -166.450606) (xy 409.549581 -166.411897)
			(xy 409.594939 -166.379446) (xy 409.644539 -166.353945) (xy 409.697323 -166.335938) (xy 409.752166 -166.325808)
			(xy 409.8079 -166.323771) (xy 409.863337 -166.329871) (xy 409.917294 -166.343977) (xy 409.968623 -166.365789)
			(xy 410.016229 -166.394843) (xy 410.059097 -166.430518) (xy 410.096314 -166.472055) (xy 410.127087 -166.518568)
			(xy 410.150759 -166.569065) (xy 410.166827 -166.622472) (xy 410.174947 -166.677648) (xy 410.175456 -166.705534)
			(xy 410.42793 -166.705534) (xy 410.432001 -166.649912) (xy 410.444127 -166.595475) (xy 410.46405 -166.543384)
			(xy 410.491346 -166.494749) (xy 410.525432 -166.450606) (xy 410.565581 -166.411897) (xy 410.610939 -166.379446)
			(xy 410.660539 -166.353945) (xy 410.713323 -166.335938) (xy 410.768166 -166.325808) (xy 410.8239 -166.323771)
			(xy 410.879337 -166.329871) (xy 410.933294 -166.343977) (xy 410.984623 -166.365789) (xy 411.032229 -166.394843)
			(xy 411.075097 -166.430518) (xy 411.112314 -166.472055) (xy 411.143087 -166.518568) (xy 411.166759 -166.569065)
			(xy 411.182827 -166.622472) (xy 411.190947 -166.677648) (xy 411.191456 -166.705534) (xy 411.44393 -166.705534)
			(xy 411.448001 -166.649912) (xy 411.460127 -166.595475) (xy 411.48005 -166.543384) (xy 411.507346 -166.494749)
			(xy 411.541432 -166.450606) (xy 411.581581 -166.411897) (xy 411.626939 -166.379446) (xy 411.676539 -166.353945)
			(xy 411.729323 -166.335938) (xy 411.784166 -166.325808) (xy 411.8399 -166.323771) (xy 411.895337 -166.329871)
			(xy 411.949294 -166.343977) (xy 412.000623 -166.365789) (xy 412.048229 -166.394843) (xy 412.091097 -166.430518)
			(xy 412.128314 -166.472055) (xy 412.159087 -166.518568) (xy 412.182759 -166.569065) (xy 412.198827 -166.622472)
			(xy 412.206947 -166.677648) (xy 412.207456 -166.705534) (xy 412.206947 -166.73342) (xy 412.198827 -166.788596)
			(xy 412.182759 -166.842003) (xy 412.159087 -166.8925) (xy 412.128314 -166.939013) (xy 412.091097 -166.98055)
			(xy 412.048229 -167.016225) (xy 412.000623 -167.045279) (xy 411.949294 -167.067091) (xy 411.895337 -167.081197)
			(xy 411.8399 -167.087297) (xy 411.784166 -167.08526) (xy 411.729323 -167.07513) (xy 411.676539 -167.057123)
			(xy 411.626939 -167.031622) (xy 411.581581 -166.999171) (xy 411.541432 -166.960462) (xy 411.507346 -166.916319)
			(xy 411.48005 -166.867684) (xy 411.460127 -166.815593) (xy 411.448001 -166.761156) (xy 411.44393 -166.705534)
			(xy 411.191456 -166.705534) (xy 411.190947 -166.73342) (xy 411.182827 -166.788596) (xy 411.166759 -166.842003)
			(xy 411.143087 -166.8925) (xy 411.112314 -166.939013) (xy 411.075097 -166.98055) (xy 411.032229 -167.016225)
			(xy 410.984623 -167.045279) (xy 410.933294 -167.067091) (xy 410.879337 -167.081197) (xy 410.8239 -167.087297)
			(xy 410.768166 -167.08526) (xy 410.713323 -167.07513) (xy 410.660539 -167.057123) (xy 410.610939 -167.031622)
			(xy 410.565581 -166.999171) (xy 410.525432 -166.960462) (xy 410.491346 -166.916319) (xy 410.46405 -166.867684)
			(xy 410.444127 -166.815593) (xy 410.432001 -166.761156) (xy 410.42793 -166.705534) (xy 410.175456 -166.705534)
			(xy 410.174947 -166.73342) (xy 410.166827 -166.788596) (xy 410.150759 -166.842003) (xy 410.127087 -166.8925)
			(xy 410.096314 -166.939013) (xy 410.059097 -166.98055) (xy 410.016229 -167.016225) (xy 409.968623 -167.045279)
			(xy 409.917294 -167.067091) (xy 409.863337 -167.081197) (xy 409.8079 -167.087297) (xy 409.752166 -167.08526)
			(xy 409.697323 -167.07513) (xy 409.644539 -167.057123) (xy 409.594939 -167.031622) (xy 409.549581 -166.999171)
			(xy 409.509432 -166.960462) (xy 409.475346 -166.916319) (xy 409.44805 -166.867684) (xy 409.428127 -166.815593)
			(xy 409.416001 -166.761156) (xy 409.41193 -166.705534) (xy 396.251114 -166.705534) (xy 396.701579 -168.397174)
			(xy 398.941796 -168.397174) (xy 398.945867 -168.341552) (xy 398.957993 -168.287115) (xy 398.977916 -168.235024)
			(xy 399.005212 -168.186389) (xy 399.039298 -168.142246) (xy 399.079447 -168.103537) (xy 399.124805 -168.071086)
			(xy 399.174405 -168.045585) (xy 399.227189 -168.027578) (xy 399.282032 -168.017448) (xy 399.337766 -168.015411)
			(xy 399.393203 -168.021511) (xy 399.44716 -168.035617) (xy 399.498489 -168.057429) (xy 399.546095 -168.086483)
			(xy 399.588963 -168.122158) (xy 399.62618 -168.163695) (xy 399.656953 -168.210208) (xy 399.680625 -168.260705)
			(xy 399.696693 -168.314112) (xy 399.704813 -168.369288) (xy 399.705322 -168.397174) (xy 399.704813 -168.42506)
			(xy 399.696693 -168.480236) (xy 399.680625 -168.533643) (xy 399.656953 -168.58414) (xy 399.62618 -168.630653)
			(xy 399.588963 -168.67219) (xy 399.546095 -168.707865) (xy 399.498489 -168.736919) (xy 399.44716 -168.758731)
			(xy 399.393203 -168.772837) (xy 399.337766 -168.778937) (xy 399.282032 -168.7769) (xy 399.227189 -168.76677)
			(xy 399.174405 -168.748763) (xy 399.124805 -168.723262) (xy 399.079447 -168.690811) (xy 399.039298 -168.652102)
			(xy 399.005212 -168.607959) (xy 398.977916 -168.559324) (xy 398.957993 -168.507233) (xy 398.945867 -168.452796)
			(xy 398.941796 -168.397174) (xy 396.701579 -168.397174) (xy 396.768066 -168.646856) (xy 396.769756 -168.652584)
			(xy 396.77541 -168.663102) (xy 396.779242 -168.667684) (xy 396.785592 -168.674796) (xy 396.795244 -168.679622)
			(xy 396.79626 -168.68013) (xy 396.820513 -168.692025) (xy 396.865691 -168.721637) (xy 396.906239 -168.757327)
			(xy 396.941345 -168.798381) (xy 396.970307 -168.843979) (xy 396.992544 -168.893207) (xy 397.007613 -168.94508)
			(xy 397.015212 -168.998561) (xy 397.015716 -169.02557) (xy 397.015178 -169.054851) (xy 397.006223 -169.112724)
			(xy 396.988534 -169.168551) (xy 396.962526 -169.221021) (xy 396.94612 -169.24528) (xy 396.942978 -169.249954)
			(xy 396.938618 -169.260337) (xy 396.937484 -169.265854) (xy 396.935706 -169.276522) (xy 397.005302 -169.537888)
			(xy 397.008258 -169.547365) (xy 397.02017 -169.56322) (xy 397.03721 -169.573363) (xy 397.046958 -169.575226)
			(xy 397.149066 -169.583608) (xy 397.157992 -169.583392) (xy 397.174836 -169.577507) (xy 397.188634 -169.566194)
			(xy 397.193516 -169.558716) (xy 397.195802 -169.553636) (xy 397.207512 -169.528923) (xy 397.236955 -169.482839)
			(xy 397.272671 -169.441427) (xy 397.313929 -169.405534) (xy 397.359887 -169.375895) (xy 397.409603 -169.353115)
			(xy 397.46206 -169.337661) (xy 397.516185 -169.329849) (xy 397.543528 -169.329354) (xy 397.570781 -169.329842)
			(xy 397.624731 -169.337602) (xy 397.677027 -169.352961) (xy 397.726606 -169.375606) (xy 397.772457 -169.405076)
			(xy 397.813648 -169.440771) (xy 397.84934 -169.481965) (xy 397.878807 -169.527819) (xy 397.901448 -169.577399)
			(xy 397.916804 -169.629697) (xy 397.92456 -169.683647) (xy 397.92456 -169.738153) (xy 397.916804 -169.792103)
			(xy 397.901448 -169.844401) (xy 397.878807 -169.893981) (xy 397.84934 -169.939835) (xy 397.813648 -169.981029)
			(xy 397.772457 -170.016724) (xy 397.726606 -170.046194) (xy 397.677027 -170.068839) (xy 397.624731 -170.084198)
			(xy 397.570781 -170.091958) (xy 397.543528 -170.09237) (xy 397.54302 -170.09237) (xy 397.513224 -170.091781)
			(xy 397.454361 -170.082484) (xy 397.39766 -170.064145) (xy 397.344503 -170.037209) (xy 397.320008 -170.020234)
			(xy 397.31141 -170.014618) (xy 397.291396 -170.010096) (xy 397.271207 -170.013761) (xy 397.26235 -170.018964)
			(xy 397.220186 -170.048174) (xy 397.182848 -170.073828) (xy 397.174898 -170.079891) (xy 397.164029 -170.096648)
			(xy 397.160397 -170.116287) (xy 397.16202 -170.126152) (xy 397.400018 -171.020994) (xy 397.598392 -171.765722)
			(xy 397.600363 -171.772209) (xy 397.607182 -171.783923) (xy 397.611854 -171.788836) (xy 397.616426 -171.793408)
			(xy 397.628364 -171.800266) (xy 397.635222 -171.80179) (xy 397.663129 -171.809253) (xy 397.716465 -171.831439)
			(xy 397.765849 -171.861407) (xy 397.810153 -171.898474) (xy 397.848367 -171.941794) (xy 397.876926 -171.986194)
			(xy 398.254218 -171.986194) (xy 398.258289 -171.930572) (xy 398.270415 -171.876135) (xy 398.290338 -171.824044)
			(xy 398.317634 -171.775409) (xy 398.35172 -171.731266) (xy 398.391869 -171.692557) (xy 398.437227 -171.660106)
			(xy 398.486827 -171.634605) (xy 398.539611 -171.616598) (xy 398.594454 -171.606468) (xy 398.650188 -171.604431)
			(xy 398.705625 -171.610531) (xy 398.759582 -171.624637) (xy 398.810911 -171.646449) (xy 398.858517 -171.675503)
			(xy 398.901385 -171.711178) (xy 398.938602 -171.752715) (xy 398.969375 -171.799228) (xy 398.993047 -171.849725)
			(xy 399.009115 -171.903132) (xy 399.017235 -171.958308) (xy 399.017744 -171.986194) (xy 399.017235 -172.01408)
			(xy 399.009115 -172.069256) (xy 398.993047 -172.122663) (xy 398.969375 -172.17316) (xy 398.938602 -172.219673)
			(xy 398.901385 -172.26121) (xy 398.858517 -172.296885) (xy 398.810911 -172.325939) (xy 398.759582 -172.347751)
			(xy 398.705625 -172.361857) (xy 398.650188 -172.367957) (xy 398.594454 -172.36592) (xy 398.539611 -172.35579)
			(xy 398.486827 -172.337783) (xy 398.437227 -172.312282) (xy 398.391869 -172.279831) (xy 398.35172 -172.241122)
			(xy 398.317634 -172.196979) (xy 398.290338 -172.148344) (xy 398.270415 -172.096253) (xy 398.258289 -172.041816)
			(xy 398.254218 -171.986194) (xy 397.876926 -171.986194) (xy 397.879617 -171.990377) (xy 397.90319 -172.043114)
			(xy 397.918548 -172.098801) (xy 397.922496 -172.127418) (xy 397.92402 -172.141134) (xy 397.925833 -172.170017)
			(xy 397.921772 -172.227743) (xy 397.909051 -172.284197) (xy 397.887962 -172.338086) (xy 397.858988 -172.38818)
			(xy 397.842213 -172.409104) (xy 400.429982 -172.409104) (xy 400.434053 -172.353482) (xy 400.446179 -172.299045)
			(xy 400.466102 -172.246954) (xy 400.493398 -172.198319) (xy 400.527484 -172.154176) (xy 400.567633 -172.115467)
			(xy 400.612991 -172.083016) (xy 400.662591 -172.057515) (xy 400.715375 -172.039508) (xy 400.770218 -172.029378)
			(xy 400.825952 -172.027341) (xy 400.881389 -172.033441) (xy 400.935346 -172.047547) (xy 400.986675 -172.069359)
			(xy 401.034281 -172.098413) (xy 401.077149 -172.134088) (xy 401.114366 -172.175625) (xy 401.145139 -172.222138)
			(xy 401.168811 -172.272635) (xy 401.184879 -172.326042) (xy 401.185366 -172.329348) (xy 410.148022 -172.329348)
			(xy 410.152093 -172.273726) (xy 410.164219 -172.219289) (xy 410.184142 -172.167198) (xy 410.211438 -172.118563)
			(xy 410.245524 -172.07442) (xy 410.285673 -172.035711) (xy 410.331031 -172.00326) (xy 410.380631 -171.977759)
			(xy 410.433415 -171.959752) (xy 410.488258 -171.949622) (xy 410.543992 -171.947585) (xy 410.599429 -171.953685)
			(xy 410.653386 -171.967791) (xy 410.704715 -171.989603) (xy 410.752321 -172.018657) (xy 410.795189 -172.054332)
			(xy 410.832406 -172.095869) (xy 410.863179 -172.142382) (xy 410.886851 -172.192879) (xy 410.902919 -172.246286)
			(xy 410.911039 -172.301462) (xy 410.911548 -172.329348) (xy 410.911284 -172.343826) (xy 411.085282 -172.343826)
			(xy 411.089353 -172.288204) (xy 411.101479 -172.233767) (xy 411.121402 -172.181676) (xy 411.148698 -172.133041)
			(xy 411.182784 -172.088898) (xy 411.222933 -172.050189) (xy 411.268291 -172.017738) (xy 411.317891 -171.992237)
			(xy 411.370675 -171.97423) (xy 411.425518 -171.9641) (xy 411.481252 -171.962063) (xy 411.536689 -171.968163)
			(xy 411.590646 -171.982269) (xy 411.641975 -172.004081) (xy 411.689581 -172.033135) (xy 411.732449 -172.06881)
			(xy 411.769666 -172.110347) (xy 411.800439 -172.15686) (xy 411.824111 -172.207357) (xy 411.840179 -172.260764)
			(xy 411.848299 -172.31594) (xy 411.848808 -172.343826) (xy 411.848299 -172.371712) (xy 411.840179 -172.426888)
			(xy 411.824111 -172.480295) (xy 411.800439 -172.530792) (xy 411.769666 -172.577305) (xy 411.732449 -172.618842)
			(xy 411.689581 -172.654517) (xy 411.641975 -172.683571) (xy 411.590646 -172.705383) (xy 411.536689 -172.719489)
			(xy 411.481252 -172.725589) (xy 411.425518 -172.723552) (xy 411.370675 -172.713422) (xy 411.317891 -172.695415)
			(xy 411.268291 -172.669914) (xy 411.222933 -172.637463) (xy 411.182784 -172.598754) (xy 411.148698 -172.554611)
			(xy 411.121402 -172.505976) (xy 411.101479 -172.453885) (xy 411.089353 -172.399448) (xy 411.085282 -172.343826)
			(xy 410.911284 -172.343826) (xy 410.911039 -172.357234) (xy 410.902919 -172.41241) (xy 410.886851 -172.465817)
			(xy 410.863179 -172.516314) (xy 410.832406 -172.562827) (xy 410.795189 -172.604364) (xy 410.752321 -172.640039)
			(xy 410.704715 -172.669093) (xy 410.653386 -172.690905) (xy 410.599429 -172.705011) (xy 410.543992 -172.711111)
			(xy 410.488258 -172.709074) (xy 410.433415 -172.698944) (xy 410.380631 -172.680937) (xy 410.331031 -172.655436)
			(xy 410.285673 -172.622985) (xy 410.245524 -172.584276) (xy 410.211438 -172.540133) (xy 410.184142 -172.491498)
			(xy 410.164219 -172.439407) (xy 410.152093 -172.38497) (xy 410.148022 -172.329348) (xy 401.185366 -172.329348)
			(xy 401.192999 -172.381218) (xy 401.193508 -172.409104) (xy 401.192999 -172.43699) (xy 401.184879 -172.492166)
			(xy 401.168811 -172.545573) (xy 401.145139 -172.59607) (xy 401.114366 -172.642583) (xy 401.077149 -172.68412)
			(xy 401.034281 -172.719795) (xy 400.986675 -172.748849) (xy 400.935346 -172.770661) (xy 400.881389 -172.784767)
			(xy 400.825952 -172.790867) (xy 400.770218 -172.78883) (xy 400.715375 -172.7787) (xy 400.662591 -172.760693)
			(xy 400.612991 -172.735192) (xy 400.567633 -172.702741) (xy 400.527484 -172.664032) (xy 400.493398 -172.619889)
			(xy 400.466102 -172.571254) (xy 400.446179 -172.519163) (xy 400.434053 -172.464726) (xy 400.429982 -172.409104)
			(xy 397.842213 -172.409104) (xy 397.822791 -172.43333) (xy 397.801846 -172.4533) (xy 397.79702 -172.458126)
			(xy 397.793464 -172.47108) (xy 397.791795 -172.477702) (xy 397.791666 -172.491352) (xy 397.79321 -172.498004)
			(xy 397.907764 -172.927772) (xy 398.211802 -174.069756) (xy 398.21509 -174.080053) (xy 398.228771 -174.096762)
			(xy 398.238218 -174.102014) (xy 398.267936 -174.116746) (xy 398.307052 -174.136304) (xy 398.311956 -174.138624)
			(xy 398.322465 -174.141305) (xy 398.32788 -174.141638) (xy 398.337786 -174.141892) (xy 398.346422 -174.138336)
			(xy 398.369691 -174.129084) (xy 398.418046 -174.116074) (xy 398.467689 -174.109514) (xy 398.492726 -174.109126)
			(xy 398.494504 -174.109126) (xy 398.514062 -174.109634) (xy 398.525238 -174.110396) (xy 398.537006 -174.111481)
			(xy 398.56039 -174.114915) (xy 398.571974 -174.117254) (xy 398.596866 -174.122897) (xy 398.644969 -174.13996)
			(xy 398.690362 -174.163298) (xy 398.732228 -174.192492) (xy 398.733024 -174.1932) (xy 408.892246 -174.1932)
			(xy 408.896317 -174.137578) (xy 408.908443 -174.083141) (xy 408.928366 -174.03105) (xy 408.955662 -173.982415)
			(xy 408.989748 -173.938272) (xy 409.029897 -173.899563) (xy 409.075255 -173.867112) (xy 409.124855 -173.841611)
			(xy 409.177639 -173.823604) (xy 409.232482 -173.813474) (xy 409.288216 -173.811437) (xy 409.343653 -173.817537)
			(xy 409.39761 -173.831643) (xy 409.448939 -173.853455) (xy 409.496545 -173.882509) (xy 409.539413 -173.918184)
			(xy 409.57663 -173.959721) (xy 409.607403 -174.006234) (xy 409.631075 -174.056731) (xy 409.647143 -174.110138)
			(xy 409.655263 -174.165314) (xy 409.655772 -174.1932) (xy 409.655263 -174.221086) (xy 409.647143 -174.276262)
			(xy 409.631075 -174.329669) (xy 409.607403 -174.380166) (xy 409.57663 -174.426679) (xy 409.539413 -174.468216)
			(xy 409.496545 -174.503891) (xy 409.448939 -174.532945) (xy 409.39761 -174.554757) (xy 409.343653 -174.568863)
			(xy 409.288216 -174.574963) (xy 409.232482 -174.572926) (xy 409.177639 -174.562796) (xy 409.124855 -174.544789)
			(xy 409.075255 -174.519288) (xy 409.029897 -174.486837) (xy 408.989748 -174.448128) (xy 408.955662 -174.403985)
			(xy 408.928366 -174.35535) (xy 408.908443 -174.303259) (xy 408.896317 -174.248822) (xy 408.892246 -174.1932)
			(xy 398.733024 -174.1932) (xy 398.751298 -174.209456) (xy 398.777968 -174.23638) (xy 398.796133 -174.257481)
			(xy 398.826791 -174.303956) (xy 398.850378 -174.35439) (xy 398.866395 -174.407713) (xy 398.874501 -174.462796)
			(xy 398.874996 -174.490634) (xy 398.874509 -174.51786) (xy 398.866762 -174.571759) (xy 398.851429 -174.624008)
			(xy 398.828823 -174.673547) (xy 398.799403 -174.719367) (xy 398.763766 -174.760539) (xy 398.722638 -174.796226)
			(xy 398.676853 -174.825701) (xy 398.627342 -174.848367) (xy 398.575111 -174.863763) (xy 398.521222 -174.871576)
			(xy 398.493996 -174.872142) (xy 398.484852 -174.872142) (xy 398.478502 -174.87392) (xy 398.476978 -174.874428)
			(xy 398.467702 -174.877676) (xy 398.452379 -174.889955) (xy 398.442776 -174.907082) (xy 398.440294 -174.926561)
			(xy 398.442434 -174.93615) (xy 398.680412 -175.83023) (xy 410.059884 -175.83023) (xy 410.063955 -175.774608)
			(xy 410.076081 -175.720171) (xy 410.096004 -175.66808) (xy 410.1233 -175.619445) (xy 410.157386 -175.575302)
			(xy 410.197535 -175.536593) (xy 410.242893 -175.504142) (xy 410.292493 -175.478641) (xy 410.345277 -175.460634)
			(xy 410.40012 -175.450504) (xy 410.455854 -175.448467) (xy 410.511291 -175.454567) (xy 410.565248 -175.468673)
			(xy 410.616577 -175.490485) (xy 410.664183 -175.519539) (xy 410.707051 -175.555214) (xy 410.744268 -175.596751)
			(xy 410.775041 -175.643264) (xy 410.798713 -175.693761) (xy 410.814781 -175.747168) (xy 410.822901 -175.802344)
			(xy 410.82341 -175.83023) (xy 410.822901 -175.858116) (xy 410.814781 -175.913292) (xy 410.798713 -175.966699)
			(xy 410.775041 -176.017196) (xy 410.744268 -176.063709) (xy 410.707051 -176.105246) (xy 410.664183 -176.140921)
			(xy 410.616577 -176.169975) (xy 410.565248 -176.191787) (xy 410.511291 -176.205893) (xy 410.455854 -176.211993)
			(xy 410.40012 -176.209956) (xy 410.345277 -176.199826) (xy 410.292493 -176.181819) (xy 410.242893 -176.156318)
			(xy 410.197535 -176.123867) (xy 410.157386 -176.085158) (xy 410.1233 -176.041015) (xy 410.096004 -175.99238)
			(xy 410.076081 -175.940289) (xy 410.063955 -175.885852) (xy 410.059884 -175.83023) (xy 398.680412 -175.83023)
			(xy 399.278602 -178.077622) (xy 399.603724 -179.2986) (xy 409.269182 -179.2986) (xy 409.273253 -179.242978)
			(xy 409.285379 -179.188541) (xy 409.305302 -179.13645) (xy 409.332598 -179.087815) (xy 409.366684 -179.043672)
			(xy 409.406833 -179.004963) (xy 409.452191 -178.972512) (xy 409.501791 -178.947011) (xy 409.554575 -178.929004)
			(xy 409.609418 -178.918874) (xy 409.665152 -178.916837) (xy 409.720589 -178.922937) (xy 409.774546 -178.937043)
			(xy 409.825875 -178.958855) (xy 409.873481 -178.987909) (xy 409.916349 -179.023584) (xy 409.953566 -179.065121)
			(xy 409.984339 -179.111634) (xy 410.008011 -179.162131) (xy 410.024079 -179.215538) (xy 410.032199 -179.270714)
			(xy 410.032708 -179.2986) (xy 411.250382 -179.2986) (xy 411.254453 -179.242978) (xy 411.266579 -179.188541)
			(xy 411.286502 -179.13645) (xy 411.313798 -179.087815) (xy 411.347884 -179.043672) (xy 411.388033 -179.004963)
			(xy 411.433391 -178.972512) (xy 411.482991 -178.947011) (xy 411.535775 -178.929004) (xy 411.590618 -178.918874)
			(xy 411.646352 -178.916837) (xy 411.701789 -178.922937) (xy 411.755746 -178.937043) (xy 411.807075 -178.958855)
			(xy 411.854681 -178.987909) (xy 411.897549 -179.023584) (xy 411.934766 -179.065121) (xy 411.965539 -179.111634)
			(xy 411.989211 -179.162131) (xy 412.005279 -179.215538) (xy 412.013399 -179.270714) (xy 412.013908 -179.2986)
			(xy 412.013399 -179.326486) (xy 412.005279 -179.381662) (xy 411.989211 -179.435069) (xy 411.965539 -179.485566)
			(xy 411.934766 -179.532079) (xy 411.897549 -179.573616) (xy 411.854681 -179.609291) (xy 411.807075 -179.638345)
			(xy 411.755746 -179.660157) (xy 411.701789 -179.674263) (xy 411.646352 -179.680363) (xy 411.590618 -179.678326)
			(xy 411.535775 -179.668196) (xy 411.482991 -179.650189) (xy 411.433391 -179.624688) (xy 411.388033 -179.592237)
			(xy 411.347884 -179.553528) (xy 411.313798 -179.509385) (xy 411.286502 -179.46075) (xy 411.266579 -179.408659)
			(xy 411.254453 -179.354222) (xy 411.250382 -179.2986) (xy 410.032708 -179.2986) (xy 410.032199 -179.326486)
			(xy 410.024079 -179.381662) (xy 410.008011 -179.435069) (xy 409.984339 -179.485566) (xy 409.953566 -179.532079)
			(xy 409.916349 -179.573616) (xy 409.873481 -179.609291) (xy 409.825875 -179.638345) (xy 409.774546 -179.660157)
			(xy 409.720589 -179.674263) (xy 409.665152 -179.680363) (xy 409.609418 -179.678326) (xy 409.554575 -179.668196)
			(xy 409.501791 -179.650189) (xy 409.452191 -179.624688) (xy 409.406833 -179.592237) (xy 409.366684 -179.553528)
			(xy 409.332598 -179.509385) (xy 409.305302 -179.46075) (xy 409.285379 -179.408659) (xy 409.273253 -179.354222)
			(xy 409.269182 -179.2986) (xy 399.603724 -179.2986) (xy 399.640044 -179.434998) (xy 399.643957 -179.446103)
			(xy 399.659982 -179.463316) (xy 399.670778 -179.468018) (xy 399.677128 -179.469796) (xy 399.763996 -179.49037)
			(xy 399.772419 -179.492051) (xy 399.7895 -179.490343) (xy 399.805073 -179.483123) (xy 399.811494 -179.477416)
			(xy 399.81378 -179.474622) (xy 399.831969 -179.454901) (xy 399.872923 -179.420246) (xy 399.918324 -179.391665)
			(xy 399.967279 -179.36972) (xy 400.018824 -179.354844) (xy 400.071944 -179.34733) (xy 400.098768 -179.34686)
			(xy 400.126025 -179.347321) (xy 400.179984 -179.355075) (xy 400.23229 -179.370429) (xy 400.281878 -179.393072)
			(xy 400.327739 -179.422541) (xy 400.368939 -179.458238) (xy 400.404639 -179.499435) (xy 400.434113 -179.545294)
			(xy 400.45676 -179.59488) (xy 400.472119 -179.647185) (xy 400.479877 -179.701143) (xy 400.479877 -179.755657)
			(xy 400.472119 -179.809615) (xy 400.45676 -179.86192) (xy 400.434113 -179.911506) (xy 400.404639 -179.957365)
			(xy 400.368939 -179.998562) (xy 400.327739 -180.034259) (xy 400.281878 -180.063728) (xy 400.23229 -180.086371)
			(xy 400.179984 -180.101725) (xy 400.126025 -180.109479) (xy 400.098768 -180.109876) (xy 400.067924 -180.10926)
			(xy 400.007045 -180.099302) (xy 399.97761 -180.090064) (xy 399.977356 -180.090064) (xy 399.968573 -180.087561)
			(xy 399.950336 -180.088264) (xy 399.933497 -180.095302) (xy 399.926556 -180.10124) (xy 399.861278 -180.162454)
			(xy 399.85491 -180.169007) (xy 399.846876 -180.185404) (xy 399.845071 -180.203573) (xy 399.847054 -180.212492)
			(xy 399.976819 -180.699918) (xy 413.180782 -180.699918) (xy 413.184853 -180.644296) (xy 413.196979 -180.589859)
			(xy 413.216902 -180.537768) (xy 413.244198 -180.489133) (xy 413.278284 -180.44499) (xy 413.318433 -180.406281)
			(xy 413.363791 -180.37383) (xy 413.413391 -180.348329) (xy 413.466175 -180.330322) (xy 413.521018 -180.320192)
			(xy 413.576752 -180.318155) (xy 413.632189 -180.324255) (xy 413.686146 -180.338361) (xy 413.737475 -180.360173)
			(xy 413.785081 -180.389227) (xy 413.827949 -180.424902) (xy 413.865166 -180.466439) (xy 413.895939 -180.512952)
			(xy 413.919611 -180.563449) (xy 413.935679 -180.616856) (xy 413.943799 -180.672032) (xy 413.944308 -180.699918)
			(xy 413.943799 -180.727804) (xy 413.935679 -180.78298) (xy 413.919611 -180.836387) (xy 413.895939 -180.886884)
			(xy 413.865166 -180.933397) (xy 413.827949 -180.974934) (xy 413.785081 -181.010609) (xy 413.737475 -181.039663)
			(xy 413.686146 -181.061475) (xy 413.632189 -181.075581) (xy 413.576752 -181.081681) (xy 413.521018 -181.079644)
			(xy 413.466175 -181.069514) (xy 413.413391 -181.051507) (xy 413.363791 -181.026006) (xy 413.318433 -180.993555)
			(xy 413.278284 -180.954846) (xy 413.244198 -180.910703) (xy 413.216902 -180.862068) (xy 413.196979 -180.809977)
			(xy 413.184853 -180.75554) (xy 413.180782 -180.699918) (xy 399.976819 -180.699918) (xy 400.721327 -183.496458)
			(xy 408.81884 -183.496458) (xy 408.822911 -183.440836) (xy 408.835037 -183.386399) (xy 408.85496 -183.334308)
			(xy 408.882256 -183.285673) (xy 408.916342 -183.24153) (xy 408.956491 -183.202821) (xy 409.001849 -183.17037)
			(xy 409.051449 -183.144869) (xy 409.104233 -183.126862) (xy 409.159076 -183.116732) (xy 409.21481 -183.114695)
			(xy 409.270247 -183.120795) (xy 409.324204 -183.134901) (xy 409.375533 -183.156713) (xy 409.423139 -183.185767)
			(xy 409.466007 -183.221442) (xy 409.503224 -183.262979) (xy 409.533997 -183.309492) (xy 409.557669 -183.359989)
			(xy 409.573737 -183.413396) (xy 409.581857 -183.468572) (xy 409.582366 -183.496458) (xy 409.581857 -183.524344)
			(xy 409.573737 -183.57952) (xy 409.557669 -183.632927) (xy 409.533997 -183.683424) (xy 409.527794 -183.6928)
			(xy 411.224982 -183.6928) (xy 411.229053 -183.637178) (xy 411.241179 -183.582741) (xy 411.261102 -183.53065)
			(xy 411.288398 -183.482015) (xy 411.322484 -183.437872) (xy 411.362633 -183.399163) (xy 411.407991 -183.366712)
			(xy 411.457591 -183.341211) (xy 411.510375 -183.323204) (xy 411.565218 -183.313074) (xy 411.620952 -183.311037)
			(xy 411.676389 -183.317137) (xy 411.730346 -183.331243) (xy 411.781675 -183.353055) (xy 411.829281 -183.382109)
			(xy 411.872149 -183.417784) (xy 411.909366 -183.459321) (xy 411.940139 -183.505834) (xy 411.963811 -183.556331)
			(xy 411.979879 -183.609738) (xy 411.987999 -183.664914) (xy 411.988508 -183.6928) (xy 411.987999 -183.720686)
			(xy 411.979879 -183.775862) (xy 411.963811 -183.829269) (xy 411.940139 -183.879766) (xy 411.909366 -183.926279)
			(xy 411.872149 -183.967816) (xy 411.829281 -184.003491) (xy 411.781675 -184.032545) (xy 411.730346 -184.054357)
			(xy 411.676389 -184.068463) (xy 411.620952 -184.074563) (xy 411.565218 -184.072526) (xy 411.510375 -184.062396)
			(xy 411.457591 -184.044389) (xy 411.407991 -184.018888) (xy 411.362633 -183.986437) (xy 411.322484 -183.947728)
			(xy 411.288398 -183.903585) (xy 411.261102 -183.85495) (xy 411.241179 -183.802859) (xy 411.229053 -183.748422)
			(xy 411.224982 -183.6928) (xy 409.527794 -183.6928) (xy 409.503224 -183.729937) (xy 409.466007 -183.771474)
			(xy 409.423139 -183.807149) (xy 409.375533 -183.836203) (xy 409.324204 -183.858015) (xy 409.270247 -183.872121)
			(xy 409.21481 -183.878221) (xy 409.159076 -183.876184) (xy 409.104233 -183.866054) (xy 409.051449 -183.848047)
			(xy 409.001849 -183.822546) (xy 408.956491 -183.790095) (xy 408.916342 -183.751386) (xy 408.882256 -183.707243)
			(xy 408.85496 -183.658608) (xy 408.835037 -183.606517) (xy 408.822911 -183.55208) (xy 408.81884 -183.496458)
			(xy 400.721327 -183.496458) (xy 401.106091 -184.941718) (xy 414.979864 -184.941718) (xy 414.983935 -184.886096)
			(xy 414.996061 -184.831659) (xy 415.015984 -184.779568) (xy 415.04328 -184.730933) (xy 415.077366 -184.68679)
			(xy 415.117515 -184.648081) (xy 415.162873 -184.61563) (xy 415.212473 -184.590129) (xy 415.265257 -184.572122)
			(xy 415.3201 -184.561992) (xy 415.375834 -184.559955) (xy 415.431271 -184.566055) (xy 415.485228 -184.580161)
			(xy 415.536557 -184.601973) (xy 415.584163 -184.631027) (xy 415.627031 -184.666702) (xy 415.664248 -184.708239)
			(xy 415.695021 -184.754752) (xy 415.718693 -184.805249) (xy 415.734761 -184.858656) (xy 415.742881 -184.913832)
			(xy 415.74339 -184.941718) (xy 415.742881 -184.969604) (xy 415.734761 -185.02478) (xy 415.718693 -185.078187)
			(xy 415.695021 -185.128684) (xy 415.664248 -185.175197) (xy 415.627031 -185.216734) (xy 415.584163 -185.252409)
			(xy 415.536557 -185.281463) (xy 415.485228 -185.303275) (xy 415.431271 -185.317381) (xy 415.375834 -185.323481)
			(xy 415.3201 -185.321444) (xy 415.265257 -185.311314) (xy 415.212473 -185.293307) (xy 415.162873 -185.267806)
			(xy 415.117515 -185.235355) (xy 415.077366 -185.196646) (xy 415.04328 -185.152503) (xy 415.015984 -185.103868)
			(xy 414.996061 -185.051777) (xy 414.983935 -184.99734) (xy 414.979864 -184.941718) (xy 401.106091 -184.941718)
			(xy 401.637322 -186.937142) (xy 408.89504 -186.937142) (xy 408.899111 -186.88152) (xy 408.911237 -186.827083)
			(xy 408.93116 -186.774992) (xy 408.958456 -186.726357) (xy 408.992542 -186.682214) (xy 409.032691 -186.643505)
			(xy 409.078049 -186.611054) (xy 409.127649 -186.585553) (xy 409.180433 -186.567546) (xy 409.235276 -186.557416)
			(xy 409.29101 -186.555379) (xy 409.346447 -186.561479) (xy 409.400404 -186.575585) (xy 409.451733 -186.597397)
			(xy 409.499339 -186.626451) (xy 409.542207 -186.662126) (xy 409.579424 -186.703663) (xy 409.610197 -186.750176)
			(xy 409.633869 -186.800673) (xy 409.649937 -186.85408) (xy 409.658057 -186.909256) (xy 409.658566 -186.937142)
			(xy 409.658057 -186.965028) (xy 409.649937 -187.020204) (xy 409.633869 -187.073611) (xy 409.610197 -187.124108)
			(xy 409.579424 -187.170621) (xy 409.542207 -187.212158) (xy 409.499339 -187.247833) (xy 409.451733 -187.276887)
			(xy 409.400404 -187.298699) (xy 409.346447 -187.312805) (xy 409.29101 -187.318905) (xy 409.235276 -187.316868)
			(xy 409.180433 -187.306738) (xy 409.127649 -187.288731) (xy 409.078049 -187.26323) (xy 409.032691 -187.230779)
			(xy 408.992542 -187.19207) (xy 408.958456 -187.147927) (xy 408.93116 -187.099292) (xy 408.911237 -187.047201)
			(xy 408.899111 -186.992764) (xy 408.89504 -186.937142) (xy 401.637322 -186.937142) (xy 401.794676 -187.5282)
			(xy 411.123382 -187.5282) (xy 411.127453 -187.472578) (xy 411.139579 -187.418141) (xy 411.159502 -187.36605)
			(xy 411.186798 -187.317415) (xy 411.220884 -187.273272) (xy 411.261033 -187.234563) (xy 411.306391 -187.202112)
			(xy 411.355991 -187.176611) (xy 411.408775 -187.158604) (xy 411.463618 -187.148474) (xy 411.519352 -187.146437)
			(xy 411.574789 -187.152537) (xy 411.628746 -187.166643) (xy 411.680075 -187.188455) (xy 411.727681 -187.217509)
			(xy 411.770549 -187.253184) (xy 411.807766 -187.294721) (xy 411.838539 -187.341234) (xy 411.862211 -187.391731)
			(xy 411.878279 -187.445138) (xy 411.886399 -187.500314) (xy 411.886908 -187.5282) (xy 411.886399 -187.556086)
			(xy 411.878279 -187.611262) (xy 411.862211 -187.664669) (xy 411.838539 -187.715166) (xy 411.807766 -187.761679)
			(xy 411.770549 -187.803216) (xy 411.727681 -187.838891) (xy 411.680075 -187.867945) (xy 411.628746 -187.889757)
			(xy 411.574789 -187.903863) (xy 411.519352 -187.909963) (xy 411.463618 -187.907926) (xy 411.408775 -187.897796)
			(xy 411.355991 -187.879789) (xy 411.306391 -187.854288) (xy 411.261033 -187.821837) (xy 411.220884 -187.783128)
			(xy 411.186798 -187.738985) (xy 411.159502 -187.69035) (xy 411.139579 -187.638259) (xy 411.127453 -187.583822)
			(xy 411.123382 -187.5282) (xy 401.794676 -187.5282) (xy 402.215077 -189.107318) (xy 410.255464 -189.107318)
			(xy 410.259535 -189.051696) (xy 410.271661 -188.997259) (xy 410.291584 -188.945168) (xy 410.31888 -188.896533)
			(xy 410.352966 -188.85239) (xy 410.393115 -188.813681) (xy 410.438473 -188.78123) (xy 410.488073 -188.755729)
			(xy 410.540857 -188.737722) (xy 410.5957 -188.727592) (xy 410.651434 -188.725555) (xy 410.706871 -188.731655)
			(xy 410.760828 -188.745761) (xy 410.812157 -188.767573) (xy 410.859763 -188.796627) (xy 410.902631 -188.832302)
			(xy 410.939848 -188.873839) (xy 410.970621 -188.920352) (xy 410.994293 -188.970849) (xy 411.010361 -189.024256)
			(xy 411.018481 -189.079432) (xy 411.01899 -189.107318) (xy 411.018481 -189.135204) (xy 411.010361 -189.19038)
			(xy 410.994293 -189.243787) (xy 410.970621 -189.294284) (xy 410.939848 -189.340797) (xy 410.902631 -189.382334)
			(xy 410.859763 -189.418009) (xy 410.812157 -189.447063) (xy 410.760828 -189.468875) (xy 410.706871 -189.482981)
			(xy 410.651434 -189.489081) (xy 410.5957 -189.487044) (xy 410.540857 -189.476914) (xy 410.488073 -189.458907)
			(xy 410.438473 -189.433406) (xy 410.393115 -189.400955) (xy 410.352966 -189.362246) (xy 410.31888 -189.318103)
			(xy 410.291584 -189.269468) (xy 410.271661 -189.217377) (xy 410.259535 -189.16294) (xy 410.255464 -189.107318)
			(xy 402.215077 -189.107318) (xy 402.402455 -189.811152) (xy 413.217104 -189.811152) (xy 413.221175 -189.75553)
			(xy 413.233301 -189.701093) (xy 413.253224 -189.649002) (xy 413.28052 -189.600367) (xy 413.314606 -189.556224)
			(xy 413.354755 -189.517515) (xy 413.400113 -189.485064) (xy 413.449713 -189.459563) (xy 413.502497 -189.441556)
			(xy 413.55734 -189.431426) (xy 413.613074 -189.429389) (xy 413.668511 -189.435489) (xy 413.722468 -189.449595)
			(xy 413.773797 -189.471407) (xy 413.821403 -189.500461) (xy 413.864271 -189.536136) (xy 413.901488 -189.577673)
			(xy 413.932261 -189.624186) (xy 413.955933 -189.674683) (xy 413.972001 -189.72809) (xy 413.980121 -189.783266)
			(xy 413.98063 -189.811152) (xy 413.980121 -189.839038) (xy 413.972001 -189.894214) (xy 413.955933 -189.947621)
			(xy 413.932261 -189.998118) (xy 413.901488 -190.044631) (xy 413.864271 -190.086168) (xy 413.821403 -190.121843)
			(xy 413.773797 -190.150897) (xy 413.722468 -190.172709) (xy 413.668511 -190.186815) (xy 413.613074 -190.192915)
			(xy 413.55734 -190.190878) (xy 413.502497 -190.180748) (xy 413.449713 -190.162741) (xy 413.400113 -190.13724)
			(xy 413.354755 -190.104789) (xy 413.314606 -190.06608) (xy 413.28052 -190.021937) (xy 413.253224 -189.973302)
			(xy 413.233301 -189.921211) (xy 413.221175 -189.866774) (xy 413.217104 -189.811152) (xy 402.402455 -189.811152)
			(xy 403.358549 -193.402458) (xy 409.211524 -193.402458) (xy 409.215595 -193.346836) (xy 409.227721 -193.292399)
			(xy 409.247644 -193.240308) (xy 409.27494 -193.191673) (xy 409.309026 -193.14753) (xy 409.349175 -193.108821)
			(xy 409.394533 -193.07637) (xy 409.444133 -193.050869) (xy 409.496917 -193.032862) (xy 409.55176 -193.022732)
			(xy 409.607494 -193.020695) (xy 409.662931 -193.026795) (xy 409.716888 -193.040901) (xy 409.768217 -193.062713)
			(xy 409.815823 -193.091767) (xy 409.858691 -193.127442) (xy 409.895908 -193.168979) (xy 409.926681 -193.215492)
			(xy 409.950353 -193.265989) (xy 409.951139 -193.2686) (xy 412.113982 -193.2686) (xy 412.118053 -193.212978)
			(xy 412.130179 -193.158541) (xy 412.150102 -193.10645) (xy 412.177398 -193.057815) (xy 412.211484 -193.013672)
			(xy 412.251633 -192.974963) (xy 412.296991 -192.942512) (xy 412.346591 -192.917011) (xy 412.399375 -192.899004)
			(xy 412.454218 -192.888874) (xy 412.509952 -192.886837) (xy 412.565389 -192.892937) (xy 412.619346 -192.907043)
			(xy 412.670675 -192.928855) (xy 412.718281 -192.957909) (xy 412.761149 -192.993584) (xy 412.798366 -193.035121)
			(xy 412.829139 -193.081634) (xy 412.852811 -193.132131) (xy 412.868879 -193.185538) (xy 412.876999 -193.240714)
			(xy 412.877508 -193.2686) (xy 412.876999 -193.296486) (xy 412.868879 -193.351662) (xy 412.852811 -193.405069)
			(xy 412.829139 -193.455566) (xy 412.798366 -193.502079) (xy 412.761149 -193.543616) (xy 412.718281 -193.579291)
			(xy 412.670675 -193.608345) (xy 412.619346 -193.630157) (xy 412.565389 -193.644263) (xy 412.509952 -193.650363)
			(xy 412.454218 -193.648326) (xy 412.399375 -193.638196) (xy 412.346591 -193.620189) (xy 412.296991 -193.594688)
			(xy 412.251633 -193.562237) (xy 412.211484 -193.523528) (xy 412.177398 -193.479385) (xy 412.150102 -193.43075)
			(xy 412.130179 -193.378659) (xy 412.118053 -193.324222) (xy 412.113982 -193.2686) (xy 409.951139 -193.2686)
			(xy 409.966421 -193.319396) (xy 409.974541 -193.374572) (xy 409.97505 -193.402458) (xy 409.974541 -193.430344)
			(xy 409.966421 -193.48552) (xy 409.950353 -193.538927) (xy 409.926681 -193.589424) (xy 409.895908 -193.635937)
			(xy 409.858691 -193.677474) (xy 409.815823 -193.713149) (xy 409.768217 -193.742203) (xy 409.716888 -193.764015)
			(xy 409.662931 -193.778121) (xy 409.607494 -193.784221) (xy 409.55176 -193.782184) (xy 409.496917 -193.772054)
			(xy 409.444133 -193.754047) (xy 409.394533 -193.728546) (xy 409.349175 -193.696095) (xy 409.309026 -193.657386)
			(xy 409.27494 -193.613243) (xy 409.247644 -193.564608) (xy 409.227721 -193.512517) (xy 409.215595 -193.45808)
			(xy 409.211524 -193.402458) (xy 403.358549 -193.402458) (xy 404.350753 -197.1294) (xy 408.430982 -197.1294)
			(xy 408.435053 -197.073778) (xy 408.447179 -197.019341) (xy 408.467102 -196.96725) (xy 408.494398 -196.918615)
			(xy 408.528484 -196.874472) (xy 408.568633 -196.835763) (xy 408.613991 -196.803312) (xy 408.663591 -196.777811)
			(xy 408.716375 -196.759804) (xy 408.771218 -196.749674) (xy 408.826952 -196.747637) (xy 408.882389 -196.753737)
			(xy 408.888207 -196.755258) (xy 413.72104 -196.755258) (xy 413.725111 -196.699636) (xy 413.737237 -196.645199)
			(xy 413.75716 -196.593108) (xy 413.784456 -196.544473) (xy 413.818542 -196.50033) (xy 413.858691 -196.461621)
			(xy 413.904049 -196.42917) (xy 413.953649 -196.403669) (xy 414.006433 -196.385662) (xy 414.061276 -196.375532)
			(xy 414.11701 -196.373495) (xy 414.172447 -196.379595) (xy 414.226404 -196.393701) (xy 414.277733 -196.415513)
			(xy 414.325339 -196.444567) (xy 414.368207 -196.480242) (xy 414.405424 -196.521779) (xy 414.436197 -196.568292)
			(xy 414.459869 -196.618789) (xy 414.475937 -196.672196) (xy 414.484057 -196.727372) (xy 414.484566 -196.755258)
			(xy 414.484057 -196.783144) (xy 414.475937 -196.83832) (xy 414.459869 -196.891727) (xy 414.436197 -196.942224)
			(xy 414.405424 -196.988737) (xy 414.368207 -197.030274) (xy 414.325339 -197.065949) (xy 414.277733 -197.095003)
			(xy 414.226404 -197.116815) (xy 414.172447 -197.130921) (xy 414.11701 -197.137021) (xy 414.061276 -197.134984)
			(xy 414.006433 -197.124854) (xy 413.953649 -197.106847) (xy 413.904049 -197.081346) (xy 413.858691 -197.048895)
			(xy 413.818542 -197.010186) (xy 413.784456 -196.966043) (xy 413.75716 -196.917408) (xy 413.737237 -196.865317)
			(xy 413.725111 -196.81088) (xy 413.72104 -196.755258) (xy 408.888207 -196.755258) (xy 408.936346 -196.767843)
			(xy 408.987675 -196.789655) (xy 409.035281 -196.818709) (xy 409.078149 -196.854384) (xy 409.115366 -196.895921)
			(xy 409.146139 -196.942434) (xy 409.169811 -196.992931) (xy 409.185879 -197.046338) (xy 409.193999 -197.101514)
			(xy 409.194508 -197.1294) (xy 409.193999 -197.157286) (xy 409.185879 -197.212462) (xy 409.169811 -197.265869)
			(xy 409.146139 -197.316366) (xy 409.115366 -197.362879) (xy 409.078149 -197.404416) (xy 409.035281 -197.440091)
			(xy 408.987675 -197.469145) (xy 408.936346 -197.490957) (xy 408.882389 -197.505063) (xy 408.826952 -197.511163)
			(xy 408.771218 -197.509126) (xy 408.716375 -197.498996) (xy 408.663591 -197.480989) (xy 408.613991 -197.455488)
			(xy 408.568633 -197.423037) (xy 408.528484 -197.384328) (xy 408.494398 -197.340185) (xy 408.467102 -197.29155)
			(xy 408.447179 -197.239459) (xy 408.435053 -197.185022) (xy 408.430982 -197.1294) (xy 404.350753 -197.1294)
			(xy 404.636587 -198.203058) (xy 408.97124 -198.203058) (xy 408.975311 -198.147436) (xy 408.987437 -198.092999)
			(xy 409.00736 -198.040908) (xy 409.034656 -197.992273) (xy 409.068742 -197.94813) (xy 409.108891 -197.909421)
			(xy 409.154249 -197.87697) (xy 409.203849 -197.851469) (xy 409.256633 -197.833462) (xy 409.311476 -197.823332)
			(xy 409.36721 -197.821295) (xy 409.422647 -197.827395) (xy 409.476604 -197.841501) (xy 409.527933 -197.863313)
			(xy 409.575539 -197.892367) (xy 409.618407 -197.928042) (xy 409.655624 -197.969579) (xy 409.686397 -198.016092)
			(xy 409.710069 -198.066589) (xy 409.726137 -198.119996) (xy 409.734257 -198.175172) (xy 409.734766 -198.203058)
			(xy 409.734257 -198.230944) (xy 409.726137 -198.28612) (xy 409.710069 -198.339527) (xy 409.686397 -198.390024)
			(xy 409.655624 -198.436537) (xy 409.618407 -198.478074) (xy 409.575539 -198.513749) (xy 409.527933 -198.542803)
			(xy 409.476604 -198.564615) (xy 409.422647 -198.578721) (xy 409.36721 -198.584821) (xy 409.311476 -198.582784)
			(xy 409.256633 -198.572654) (xy 409.203849 -198.554647) (xy 409.154249 -198.529146) (xy 409.108891 -198.496695)
			(xy 409.068742 -198.457986) (xy 409.034656 -198.413843) (xy 409.00736 -198.365208) (xy 408.987437 -198.313117)
			(xy 408.975311 -198.25868) (xy 408.97124 -198.203058) (xy 404.636587 -198.203058) (xy 405.109935 -199.981058)
			(xy 413.61944 -199.981058) (xy 413.623511 -199.925436) (xy 413.635637 -199.870999) (xy 413.65556 -199.818908)
			(xy 413.682856 -199.770273) (xy 413.716942 -199.72613) (xy 413.757091 -199.687421) (xy 413.802449 -199.65497)
			(xy 413.852049 -199.629469) (xy 413.904833 -199.611462) (xy 413.959676 -199.601332) (xy 414.01541 -199.599295)
			(xy 414.070847 -199.605395) (xy 414.124804 -199.619501) (xy 414.176133 -199.641313) (xy 414.223739 -199.670367)
			(xy 414.266607 -199.706042) (xy 414.303824 -199.747579) (xy 414.334597 -199.794092) (xy 414.358269 -199.844589)
			(xy 414.374337 -199.897996) (xy 414.382457 -199.953172) (xy 414.382966 -199.981058) (xy 414.382457 -200.008944)
			(xy 414.374337 -200.06412) (xy 414.358269 -200.117527) (xy 414.334597 -200.168024) (xy 414.303824 -200.214537)
			(xy 414.266607 -200.256074) (xy 414.223739 -200.291749) (xy 414.176133 -200.320803) (xy 414.124804 -200.342615)
			(xy 414.070847 -200.356721) (xy 414.01541 -200.362821) (xy 413.959676 -200.360784) (xy 413.904833 -200.350654)
			(xy 413.852049 -200.332647) (xy 413.802449 -200.307146) (xy 413.757091 -200.274695) (xy 413.716942 -200.235986)
			(xy 413.682856 -200.191843) (xy 413.65556 -200.143208) (xy 413.635637 -200.091117) (xy 413.623511 -200.03668)
			(xy 413.61944 -199.981058) (xy 405.109935 -199.981058) (xy 405.637379 -201.962258) (xy 409.033724 -201.962258)
			(xy 409.037795 -201.906636) (xy 409.049921 -201.852199) (xy 409.069844 -201.800108) (xy 409.09714 -201.751473)
			(xy 409.131226 -201.70733) (xy 409.171375 -201.668621) (xy 409.216733 -201.63617) (xy 409.266333 -201.610669)
			(xy 409.319117 -201.592662) (xy 409.37396 -201.582532) (xy 409.429694 -201.580495) (xy 409.485131 -201.586595)
			(xy 409.539088 -201.600701) (xy 409.590417 -201.622513) (xy 409.638023 -201.651567) (xy 409.680891 -201.687242)
			(xy 409.718108 -201.728779) (xy 409.748881 -201.775292) (xy 409.772553 -201.825789) (xy 409.788621 -201.879196)
			(xy 409.796741 -201.934372) (xy 409.79725 -201.962258) (xy 409.796741 -201.990144) (xy 409.788621 -202.04532)
			(xy 409.772553 -202.098727) (xy 409.748881 -202.149224) (xy 409.718108 -202.195737) (xy 409.680891 -202.237274)
			(xy 409.638023 -202.272949) (xy 409.590417 -202.302003) (xy 409.539088 -202.323815) (xy 409.485131 -202.337921)
			(xy 409.429694 -202.344021) (xy 409.37396 -202.341984) (xy 409.319117 -202.331854) (xy 409.266333 -202.313847)
			(xy 409.216733 -202.288346) (xy 409.171375 -202.255895) (xy 409.131226 -202.217186) (xy 409.09714 -202.173043)
			(xy 409.069844 -202.124408) (xy 409.049921 -202.072317) (xy 409.037795 -202.01788) (xy 409.033724 -201.962258)
			(xy 405.637379 -201.962258) (xy 406.063391 -203.562458) (xy 413.13684 -203.562458) (xy 413.140911 -203.506836)
			(xy 413.153037 -203.452399) (xy 413.17296 -203.400308) (xy 413.200256 -203.351673) (xy 413.234342 -203.30753)
			(xy 413.274491 -203.268821) (xy 413.319849 -203.23637) (xy 413.369449 -203.210869) (xy 413.422233 -203.192862)
			(xy 413.477076 -203.182732) (xy 413.53281 -203.180695) (xy 413.588247 -203.186795) (xy 413.642204 -203.200901)
			(xy 413.693533 -203.222713) (xy 413.741139 -203.251767) (xy 413.784007 -203.287442) (xy 413.821224 -203.328979)
			(xy 413.851997 -203.375492) (xy 413.875669 -203.425989) (xy 413.891737 -203.479396) (xy 413.899857 -203.534572)
			(xy 413.900366 -203.562458) (xy 413.899857 -203.590344) (xy 413.891737 -203.64552) (xy 413.875669 -203.698927)
			(xy 413.851997 -203.749424) (xy 413.821224 -203.795937) (xy 413.784007 -203.837474) (xy 413.741139 -203.873149)
			(xy 413.693533 -203.902203) (xy 413.642204 -203.924015) (xy 413.588247 -203.938121) (xy 413.53281 -203.944221)
			(xy 413.477076 -203.942184) (xy 413.422233 -203.932054) (xy 413.369449 -203.914047) (xy 413.319849 -203.888546)
			(xy 413.274491 -203.856095) (xy 413.234342 -203.817386) (xy 413.200256 -203.773243) (xy 413.17296 -203.724608)
			(xy 413.153037 -203.672517) (xy 413.140911 -203.61808) (xy 413.13684 -203.562458) (xy 406.063391 -203.562458)
			(xy 406.222098 -204.158596) (xy 407.590242 -204.158596) (xy 407.594313 -204.102974) (xy 407.606439 -204.048537)
			(xy 407.626362 -203.996446) (xy 407.653658 -203.947811) (xy 407.687744 -203.903668) (xy 407.727893 -203.864959)
			(xy 407.773251 -203.832508) (xy 407.822851 -203.807007) (xy 407.875635 -203.789) (xy 407.930478 -203.77887)
			(xy 407.986212 -203.776833) (xy 408.041649 -203.782933) (xy 408.095606 -203.797039) (xy 408.146935 -203.818851)
			(xy 408.194541 -203.847905) (xy 408.237409 -203.88358) (xy 408.274626 -203.925117) (xy 408.305399 -203.97163)
			(xy 408.329071 -204.022127) (xy 408.345139 -204.075534) (xy 408.353259 -204.13071) (xy 408.353768 -204.158596)
			(xy 408.353259 -204.186482) (xy 408.345139 -204.241658) (xy 408.329071 -204.295065) (xy 408.305399 -204.345562)
			(xy 408.274626 -204.392075) (xy 408.237409 -204.433612) (xy 408.194541 -204.469287) (xy 408.146935 -204.498341)
			(xy 408.095606 -204.520153) (xy 408.041649 -204.534259) (xy 407.986212 -204.540359) (xy 407.930478 -204.538322)
			(xy 407.875635 -204.528192) (xy 407.822851 -204.510185) (xy 407.773251 -204.484684) (xy 407.727893 -204.452233)
			(xy 407.687744 -204.413524) (xy 407.653658 -204.369381) (xy 407.626362 -204.320746) (xy 407.606439 -204.268655)
			(xy 407.594313 -204.214218) (xy 407.590242 -204.158596) (xy 406.222098 -204.158596) (xy 407.262854 -208.06791)
			(xy 407.722068 -208.06791) (xy 407.726139 -208.012288) (xy 407.738265 -207.957851) (xy 407.758188 -207.90576)
			(xy 407.785484 -207.857125) (xy 407.81957 -207.812982) (xy 407.859719 -207.774273) (xy 407.905077 -207.741822)
			(xy 407.954677 -207.716321) (xy 408.007461 -207.698314) (xy 408.062304 -207.688184) (xy 408.118038 -207.686147)
			(xy 408.173475 -207.692247) (xy 408.227432 -207.706353) (xy 408.278761 -207.728165) (xy 408.326367 -207.757219)
			(xy 408.369235 -207.792894) (xy 408.406452 -207.834431) (xy 408.437225 -207.880944) (xy 408.460897 -207.931441)
			(xy 408.476965 -207.984848) (xy 408.485085 -208.040024) (xy 408.485594 -208.06791) (xy 408.485085 -208.095796)
			(xy 408.476965 -208.150972) (xy 408.460897 -208.204379) (xy 408.437225 -208.254876) (xy 408.406452 -208.301389)
			(xy 408.369235 -208.342926) (xy 408.326367 -208.378601) (xy 408.278761 -208.407655) (xy 408.227432 -208.429467)
			(xy 408.173475 -208.443573) (xy 408.118038 -208.449673) (xy 408.062304 -208.447636) (xy 408.007461 -208.437506)
			(xy 407.954677 -208.419499) (xy 407.905077 -208.393998) (xy 407.859719 -208.361547) (xy 407.81957 -208.322838)
			(xy 407.785484 -208.278695) (xy 407.758188 -208.23006) (xy 407.738265 -208.177969) (xy 407.726139 -208.123532)
			(xy 407.722068 -208.06791) (xy 407.262854 -208.06791) (xy 407.868198 -210.341718) (xy 409.3497 -210.341718)
			(xy 409.353771 -210.286096) (xy 409.365897 -210.231659) (xy 409.38582 -210.179568) (xy 409.413116 -210.130933)
			(xy 409.447202 -210.08679) (xy 409.487351 -210.048081) (xy 409.532709 -210.01563) (xy 409.582309 -209.990129)
			(xy 409.635093 -209.972122) (xy 409.689936 -209.961992) (xy 409.74567 -209.959955) (xy 409.801107 -209.966055)
			(xy 409.855064 -209.980161) (xy 409.906393 -210.001973) (xy 409.953999 -210.031027) (xy 409.996867 -210.066702)
			(xy 410.034084 -210.108239) (xy 410.064857 -210.154752) (xy 410.088529 -210.205249) (xy 410.104597 -210.258656)
			(xy 410.112717 -210.313832) (xy 410.113226 -210.341718) (xy 410.112717 -210.369604) (xy 410.104597 -210.42478)
			(xy 410.088529 -210.478187) (xy 410.064857 -210.528684) (xy 410.034084 -210.575197) (xy 409.996867 -210.616734)
			(xy 409.953999 -210.652409) (xy 409.906393 -210.681463) (xy 409.855064 -210.703275) (xy 409.801107 -210.717381)
			(xy 409.74567 -210.723481) (xy 409.689936 -210.721444) (xy 409.635093 -210.711314) (xy 409.582309 -210.693307)
			(xy 409.532709 -210.667806) (xy 409.487351 -210.635355) (xy 409.447202 -210.596646) (xy 409.413116 -210.552503)
			(xy 409.38582 -210.503868) (xy 409.365897 -210.451777) (xy 409.353771 -210.39734) (xy 409.3497 -210.341718)
			(xy 407.868198 -210.341718) (xy 410.791863 -221.323662) (xy 417.33419 -221.323662) (xy 417.338261 -221.26804)
			(xy 417.350387 -221.213603) (xy 417.37031 -221.161512) (xy 417.397606 -221.112877) (xy 417.431692 -221.068734)
			(xy 417.471841 -221.030025) (xy 417.517199 -220.997574) (xy 417.566799 -220.972073) (xy 417.619583 -220.954066)
			(xy 417.674426 -220.943936) (xy 417.73016 -220.941899) (xy 417.785597 -220.947999) (xy 417.839554 -220.962105)
			(xy 417.890883 -220.983917) (xy 417.938489 -221.012971) (xy 417.981357 -221.048646) (xy 418.018574 -221.090183)
			(xy 418.049347 -221.136696) (xy 418.073019 -221.187193) (xy 418.089087 -221.2406) (xy 418.097207 -221.295776)
			(xy 418.097716 -221.323662) (xy 418.097207 -221.351548) (xy 418.089087 -221.406724) (xy 418.073019 -221.460131)
			(xy 418.049347 -221.510628) (xy 418.018574 -221.557141) (xy 417.981357 -221.598678) (xy 417.938489 -221.634353)
			(xy 417.890883 -221.663407) (xy 417.839554 -221.685219) (xy 417.785597 -221.699325) (xy 417.73016 -221.705425)
			(xy 417.674426 -221.703388) (xy 417.619583 -221.693258) (xy 417.566799 -221.675251) (xy 417.517199 -221.64975)
			(xy 417.471841 -221.617299) (xy 417.431692 -221.57859) (xy 417.397606 -221.534447) (xy 417.37031 -221.485812)
			(xy 417.350387 -221.433721) (xy 417.338261 -221.379284) (xy 417.33419 -221.323662) (xy 410.791863 -221.323662)
			(xy 411.475309 -223.89084) (xy 418.05809 -223.89084) (xy 418.062161 -223.835218) (xy 418.074287 -223.780781)
			(xy 418.09421 -223.72869) (xy 418.121506 -223.680055) (xy 418.155592 -223.635912) (xy 418.195741 -223.597203)
			(xy 418.241099 -223.564752) (xy 418.290699 -223.539251) (xy 418.343483 -223.521244) (xy 418.398326 -223.511114)
			(xy 418.45406 -223.509077) (xy 418.509497 -223.515177) (xy 418.563454 -223.529283) (xy 418.614783 -223.551095)
			(xy 418.662389 -223.580149) (xy 418.705257 -223.615824) (xy 418.742474 -223.657361) (xy 418.773247 -223.703874)
			(xy 418.796919 -223.754371) (xy 418.812987 -223.807778) (xy 418.821107 -223.862954) (xy 418.821616 -223.89084)
			(xy 418.821107 -223.918726) (xy 418.812987 -223.973902) (xy 418.796919 -224.027309) (xy 418.773247 -224.077806)
			(xy 418.742474 -224.124319) (xy 418.705257 -224.165856) (xy 418.662389 -224.201531) (xy 418.614783 -224.230585)
			(xy 418.563454 -224.252397) (xy 418.509497 -224.266503) (xy 418.45406 -224.272603) (xy 418.398326 -224.270566)
			(xy 418.343483 -224.260436) (xy 418.290699 -224.242429) (xy 418.241099 -224.216928) (xy 418.195741 -224.184477)
			(xy 418.155592 -224.145768) (xy 418.121506 -224.101625) (xy 418.09421 -224.05299) (xy 418.074287 -224.000899)
			(xy 418.062161 -223.946462) (xy 418.05809 -223.89084) (xy 411.475309 -223.89084) (xy 411.833768 -225.237294)
			(xy 414.952686 -225.237294) (xy 414.956757 -225.181672) (xy 414.968883 -225.127235) (xy 414.988806 -225.075144)
			(xy 415.016102 -225.026509) (xy 415.050188 -224.982366) (xy 415.090337 -224.943657) (xy 415.135695 -224.911206)
			(xy 415.185295 -224.885705) (xy 415.238079 -224.867698) (xy 415.292922 -224.857568) (xy 415.348656 -224.855531)
			(xy 415.404093 -224.861631) (xy 415.45805 -224.875737) (xy 415.509379 -224.897549) (xy 415.556985 -224.926603)
			(xy 415.599853 -224.962278) (xy 415.63707 -225.003815) (xy 415.667843 -225.050328) (xy 415.691515 -225.100825)
			(xy 415.707583 -225.154232) (xy 415.715703 -225.209408) (xy 415.716212 -225.237294) (xy 415.716189 -225.238564)
			(xy 418.305232 -225.238564) (xy 418.309303 -225.182942) (xy 418.321429 -225.128505) (xy 418.341352 -225.076414)
			(xy 418.368648 -225.027779) (xy 418.402734 -224.983636) (xy 418.442883 -224.944927) (xy 418.488241 -224.912476)
			(xy 418.537841 -224.886975) (xy 418.590625 -224.868968) (xy 418.645468 -224.858838) (xy 418.701202 -224.856801)
			(xy 418.756639 -224.862901) (xy 418.810596 -224.877007) (xy 418.861925 -224.898819) (xy 418.909531 -224.927873)
			(xy 418.952399 -224.963548) (xy 418.989616 -225.005085) (xy 419.020389 -225.051598) (xy 419.044061 -225.102095)
			(xy 419.060129 -225.155502) (xy 419.068249 -225.210678) (xy 419.068758 -225.238564) (xy 419.068249 -225.26645)
			(xy 419.060129 -225.321626) (xy 419.044061 -225.375033) (xy 419.020389 -225.42553) (xy 418.989616 -225.472043)
			(xy 418.952399 -225.51358) (xy 418.909531 -225.549255) (xy 418.861925 -225.578309) (xy 418.810596 -225.600121)
			(xy 418.756639 -225.614227) (xy 418.701202 -225.620327) (xy 418.645468 -225.61829) (xy 418.590625 -225.60816)
			(xy 418.537841 -225.590153) (xy 418.488241 -225.564652) (xy 418.442883 -225.532201) (xy 418.402734 -225.493492)
			(xy 418.368648 -225.449349) (xy 418.341352 -225.400714) (xy 418.321429 -225.348623) (xy 418.309303 -225.294186)
			(xy 418.305232 -225.238564) (xy 415.716189 -225.238564) (xy 415.715703 -225.26518) (xy 415.707583 -225.320356)
			(xy 415.691515 -225.373763) (xy 415.667843 -225.42426) (xy 415.63707 -225.470773) (xy 415.599853 -225.51231)
			(xy 415.556985 -225.547985) (xy 415.509379 -225.577039) (xy 415.45805 -225.598851) (xy 415.404093 -225.612957)
			(xy 415.348656 -225.619057) (xy 415.292922 -225.61702) (xy 415.238079 -225.60689) (xy 415.185295 -225.588883)
			(xy 415.135695 -225.563382) (xy 415.090337 -225.530931) (xy 415.050188 -225.492222) (xy 415.016102 -225.448079)
			(xy 414.988806 -225.399444) (xy 414.968883 -225.347353) (xy 414.956757 -225.292916) (xy 414.952686 -225.237294)
			(xy 411.833768 -225.237294) (xy 413.355377 -230.952802) (xy 417.376354 -230.952802) (xy 417.380425 -230.89718)
			(xy 417.392551 -230.842743) (xy 417.412474 -230.790652) (xy 417.43977 -230.742017) (xy 417.473856 -230.697874)
			(xy 417.514005 -230.659165) (xy 417.559363 -230.626714) (xy 417.608963 -230.601213) (xy 417.661747 -230.583206)
			(xy 417.71659 -230.573076) (xy 417.772324 -230.571039) (xy 417.827761 -230.577139) (xy 417.881718 -230.591245)
			(xy 417.933047 -230.613057) (xy 417.980653 -230.642111) (xy 418.023521 -230.677786) (xy 418.060738 -230.719323)
			(xy 418.091511 -230.765836) (xy 418.115183 -230.816333) (xy 418.131251 -230.86974) (xy 418.139371 -230.924916)
			(xy 418.13988 -230.952802) (xy 418.139371 -230.980688) (xy 418.131251 -231.035864) (xy 418.115183 -231.089271)
			(xy 418.091511 -231.139768) (xy 418.060738 -231.186281) (xy 418.023521 -231.227818) (xy 417.980653 -231.263493)
			(xy 417.933047 -231.292547) (xy 417.881718 -231.314359) (xy 417.827761 -231.328465) (xy 417.772324 -231.334565)
			(xy 417.71659 -231.332528) (xy 417.661747 -231.322398) (xy 417.608963 -231.304391) (xy 417.559363 -231.27889)
			(xy 417.514005 -231.246439) (xy 417.473856 -231.20773) (xy 417.43977 -231.163587) (xy 417.412474 -231.114952)
			(xy 417.392551 -231.062861) (xy 417.380425 -231.008424) (xy 417.376354 -230.952802) (xy 413.355377 -230.952802)
			(xy 414.031588 -233.492802) (xy 414.907982 -233.492802) (xy 414.912053 -233.43718) (xy 414.924179 -233.382743)
			(xy 414.944102 -233.330652) (xy 414.971398 -233.282017) (xy 415.005484 -233.237874) (xy 415.045633 -233.199165)
			(xy 415.090991 -233.166714) (xy 415.140591 -233.141213) (xy 415.193375 -233.123206) (xy 415.248218 -233.113076)
			(xy 415.303952 -233.111039) (xy 415.359389 -233.117139) (xy 415.413346 -233.131245) (xy 415.464675 -233.153057)
			(xy 415.512281 -233.182111) (xy 415.555149 -233.217786) (xy 415.592366 -233.259323) (xy 415.623139 -233.305836)
			(xy 415.646811 -233.356333) (xy 415.662879 -233.40974) (xy 415.670999 -233.464916) (xy 415.671508 -233.492802)
			(xy 415.671485 -233.494072) (xy 418.149784 -233.494072) (xy 418.153855 -233.43845) (xy 418.165981 -233.384013)
			(xy 418.185904 -233.331922) (xy 418.2132 -233.283287) (xy 418.247286 -233.239144) (xy 418.287435 -233.200435)
			(xy 418.332793 -233.167984) (xy 418.382393 -233.142483) (xy 418.435177 -233.124476) (xy 418.49002 -233.114346)
			(xy 418.545754 -233.112309) (xy 418.601191 -233.118409) (xy 418.655148 -233.132515) (xy 418.706477 -233.154327)
			(xy 418.754083 -233.183381) (xy 418.796951 -233.219056) (xy 418.834168 -233.260593) (xy 418.864941 -233.307106)
			(xy 418.888613 -233.357603) (xy 418.904681 -233.41101) (xy 418.912801 -233.466186) (xy 418.91331 -233.494072)
			(xy 418.912801 -233.521958) (xy 418.904681 -233.577134) (xy 418.888613 -233.630541) (xy 418.864941 -233.681038)
			(xy 418.834168 -233.727551) (xy 418.796951 -233.769088) (xy 418.754083 -233.804763) (xy 418.706477 -233.833817)
			(xy 418.655148 -233.855629) (xy 418.601191 -233.869735) (xy 418.545754 -233.875835) (xy 418.49002 -233.873798)
			(xy 418.435177 -233.863668) (xy 418.382393 -233.845661) (xy 418.332793 -233.82016) (xy 418.287435 -233.787709)
			(xy 418.247286 -233.749) (xy 418.2132 -233.704857) (xy 418.185904 -233.656222) (xy 418.165981 -233.604131)
			(xy 418.153855 -233.549694) (xy 418.149784 -233.494072) (xy 415.671485 -233.494072) (xy 415.670999 -233.520688)
			(xy 415.662879 -233.575864) (xy 415.646811 -233.629271) (xy 415.623139 -233.679768) (xy 415.592366 -233.726281)
			(xy 415.555149 -233.767818) (xy 415.512281 -233.803493) (xy 415.464675 -233.832547) (xy 415.413346 -233.854359)
			(xy 415.359389 -233.868465) (xy 415.303952 -233.874565) (xy 415.248218 -233.872528) (xy 415.193375 -233.862398)
			(xy 415.140591 -233.844391) (xy 415.090991 -233.81889) (xy 415.045633 -233.786439) (xy 415.005484 -233.74773)
			(xy 414.971398 -233.703587) (xy 414.944102 -233.654952) (xy 414.924179 -233.602861) (xy 414.912053 -233.548424)
			(xy 414.907982 -233.492802) (xy 414.031588 -233.492802) (xy 414.481133 -235.181394) (xy 418.770052 -235.181394)
			(xy 418.774123 -235.125772) (xy 418.786249 -235.071335) (xy 418.806172 -235.019244) (xy 418.833468 -234.970609)
			(xy 418.867554 -234.926466) (xy 418.907703 -234.887757) (xy 418.953061 -234.855306) (xy 419.002661 -234.829805)
			(xy 419.055445 -234.811798) (xy 419.110288 -234.801668) (xy 419.166022 -234.799631) (xy 419.221459 -234.805731)
			(xy 419.275416 -234.819837) (xy 419.326745 -234.841649) (xy 419.374351 -234.870703) (xy 419.417219 -234.906378)
			(xy 419.454436 -234.947915) (xy 419.485209 -234.994428) (xy 419.508881 -235.044925) (xy 419.524949 -235.098332)
			(xy 419.533069 -235.153508) (xy 419.533578 -235.181394) (xy 419.533069 -235.20928) (xy 419.524949 -235.264456)
			(xy 419.508881 -235.317863) (xy 419.485209 -235.36836) (xy 419.454436 -235.414873) (xy 419.417219 -235.45641)
			(xy 419.374351 -235.492085) (xy 419.326745 -235.521139) (xy 419.275416 -235.542951) (xy 419.221459 -235.557057)
			(xy 419.166022 -235.563157) (xy 419.110288 -235.56112) (xy 419.055445 -235.55099) (xy 419.002661 -235.532983)
			(xy 418.953061 -235.507482) (xy 418.907703 -235.475031) (xy 418.867554 -235.436322) (xy 418.833468 -235.392179)
			(xy 418.806172 -235.343544) (xy 418.786249 -235.291453) (xy 418.774123 -235.237016) (xy 418.770052 -235.181394)
			(xy 414.481133 -235.181394) (xy 415.577203 -239.29848) (xy 417.276532 -239.29848) (xy 417.280603 -239.242858)
			(xy 417.292729 -239.188421) (xy 417.312652 -239.13633) (xy 417.339948 -239.087695) (xy 417.374034 -239.043552)
			(xy 417.414183 -239.004843) (xy 417.459541 -238.972392) (xy 417.509141 -238.946891) (xy 417.561925 -238.928884)
			(xy 417.616768 -238.918754) (xy 417.672502 -238.916717) (xy 417.727939 -238.922817) (xy 417.781896 -238.936923)
			(xy 417.833225 -238.958735) (xy 417.880831 -238.987789) (xy 417.923699 -239.023464) (xy 417.960916 -239.065001)
			(xy 417.991689 -239.111514) (xy 418.015361 -239.162011) (xy 418.031429 -239.215418) (xy 418.039549 -239.270594)
			(xy 418.040058 -239.29848) (xy 418.039549 -239.326366) (xy 418.031429 -239.381542) (xy 418.015361 -239.434949)
			(xy 417.991689 -239.485446) (xy 417.960916 -239.531959) (xy 417.923699 -239.573496) (xy 417.880831 -239.609171)
			(xy 417.833225 -239.638225) (xy 417.781896 -239.660037) (xy 417.727939 -239.674143) (xy 417.672502 -239.680243)
			(xy 417.616768 -239.678206) (xy 417.561925 -239.668076) (xy 417.509141 -239.650069) (xy 417.459541 -239.624568)
			(xy 417.414183 -239.592117) (xy 417.374034 -239.553408) (xy 417.339948 -239.509265) (xy 417.312652 -239.46063)
			(xy 417.292729 -239.408539) (xy 417.280603 -239.354102) (xy 417.276532 -239.29848) (xy 415.577203 -239.29848)
			(xy 415.809414 -240.170716) (xy 418.30828 -240.170716) (xy 418.312351 -240.115094) (xy 418.324477 -240.060657)
			(xy 418.3444 -240.008566) (xy 418.371696 -239.959931) (xy 418.405782 -239.915788) (xy 418.445931 -239.877079)
			(xy 418.491289 -239.844628) (xy 418.540889 -239.819127) (xy 418.593673 -239.80112) (xy 418.648516 -239.79099)
			(xy 418.70425 -239.788953) (xy 418.759687 -239.795053) (xy 418.813644 -239.809159) (xy 418.864973 -239.830971)
			(xy 418.912579 -239.860025) (xy 418.955447 -239.8957) (xy 418.992664 -239.937237) (xy 419.023437 -239.98375)
			(xy 419.047109 -240.034247) (xy 419.063177 -240.087654) (xy 419.071297 -240.14283) (xy 419.071806 -240.170716)
			(xy 419.071297 -240.198602) (xy 419.063177 -240.253778) (xy 419.047109 -240.307185) (xy 419.023437 -240.357682)
			(xy 418.992664 -240.404195) (xy 418.955447 -240.445732) (xy 418.912579 -240.481407) (xy 418.864973 -240.510461)
			(xy 418.813644 -240.532273) (xy 418.759687 -240.546379) (xy 418.70425 -240.552479) (xy 418.648516 -240.550442)
			(xy 418.593673 -240.540312) (xy 418.540889 -240.522305) (xy 418.491289 -240.496804) (xy 418.445931 -240.464353)
			(xy 418.405782 -240.425644) (xy 418.371696 -240.381501) (xy 418.3444 -240.332866) (xy 418.324477 -240.280775)
			(xy 418.312351 -240.226338) (xy 418.30828 -240.170716) (xy 415.809414 -240.170716) (xy 416.156648 -241.475006)
			(xy 416.158036 -241.479728) (xy 416.162382 -241.488557) (xy 416.165284 -241.492532) (xy 416.17138 -241.50066)
			(xy 416.180524 -241.50574) (xy 416.205457 -241.520339) (xy 416.251006 -241.555883) (xy 416.290673 -241.59789)
			(xy 416.323552 -241.645399) (xy 416.348889 -241.697323) (xy 416.366105 -241.752475) (xy 416.374806 -241.809592)
			(xy 416.375342 -241.83848) (xy 416.375342 -241.83975) (xy 418.075362 -241.83975) (xy 418.079433 -241.784128)
			(xy 418.091559 -241.729691) (xy 418.111482 -241.6776) (xy 418.138778 -241.628965) (xy 418.172864 -241.584822)
			(xy 418.213013 -241.546113) (xy 418.258371 -241.513662) (xy 418.307971 -241.488161) (xy 418.360755 -241.470154)
			(xy 418.415598 -241.460024) (xy 418.471332 -241.457987) (xy 418.526769 -241.464087) (xy 418.580726 -241.478193)
			(xy 418.632055 -241.500005) (xy 418.679661 -241.529059) (xy 418.722529 -241.564734) (xy 418.759746 -241.606271)
			(xy 418.790519 -241.652784) (xy 418.814191 -241.703281) (xy 418.830259 -241.756688) (xy 418.838379 -241.811864)
			(xy 418.838888 -241.83975) (xy 418.838379 -241.867636) (xy 418.830259 -241.922812) (xy 418.814191 -241.976219)
			(xy 418.790519 -242.026716) (xy 418.759746 -242.073229) (xy 418.722529 -242.114766) (xy 418.679661 -242.150441)
			(xy 418.632055 -242.179495) (xy 418.580726 -242.201307) (xy 418.526769 -242.215413) (xy 418.471332 -242.221513)
			(xy 418.415598 -242.219476) (xy 418.360755 -242.209346) (xy 418.307971 -242.191339) (xy 418.258371 -242.165838)
			(xy 418.213013 -242.133387) (xy 418.172864 -242.094678) (xy 418.138778 -242.050535) (xy 418.111482 -242.0019)
			(xy 418.091559 -241.949809) (xy 418.079433 -241.895372) (xy 418.075362 -241.83975) (xy 416.375342 -241.83975)
			(xy 416.375342 -241.851942) (xy 416.373528 -241.884001) (xy 416.36052 -241.946877) (xy 416.337179 -242.006692)
			(xy 416.32124 -242.034568) (xy 416.315906 -242.043712) (xy 416.314636 -242.053364) (xy 416.313989 -242.058386)
			(xy 416.314506 -242.068497) (xy 416.315652 -242.07343) (xy 416.604958 -243.159788) (xy 418.133276 -248.899934)
			(xy 418.137047 -248.90964) (xy 418.150958 -248.925105) (xy 418.1602 -248.929906) (xy 418.237924 -248.961656)
			(xy 418.243583 -248.963759) (xy 418.255519 -248.965554) (xy 418.261546 -248.965212) (xy 418.272468 -248.964196)
			(xy 418.282882 -248.957846) (xy 418.28339 -248.957846) (xy 418.305878 -248.94468) (xy 418.353665 -248.923902)
			(xy 418.403835 -248.909822) (xy 418.455456 -248.902703) (xy 418.48151 -248.90222) (xy 418.508759 -248.902707)
			(xy 418.562701 -248.910464) (xy 418.614991 -248.925819) (xy 418.664563 -248.948459) (xy 418.710409 -248.977923)
			(xy 418.751595 -249.013612) (xy 418.787283 -249.054799) (xy 418.816746 -249.100645) (xy 418.839385 -249.150218)
			(xy 418.854738 -249.202508) (xy 418.862494 -249.256451) (xy 418.862494 -249.30481) (xy 419.084504 -249.30481)
			(xy 419.088575 -249.249188) (xy 419.100701 -249.194751) (xy 419.120624 -249.14266) (xy 419.14792 -249.094025)
			(xy 419.182006 -249.049882) (xy 419.222155 -249.011173) (xy 419.267513 -248.978722) (xy 419.317113 -248.953221)
			(xy 419.369897 -248.935214) (xy 419.42474 -248.925084) (xy 419.480474 -248.923047) (xy 419.535911 -248.929147)
			(xy 419.589868 -248.943253) (xy 419.641197 -248.965065) (xy 419.688803 -248.994119) (xy 419.731671 -249.029794)
			(xy 419.768888 -249.071331) (xy 419.799661 -249.117844) (xy 419.823333 -249.168341) (xy 419.839401 -249.221748)
			(xy 419.847521 -249.276924) (xy 419.84803 -249.30481) (xy 419.847521 -249.332696) (xy 419.839401 -249.387872)
			(xy 419.823333 -249.441279) (xy 419.799661 -249.491776) (xy 419.768888 -249.538289) (xy 419.731671 -249.579826)
			(xy 419.688803 -249.615501) (xy 419.641197 -249.644555) (xy 419.589868 -249.666367) (xy 419.535911 -249.680473)
			(xy 419.480474 -249.686573) (xy 419.42474 -249.684536) (xy 419.369897 -249.674406) (xy 419.317113 -249.656399)
			(xy 419.267513 -249.630898) (xy 419.222155 -249.598447) (xy 419.182006 -249.559738) (xy 419.14792 -249.515595)
			(xy 419.120624 -249.46696) (xy 419.100701 -249.414869) (xy 419.088575 -249.360432) (xy 419.084504 -249.30481)
			(xy 418.862494 -249.30481) (xy 418.862494 -249.310949) (xy 418.854738 -249.364892) (xy 418.839385 -249.417182)
			(xy 418.816746 -249.466755) (xy 418.787283 -249.512601) (xy 418.751595 -249.553788) (xy 418.710409 -249.589477)
			(xy 418.664563 -249.618941) (xy 418.614991 -249.641581) (xy 418.562701 -249.656936) (xy 418.508759 -249.664693)
			(xy 418.48151 -249.665236) (xy 418.471604 -249.665236) (xy 418.459666 -249.664982) (xy 418.448744 -249.670062)
			(xy 418.44341 -249.67277) (xy 418.434047 -249.680211) (xy 418.430202 -249.684794) (xy 418.378894 -249.750072)
			(xy 418.372777 -249.759552) (xy 418.368681 -249.781708) (xy 418.37102 -249.792744) (xy 418.37102 -249.792998)
			(xy 418.985192 -252.100334) (xy 419.071388 -252.424184) (xy 419.466268 -252.424184) (xy 419.466767 -252.396394)
			(xy 419.474833 -252.341403) (xy 419.490793 -252.288164) (xy 419.514309 -252.237804) (xy 419.544883 -252.191389)
			(xy 419.581868 -252.149902) (xy 419.624481 -252.114219) (xy 419.67182 -252.085097) (xy 419.697154 -252.073664)
			(xy 419.710619 -252.067418) (xy 419.733398 -252.048401) (xy 419.749744 -252.023634) (xy 419.758273 -251.995213)
			(xy 419.758266 -251.96554) (xy 419.749723 -251.937122) (xy 419.733366 -251.912364) (xy 419.7223 -251.902468)
			(xy 419.701324 -251.884218) (xy 419.664322 -251.842721) (xy 419.633732 -251.796295) (xy 419.610202 -251.745922)
			(xy 419.59423 -251.692667) (xy 419.586154 -251.637659) (xy 419.585648 -251.60986) (xy 419.586134 -251.582609)
			(xy 419.59389 -251.528661) (xy 419.609245 -251.476366) (xy 419.631887 -251.426789) (xy 419.661353 -251.380939)
			(xy 419.697044 -251.339748) (xy 419.738235 -251.304057) (xy 419.784085 -251.274591) (xy 419.833662 -251.251949)
			(xy 419.885957 -251.236594) (xy 419.939905 -251.228838) (xy 419.994407 -251.228838) (xy 420.048355 -251.236594)
			(xy 420.10065 -251.251949) (xy 420.150227 -251.274591) (xy 420.196077 -251.304057) (xy 420.237268 -251.339748)
			(xy 420.272959 -251.380939) (xy 420.302425 -251.426789) (xy 420.325067 -251.476366) (xy 420.340422 -251.528661)
			(xy 420.348178 -251.582609) (xy 420.348664 -251.60986) (xy 420.348158 -251.63765) (xy 420.340098 -251.692643)
			(xy 420.324142 -251.745884) (xy 420.300629 -251.796245) (xy 420.270056 -251.842661) (xy 420.23307 -251.884149)
			(xy 420.190455 -251.91983) (xy 420.143113 -251.948949) (xy 420.117778 -251.96038) (xy 420.104353 -251.966698)
			(xy 420.081593 -251.985709) (xy 420.065258 -252.01046) (xy 420.05673 -252.038863) (xy 420.056727 -252.068519)
			(xy 420.06525 -252.096923) (xy 420.08158 -252.121677) (xy 420.092632 -252.131576) (xy 420.113636 -252.149796)
			(xy 420.150635 -252.191299) (xy 420.18122 -252.237732) (xy 420.204745 -252.288112) (xy 420.220711 -252.341371)
			(xy 420.228781 -252.396383) (xy 420.229284 -252.424184) (xy 420.228798 -252.451435) (xy 420.221042 -252.505383)
			(xy 420.205687 -252.557678) (xy 420.183045 -252.607255) (xy 420.153579 -252.653105) (xy 420.117888 -252.694296)
			(xy 420.076697 -252.729987) (xy 420.030847 -252.759453) (xy 419.98127 -252.782095) (xy 419.928975 -252.79745)
			(xy 419.875027 -252.805206) (xy 419.820525 -252.805206) (xy 419.766577 -252.79745) (xy 419.714282 -252.782095)
			(xy 419.664705 -252.759453) (xy 419.618855 -252.729987) (xy 419.577664 -252.694296) (xy 419.541973 -252.653105)
			(xy 419.512507 -252.607255) (xy 419.489865 -252.557678) (xy 419.47451 -252.505383) (xy 419.466754 -252.451435)
			(xy 419.466268 -252.424184) (xy 419.071388 -252.424184) (xy 419.27907 -253.204472) (xy 419.282719 -253.214103)
			(xy 419.296265 -253.22959) (xy 419.314791 -253.238542) (xy 419.325044 -253.239524)
		)
		(stroke
			(width 0)
			(type solid)
		)
		(fill yes)
		(layer "In5.Cu")
		(net "GND")
	)
	(gr_line
		(start 23.745698 -327.313544)
		(end 23.711408 -326.61606)
		(stroke
			(width 0.08255)
			(type default)
		)
		(layer "In5.Cu")
	)
	(gr_line
		(start 23.769828 -327.808082)
		(end 23.766526 -327.737216)
		(stroke
			(width 0.08255)
			(type default)
		)
		(layer "In5.Cu")
	)
	(gr_line
		(start 23.804118 -328.50582)
		(end 23.804118 -328.504042)
		(stroke
			(width 0.08255)
			(type default)
		)
		(layer "In5.Cu")
	)
	(gr_line
		(start 23.804118 -328.504042)
		(end 23.769828 -327.808082)
		(stroke
			(width 0.08255)
			(type default)
		)
		(layer "In5.Cu")
	)
	(gr_line
		(start 23.804372 -328.506074)
		(end 23.804118 -328.50582)
		(stroke
			(width 0.08255)
			(type default)
		)
		(layer "In5.Cu")
	)
	(gr_line
		(start 23.99284 -326.60209)
		(end 23.993094 -326.60209)
		(stroke
			(width 0.08255)
			(type default)
		)
		(layer "In5.Cu")
	)
	(gr_line
		(start 24.0284 -327.298558)
		(end 24.123904 -327.193402)
		(stroke
			(width 0.08255)
			(type default)
		)
		(layer "In5.Cu")
	)
	(gr_line
		(start 24.051514 -327.794366)
		(end 24.047958 -327.723246)
		(stroke
			(width 0.08255)
			(type default)
		)
		(layer "In5.Cu")
	)
	(gr_line
		(start 24.086058 -328.492358)
		(end 24.182578 -328.385932)
		(stroke
			(width 0.08255)
			(type default)
		)
		(layer "In5.Cu")
	)
	(gr_line
		(start 24.09952 -326.698356)
		(end 23.994364 -326.60336)
		(stroke
			(width 0.08255)
			(type default)
		)
		(layer "In5.Cu")
	)
	(gr_line
		(start 24.123904 -327.193402)
		(end 24.09952 -326.698356)
		(stroke
			(width 0.08255)
			(type default)
		)
		(layer "In5.Cu")
	)
	(gr_line
		(start 24.158194 -327.890886)
		(end 24.052784 -327.795636)
		(stroke
			(width 0.08255)
			(type default)
		)
		(layer "In5.Cu")
	)
	(gr_line
		(start 24.182578 -328.385932)
		(end 24.158194 -327.890886)
		(stroke
			(width 0.08255)
			(type default)
		)
		(layer "In5.Cu")
	)
	(gr_line
		(start 29.261816 -310.894984)
		(end 29.738066 -310.418734)
		(stroke
			(width 0.08255)
			(type default)
		)
		(layer "In5.Cu")
	)
	(gr_line
		(start 29.462984 -311.094374)
		(end 29.586936 -311.094374)
		(stroke
			(width 0.08255)
			(type default)
		)
		(layer "In5.Cu")
	)
	(gr_line
		(start 29.586936 -311.094374)
		(end 29.937456 -310.743854)
		(stroke
			(width 0.08255)
			(type default)
		)
		(layer "In5.Cu")
	)
	(gr_line
		(start 29.937456 -310.743854)
		(end 29.937456 -310.619902)
		(stroke
			(width 0.08255)
			(type default)
		)
		(layer "In5.Cu")
	)
	(gr_line
		(start 30.088078 -310.068722)
		(end 30.564328 -309.592472)
		(stroke
			(width 0.08255)
			(type default)
		)
		(layer "In5.Cu")
	)
	(gr_line
		(start 30.289246 -310.268112)
		(end 30.413198 -310.268112)
		(stroke
			(width 0.08255)
			(type default)
		)
		(layer "In5.Cu")
	)
	(gr_line
		(start 30.413198 -310.268112)
		(end 30.763718 -309.917592)
		(stroke
			(width 0.08255)
			(type default)
		)
		(layer "In5.Cu")
	)
	(gr_line
		(start 30.763718 -309.917592)
		(end 30.763718 -309.79364)
		(stroke
			(width 0.08255)
			(type default)
		)
		(layer "In5.Cu")
	)
	(gr_line
		(start 30.91434 -309.24246)
		(end 31.39059 -308.76621)
		(stroke
			(width 0.08255)
			(type default)
		)
		(layer "In5.Cu")
	)
	(gr_line
		(start 31.115508 -309.44185)
		(end 31.23946 -309.44185)
		(stroke
			(width 0.08255)
			(type default)
		)
		(layer "In5.Cu")
	)
	(gr_line
		(start 31.23946 -309.44185)
		(end 31.58998 -309.09133)
		(stroke
			(width 0.08255)
			(type default)
		)
		(layer "In5.Cu")
	)
	(gr_line
		(start 31.58998 -309.09133)
		(end 31.58998 -308.967378)
		(stroke
			(width 0.08255)
			(type default)
		)
		(layer "In5.Cu")
	)
	(gr_line
		(start 31.740602 -308.416198)
		(end 32.216598 -307.940202)
		(stroke
			(width 0.08255)
			(type default)
		)
		(layer "In5.Cu")
	)
	(gr_line
		(start 31.94177 -308.615588)
		(end 32.065722 -308.615588)
		(stroke
			(width 0.08255)
			(type default)
		)
		(layer "In5.Cu")
	)
	(gr_line
		(start 32.065722 -308.615588)
		(end 32.415988 -308.265322)
		(stroke
			(width 0.08255)
			(type default)
		)
		(layer "In5.Cu")
	)
	(gr_line
		(start 32.415988 -308.265322)
		(end 32.415988 -308.14137)
		(stroke
			(width 0.08255)
			(type default)
		)
		(layer "In5.Cu")
	)
	(gr_line
		(start 35.56 -306.965858)
		(end 35.588448 -306.965858)
		(stroke
			(width 0.05715)
			(type default)
		)
		(layer "In5.Cu")
	)
	(gr_line
		(start 35.56 -306.683918)
		(end 35.588448 -306.683918)
		(stroke
			(width 0.05715)
			(type default)
		)
		(layer "In5.Cu")
	)
	(gr_line
		(start 35.588448 -306.965858)
		(end 35.634168 -306.920138)
		(stroke
			(width 0.05715)
			(type default)
		)
		(layer "In5.Cu")
	)
	(gr_line
		(start 35.588448 -306.683918)
		(end 35.634168 -306.729638)
		(stroke
			(width 0.05715)
			(type default)
		)
		(layer "In5.Cu")
	)
	(gr_line
		(start 36.710112 -382.57226)
		(end 36.837112 -382.69926)
		(stroke
			(width 0.08255)
			(type default)
		)
		(layer "In5.Cu")
	)
	(gr_line
		(start 36.710112 -382.18999)
		(end 36.710112 -382.57226)
		(stroke
			(width 0.08255)
			(type default)
		)
		(layer "In5.Cu")
	)
	(gr_line
		(start 37.33292 -392.104626)
		(end 37.332666 -392.10488)
		(stroke
			(width 0.08255)
			(type default)
		)
		(layer "In5.Cu")
	)
	(gr_line
		(start 37.369242 -392.225022)
		(end 37.333428 -392.106404)
		(stroke
			(width 0.08255)
			(type default)
		)
		(layer "In5.Cu")
	)
	(gr_line
		(start 37.806376 -392.458702)
		(end 37.369242 -392.225022)
		(stroke
			(width 0.08255)
			(type default)
		)
		(layer "In5.Cu")
	)
	(gr_line
		(start 37.924994 -392.422634)
		(end 37.806376 -392.458702)
		(stroke
			(width 0.08255)
			(type default)
		)
		(layer "In5.Cu")
	)
	(gr_line
		(start 38.059614 -392.17346)
		(end 37.465762 -391.85596)
		(stroke
			(width 0.08255)
			(type default)
		)
		(layer "In5.Cu")
	)
	(gr_line
		(start 38.39972 -392.775948)
		(end 38.363906 -392.657076)
		(stroke
			(width 0.08255)
			(type default)
		)
		(layer "In5.Cu")
	)
	(gr_line
		(start 38.836854 -393.009628)
		(end 38.39972 -392.775948)
		(stroke
			(width 0.08255)
			(type default)
		)
		(layer "In5.Cu")
	)
	(gr_line
		(start 38.955726 -392.97356)
		(end 38.836854 -393.009628)
		(stroke
			(width 0.08255)
			(type default)
		)
		(layer "In5.Cu")
	)
	(gr_line
		(start 39.015416 -307.299868)
		(end 38.749986 -307.299868)
		(stroke
			(width 0.05715)
			(type default)
		)
		(layer "In5.Cu")
	)
	(gr_line
		(start 39.083996 -319.995296)
		(end 39.083996 -319.966848)
		(stroke
			(width 0.05715)
			(type default)
		)
		(layer "In5.Cu")
	)
	(gr_line
		(start 39.083996 -319.966848)
		(end 39.129716 -319.921128)
		(stroke
			(width 0.05715)
			(type default)
		)
		(layer "In5.Cu")
	)
	(gr_line
		(start 39.090346 -392.724386)
		(end 38.49624 -392.406886)
		(stroke
			(width 0.08255)
			(type default)
		)
		(layer "In5.Cu")
	)
	(gr_line
		(start 39.129716 -307.185568)
		(end 39.015416 -307.299868)
		(stroke
			(width 0.05715)
			(type default)
		)
		(layer "In5.Cu")
	)
	(gr_line
		(start 39.320216 -307.185568)
		(end 39.434516 -307.299868)
		(stroke
			(width 0.05715)
			(type default)
		)
		(layer "In5.Cu")
	)
	(gr_line
		(start 39.430452 -393.326874)
		(end 39.394384 -393.208002)
		(stroke
			(width 0.08255)
			(type default)
		)
		(layer "In5.Cu")
	)
	(gr_line
		(start 39.434516 -307.299868)
		(end 39.699946 -307.299868)
		(stroke
			(width 0.05715)
			(type default)
		)
		(layer "In5.Cu")
	)
	(gr_line
		(start 39.585646 -316.229492)
		(end 39.699946 -316.115192)
		(stroke
			(width 0.05715)
			(type default)
		)
		(layer "In5.Cu")
	)
	(gr_line
		(start 39.699946 -316.115192)
		(end 39.699946 -315.849762)
		(stroke
			(width 0.05715)
			(type default)
		)
		(layer "In5.Cu")
	)
	(gr_line
		(start 39.867332 -393.560554)
		(end 39.430452 -393.326874)
		(stroke
			(width 0.08255)
			(type default)
		)
		(layer "In5.Cu")
	)
	(gr_line
		(start 39.986458 -393.524486)
		(end 39.867332 -393.560554)
		(stroke
			(width 0.08255)
			(type default)
		)
		(layer "In5.Cu")
	)
	(gr_line
		(start 40.120824 -393.275058)
		(end 39.526972 -392.957558)
		(stroke
			(width 0.08255)
			(type default)
		)
		(layer "In5.Cu")
	)
	(gr_line
		(start 40.439848 -331.121512)
		(end 40.498522 -331.012038)
		(stroke
			(width 0.08255)
			(type default)
		)
		(layer "In5.Cu")
	)
	(gr_line
		(start 40.498776 -331.011276)
		(end 40.49903 -331.010768)
		(stroke
			(width 0.08255)
			(type default)
		)
		(layer "In5.Cu")
	)
	(gr_line
		(start 40.583612 -331.59573)
		(end 40.439848 -331.121512)
		(stroke
			(width 0.08255)
			(type default)
		)
		(layer "In5.Cu")
	)
	(gr_line
		(start 40.69334 -331.654404)
		(end 40.583612 -331.59573)
		(stroke
			(width 0.08255)
			(type default)
		)
		(layer "In5.Cu")
	)
	(gr_line
		(start 40.694864 -331.655166)
		(end 40.694356 -331.654912)
		(stroke
			(width 0.08255)
			(type default)
		)
		(layer "In5.Cu")
	)
	(gr_line
		(start 40.779192 -332.239874)
		(end 40.837866 -332.1304)
		(stroke
			(width 0.08255)
			(type default)
		)
		(layer "In5.Cu")
	)
	(gr_line
		(start 40.922956 -332.714092)
		(end 40.779192 -332.239874)
		(stroke
			(width 0.08255)
			(type default)
		)
		(layer "In5.Cu")
	)
	(gr_line
		(start 40.983916 -319.995296)
		(end 40.983916 -319.966848)
		(stroke
			(width 0.05715)
			(type default)
		)
		(layer "In5.Cu")
	)
	(gr_line
		(start 40.983916 -319.966848)
		(end 41.029636 -319.921128)
		(stroke
			(width 0.05715)
			(type default)
		)
		(layer "In5.Cu")
	)
	(gr_line
		(start 41.032684 -332.772512)
		(end 40.922956 -332.714092)
		(stroke
			(width 0.08255)
			(type default)
		)
		(layer "In5.Cu")
	)
	(gr_line
		(start 41.033954 -332.773274)
		(end 41.034208 -332.773274)
		(stroke
			(width 0.08255)
			(type default)
		)
		(layer "In5.Cu")
	)
	(gr_line
		(start 41.1099 -409.490164)
		(end 41.1099 -409.108148)
		(stroke
			(width 0.08255)
			(type default)
		)
		(layer "In5.Cu")
	)
	(gr_line
		(start 41.1099 -409.108148)
		(end 41.2369 -408.981148)
		(stroke
			(width 0.08255)
			(type default)
		)
		(layer "In5.Cu")
	)
	(gr_line
		(start 41.1099 -408.572208)
		(end 41.2369 -408.699208)
		(stroke
			(width 0.08255)
			(type default)
		)
		(layer "In5.Cu")
	)
	(gr_line
		(start 41.1099 -408.190192)
		(end 41.1099 -408.572208)
		(stroke
			(width 0.08255)
			(type default)
		)
		(layer "In5.Cu")
	)
	(gr_line
		(start 41.1099 -382.57226)
		(end 41.2369 -382.69926)
		(stroke
			(width 0.08255)
			(type default)
		)
		(layer "In5.Cu")
	)
	(gr_line
		(start 41.1099 -382.18999)
		(end 41.1099 -382.57226)
		(stroke
			(width 0.08255)
			(type default)
		)
		(layer "In5.Cu")
	)
	(gr_line
		(start 41.118536 -333.357982)
		(end 41.17721 -333.248762)
		(stroke
			(width 0.08255)
			(type default)
		)
		(layer "In5.Cu")
	)
	(gr_line
		(start 41.177972 -333.247238)
		(end 41.177718 -333.247238)
		(stroke
			(width 0.08255)
			(type default)
		)
		(layer "In5.Cu")
	)
	(gr_line
		(start 41.2623 -333.8322)
		(end 41.118536 -333.357982)
		(stroke
			(width 0.08255)
			(type default)
		)
		(layer "In5.Cu")
	)
	(gr_line
		(start 41.371774 -333.89062)
		(end 41.2623 -333.8322)
		(stroke
			(width 0.08255)
			(type default)
		)
		(layer "In5.Cu")
	)
	(gr_line
		(start 41.373044 -333.891382)
		(end 41.373552 -333.891382)
		(stroke
			(width 0.08255)
			(type default)
		)
		(layer "In5.Cu")
	)
	(gr_line
		(start 41.485566 -316.229492)
		(end 41.599866 -316.115192)
		(stroke
			(width 0.05715)
			(type default)
		)
		(layer "In5.Cu")
	)
	(gr_line
		(start 41.599866 -316.115192)
		(end 41.599866 -315.849762)
		(stroke
			(width 0.05715)
			(type default)
		)
		(layer "In5.Cu")
	)
	(gr_line
		(start 43.149774 -150.576026)
		(end 43.14952 -150.576026)
		(stroke
			(width 0.08255)
			(type default)
		)
		(layer "In5.Cu")
	)
	(gr_line
		(start 43.198796 -151.297386)
		(end 43.304206 -151.17699)
		(stroke
			(width 0.08255)
			(type default)
		)
		(layer "In5.Cu")
	)
	(gr_line
		(start 43.27144 -150.682452)
		(end 43.151044 -150.577296)
		(stroke
			(width 0.08255)
			(type default)
		)
		(layer "In5.Cu")
	)
	(gr_line
		(start 43.279568 -152.5143)
		(end 43.375072 -152.40508)
		(stroke
			(width 0.08255)
			(type default)
		)
		(layer "In5.Cu")
	)
	(gr_line
		(start 43.304206 -151.17699)
		(end 43.27144 -150.682452)
		(stroke
			(width 0.08255)
			(type default)
		)
		(layer "In5.Cu")
	)
	(gr_line
		(start 43.340782 -151.889206)
		(end 43.231816 -151.793702)
		(stroke
			(width 0.08255)
			(type default)
		)
		(layer "In5.Cu")
	)
	(gr_line
		(start 43.356784 -153.68016)
		(end 43.438826 -153.586688)
		(stroke
			(width 0.08255)
			(type default)
		)
		(layer "In5.Cu")
	)
	(gr_line
		(start 43.375072 -152.40508)
		(end 43.340782 -151.889206)
		(stroke
			(width 0.08255)
			(type default)
		)
		(layer "In5.Cu")
	)
	(gr_line
		(start 43.40606 -153.09215)
		(end 43.312334 -153.010362)
		(stroke
			(width 0.08255)
			(type default)
		)
		(layer "In5.Cu")
	)
	(gr_line
		(start 43.434254 -154.846274)
		(end 43.503596 -154.767026)
		(stroke
			(width 0.08255)
			(type default)
		)
		(layer "In5.Cu")
	)
	(gr_line
		(start 43.438826 -153.586688)
		(end 43.40606 -153.09215)
		(stroke
			(width 0.08255)
			(type default)
		)
		(layer "In5.Cu")
	)
	(gr_line
		(start 43.469052 -154.245564)
		(end 43.389804 -154.176222)
		(stroke
			(width 0.08255)
			(type default)
		)
		(layer "In5.Cu")
	)
	(gr_line
		(start 43.503596 -154.767026)
		(end 43.469052 -154.245564)
		(stroke
			(width 0.08255)
			(type default)
		)
		(layer "In5.Cu")
	)
	(gr_line
		(start 45.719492 -334.82407)
		(end 45.761402 -334.706976)
		(stroke
			(width 0.08255)
			(type default)
		)
		(layer "In5.Cu")
	)
	(gr_line
		(start 45.931582 -335.272126)
		(end 45.719492 -334.82407)
		(stroke
			(width 0.08255)
			(type default)
		)
		(layer "In5.Cu")
	)
	(gr_line
		(start 46.048422 -335.314036)
		(end 45.931582 -335.272126)
		(stroke
			(width 0.08255)
			(type default)
		)
		(layer "In5.Cu")
	)
	(gr_line
		(start 46.21911 -335.880456)
		(end 46.26102 -335.763616)
		(stroke
			(width 0.08255)
			(type default)
		)
		(layer "In5.Cu")
	)
	(gr_line
		(start 46.4312 -336.328512)
		(end 46.21911 -335.880456)
		(stroke
			(width 0.08255)
			(type default)
		)
		(layer "In5.Cu")
	)
	(gr_line
		(start 46.547786 -336.370168)
		(end 46.4312 -336.328512)
		(stroke
			(width 0.08255)
			(type default)
		)
		(layer "In5.Cu")
	)
	(gr_line
		(start 46.54931 -336.371184)
		(end 46.549564 -336.37093)
		(stroke
			(width 0.08255)
			(type default)
		)
		(layer "In5.Cu")
	)
	(gr_line
		(start 46.718474 -336.937096)
		(end 46.760384 -336.820002)
		(stroke
			(width 0.08255)
			(type default)
		)
		(layer "In5.Cu")
	)
	(gr_line
		(start 46.930564 -337.385152)
		(end 46.718474 -336.937096)
		(stroke
			(width 0.08255)
			(type default)
		)
		(layer "In5.Cu")
	)
	(gr_line
		(start 47.047404 -337.427062)
		(end 46.930564 -337.385152)
		(stroke
			(width 0.08255)
			(type default)
		)
		(layer "In5.Cu")
	)
	(gr_line
		(start 48.745648 -341.01659)
		(end 48.745648 -341.016336)
		(stroke
			(width 0.08255)
			(type default)
		)
		(layer "In5.Cu")
	)
	(gr_line
		(start 49.425352 -142.648178)
		(end 49.425352 -142.648432)
		(stroke
			(width 0.08255)
			(type default)
		)
		(layer "In5.Cu")
	)
	(gr_line
		(start 49.42713 -142.647416)
		(end 49.574958 -142.586202)
		(stroke
			(width 0.08255)
			(type default)
		)
		(layer "In5.Cu")
	)
	(gr_line
		(start 49.574958 -142.586202)
		(end 49.764442 -142.128494)
		(stroke
			(width 0.08255)
			(type default)
		)
		(layer "In5.Cu")
	)
	(gr_line
		(start 49.764442 -142.128494)
		(end 49.703228 -141.980666)
		(stroke
			(width 0.08255)
			(type default)
		)
		(layer "In5.Cu")
	)
	(gr_line
		(start 50.022506 -140.713206)
		(end 50.135536 -140.600176)
		(stroke
			(width 0.08255)
			(type default)
		)
		(layer "In5.Cu")
	)
	(gr_line
		(start 50.022506 -139.494006)
		(end 50.135536 -139.380976)
		(stroke
			(width 0.08255)
			(type default)
		)
		(layer "In5.Cu")
	)
	(gr_line
		(start 50.135536 -140.600176)
		(end 50.135536 -140.104876)
		(stroke
			(width 0.08255)
			(type default)
		)
		(layer "In5.Cu")
	)
	(gr_line
		(start 50.135536 -140.104876)
		(end 50.022506 -139.991846)
		(stroke
			(width 0.08255)
			(type default)
		)
		(layer "In5.Cu")
	)
	(gr_line
		(start 50.135536 -139.380976)
		(end 50.135536 -138.885676)
		(stroke
			(width 0.08255)
			(type default)
		)
		(layer "In5.Cu")
	)
	(gr_line
		(start 50.135536 -138.885676)
		(end 50.022506 -138.772646)
		(stroke
			(width 0.08255)
			(type default)
		)
		(layer "In5.Cu")
	)
	(gr_line
		(start 50.501804 -136.147048)
		(end 50.501804 -136.147302)
		(stroke
			(width 0.08255)
			(type default)
		)
		(layer "In5.Cu")
	)
	(gr_line
		(start 50.503582 -136.14654)
		(end 50.65395 -136.092438)
		(stroke
			(width 0.08255)
			(type default)
		)
		(layer "In5.Cu")
	)
	(gr_line
		(start 50.65395 -136.092438)
		(end 50.86604 -135.644382)
		(stroke
			(width 0.08255)
			(type default)
		)
		(layer "In5.Cu")
	)
	(gr_line
		(start 50.86604 -135.644382)
		(end 50.812192 -135.49376)
		(stroke
			(width 0.08255)
			(type default)
		)
		(layer "In5.Cu")
	)
	(gr_line
		(start 52.434236 -134.606792)
		(end 52.547266 -134.719822)
		(stroke
			(width 0.08255)
			(type default)
		)
		(layer "In5.Cu")
	)
	(gr_line
		(start 52.547266 -134.719822)
		(end 53.042566 -134.719822)
		(stroke
			(width 0.08255)
			(type default)
		)
		(layer "In5.Cu")
	)
	(gr_line
		(start 53.042566 -134.719822)
		(end 53.155596 -134.606792)
		(stroke
			(width 0.08255)
			(type default)
		)
		(layer "In5.Cu")
	)
	(gr_line
		(start 53.797708 -134.605522)
		(end 53.803804 -134.603236)
		(stroke
			(width 0.08255)
			(type default)
		)
		(layer "In5.Cu")
	)
	(gr_line
		(start 53.803804 -134.603236)
		(end 53.80609 -134.605522)
		(stroke
			(width 0.08255)
			(type default)
		)
		(layer "In5.Cu")
	)
	(gr_line
		(start 53.80609 -134.605522)
		(end 54.09692 -134.896352)
		(stroke
			(width 0.08255)
			(type default)
		)
		(layer "In5.Cu")
	)
	(gr_line
		(start 65.20307 -148.887434)
		(end 65.4939 -148.596604)
		(stroke
			(width 0.08255)
			(type default)
		)
		(layer "In5.Cu")
	)
	(gr_line
		(start 65.20307 -136.177274)
		(end 65.4939 -135.886444)
		(stroke
			(width 0.08255)
			(type default)
		)
		(layer "In5.Cu")
	)
	(gr_line
		(start 65.20307 -121.367296)
		(end 65.4939 -121.076466)
		(stroke
			(width 0.08255)
			(type default)
		)
		(layer "In5.Cu")
	)
	(gr_line
		(start 68.016628 -121.266712)
		(end 68.016628 -121.266966)
		(stroke
			(width 0.08255)
			(type default)
		)
		(layer "In5.Cu")
	)
	(gr_line
		(start 68.01739 -121.26849)
		(end 68.078096 -121.416572)
		(stroke
			(width 0.08255)
			(type default)
		)
		(layer "In5.Cu")
	)
	(gr_line
		(start 68.078096 -121.416572)
		(end 68.53555 -121.606818)
		(stroke
			(width 0.08255)
			(type default)
		)
		(layer "In5.Cu")
	)
	(gr_line
		(start 68.146676 -136.184132)
		(end 68.20916 -136.331706)
		(stroke
			(width 0.08255)
			(type default)
		)
		(layer "In5.Cu")
	)
	(gr_line
		(start 68.20916 -136.331706)
		(end 68.668138 -136.518396)
		(stroke
			(width 0.08255)
			(type default)
		)
		(layer "In5.Cu")
	)
	(gr_line
		(start 68.27647 -149.413468)
		(end 68.62699 -149.763988)
		(stroke
			(width 0.08255)
			(type default)
		)
		(layer "In5.Cu")
	)
	(gr_line
		(start 68.27647 -149.289516)
		(end 68.27647 -149.413468)
		(stroke
			(width 0.08255)
			(type default)
		)
		(layer "In5.Cu")
	)
	(gr_line
		(start 68.53555 -121.606818)
		(end 68.683632 -121.545858)
		(stroke
			(width 0.08255)
			(type default)
		)
		(layer "In5.Cu")
	)
	(gr_line
		(start 68.62699 -149.763988)
		(end 68.750942 -149.763988)
		(stroke
			(width 0.08255)
			(type default)
		)
		(layer "In5.Cu")
	)
	(gr_line
		(start 68.668138 -136.518396)
		(end 68.815458 -136.455912)
		(stroke
			(width 0.08255)
			(type default)
		)
		(layer "In5.Cu")
	)
	(gr_line
		(start 69.102732 -150.23973)
		(end 69.453252 -150.59025)
		(stroke
			(width 0.08255)
			(type default)
		)
		(layer "In5.Cu")
	)
	(gr_line
		(start 69.102732 -150.115778)
		(end 69.102732 -150.23973)
		(stroke
			(width 0.08255)
			(type default)
		)
		(layer "In5.Cu")
	)
	(gr_line
		(start 69.143118 -121.73712)
		(end 69.203824 -121.885202)
		(stroke
			(width 0.08255)
			(type default)
		)
		(layer "In5.Cu")
	)
	(gr_line
		(start 69.203824 -121.885202)
		(end 69.661278 -122.075702)
		(stroke
			(width 0.08255)
			(type default)
		)
		(layer "In5.Cu")
	)
	(gr_line
		(start 69.276468 -136.643364)
		(end 69.338444 -136.791192)
		(stroke
			(width 0.08255)
			(type default)
		)
		(layer "In5.Cu")
	)
	(gr_line
		(start 69.338444 -136.791192)
		(end 69.797422 -136.977628)
		(stroke
			(width 0.08255)
			(type default)
		)
		(layer "In5.Cu")
	)
	(gr_line
		(start 69.453252 -150.59025)
		(end 69.577204 -150.59025)
		(stroke
			(width 0.08255)
			(type default)
		)
		(layer "In5.Cu")
	)
	(gr_line
		(start 69.661278 -122.075702)
		(end 69.809614 -122.014742)
		(stroke
			(width 0.08255)
			(type default)
		)
		(layer "In5.Cu")
	)
	(gr_line
		(start 69.797422 -136.977628)
		(end 69.94525 -136.915398)
		(stroke
			(width 0.08255)
			(type default)
		)
		(layer "In5.Cu")
	)
	(gr_line
		(start 70.268592 -122.20575)
		(end 70.329552 -122.354086)
		(stroke
			(width 0.08255)
			(type default)
		)
		(layer "In5.Cu")
	)
	(gr_line
		(start 70.329552 -122.354086)
		(end 70.787006 -122.544586)
		(stroke
			(width 0.08255)
			(type default)
		)
		(layer "In5.Cu")
	)
	(gr_line
		(start 70.405752 -137.10285)
		(end 70.467982 -137.250424)
		(stroke
			(width 0.08255)
			(type default)
		)
		(layer "In5.Cu")
	)
	(gr_line
		(start 70.467982 -137.250424)
		(end 70.927214 -137.437114)
		(stroke
			(width 0.08255)
			(type default)
		)
		(layer "In5.Cu")
	)
	(gr_line
		(start 70.787006 -122.544586)
		(end 70.935342 -122.483372)
		(stroke
			(width 0.08255)
			(type default)
		)
		(layer "In5.Cu")
	)
	(gr_line
		(start 70.927214 -137.437114)
		(end 71.074788 -137.374884)
		(stroke
			(width 0.08255)
			(type default)
		)
		(layer "In5.Cu")
	)
	(gr_line
		(start 71.39432 -122.674634)
		(end 71.45528 -122.822716)
		(stroke
			(width 0.08255)
			(type default)
		)
		(layer "In5.Cu")
	)
	(gr_line
		(start 71.45528 -122.822716)
		(end 71.912734 -123.013216)
		(stroke
			(width 0.08255)
			(type default)
		)
		(layer "In5.Cu")
	)
	(gr_line
		(start 71.912734 -123.013216)
		(end 72.060816 -122.952002)
		(stroke
			(width 0.08255)
			(type default)
		)
		(layer "In5.Cu")
	)
	(gr_line
		(start 72.570086 -271.600168)
		(end 72.615806 -271.554448)
		(stroke
			(width 0.05715)
			(type default)
		)
		(layer "In5.Cu")
	)
	(gr_line
		(start 72.615806 -271.554448)
		(end 72.615806 -271.526)
		(stroke
			(width 0.05715)
			(type default)
		)
		(layer "In5.Cu")
	)
	(gr_line
		(start 72.615806 -271.398238)
		(end 72.615806 -271.39773)
		(stroke
			(width 0.08255)
			(type default)
		)
		(layer "In5.Cu")
	)
	(gr_line
		(start 72.615806 -271.397222)
		(end 72.615806 -271.396714)
		(stroke
			(width 0.08255)
			(type default)
		)
		(layer "In5.Cu")
	)
	(gr_line
		(start 72.949562 -273.365214)
		(end 72.835262 -273.479514)
		(stroke
			(width 0.05715)
			(type default)
		)
		(layer "In5.Cu")
	)
	(gr_line
		(start 72.949562 -273.099784)
		(end 72.949562 -273.365214)
		(stroke
			(width 0.05715)
			(type default)
		)
		(layer "In5.Cu")
	)
	(gr_line
		(start 74.992484 -161.108136)
		(end 74.992992 -161.110676)
		(stroke
			(width 0.08255)
			(type default)
		)
		(layer "In5.Cu")
	)
	(gr_line
		(start 74.992738 -161.108136)
		(end 74.992484 -161.108136)
		(stroke
			(width 0.08255)
			(type default)
		)
		(layer "In5.Cu")
	)
	(gr_line
		(start 74.992738 -161.107882)
		(end 74.992738 -161.108136)
		(stroke
			(width 0.08255)
			(type default)
		)
		(layer "In5.Cu")
	)
	(gr_line
		(start 75.027536 -143.590518)
		(end 75.137518 -144.073626)
		(stroke
			(width 0.08255)
			(type default)
		)
		(layer "In5.Cu")
	)
	(gr_line
		(start 75.11288 -143.454882)
		(end 75.027536 -143.590518)
		(stroke
			(width 0.08255)
			(type default)
		)
		(layer "In5.Cu")
	)
	(gr_line
		(start 75.137518 -144.073626)
		(end 75.273154 -144.158716)
		(stroke
			(width 0.08255)
			(type default)
		)
		(layer "In5.Cu")
	)
	(gr_line
		(start 75.298554 -144.779492)
		(end 75.408536 -145.2626)
		(stroke
			(width 0.08255)
			(type default)
		)
		(layer "In5.Cu")
	)
	(gr_line
		(start 75.347576 -126.049786)
		(end 75.671426 -126.425198)
		(stroke
			(width 0.08255)
			(type default)
		)
		(layer "In5.Cu")
	)
	(gr_line
		(start 75.35672 -125.925834)
		(end 75.347576 -126.049786)
		(stroke
			(width 0.08255)
			(type default)
		)
		(layer "In5.Cu")
	)
	(gr_line
		(start 75.383644 -144.643856)
		(end 75.298554 -144.779492)
		(stroke
			(width 0.08255)
			(type default)
		)
		(layer "In5.Cu")
	)
	(gr_line
		(start 75.408536 -145.2626)
		(end 75.543918 -145.34769)
		(stroke
			(width 0.08255)
			(type default)
		)
		(layer "In5.Cu")
	)
	(gr_line
		(start 75.569318 -145.968466)
		(end 75.6793 -146.451574)
		(stroke
			(width 0.08255)
			(type default)
		)
		(layer "In5.Cu")
	)
	(gr_line
		(start 75.654408 -145.83283)
		(end 75.569318 -145.968466)
		(stroke
			(width 0.08255)
			(type default)
		)
		(layer "In5.Cu")
	)
	(gr_line
		(start 75.671426 -126.425198)
		(end 75.795124 -126.434342)
		(stroke
			(width 0.08255)
			(type default)
		)
		(layer "In5.Cu")
	)
	(gr_line
		(start 75.6793 -146.451574)
		(end 75.814682 -146.536664)
		(stroke
			(width 0.08255)
			(type default)
		)
		(layer "In5.Cu")
	)
	(gr_line
		(start 76.110846 -126.934722)
		(end 76.434442 -127.310134)
		(stroke
			(width 0.08255)
			(type default)
		)
		(layer "In5.Cu")
	)
	(gr_line
		(start 76.11999 -126.81077)
		(end 76.110846 -126.934722)
		(stroke
			(width 0.08255)
			(type default)
		)
		(layer "In5.Cu")
	)
	(gr_line
		(start 76.434442 -127.310134)
		(end 76.55814 -127.319278)
		(stroke
			(width 0.08255)
			(type default)
		)
		(layer "In5.Cu")
	)
	(gr_line
		(start 76.874116 -127.819658)
		(end 77.197712 -128.19507)
		(stroke
			(width 0.08255)
			(type default)
		)
		(layer "In5.Cu")
	)
	(gr_line
		(start 76.88326 -127.69596)
		(end 76.874116 -127.819658)
		(stroke
			(width 0.08255)
			(type default)
		)
		(layer "In5.Cu")
	)
	(gr_line
		(start 77.197712 -128.19507)
		(end 77.32141 -128.204214)
		(stroke
			(width 0.08255)
			(type default)
		)
		(layer "In5.Cu")
	)
	(gr_line
		(start 78.03388 -271.802352)
		(end 78.0796 -271.848072)
		(stroke
			(width 0.05715)
			(type default)
		)
		(layer "In5.Cu")
	)
	(gr_line
		(start 78.03388 -271.773904)
		(end 78.03388 -271.802352)
		(stroke
			(width 0.05715)
			(type default)
		)
		(layer "In5.Cu")
	)
	(gr_line
		(start 78.535276 -273.670014)
		(end 78.649576 -273.784314)
		(stroke
			(width 0.05715)
			(type default)
		)
		(layer "In5.Cu")
	)
	(gr_line
		(start 78.649576 -273.784314)
		(end 78.649576 -274.049744)
		(stroke
			(width 0.05715)
			(type default)
		)
		(layer "In5.Cu")
	)
	(gr_line
		(start 81.765394 -287.349946)
		(end 81.499964 -287.349946)
		(stroke
			(width 0.05715)
			(type default)
		)
		(layer "In5.Cu")
	)
	(gr_line
		(start 81.765394 -281.649932)
		(end 81.499964 -281.649932)
		(stroke
			(width 0.05715)
			(type default)
		)
		(layer "In5.Cu")
	)
	(gr_line
		(start 81.879694 -287.235646)
		(end 81.765394 -287.349946)
		(stroke
			(width 0.05715)
			(type default)
		)
		(layer "In5.Cu")
	)
	(gr_line
		(start 81.879694 -281.535632)
		(end 81.765394 -281.649932)
		(stroke
			(width 0.05715)
			(type default)
		)
		(layer "In5.Cu")
	)
	(gr_line
		(start 83.9216 -286.733996)
		(end 83.87588 -286.779716)
		(stroke
			(width 0.05715)
			(type default)
		)
		(layer "In5.Cu")
	)
	(gr_line
		(start 83.9216 -281.033982)
		(end 83.87588 -281.079702)
		(stroke
			(width 0.05715)
			(type default)
		)
		(layer "In5.Cu")
	)
	(gr_line
		(start 83.950048 -286.733996)
		(end 83.9216 -286.733996)
		(stroke
			(width 0.05715)
			(type default)
		)
		(layer "In5.Cu")
	)
	(gr_line
		(start 83.950048 -281.033982)
		(end 83.9216 -281.033982)
		(stroke
			(width 0.05715)
			(type default)
		)
		(layer "In5.Cu")
	)
	(gr_line
		(start 89.509854 -382.57607)
		(end 89.629234 -382.69545)
		(stroke
			(width 0.08255)
			(type default)
		)
		(layer "In5.Cu")
	)
	(gr_line
		(start 89.509854 -382.18999)
		(end 89.509854 -382.57607)
		(stroke
			(width 0.08255)
			(type default)
		)
		(layer "In5.Cu")
	)
	(gr_line
		(start 89.629234 -382.69545)
		(end 89.636854 -382.69545)
		(stroke
			(width 0.08255)
			(type default)
		)
		(layer "In5.Cu")
	)
	(gr_line
		(start 92.019628 -366.19942)
		(end 92.292932 -365.801148)
		(stroke
			(width 0.08255)
			(type default)
		)
		(layer "In5.Cu")
	)
	(gr_line
		(start 92.048076 -366.35309)
		(end 92.019628 -366.19942)
		(stroke
			(width 0.08255)
			(type default)
		)
		(layer "In5.Cu")
	)
	(gr_line
		(start 92.292932 -365.801148)
		(end 92.446602 -365.7727)
		(stroke
			(width 0.08255)
			(type default)
		)
		(layer "In5.Cu")
	)
	(gr_line
		(start 92.692728 -365.219488)
		(end 92.966032 -364.821216)
		(stroke
			(width 0.08255)
			(type default)
		)
		(layer "In5.Cu")
	)
	(gr_line
		(start 92.721176 -365.373158)
		(end 92.692728 -365.219488)
		(stroke
			(width 0.08255)
			(type default)
		)
		(layer "In5.Cu")
	)
	(gr_line
		(start 92.966032 -364.821216)
		(end 93.119702 -364.792768)
		(stroke
			(width 0.08255)
			(type default)
		)
		(layer "In5.Cu")
	)
	(gr_line
		(start 93.365828 -364.239556)
		(end 93.639386 -363.841284)
		(stroke
			(width 0.08255)
			(type default)
		)
		(layer "In5.Cu")
	)
	(gr_line
		(start 93.394276 -364.393226)
		(end 93.365828 -364.239556)
		(stroke
			(width 0.08255)
			(type default)
		)
		(layer "In5.Cu")
	)
	(gr_line
		(start 93.639386 -363.841284)
		(end 93.792802 -363.812836)
		(stroke
			(width 0.08255)
			(type default)
		)
		(layer "In5.Cu")
	)
	(gr_line
		(start 94.038928 -363.259624)
		(end 94.312486 -362.861352)
		(stroke
			(width 0.08255)
			(type default)
		)
		(layer "In5.Cu")
	)
	(gr_line
		(start 94.067376 -363.413294)
		(end 94.038928 -363.259624)
		(stroke
			(width 0.08255)
			(type default)
		)
		(layer "In5.Cu")
	)
	(gr_line
		(start 94.312486 -362.861352)
		(end 94.466156 -362.832904)
		(stroke
			(width 0.08255)
			(type default)
		)
		(layer "In5.Cu")
	)
	(gr_line
		(start 94.712028 -362.279692)
		(end 94.985586 -361.881674)
		(stroke
			(width 0.08255)
			(type default)
		)
		(layer "In5.Cu")
	)
	(gr_line
		(start 94.740476 -362.433362)
		(end 94.712028 -362.279692)
		(stroke
			(width 0.08255)
			(type default)
		)
		(layer "In5.Cu")
	)
	(gr_line
		(start 94.985586 -361.881674)
		(end 95.139256 -361.852972)
		(stroke
			(width 0.08255)
			(type default)
		)
		(layer "In5.Cu")
	)
	(gr_line
		(start 95.385128 -361.29976)
		(end 95.658686 -360.901742)
		(stroke
			(width 0.08255)
			(type default)
		)
		(layer "In5.Cu")
	)
	(gr_line
		(start 95.413576 -361.453684)
		(end 95.385128 -361.29976)
		(stroke
			(width 0.08255)
			(type default)
		)
		(layer "In5.Cu")
	)
	(gr_line
		(start 95.658686 -360.901742)
		(end 95.812356 -360.87304)
		(stroke
			(width 0.08255)
			(type default)
		)
		(layer "In5.Cu")
	)
	(gr_line
		(start 96.2787 -359.43921)
		(end 96.2787 -358.95661)
		(stroke
			(width 0.08255)
			(type default)
		)
		(layer "In5.Cu")
	)
	(gr_line
		(start 96.2787 -358.95661)
		(end 96.38919 -358.84612)
		(stroke
			(width 0.08255)
			(type default)
		)
		(layer "In5.Cu")
	)
	(gr_line
		(start 96.2787 -358.25049)
		(end 96.2787 -357.76789)
		(stroke
			(width 0.08255)
			(type default)
		)
		(layer "In5.Cu")
	)
	(gr_line
		(start 96.2787 -357.76789)
		(end 96.38919 -357.6574)
		(stroke
			(width 0.08255)
			(type default)
		)
		(layer "In5.Cu")
	)
	(gr_line
		(start 96.2787 -357.06177)
		(end 96.2787 -356.57917)
		(stroke
			(width 0.08255)
			(type default)
		)
		(layer "In5.Cu")
	)
	(gr_line
		(start 96.2787 -356.57917)
		(end 96.38919 -356.46868)
		(stroke
			(width 0.08255)
			(type default)
		)
		(layer "In5.Cu")
	)
	(gr_line
		(start 96.38919 -359.5497)
		(end 96.2787 -359.43921)
		(stroke
			(width 0.08255)
			(type default)
		)
		(layer "In5.Cu")
	)
	(gr_line
		(start 96.38919 -358.36098)
		(end 96.2787 -358.25049)
		(stroke
			(width 0.08255)
			(type default)
		)
		(layer "In5.Cu")
	)
	(gr_line
		(start 96.38919 -357.17226)
		(end 96.2787 -357.06177)
		(stroke
			(width 0.08255)
			(type default)
		)
		(layer "In5.Cu")
	)
	(gr_line
		(start 114.718338 -334.435958)
		(end 114.718338 -334.279494)
		(stroke
			(width 0.08255)
			(type default)
		)
		(layer "In5.Cu")
	)
	(gr_line
		(start 114.718338 -334.279494)
		(end 115.059968 -333.938118)
		(stroke
			(width 0.08255)
			(type default)
		)
		(layer "In5.Cu")
	)
	(gr_line
		(start 115.059968 -333.938118)
		(end 115.216178 -333.938118)
		(stroke
			(width 0.08255)
			(type default)
		)
		(layer "In5.Cu")
	)
	(gr_line
		(start 115.70462 -331.2414)
		(end 115.41379 -331.53223)
		(stroke
			(width 0.08255)
			(type default)
		)
		(layer "In5.Cu")
	)
	(gr_line
		(start 115.910106 -396.871952)
		(end 116.03736 -396.999206)
		(stroke
			(width 0.08255)
			(type default)
		)
		(layer "In5.Cu")
	)
	(gr_line
		(start 115.910106 -396.49019)
		(end 115.910106 -396.871952)
		(stroke
			(width 0.08255)
			(type default)
		)
		(layer "In5.Cu")
	)
	(gr_line
		(start 116.875306 -395.771624)
		(end 117.119908 -395.310868)
		(stroke
			(width 0.08255)
			(type default)
		)
		(layer "In5.Cu")
	)
	(gr_line
		(start 116.913152 -395.895068)
		(end 116.875306 -395.771624)
		(stroke
			(width 0.08255)
			(type default)
		)
		(layer "In5.Cu")
	)
	(gr_line
		(start 117.119908 -395.310868)
		(end 117.243098 -395.273022)
		(stroke
			(width 0.08255)
			(type default)
		)
		(layer "In5.Cu")
	)
	(gr_line
		(start 118.11 -397.972026)
		(end 118.237254 -398.09928)
		(stroke
			(width 0.08255)
			(type default)
		)
		(layer "In5.Cu")
	)
	(gr_line
		(start 118.11 -397.59001)
		(end 118.11 -397.972026)
		(stroke
			(width 0.08255)
			(type default)
		)
		(layer "In5.Cu")
	)
	(gr_line
		(start 118.284498 -393.911582)
		(end 118.334282 -393.763246)
		(stroke
			(width 0.08255)
			(type default)
		)
		(layer "In5.Cu")
	)
	(gr_line
		(start 118.334282 -393.763246)
		(end 118.76659 -393.548108)
		(stroke
			(width 0.08255)
			(type default)
		)
		(layer "In5.Cu")
	)
	(gr_line
		(start 118.76659 -393.548108)
		(end 118.91518 -393.597892)
		(stroke
			(width 0.08255)
			(type default)
		)
		(layer "In5.Cu")
	)
	(gr_line
		(start 118.7958 -397.212566)
		(end 118.7958 -396.689834)
		(stroke
			(width 0.08255)
			(type default)
		)
		(layer "In5.Cu")
	)
	(gr_line
		(start 118.7958 -396.689834)
		(end 118.886224 -396.59941)
		(stroke
			(width 0.08255)
			(type default)
		)
		(layer "In5.Cu")
	)
	(gr_line
		(start 118.886224 -397.30299)
		(end 118.7958 -397.212566)
		(stroke
			(width 0.08255)
			(type default)
		)
		(layer "In5.Cu")
	)
	(gr_line
		(start 118.977918 -395.561312)
		(end 119.18315 -395.082014)
		(stroke
			(width 0.08255)
			(type default)
		)
		(layer "In5.Cu")
	)
	(gr_line
		(start 119.025924 -395.6812)
		(end 118.977918 -395.561312)
		(stroke
			(width 0.08255)
			(type default)
		)
		(layer "In5.Cu")
	)
	(gr_line
		(start 119.18315 -395.082014)
		(end 119.303292 -395.034008)
		(stroke
			(width 0.08255)
			(type default)
		)
		(layer "In5.Cu")
	)
	(gr_line
		(start 119.304816 -395.033246)
		(end 119.304816 -395.032738)
		(stroke
			(width 0.08255)
			(type default)
		)
		(layer "In5.Cu")
	)
	(gr_line
		(start 120.310148 -396.871952)
		(end 120.437402 -396.999206)
		(stroke
			(width 0.08255)
			(type default)
		)
		(layer "In5.Cu")
	)
	(gr_line
		(start 120.310148 -396.49019)
		(end 120.310148 -396.871952)
		(stroke
			(width 0.08255)
			(type default)
		)
		(layer "In5.Cu")
	)
	(gr_line
		(start 120.310148 -374.772174)
		(end 120.437148 -374.899174)
		(stroke
			(width 0.08255)
			(type default)
		)
		(layer "In5.Cu")
	)
	(gr_line
		(start 120.310148 -374.390158)
		(end 120.310148 -374.772174)
		(stroke
			(width 0.08255)
			(type default)
		)
		(layer "In5.Cu")
	)
	(gr_line
		(start 121.37898 -395.344142)
		(end 121.703338 -394.946378)
		(stroke
			(width 0.08255)
			(type default)
		)
		(layer "In5.Cu")
	)
	(gr_line
		(start 121.392442 -395.478508)
		(end 121.37898 -395.344142)
		(stroke
			(width 0.08255)
			(type default)
		)
		(layer "In5.Cu")
	)
	(gr_line
		(start 121.703338 -394.946378)
		(end 121.837704 -394.932916)
		(stroke
			(width 0.08255)
			(type default)
		)
		(layer "In5.Cu")
	)
	(gr_line
		(start 121.92889 -367.927382)
		(end 122.21337 -367.537238)
		(stroke
			(width 0.08255)
			(type default)
		)
		(layer "In5.Cu")
	)
	(gr_line
		(start 121.953274 -368.082322)
		(end 121.92889 -367.927382)
		(stroke
			(width 0.08255)
			(type default)
		)
		(layer "In5.Cu")
	)
	(gr_line
		(start 122.21337 -367.537238)
		(end 122.36831 -367.512854)
		(stroke
			(width 0.08255)
			(type default)
		)
		(layer "In5.Cu")
	)
	(gr_line
		(start 122.497088 -394.29182)
		(end 122.510804 -394.168376)
		(stroke
			(width 0.08255)
			(type default)
		)
		(layer "In5.Cu")
	)
	(gr_line
		(start 122.510042 -397.972026)
		(end 122.637296 -398.09928)
		(stroke
			(width 0.08255)
			(type default)
		)
		(layer "In5.Cu")
	)
	(gr_line
		(start 122.510042 -397.59001)
		(end 122.510042 -397.972026)
		(stroke
			(width 0.08255)
			(type default)
		)
		(layer "In5.Cu")
	)
	(gr_line
		(start 122.510804 -394.168376)
		(end 122.898154 -393.859004)
		(stroke
			(width 0.08255)
			(type default)
		)
		(layer "In5.Cu")
	)
	(gr_line
		(start 122.629168 -366.9665)
		(end 122.913648 -366.576356)
		(stroke
			(width 0.08255)
			(type default)
		)
		(layer "In5.Cu")
	)
	(gr_line
		(start 122.653552 -367.12144)
		(end 122.629168 -366.9665)
		(stroke
			(width 0.08255)
			(type default)
		)
		(layer "In5.Cu")
	)
	(gr_line
		(start 122.898154 -393.859004)
		(end 123.021852 -393.87272)
		(stroke
			(width 0.08255)
			(type default)
		)
		(layer "In5.Cu")
	)
	(gr_line
		(start 122.913648 -366.576356)
		(end 123.068588 -366.551972)
		(stroke
			(width 0.08255)
			(type default)
		)
		(layer "In5.Cu")
	)
	(gr_line
		(start 123.2154 -397.257524)
		(end 123.2154 -396.695676)
		(stroke
			(width 0.08255)
			(type default)
		)
		(layer "In5.Cu")
	)
	(gr_line
		(start 123.2154 -396.695676)
		(end 123.286266 -396.62481)
		(stroke
			(width 0.08255)
			(type default)
		)
		(layer "In5.Cu")
	)
	(gr_line
		(start 123.286266 -397.32839)
		(end 123.2154 -397.257524)
		(stroke
			(width 0.08255)
			(type default)
		)
		(layer "In5.Cu")
	)
	(gr_line
		(start 123.33478 -366.039908)
		(end 123.648216 -365.61014)
		(stroke
			(width 0.08255)
			(type default)
		)
		(layer "In5.Cu")
	)
	(gr_line
		(start 123.340368 -395.650974)
		(end 123.530868 -395.192758)
		(stroke
			(width 0.08255)
			(type default)
		)
		(layer "In5.Cu")
	)
	(gr_line
		(start 123.35383 -366.160558)
		(end 123.33478 -366.039908)
		(stroke
			(width 0.08255)
			(type default)
		)
		(layer "In5.Cu")
	)
	(gr_line
		(start 123.396248 -395.78661)
		(end 123.340368 -395.650974)
		(stroke
			(width 0.08255)
			(type default)
		)
		(layer "In5.Cu")
	)
	(gr_line
		(start 123.523248 -393.47394)
		(end 123.54687 -393.45489)
		(stroke
			(width 0.08255)
			(type default)
		)
		(layer "In5.Cu")
	)
	(gr_line
		(start 123.530868 -395.192758)
		(end 123.666758 -395.136624)
		(stroke
			(width 0.08255)
			(type default)
		)
		(layer "In5.Cu")
	)
	(gr_line
		(start 123.54687 -393.45489)
		(end 123.573794 -393.441682)
		(stroke
			(width 0.08255)
			(type default)
		)
		(layer "In5.Cu")
	)
	(gr_line
		(start 123.648216 -365.61014)
		(end 123.768866 -365.59109)
		(stroke
			(width 0.08255)
			(type default)
		)
		(layer "In5.Cu")
	)
	(gr_line
		(start 124.045218 -365.085376)
		(end 124.383038 -364.62208)
		(stroke
			(width 0.08255)
			(type default)
		)
		(layer "In5.Cu")
	)
	(gr_line
		(start 124.061474 -365.189516)
		(end 124.045218 -365.085376)
		(stroke
			(width 0.08255)
			(type default)
		)
		(layer "In5.Cu")
	)
	(gr_line
		(start 124.383038 -364.62208)
		(end 124.487178 -364.605824)
		(stroke
			(width 0.08255)
			(type default)
		)
		(layer "In5.Cu")
	)
	(gr_line
		(start 126.910084 -397.972026)
		(end 127.037338 -398.09928)
		(stroke
			(width 0.08255)
			(type default)
		)
		(layer "In5.Cu")
	)
	(gr_line
		(start 126.910084 -397.59001)
		(end 126.910084 -397.972026)
		(stroke
			(width 0.08255)
			(type default)
		)
		(layer "In5.Cu")
	)
	(gr_line
		(start 127.6096 -397.226282)
		(end 127.6096 -396.676118)
		(stroke
			(width 0.08255)
			(type default)
		)
		(layer "In5.Cu")
	)
	(gr_line
		(start 127.6096 -396.676118)
		(end 127.686308 -396.59941)
		(stroke
			(width 0.08255)
			(type default)
		)
		(layer "In5.Cu")
	)
	(gr_line
		(start 127.676148 -395.708632)
		(end 127.815594 -395.234668)
		(stroke
			(width 0.08255)
			(type default)
		)
		(layer "In5.Cu")
	)
	(gr_line
		(start 127.686308 -397.30299)
		(end 127.6096 -397.226282)
		(stroke
			(width 0.08255)
			(type default)
		)
		(layer "In5.Cu")
	)
	(gr_line
		(start 127.747014 -395.839188)
		(end 127.676148 -395.708632)
		(stroke
			(width 0.08255)
			(type default)
		)
		(layer "In5.Cu")
	)
	(gr_line
		(start 127.815594 -395.234668)
		(end 127.946658 -395.163802)
		(stroke
			(width 0.08255)
			(type default)
		)
		(layer "In5.Cu")
	)
	(gr_line
		(start 131.310126 -397.972026)
		(end 131.43738 -398.09928)
		(stroke
			(width 0.08255)
			(type default)
		)
		(layer "In5.Cu")
	)
	(gr_line
		(start 131.310126 -397.59001)
		(end 131.310126 -397.972026)
		(stroke
			(width 0.08255)
			(type default)
		)
		(layer "In5.Cu")
	)
	(gr_line
		(start 135.722614 -393.836652)
		(end 135.77443 -393.75842)
		(stroke
			(width 0.08255)
			(type default)
		)
		(layer "In5.Cu")
	)
	(gr_line
		(start 135.77443 -393.75842)
		(end 136.335262 -393.64666)
		(stroke
			(width 0.08255)
			(type default)
		)
		(layer "In5.Cu")
	)
	(gr_line
		(start 136.335262 -393.64666)
		(end 136.41324 -393.698984)
		(stroke
			(width 0.08255)
			(type default)
		)
		(layer "In5.Cu")
	)
	(gr_line
		(start 136.888474 -393.604242)
		(end 136.967976 -393.484862)
		(stroke
			(width 0.08255)
			(type default)
		)
		(layer "In5.Cu")
	)
	(gr_line
		(start 136.967976 -393.484862)
		(end 137.459974 -393.387072)
		(stroke
			(width 0.08255)
			(type default)
		)
		(layer "In5.Cu")
	)
	(gr_line
		(start 137.459974 -393.387072)
		(end 137.5791 -393.466828)
		(stroke
			(width 0.08255)
			(type default)
		)
		(layer "In5.Cu")
	)
	(gr_line
		(start 140.39723 -378.13234)
		(end 140.397738 -378.13234)
		(stroke
			(width 0.08255)
			(type default)
		)
		(layer "In5.Cu")
	)
	(gr_line
		(start 141.345666 -378.42444)
		(end 141.34592 -378.42444)
		(stroke
			(width 0.08255)
			(type default)
		)
		(layer "In5.Cu")
	)
	(gr_line
		(start 159.249364 -150.576026)
		(end 159.249618 -150.576026)
		(stroke
			(width 0.08255)
			(type default)
		)
		(layer "In5.Cu")
	)
	(gr_line
		(start 159.29864 -151.297386)
		(end 159.40405 -151.17699)
		(stroke
			(width 0.08255)
			(type default)
		)
		(layer "In5.Cu")
	)
	(gr_line
		(start 159.371284 -150.682452)
		(end 159.250888 -150.577296)
		(stroke
			(width 0.08255)
			(type default)
		)
		(layer "In5.Cu")
	)
	(gr_line
		(start 159.379412 -152.5143)
		(end 159.474916 -152.40508)
		(stroke
			(width 0.08255)
			(type default)
		)
		(layer "In5.Cu")
	)
	(gr_line
		(start 159.40405 -151.17699)
		(end 159.371284 -150.682452)
		(stroke
			(width 0.08255)
			(type default)
		)
		(layer "In5.Cu")
	)
	(gr_line
		(start 159.440626 -151.889206)
		(end 159.33166 -151.793702)
		(stroke
			(width 0.08255)
			(type default)
		)
		(layer "In5.Cu")
	)
	(gr_line
		(start 159.456628 -153.68016)
		(end 159.53867 -153.586688)
		(stroke
			(width 0.08255)
			(type default)
		)
		(layer "In5.Cu")
	)
	(gr_line
		(start 159.474916 -152.40508)
		(end 159.440626 -151.889206)
		(stroke
			(width 0.08255)
			(type default)
		)
		(layer "In5.Cu")
	)
	(gr_line
		(start 159.505904 -153.09215)
		(end 159.412178 -153.010362)
		(stroke
			(width 0.08255)
			(type default)
		)
		(layer "In5.Cu")
	)
	(gr_line
		(start 159.534098 -154.846274)
		(end 159.60344 -154.767026)
		(stroke
			(width 0.08255)
			(type default)
		)
		(layer "In5.Cu")
	)
	(gr_line
		(start 159.53867 -153.586688)
		(end 159.505904 -153.09215)
		(stroke
			(width 0.08255)
			(type default)
		)
		(layer "In5.Cu")
	)
	(gr_line
		(start 159.568896 -154.245564)
		(end 159.489648 -154.176222)
		(stroke
			(width 0.08255)
			(type default)
		)
		(layer "In5.Cu")
	)
	(gr_line
		(start 159.60344 -154.767026)
		(end 159.568896 -154.245564)
		(stroke
			(width 0.08255)
			(type default)
		)
		(layer "In5.Cu")
	)
	(gr_line
		(start 159.910018 -378.67209)
		(end 160.037018 -378.79909)
		(stroke
			(width 0.08255)
			(type default)
		)
		(layer "In5.Cu")
	)
	(gr_line
		(start 159.910018 -378.290074)
		(end 159.910018 -378.67209)
		(stroke
			(width 0.08255)
			(type default)
		)
		(layer "In5.Cu")
	)
	(gr_line
		(start 162.109912 -379.772164)
		(end 162.236912 -379.899164)
		(stroke
			(width 0.08255)
			(type default)
		)
		(layer "In5.Cu")
	)
	(gr_line
		(start 162.109912 -379.390148)
		(end 162.109912 -379.772164)
		(stroke
			(width 0.08255)
			(type default)
		)
		(layer "In5.Cu")
	)
	(gr_line
		(start 165.525196 -142.648432)
		(end 165.525196 -142.648178)
		(stroke
			(width 0.08255)
			(type default)
		)
		(layer "In5.Cu")
	)
	(gr_line
		(start 165.526974 -142.647416)
		(end 165.674802 -142.586202)
		(stroke
			(width 0.08255)
			(type default)
		)
		(layer "In5.Cu")
	)
	(gr_line
		(start 165.674802 -142.586202)
		(end 165.864286 -142.128494)
		(stroke
			(width 0.08255)
			(type default)
		)
		(layer "In5.Cu")
	)
	(gr_line
		(start 165.864286 -142.128494)
		(end 165.803072 -141.980666)
		(stroke
			(width 0.08255)
			(type default)
		)
		(layer "In5.Cu")
	)
	(gr_line
		(start 166.12235 -140.713206)
		(end 166.23538 -140.600176)
		(stroke
			(width 0.08255)
			(type default)
		)
		(layer "In5.Cu")
	)
	(gr_line
		(start 166.12235 -139.494006)
		(end 166.23538 -139.380976)
		(stroke
			(width 0.08255)
			(type default)
		)
		(layer "In5.Cu")
	)
	(gr_line
		(start 166.23538 -140.600176)
		(end 166.23538 -140.104876)
		(stroke
			(width 0.08255)
			(type default)
		)
		(layer "In5.Cu")
	)
	(gr_line
		(start 166.23538 -140.104876)
		(end 166.12235 -139.991846)
		(stroke
			(width 0.08255)
			(type default)
		)
		(layer "In5.Cu")
	)
	(gr_line
		(start 166.23538 -139.380976)
		(end 166.23538 -138.885676)
		(stroke
			(width 0.08255)
			(type default)
		)
		(layer "In5.Cu")
	)
	(gr_line
		(start 166.23538 -138.885676)
		(end 166.12235 -138.772646)
		(stroke
			(width 0.08255)
			(type default)
		)
		(layer "In5.Cu")
	)
	(gr_line
		(start 166.601648 -136.147302)
		(end 166.601648 -136.147048)
		(stroke
			(width 0.08255)
			(type default)
		)
		(layer "In5.Cu")
	)
	(gr_line
		(start 166.603426 -136.14654)
		(end 166.753794 -136.092438)
		(stroke
			(width 0.08255)
			(type default)
		)
		(layer "In5.Cu")
	)
	(gr_line
		(start 166.753794 -136.092438)
		(end 166.965884 -135.644382)
		(stroke
			(width 0.08255)
			(type default)
		)
		(layer "In5.Cu")
	)
	(gr_line
		(start 166.965884 -135.644382)
		(end 166.912036 -135.49376)
		(stroke
			(width 0.08255)
			(type default)
		)
		(layer "In5.Cu")
	)
	(gr_line
		(start 168.484042 -319.966848)
		(end 168.484042 -319.9384)
		(stroke
			(width 0.05715)
			(type default)
		)
		(layer "In5.Cu")
	)
	(gr_line
		(start 168.484042 -319.9384)
		(end 168.529762 -319.89268)
		(stroke
			(width 0.05715)
			(type default)
		)
		(layer "In5.Cu")
	)
	(gr_line
		(start 168.53408 -134.606792)
		(end 168.64711 -134.719822)
		(stroke
			(width 0.08255)
			(type default)
		)
		(layer "In5.Cu")
	)
	(gr_line
		(start 168.64711 -134.719822)
		(end 169.14241 -134.719822)
		(stroke
			(width 0.08255)
			(type default)
		)
		(layer "In5.Cu")
	)
	(gr_line
		(start 168.710102 -378.67209)
		(end 168.837102 -378.79909)
		(stroke
			(width 0.08255)
			(type default)
		)
		(layer "In5.Cu")
	)
	(gr_line
		(start 168.710102 -378.290074)
		(end 168.710102 -378.67209)
		(stroke
			(width 0.08255)
			(type default)
		)
		(layer "In5.Cu")
	)
	(gr_line
		(start 168.985692 -316.229492)
		(end 169.099992 -316.115192)
		(stroke
			(width 0.05715)
			(type default)
		)
		(layer "In5.Cu")
	)
	(gr_line
		(start 169.099992 -316.115192)
		(end 169.099992 -315.849762)
		(stroke
			(width 0.05715)
			(type default)
		)
		(layer "In5.Cu")
	)
	(gr_line
		(start 169.14241 -134.719822)
		(end 169.25544 -134.606792)
		(stroke
			(width 0.08255)
			(type default)
		)
		(layer "In5.Cu")
	)
	(gr_line
		(start 169.897552 -134.605522)
		(end 169.903648 -134.603236)
		(stroke
			(width 0.08255)
			(type default)
		)
		(layer "In5.Cu")
	)
	(gr_line
		(start 169.903648 -134.603236)
		(end 169.905934 -134.605522)
		(stroke
			(width 0.08255)
			(type default)
		)
		(layer "In5.Cu")
	)
	(gr_line
		(start 169.905934 -134.605522)
		(end 170.196764 -134.896352)
		(stroke
			(width 0.08255)
			(type default)
		)
		(layer "In5.Cu")
	)
	(gr_line
		(start 173.10989 -378.67209)
		(end 173.23689 -378.79909)
		(stroke
			(width 0.08255)
			(type default)
		)
		(layer "In5.Cu")
	)
	(gr_line
		(start 173.10989 -378.290074)
		(end 173.10989 -378.67209)
		(stroke
			(width 0.08255)
			(type default)
		)
		(layer "In5.Cu")
	)
	(gr_line
		(start 174.184056 -319.91173)
		(end 174.184056 -319.883282)
		(stroke
			(width 0.05715)
			(type default)
		)
		(layer "In5.Cu")
	)
	(gr_line
		(start 174.184056 -319.883282)
		(end 174.229776 -319.837562)
		(stroke
			(width 0.05715)
			(type default)
		)
		(layer "In5.Cu")
	)
	(gr_line
		(start 174.685706 -316.229492)
		(end 174.800006 -316.115192)
		(stroke
			(width 0.05715)
			(type default)
		)
		(layer "In5.Cu")
	)
	(gr_line
		(start 174.800006 -316.115192)
		(end 174.800006 -315.849762)
		(stroke
			(width 0.05715)
			(type default)
		)
		(layer "In5.Cu")
	)
	(gr_line
		(start 175.134016 -319.91173)
		(end 175.134016 -319.883282)
		(stroke
			(width 0.05715)
			(type default)
		)
		(layer "In5.Cu")
	)
	(gr_line
		(start 175.134016 -319.883282)
		(end 175.179736 -319.837562)
		(stroke
			(width 0.05715)
			(type default)
		)
		(layer "In5.Cu")
	)
	(gr_line
		(start 175.635666 -318.129666)
		(end 175.749966 -318.015366)
		(stroke
			(width 0.05715)
			(type default)
		)
		(layer "In5.Cu")
	)
	(gr_line
		(start 175.749966 -318.015366)
		(end 175.749966 -317.749936)
		(stroke
			(width 0.05715)
			(type default)
		)
		(layer "In5.Cu")
	)
	(gr_line
		(start 176.083976 -319.91173)
		(end 176.083976 -319.883282)
		(stroke
			(width 0.05715)
			(type default)
		)
		(layer "In5.Cu")
	)
	(gr_line
		(start 176.083976 -319.883282)
		(end 176.129696 -319.837562)
		(stroke
			(width 0.05715)
			(type default)
		)
		(layer "In5.Cu")
	)
	(gr_line
		(start 176.585626 -316.229492)
		(end 176.699926 -316.115192)
		(stroke
			(width 0.05715)
			(type default)
		)
		(layer "In5.Cu")
	)
	(gr_line
		(start 176.699926 -316.115192)
		(end 176.699926 -315.849762)
		(stroke
			(width 0.05715)
			(type default)
		)
		(layer "In5.Cu")
	)
	(gr_line
		(start 177.033936 -319.91173)
		(end 177.033936 -319.883282)
		(stroke
			(width 0.05715)
			(type default)
		)
		(layer "In5.Cu")
	)
	(gr_line
		(start 177.033936 -319.883282)
		(end 177.079656 -319.837562)
		(stroke
			(width 0.05715)
			(type default)
		)
		(layer "In5.Cu")
	)
	(gr_line
		(start 177.535586 -318.129666)
		(end 177.649886 -318.015366)
		(stroke
			(width 0.05715)
			(type default)
		)
		(layer "In5.Cu")
	)
	(gr_line
		(start 177.649886 -318.015366)
		(end 177.649886 -317.749936)
		(stroke
			(width 0.05715)
			(type default)
		)
		(layer "In5.Cu")
	)
	(gr_line
		(start 178.93411 -319.91173)
		(end 178.93411 -319.883282)
		(stroke
			(width 0.05715)
			(type default)
		)
		(layer "In5.Cu")
	)
	(gr_line
		(start 178.93411 -319.883282)
		(end 178.97983 -319.837562)
		(stroke
			(width 0.05715)
			(type default)
		)
		(layer "In5.Cu")
	)
	(gr_line
		(start 179.43576 -318.129666)
		(end 179.55006 -318.015366)
		(stroke
			(width 0.05715)
			(type default)
		)
		(layer "In5.Cu")
	)
	(gr_line
		(start 179.55006 -318.015366)
		(end 179.55006 -317.749936)
		(stroke
			(width 0.05715)
			(type default)
		)
		(layer "In5.Cu")
	)
	(gr_line
		(start 180.83403 -319.941448)
		(end 180.83403 -319.913)
		(stroke
			(width 0.05715)
			(type default)
		)
		(layer "In5.Cu")
	)
	(gr_line
		(start 180.83403 -319.913)
		(end 180.87975 -319.86728)
		(stroke
			(width 0.05715)
			(type default)
		)
		(layer "In5.Cu")
	)
	(gr_line
		(start 181.302914 -136.177274)
		(end 181.593744 -135.886444)
		(stroke
			(width 0.08255)
			(type default)
		)
		(layer "In5.Cu")
	)
	(gr_line
		(start 181.302914 -121.367296)
		(end 181.593744 -121.076466)
		(stroke
			(width 0.08255)
			(type default)
		)
		(layer "In5.Cu")
	)
	(gr_line
		(start 181.33568 -318.129666)
		(end 181.44998 -318.015366)
		(stroke
			(width 0.05715)
			(type default)
		)
		(layer "In5.Cu")
	)
	(gr_line
		(start 181.44998 -318.015366)
		(end 181.44998 -317.749936)
		(stroke
			(width 0.05715)
			(type default)
		)
		(layer "In5.Cu")
	)
	(gr_line
		(start 184.116726 -121.266966)
		(end 184.116726 -121.266712)
		(stroke
			(width 0.08255)
			(type default)
		)
		(layer "In5.Cu")
	)
	(gr_line
		(start 184.117488 -121.26849)
		(end 184.178194 -121.416572)
		(stroke
			(width 0.08255)
			(type default)
		)
		(layer "In5.Cu")
	)
	(gr_line
		(start 184.178194 -121.416572)
		(end 184.635648 -121.606818)
		(stroke
			(width 0.08255)
			(type default)
		)
		(layer "In5.Cu")
	)
	(gr_line
		(start 184.246774 -136.184132)
		(end 184.309258 -136.331706)
		(stroke
			(width 0.08255)
			(type default)
		)
		(layer "In5.Cu")
	)
	(gr_line
		(start 184.309258 -136.331706)
		(end 184.768236 -136.518396)
		(stroke
			(width 0.08255)
			(type default)
		)
		(layer "In5.Cu")
	)
	(gr_line
		(start 184.635648 -121.606818)
		(end 184.78373 -121.545858)
		(stroke
			(width 0.08255)
			(type default)
		)
		(layer "In5.Cu")
	)
	(gr_line
		(start 184.768236 -136.518396)
		(end 184.915556 -136.455912)
		(stroke
			(width 0.08255)
			(type default)
		)
		(layer "In5.Cu")
	)
	(gr_line
		(start 185.243216 -121.73712)
		(end 185.303922 -121.885202)
		(stroke
			(width 0.08255)
			(type default)
		)
		(layer "In5.Cu")
	)
	(gr_line
		(start 185.303922 -121.885202)
		(end 185.761376 -122.075702)
		(stroke
			(width 0.08255)
			(type default)
		)
		(layer "In5.Cu")
	)
	(gr_line
		(start 185.376566 -136.643364)
		(end 185.438542 -136.791192)
		(stroke
			(width 0.08255)
			(type default)
		)
		(layer "In5.Cu")
	)
	(gr_line
		(start 185.438542 -136.791192)
		(end 185.89752 -136.977628)
		(stroke
			(width 0.08255)
			(type default)
		)
		(layer "In5.Cu")
	)
	(gr_line
		(start 185.761376 -122.075702)
		(end 185.909712 -122.014742)
		(stroke
			(width 0.08255)
			(type default)
		)
		(layer "In5.Cu")
	)
	(gr_line
		(start 185.89752 -136.977628)
		(end 186.045348 -136.915398)
		(stroke
			(width 0.08255)
			(type default)
		)
		(layer "In5.Cu")
	)
	(gr_line
		(start 186.36869 -122.20575)
		(end 186.42965 -122.354086)
		(stroke
			(width 0.08255)
			(type default)
		)
		(layer "In5.Cu")
	)
	(gr_line
		(start 186.42965 -122.354086)
		(end 186.887104 -122.544586)
		(stroke
			(width 0.08255)
			(type default)
		)
		(layer "In5.Cu")
	)
	(gr_line
		(start 186.50585 -137.10285)
		(end 186.56808 -137.250424)
		(stroke
			(width 0.08255)
			(type default)
		)
		(layer "In5.Cu")
	)
	(gr_line
		(start 186.56808 -137.250424)
		(end 187.027312 -137.437114)
		(stroke
			(width 0.08255)
			(type default)
		)
		(layer "In5.Cu")
	)
	(gr_line
		(start 186.711336 -339.908388)
		(end 187.017152 -339.518244)
		(stroke
			(width 0.08255)
			(type default)
		)
		(layer "In5.Cu")
	)
	(gr_line
		(start 186.730386 -340.067138)
		(end 186.711336 -339.908388)
		(stroke
			(width 0.08255)
			(type default)
		)
		(layer "In5.Cu")
	)
	(gr_line
		(start 186.887104 -122.544586)
		(end 187.03544 -122.483372)
		(stroke
			(width 0.08255)
			(type default)
		)
		(layer "In5.Cu")
	)
	(gr_line
		(start 187.017152 -339.518244)
		(end 187.175902 -339.499194)
		(stroke
			(width 0.08255)
			(type default)
		)
		(layer "In5.Cu")
	)
	(gr_line
		(start 187.027312 -137.437114)
		(end 187.174886 -137.374884)
		(stroke
			(width 0.08255)
			(type default)
		)
		(layer "In5.Cu")
	)
	(gr_line
		(start 187.463684 -338.948776)
		(end 187.769754 -338.558886)
		(stroke
			(width 0.08255)
			(type default)
		)
		(layer "In5.Cu")
	)
	(gr_line
		(start 187.482988 -339.107526)
		(end 187.463684 -338.948776)
		(stroke
			(width 0.08255)
			(type default)
		)
		(layer "In5.Cu")
	)
	(gr_line
		(start 187.494418 -122.674634)
		(end 187.555378 -122.822716)
		(stroke
			(width 0.08255)
			(type default)
		)
		(layer "In5.Cu")
	)
	(gr_line
		(start 187.555378 -122.822716)
		(end 188.012832 -123.013216)
		(stroke
			(width 0.08255)
			(type default)
		)
		(layer "In5.Cu")
	)
	(gr_line
		(start 187.769754 -338.558886)
		(end 187.928504 -338.539582)
		(stroke
			(width 0.08255)
			(type default)
		)
		(layer "In5.Cu")
	)
	(gr_line
		(start 188.012832 -123.013216)
		(end 188.160914 -122.952002)
		(stroke
			(width 0.08255)
			(type default)
		)
		(layer "In5.Cu")
	)
	(gr_line
		(start 188.216032 -337.989164)
		(end 188.522102 -337.599274)
		(stroke
			(width 0.08255)
			(type default)
		)
		(layer "In5.Cu")
	)
	(gr_line
		(start 188.235336 -338.148168)
		(end 188.216032 -337.989164)
		(stroke
			(width 0.08255)
			(type default)
		)
		(layer "In5.Cu")
	)
	(gr_line
		(start 188.522102 -337.599274)
		(end 188.681106 -337.57997)
		(stroke
			(width 0.08255)
			(type default)
		)
		(layer "In5.Cu")
	)
	(gr_line
		(start 188.585602 -358.765094)
		(end 188.591444 -358.76357)
		(stroke
			(width 0.08255)
			(type default)
		)
		(layer "In5.Cu")
	)
	(gr_line
		(start 188.66993 -271.600168)
		(end 188.71565 -271.554448)
		(stroke
			(width 0.05715)
			(type default)
		)
		(layer "In5.Cu")
	)
	(gr_line
		(start 188.71565 -271.554448)
		(end 188.71565 -271.526)
		(stroke
			(width 0.05715)
			(type default)
		)
		(layer "In5.Cu")
	)
	(gr_line
		(start 188.71565 -271.398238)
		(end 188.71565 -271.39773)
		(stroke
			(width 0.08255)
			(type default)
		)
		(layer "In5.Cu")
	)
	(gr_line
		(start 188.71565 -271.397222)
		(end 188.71565 -271.396714)
		(stroke
			(width 0.08255)
			(type default)
		)
		(layer "In5.Cu")
	)
	(gr_line
		(start 189.04966 -273.36496)
		(end 188.935106 -273.479514)
		(stroke
			(width 0.05715)
			(type default)
		)
		(layer "In5.Cu")
	)
	(gr_line
		(start 189.04966 -273.099784)
		(end 189.04966 -273.36496)
		(stroke
			(width 0.05715)
			(type default)
		)
		(layer "In5.Cu")
	)
	(gr_line
		(start 189.882526 -339.86597)
		(end 190.119 -339.43036)
		(stroke
			(width 0.08255)
			(type default)
		)
		(layer "In5.Cu")
	)
	(gr_line
		(start 189.927738 -340.01964)
		(end 189.882526 -339.86597)
		(stroke
			(width 0.08255)
			(type default)
		)
		(layer "In5.Cu")
	)
	(gr_line
		(start 190.119 -339.43036)
		(end 190.272416 -339.385148)
		(stroke
			(width 0.08255)
			(type default)
		)
		(layer "In5.Cu")
	)
	(gr_line
		(start 191.127634 -143.590518)
		(end 191.237616 -144.073626)
		(stroke
			(width 0.08255)
			(type default)
		)
		(layer "In5.Cu")
	)
	(gr_line
		(start 191.212978 -143.454882)
		(end 191.127634 -143.590518)
		(stroke
			(width 0.08255)
			(type default)
		)
		(layer "In5.Cu")
	)
	(gr_line
		(start 191.237616 -144.073626)
		(end 191.373252 -144.158716)
		(stroke
			(width 0.08255)
			(type default)
		)
		(layer "In5.Cu")
	)
	(gr_line
		(start 191.377316 -333.672434)
		(end 191.636142 -333.249778)
		(stroke
			(width 0.08255)
			(type default)
		)
		(layer "In5.Cu")
	)
	(gr_line
		(start 191.398652 -144.779492)
		(end 191.508634 -145.2626)
		(stroke
			(width 0.08255)
			(type default)
		)
		(layer "In5.Cu")
	)
	(gr_line
		(start 191.414908 -333.828136)
		(end 191.377316 -333.672434)
		(stroke
			(width 0.08255)
			(type default)
		)
		(layer "In5.Cu")
	)
	(gr_line
		(start 191.447674 -126.049786)
		(end 191.771524 -126.425198)
		(stroke
			(width 0.08255)
			(type default)
		)
		(layer "In5.Cu")
	)
	(gr_line
		(start 191.456818 -125.925834)
		(end 191.447674 -126.049786)
		(stroke
			(width 0.08255)
			(type default)
		)
		(layer "In5.Cu")
	)
	(gr_line
		(start 191.483742 -144.643856)
		(end 191.398652 -144.779492)
		(stroke
			(width 0.08255)
			(type default)
		)
		(layer "In5.Cu")
	)
	(gr_line
		(start 191.508634 -145.2626)
		(end 191.644016 -145.34769)
		(stroke
			(width 0.08255)
			(type default)
		)
		(layer "In5.Cu")
	)
	(gr_line
		(start 191.636142 -333.249778)
		(end 191.79159 -333.212186)
		(stroke
			(width 0.08255)
			(type default)
		)
		(layer "In5.Cu")
	)
	(gr_line
		(start 191.669416 -145.968466)
		(end 191.779398 -146.451574)
		(stroke
			(width 0.08255)
			(type default)
		)
		(layer "In5.Cu")
	)
	(gr_line
		(start 191.754506 -145.83283)
		(end 191.669416 -145.968466)
		(stroke
			(width 0.08255)
			(type default)
		)
		(layer "In5.Cu")
	)
	(gr_line
		(start 191.771524 -126.425198)
		(end 191.895222 -126.434342)
		(stroke
			(width 0.08255)
			(type default)
		)
		(layer "In5.Cu")
	)
	(gr_line
		(start 191.779398 -146.451574)
		(end 191.91478 -146.536664)
		(stroke
			(width 0.08255)
			(type default)
		)
		(layer "In5.Cu")
	)
	(gr_line
		(start 192.013586 -332.632304)
		(end 192.272412 -332.209648)
		(stroke
			(width 0.08255)
			(type default)
		)
		(layer "In5.Cu")
	)
	(gr_line
		(start 192.051178 -332.78826)
		(end 192.013586 -332.632304)
		(stroke
			(width 0.08255)
			(type default)
		)
		(layer "In5.Cu")
	)
	(gr_line
		(start 192.210944 -126.934722)
		(end 192.53454 -127.310134)
		(stroke
			(width 0.08255)
			(type default)
		)
		(layer "In5.Cu")
	)
	(gr_line
		(start 192.220088 -126.81077)
		(end 192.210944 -126.934722)
		(stroke
			(width 0.08255)
			(type default)
		)
		(layer "In5.Cu")
	)
	(gr_line
		(start 192.272412 -332.209648)
		(end 192.428114 -332.172056)
		(stroke
			(width 0.08255)
			(type default)
		)
		(layer "In5.Cu")
	)
	(gr_line
		(start 192.53454 -127.310134)
		(end 192.658238 -127.319278)
		(stroke
			(width 0.08255)
			(type default)
		)
		(layer "In5.Cu")
	)
	(gr_line
		(start 192.65011 -331.592174)
		(end 192.908936 -331.169518)
		(stroke
			(width 0.08255)
			(type default)
		)
		(layer "In5.Cu")
	)
	(gr_line
		(start 192.687702 -331.74813)
		(end 192.65011 -331.592174)
		(stroke
			(width 0.08255)
			(type default)
		)
		(layer "In5.Cu")
	)
	(gr_line
		(start 192.908936 -331.169518)
		(end 193.064638 -331.131926)
		(stroke
			(width 0.08255)
			(type default)
		)
		(layer "In5.Cu")
	)
	(gr_line
		(start 192.974214 -127.819658)
		(end 193.29781 -128.19507)
		(stroke
			(width 0.08255)
			(type default)
		)
		(layer "In5.Cu")
	)
	(gr_line
		(start 192.983358 -127.69596)
		(end 192.974214 -127.819658)
		(stroke
			(width 0.08255)
			(type default)
		)
		(layer "In5.Cu")
	)
	(gr_line
		(start 193.17081 -333.839566)
		(end 193.407538 -333.40421)
		(stroke
			(width 0.08255)
			(type default)
		)
		(layer "In5.Cu")
	)
	(gr_line
		(start 193.210942 -333.975964)
		(end 193.17081 -333.839566)
		(stroke
			(width 0.08255)
			(type default)
		)
		(layer "In5.Cu")
	)
	(gr_line
		(start 193.21145 -333.977488)
		(end 193.211196 -333.977488)
		(stroke
			(width 0.08255)
			(type default)
		)
		(layer "In5.Cu")
	)
	(gr_line
		(start 193.29781 -128.19507)
		(end 193.421508 -128.204214)
		(stroke
			(width 0.08255)
			(type default)
		)
		(layer "In5.Cu")
	)
	(gr_line
		(start 193.407538 -333.40421)
		(end 193.543428 -333.363824)
		(stroke
			(width 0.08255)
			(type default)
		)
		(layer "In5.Cu")
	)
	(gr_line
		(start 193.740786 -332.790546)
		(end 193.977514 -332.354936)
		(stroke
			(width 0.08255)
			(type default)
		)
		(layer "In5.Cu")
	)
	(gr_line
		(start 193.780918 -332.92669)
		(end 193.740786 -332.790546)
		(stroke
			(width 0.08255)
			(type default)
		)
		(layer "In5.Cu")
	)
	(gr_line
		(start 193.977514 -332.354936)
		(end 194.113404 -332.314804)
		(stroke
			(width 0.08255)
			(type default)
		)
		(layer "In5.Cu")
	)
	(gr_line
		(start 194.114928 -332.314296)
		(end 194.115182 -332.314296)
		(stroke
			(width 0.08255)
			(type default)
		)
		(layer "In5.Cu")
	)
	(gr_line
		(start 194.310508 -331.741526)
		(end 194.547236 -331.305916)
		(stroke
			(width 0.08255)
			(type default)
		)
		(layer "In5.Cu")
	)
	(gr_line
		(start 194.35064 -331.877924)
		(end 194.310508 -331.741526)
		(stroke
			(width 0.08255)
			(type default)
		)
		(layer "In5.Cu")
	)
	(gr_line
		(start 194.547236 -331.305916)
		(end 194.683126 -331.265784)
		(stroke
			(width 0.08255)
			(type default)
		)
		(layer "In5.Cu")
	)
	(gr_line
		(start 194.875404 -330.675234)
		(end 195.112132 -330.239624)
		(stroke
			(width 0.08255)
			(type default)
		)
		(layer "In5.Cu")
	)
	(gr_line
		(start 194.920616 -330.82865)
		(end 194.875404 -330.675234)
		(stroke
			(width 0.08255)
			(type default)
		)
		(layer "In5.Cu")
	)
	(gr_line
		(start 195.112132 -330.239624)
		(end 195.265294 -330.194412)
		(stroke
			(width 0.08255)
			(type default)
		)
		(layer "In5.Cu")
	)
	(gr_line
		(start 195.266818 -330.193904)
		(end 195.267072 -330.193904)
		(stroke
			(width 0.08255)
			(type default)
		)
		(layer "In5.Cu")
	)
	(gr_line
		(start 195.965318 -307.299868)
		(end 195.699888 -307.299868)
		(stroke
			(width 0.05715)
			(type default)
		)
		(layer "In5.Cu")
	)
	(gr_line
		(start 195.965318 -305.399948)
		(end 195.699888 -305.399948)
		(stroke
			(width 0.05715)
			(type default)
		)
		(layer "In5.Cu")
	)
	(gr_line
		(start 195.983606 -353.332796)
		(end 196.231256 -352.903282)
		(stroke
			(width 0.08255)
			(type default)
		)
		(layer "In5.Cu")
	)
	(gr_line
		(start 196.025008 -353.487228)
		(end 195.983606 -353.332796)
		(stroke
			(width 0.08255)
			(type default)
		)
		(layer "In5.Cu")
	)
	(gr_line
		(start 196.079618 -307.414168)
		(end 195.965318 -307.299868)
		(stroke
			(width 0.05715)
			(type default)
		)
		(layer "In5.Cu")
	)
	(gr_line
		(start 196.079618 -305.514248)
		(end 195.965318 -305.399948)
		(stroke
			(width 0.05715)
			(type default)
		)
		(layer "In5.Cu")
	)
	(gr_line
		(start 196.231256 -352.903282)
		(end 196.385434 -352.86188)
		(stroke
			(width 0.08255)
			(type default)
		)
		(layer "In5.Cu")
	)
	(gr_line
		(start 196.592444 -352.276156)
		(end 196.840094 -351.846896)
		(stroke
			(width 0.08255)
			(type default)
		)
		(layer "In5.Cu")
	)
	(gr_line
		(start 196.633846 -352.430842)
		(end 196.592444 -352.276156)
		(stroke
			(width 0.08255)
			(type default)
		)
		(layer "In5.Cu")
	)
	(gr_line
		(start 196.840094 -351.846896)
		(end 196.994526 -351.805494)
		(stroke
			(width 0.08255)
			(type default)
		)
		(layer "In5.Cu")
	)
	(gr_line
		(start 197.201536 -351.21977)
		(end 197.449186 -350.79051)
		(stroke
			(width 0.08255)
			(type default)
		)
		(layer "In5.Cu")
	)
	(gr_line
		(start 197.242938 -351.374202)
		(end 197.201536 -351.21977)
		(stroke
			(width 0.08255)
			(type default)
		)
		(layer "In5.Cu")
	)
	(gr_line
		(start 197.449186 -350.79051)
		(end 197.603364 -350.749108)
		(stroke
			(width 0.08255)
			(type default)
		)
		(layer "In5.Cu")
	)
	(gr_line
		(start 197.605142 -350.7486)
		(end 197.604888 -350.7486)
		(stroke
			(width 0.08255)
			(type default)
		)
		(layer "In5.Cu")
	)
	(gr_line
		(start 197.865492 -316.799722)
		(end 197.600062 -316.799722)
		(stroke
			(width 0.05715)
			(type default)
		)
		(layer "In5.Cu")
	)
	(gr_line
		(start 197.865492 -310.149748)
		(end 197.600062 -310.149748)
		(stroke
			(width 0.05715)
			(type default)
		)
		(layer "In5.Cu")
	)
	(gr_line
		(start 197.865492 -287.349946)
		(end 197.600062 -287.349946)
		(stroke
			(width 0.05715)
			(type default)
		)
		(layer "In5.Cu")
	)
	(gr_line
		(start 197.865492 -281.649932)
		(end 197.600062 -281.649932)
		(stroke
			(width 0.05715)
			(type default)
		)
		(layer "In5.Cu")
	)
	(gr_line
		(start 197.934072 -319.204848)
		(end 197.934072 -319.1764)
		(stroke
			(width 0.05715)
			(type default)
		)
		(layer "In5.Cu")
	)
	(gr_line
		(start 197.934072 -319.1764)
		(end 197.979792 -319.13068)
		(stroke
			(width 0.05715)
			(type default)
		)
		(layer "In5.Cu")
	)
	(gr_line
		(start 197.979792 -316.914022)
		(end 197.865492 -316.799722)
		(stroke
			(width 0.05715)
			(type default)
		)
		(layer "In5.Cu")
	)
	(gr_line
		(start 197.979792 -310.264048)
		(end 197.865492 -310.149748)
		(stroke
			(width 0.05715)
			(type default)
		)
		(layer "In5.Cu")
	)
	(gr_line
		(start 197.979792 -287.235646)
		(end 197.865492 -287.349946)
		(stroke
			(width 0.05715)
			(type default)
		)
		(layer "In5.Cu")
	)
	(gr_line
		(start 197.979792 -281.535632)
		(end 197.865492 -281.649932)
		(stroke
			(width 0.05715)
			(type default)
		)
		(layer "In5.Cu")
	)
	(gr_line
		(start 199.170544 -310.905144)
		(end 199.170544 -310.841136)
		(stroke
			(width 0.05715)
			(type default)
		)
		(layer "In5.Cu")
	)
	(gr_line
		(start 199.170544 -310.841136)
		(end 199.170036 -310.840628)
		(stroke
			(width 0.05715)
			(type default)
		)
		(layer "In5.Cu")
	)
	(gr_line
		(start 199.19061 -310.92521)
		(end 199.170544 -310.905144)
		(stroke
			(width 0.05715)
			(type default)
		)
		(layer "In5.Cu")
	)
	(gr_line
		(start 199.7456 -307.915818)
		(end 199.69988 -307.870098)
		(stroke
			(width 0.05715)
			(type default)
		)
		(layer "In5.Cu")
	)
	(gr_line
		(start 199.771 -306.015898)
		(end 199.72528 -305.970178)
		(stroke
			(width 0.05715)
			(type default)
		)
		(layer "In5.Cu")
	)
	(gr_line
		(start 199.774048 -307.915818)
		(end 199.7456 -307.915818)
		(stroke
			(width 0.05715)
			(type default)
		)
		(layer "In5.Cu")
	)
	(gr_line
		(start 199.799448 -306.015898)
		(end 199.771 -306.015898)
		(stroke
			(width 0.05715)
			(type default)
		)
		(layer "In5.Cu")
	)
	(gr_line
		(start 199.90562 -346.38361)
		(end 200.139808 -345.94673)
		(stroke
			(width 0.08255)
			(type default)
		)
		(layer "In5.Cu")
	)
	(gr_line
		(start 199.951848 -346.536772)
		(end 199.90562 -346.38361)
		(stroke
			(width 0.08255)
			(type default)
		)
		(layer "In5.Cu")
	)
	(gr_line
		(start 200.021698 -286.733996)
		(end 199.975978 -286.779716)
		(stroke
			(width 0.05715)
			(type default)
		)
		(layer "In5.Cu")
	)
	(gr_line
		(start 200.021698 -281.033982)
		(end 199.975978 -281.079702)
		(stroke
			(width 0.05715)
			(type default)
		)
		(layer "In5.Cu")
	)
	(gr_line
		(start 200.050146 -286.733996)
		(end 200.021698 -286.733996)
		(stroke
			(width 0.05715)
			(type default)
		)
		(layer "In5.Cu")
	)
	(gr_line
		(start 200.050146 -281.033982)
		(end 200.021698 -281.033982)
		(stroke
			(width 0.05715)
			(type default)
		)
		(layer "In5.Cu")
	)
	(gr_line
		(start 200.139808 -345.94673)
		(end 200.29297 -345.900502)
		(stroke
			(width 0.08255)
			(type default)
		)
		(layer "In5.Cu")
	)
	(gr_line
		(start 200.481692 -345.308936)
		(end 200.71588 -344.872056)
		(stroke
			(width 0.08255)
			(type default)
		)
		(layer "In5.Cu")
	)
	(gr_line
		(start 200.521062 -351.134172)
		(end 200.742296 -350.690688)
		(stroke
			(width 0.08255)
			(type default)
		)
		(layer "In5.Cu")
	)
	(gr_line
		(start 200.52792 -345.462098)
		(end 200.481692 -345.308936)
		(stroke
			(width 0.08255)
			(type default)
		)
		(layer "In5.Cu")
	)
	(gr_line
		(start 200.571862 -351.28581)
		(end 200.521062 -351.134172)
		(stroke
			(width 0.08255)
			(type default)
		)
		(layer "In5.Cu")
	)
	(gr_line
		(start 200.71588 -344.872056)
		(end 200.869042 -344.825828)
		(stroke
			(width 0.08255)
			(type default)
		)
		(layer "In5.Cu")
	)
	(gr_line
		(start 200.742296 -350.690688)
		(end 200.894188 -350.639888)
		(stroke
			(width 0.08255)
			(type default)
		)
		(layer "In5.Cu")
	)
	(gr_line
		(start 201.057764 -344.234262)
		(end 201.291952 -343.797382)
		(stroke
			(width 0.08255)
			(type default)
		)
		(layer "In5.Cu")
	)
	(gr_line
		(start 201.065384 -350.042988)
		(end 201.286872 -349.599504)
		(stroke
			(width 0.08255)
			(type default)
		)
		(layer "In5.Cu")
	)
	(gr_line
		(start 201.103992 -344.387424)
		(end 201.057764 -344.234262)
		(stroke
			(width 0.08255)
			(type default)
		)
		(layer "In5.Cu")
	)
	(gr_line
		(start 201.116184 -350.19488)
		(end 201.065384 -350.042988)
		(stroke
			(width 0.08255)
			(type default)
		)
		(layer "In5.Cu")
	)
	(gr_line
		(start 201.286872 -349.599504)
		(end 201.43851 -349.548704)
		(stroke
			(width 0.08255)
			(type default)
		)
		(layer "In5.Cu")
	)
	(gr_line
		(start 201.291952 -343.797382)
		(end 201.445114 -343.751154)
		(stroke
			(width 0.08255)
			(type default)
		)
		(layer "In5.Cu")
	)
	(gr_line
		(start 201.446892 -343.750646)
		(end 201.446638 -343.750646)
		(stroke
			(width 0.08255)
			(type default)
		)
		(layer "In5.Cu")
	)
	(gr_line
		(start 201.609706 -348.951804)
		(end 201.831194 -348.50832)
		(stroke
			(width 0.08255)
			(type default)
		)
		(layer "In5.Cu")
	)
	(gr_line
		(start 201.63409 -343.159588)
		(end 201.868278 -342.722708)
		(stroke
			(width 0.08255)
			(type default)
		)
		(layer "In5.Cu")
	)
	(gr_line
		(start 201.660506 -349.103696)
		(end 201.609706 -348.951804)
		(stroke
			(width 0.08255)
			(type default)
		)
		(layer "In5.Cu")
	)
	(gr_line
		(start 201.680318 -343.312496)
		(end 201.63409 -343.159588)
		(stroke
			(width 0.08255)
			(type default)
		)
		(layer "In5.Cu")
	)
	(gr_line
		(start 201.680572 -343.31402)
		(end 201.680826 -343.314274)
		(stroke
			(width 0.08255)
			(type default)
		)
		(layer "In5.Cu")
	)
	(gr_line
		(start 201.831194 -348.50832)
		(end 201.983086 -348.45752)
		(stroke
			(width 0.08255)
			(type default)
		)
		(layer "In5.Cu")
	)
	(gr_line
		(start 201.868278 -342.722708)
		(end 202.021186 -342.67648)
		(stroke
			(width 0.08255)
			(type default)
		)
		(layer "In5.Cu")
	)
	(gr_line
		(start 204.26807 -307.87721)
		(end 204.26807 -307.717444)
		(stroke
			(width 0.08255)
			(type default)
		)
		(layer "In5.Cu")
	)
	(gr_line
		(start 204.61859 -308.22773)
		(end 204.26807 -307.87721)
		(stroke
			(width 0.08255)
			(type default)
		)
		(layer "In5.Cu")
	)
	(gr_line
		(start 204.778356 -308.22773)
		(end 204.61859 -308.22773)
		(stroke
			(width 0.08255)
			(type default)
		)
		(layer "In5.Cu")
	)
	(gr_line
		(start 205.086204 -312.105548)
		(end 205.086204 -312.105294)
		(stroke
			(width 0.08255)
			(type default)
		)
		(layer "In5.Cu")
	)
	(gr_line
		(start 205.086204 -312.105294)
		(end 204.850238 -311.869836)
		(stroke
			(width 0.08255)
			(type default)
		)
		(layer "In5.Cu")
	)
	(gr_line
		(start 208.93532 -312.540904)
		(end 208.93532 -312.384694)
		(stroke
			(width 0.08255)
			(type default)
		)
		(layer "In5.Cu")
	)
	(gr_line
		(start 209.276696 -312.88228)
		(end 208.93532 -312.540904)
		(stroke
			(width 0.08255)
			(type default)
		)
		(layer "In5.Cu")
	)
	(gr_line
		(start 209.432906 -312.88228)
		(end 209.276696 -312.88228)
		(stroke
			(width 0.08255)
			(type default)
		)
		(layer "In5.Cu")
	)
	(gr_line
		(start 209.784696 -313.39409)
		(end 209.784696 -313.23407)
		(stroke
			(width 0.08255)
			(type default)
		)
		(layer "In5.Cu")
	)
	(gr_line
		(start 210.135216 -313.74461)
		(end 209.784696 -313.39409)
		(stroke
			(width 0.08255)
			(type default)
		)
		(layer "In5.Cu")
	)
	(gr_line
		(start 210.295236 -313.74461)
		(end 210.135216 -313.74461)
		(stroke
			(width 0.08255)
			(type default)
		)
		(layer "In5.Cu")
	)
	(gr_line
		(start 210.647026 -314.25642)
		(end 210.647026 -314.0964)
		(stroke
			(width 0.08255)
			(type default)
		)
		(layer "In5.Cu")
	)
	(gr_line
		(start 210.997546 -314.60694)
		(end 210.647026 -314.25642)
		(stroke
			(width 0.08255)
			(type default)
		)
		(layer "In5.Cu")
	)
	(gr_line
		(start 211.157566 -314.60694)
		(end 210.997546 -314.60694)
		(stroke
			(width 0.08255)
			(type default)
		)
		(layer "In5.Cu")
	)
	(gr_line
		(start 212.636608 -316.084458)
		(end 212.636862 -316.084458)
		(stroke
			(width 0.08255)
			(type default)
		)
		(layer "In5.Cu")
	)
	(gr_line
		(start 255.154176 -306.091844)
		(end 255.64846 -305.59756)
		(stroke
			(width 0.08255)
			(type default)
		)
		(layer "In5.Cu")
	)
	(gr_line
		(start 255.355344 -306.291234)
		(end 255.49733 -306.291234)
		(stroke
			(width 0.08255)
			(type default)
		)
		(layer "In5.Cu")
	)
	(gr_line
		(start 255.49733 -306.291234)
		(end 255.84785 -305.940714)
		(stroke
			(width 0.08255)
			(type default)
		)
		(layer "In5.Cu")
	)
	(gr_line
		(start 255.84785 -305.940714)
		(end 255.84785 -305.798728)
		(stroke
			(width 0.08255)
			(type default)
		)
		(layer "In5.Cu")
	)
	(gr_line
		(start 255.998472 -305.247548)
		(end 256.492756 -304.753264)
		(stroke
			(width 0.08255)
			(type default)
		)
		(layer "In5.Cu")
	)
	(gr_line
		(start 256.19964 -305.446938)
		(end 256.341626 -305.446938)
		(stroke
			(width 0.08255)
			(type default)
		)
		(layer "In5.Cu")
	)
	(gr_line
		(start 256.341626 -305.446938)
		(end 256.692146 -305.096418)
		(stroke
			(width 0.08255)
			(type default)
		)
		(layer "In5.Cu")
	)
	(gr_line
		(start 256.549906 -313.567572)
		(end 256.645664 -313.538108)
		(stroke
			(width 0.08255)
			(type default)
		)
		(layer "In5.Cu")
	)
	(gr_line
		(start 256.645664 -313.538108)
		(end 256.91719 -313.025282)
		(stroke
			(width 0.08255)
			(type default)
		)
		(layer "In5.Cu")
	)
	(gr_line
		(start 256.692146 -305.096418)
		(end 256.692146 -304.954432)
		(stroke
			(width 0.08255)
			(type default)
		)
		(layer "In5.Cu")
	)
	(gr_line
		(start 256.842768 -304.403252)
		(end 257.337052 -303.908968)
		(stroke
			(width 0.08255)
			(type default)
		)
		(layer "In5.Cu")
	)
	(gr_line
		(start 256.84861 -315.495432)
		(end 257.005836 -315.465206)
		(stroke
			(width 0.08255)
			(type default)
		)
		(layer "In5.Cu")
	)
	(gr_line
		(start 256.91719 -313.025282)
		(end 256.887726 -312.929778)
		(stroke
			(width 0.08255)
			(type default)
		)
		(layer "In5.Cu")
	)
	(gr_line
		(start 257.005836 -315.465206)
		(end 257.284474 -315.05525)
		(stroke
			(width 0.08255)
			(type default)
		)
		(layer "In5.Cu")
	)
	(gr_line
		(start 257.043936 -304.602642)
		(end 257.185922 -304.602642)
		(stroke
			(width 0.08255)
			(type default)
		)
		(layer "In5.Cu")
	)
	(gr_line
		(start 257.118866 -312.490104)
		(end 257.11912 -312.490358)
		(stroke
			(width 0.08255)
			(type default)
		)
		(layer "In5.Cu")
	)
	(gr_line
		(start 257.120644 -312.489596)
		(end 257.211068 -312.461656)
		(stroke
			(width 0.08255)
			(type default)
		)
		(layer "In5.Cu")
	)
	(gr_line
		(start 257.185922 -304.602642)
		(end 257.536442 -304.252122)
		(stroke
			(width 0.08255)
			(type default)
		)
		(layer "In5.Cu")
	)
	(gr_line
		(start 257.211068 -312.461656)
		(end 257.474212 -311.965086)
		(stroke
			(width 0.08255)
			(type default)
		)
		(layer "In5.Cu")
	)
	(gr_line
		(start 257.284474 -315.05525)
		(end 257.254248 -314.898024)
		(stroke
			(width 0.08255)
			(type default)
		)
		(layer "In5.Cu")
	)
	(gr_line
		(start 257.474212 -311.965086)
		(end 257.446272 -311.874408)
		(stroke
			(width 0.08255)
			(type default)
		)
		(layer "In5.Cu")
	)
	(gr_line
		(start 257.532124 -314.486798)
		(end 257.53187 -314.486798)
		(stroke
			(width 0.08255)
			(type default)
		)
		(layer "In5.Cu")
	)
	(gr_line
		(start 257.533902 -314.486544)
		(end 257.67284 -314.459874)
		(stroke
			(width 0.08255)
			(type default)
		)
		(layer "In5.Cu")
	)
	(gr_line
		(start 257.536442 -304.252122)
		(end 257.536442 -304.110136)
		(stroke
			(width 0.08255)
			(type default)
		)
		(layer "In5.Cu")
	)
	(gr_line
		(start 257.57886 -311.62117)
		(end 257.677412 -311.434988)
		(stroke
			(width 0.08255)
			(type default)
		)
		(layer "In5.Cu")
	)
	(gr_line
		(start 257.67284 -314.459874)
		(end 257.951478 -314.049664)
		(stroke
			(width 0.08255)
			(type default)
		)
		(layer "In5.Cu")
	)
	(gr_line
		(start 257.67919 -311.43448)
		(end 257.814572 -311.392824)
		(stroke
			(width 0.08255)
			(type default)
		)
		(layer "In5.Cu")
	)
	(gr_line
		(start 257.814572 -311.392824)
		(end 258.046728 -310.954928)
		(stroke
			(width 0.08255)
			(type default)
		)
		(layer "In5.Cu")
	)
	(gr_line
		(start 257.887216 -316.026546)
		(end 258.029202 -316.01664)
		(stroke
			(width 0.08255)
			(type default)
		)
		(layer "In5.Cu")
	)
	(gr_line
		(start 257.9243 -313.908694)
		(end 257.924554 -313.908948)
		(stroke
			(width 0.08255)
			(type default)
		)
		(layer "In5.Cu")
	)
	(gr_line
		(start 257.951478 -314.049664)
		(end 257.924808 -313.910726)
		(stroke
			(width 0.08255)
			(type default)
		)
		(layer "In5.Cu")
	)
	(gr_line
		(start 258.029202 -316.01664)
		(end 258.35483 -315.64326)
		(stroke
			(width 0.08255)
			(type default)
		)
		(layer "In5.Cu")
	)
	(gr_line
		(start 258.046728 -310.954928)
		(end 258.004818 -310.819292)
		(stroke
			(width 0.08255)
			(type default)
		)
		(layer "In5.Cu")
	)
	(gr_line
		(start 258.202938 -313.499246)
		(end 258.20243 -313.498992)
		(stroke
			(width 0.08255)
			(type default)
		)
		(layer "In5.Cu")
	)
	(gr_line
		(start 258.204462 -313.498484)
		(end 258.343654 -313.472068)
		(stroke
			(width 0.08255)
			(type default)
		)
		(layer "In5.Cu")
	)
	(gr_line
		(start 258.235958 -310.379872)
		(end 258.235958 -310.380126)
		(stroke
			(width 0.08255)
			(type default)
		)
		(layer "In5.Cu")
	)
	(gr_line
		(start 258.237736 -310.379364)
		(end 258.373372 -310.337708)
		(stroke
			(width 0.08255)
			(type default)
		)
		(layer "In5.Cu")
	)
	(gr_line
		(start 258.343654 -313.472068)
		(end 258.622038 -313.061858)
		(stroke
			(width 0.08255)
			(type default)
		)
		(layer "In5.Cu")
	)
	(gr_line
		(start 258.35483 -315.64326)
		(end 258.345178 -315.50102)
		(stroke
			(width 0.08255)
			(type default)
		)
		(layer "In5.Cu")
	)
	(gr_line
		(start 258.373372 -310.337708)
		(end 258.605274 -309.899558)
		(stroke
			(width 0.08255)
			(type default)
		)
		(layer "In5.Cu")
	)
	(gr_line
		(start 258.595114 -312.920888)
		(end 258.595368 -312.921142)
		(stroke
			(width 0.08255)
			(type default)
		)
		(layer "In5.Cu")
	)
	(gr_line
		(start 258.605274 -309.899558)
		(end 258.563618 -309.763922)
		(stroke
			(width 0.08255)
			(type default)
		)
		(layer "In5.Cu")
	)
	(gr_line
		(start 258.622038 -313.061858)
		(end 258.595368 -312.92292)
		(stroke
			(width 0.08255)
			(type default)
		)
		(layer "In5.Cu")
	)
	(gr_line
		(start 258.671822 -315.126624)
		(end 258.813808 -315.116718)
		(stroke
			(width 0.08255)
			(type default)
		)
		(layer "In5.Cu")
	)
	(gr_line
		(start 258.813808 -315.116718)
		(end 259.13969 -314.743084)
		(stroke
			(width 0.08255)
			(type default)
		)
		(layer "In5.Cu")
	)
	(gr_line
		(start 258.873498 -312.51144)
		(end 258.873244 -312.511186)
		(stroke
			(width 0.08255)
			(type default)
		)
		(layer "In5.Cu")
	)
	(gr_line
		(start 258.875276 -312.510678)
		(end 259.014468 -312.484262)
		(stroke
			(width 0.08255)
			(type default)
		)
		(layer "In5.Cu")
	)
	(gr_line
		(start 259.014468 -312.484262)
		(end 259.292852 -312.074052)
		(stroke
			(width 0.08255)
			(type default)
		)
		(layer "In5.Cu")
	)
	(gr_line
		(start 259.13969 -314.743084)
		(end 259.129784 -314.601352)
		(stroke
			(width 0.08255)
			(type default)
		)
		(layer "In5.Cu")
	)
	(gr_line
		(start 259.292852 -312.074052)
		(end 259.266182 -311.93486)
		(stroke
			(width 0.08255)
			(type default)
		)
		(layer "In5.Cu")
	)
	(gr_line
		(start 259.3594 -308.722014)
		(end 259.501386 -308.721252)
		(stroke
			(width 0.08255)
			(type default)
		)
		(layer "In5.Cu")
	)
	(gr_line
		(start 259.501386 -308.721252)
		(end 259.850382 -308.369462)
		(stroke
			(width 0.08255)
			(type default)
		)
		(layer "In5.Cu")
	)
	(gr_line
		(start 259.544312 -311.52338)
		(end 259.544058 -311.52338)
		(stroke
			(width 0.08255)
			(type default)
		)
		(layer "In5.Cu")
	)
	(gr_line
		(start 259.54609 -311.523126)
		(end 259.685282 -311.496456)
		(stroke
			(width 0.08255)
			(type default)
		)
		(layer "In5.Cu")
	)
	(gr_line
		(start 259.685282 -311.496456)
		(end 259.963666 -311.0865)
		(stroke
			(width 0.08255)
			(type default)
		)
		(layer "In5.Cu")
	)
	(gr_line
		(start 259.723128 -302.433736)
		(end 260.368542 -302.166528)
		(stroke
			(width 0.08255)
			(type default)
		)
		(layer "In5.Cu")
	)
	(gr_line
		(start 259.832348 -302.695102)
		(end 259.963666 -302.749458)
		(stroke
			(width 0.08255)
			(type default)
		)
		(layer "In5.Cu")
	)
	(gr_line
		(start 259.850382 -308.369462)
		(end 259.849874 -308.227476)
		(stroke
			(width 0.08255)
			(type default)
		)
		(layer "In5.Cu")
	)
	(gr_line
		(start 259.963666 -311.0865)
		(end 259.936996 -310.947054)
		(stroke
			(width 0.08255)
			(type default)
		)
		(layer "In5.Cu")
	)
	(gr_line
		(start 259.963666 -302.749458)
		(end 260.421628 -302.55972)
		(stroke
			(width 0.08255)
			(type default)
		)
		(layer "In5.Cu")
	)
	(gr_line
		(start 260.421628 -302.55972)
		(end 260.47573 -302.428656)
		(stroke
			(width 0.08255)
			(type default)
		)
		(layer "In5.Cu")
	)
	(gr_line
		(start 260.476492 -302.426878)
		(end 260.476492 -302.427132)
		(stroke
			(width 0.08255)
			(type default)
		)
		(layer "In5.Cu")
	)
	(gr_line
		(start 260.61162 -307.459634)
		(end 260.75386 -307.459126)
		(stroke
			(width 0.08255)
			(type default)
		)
		(layer "In5.Cu")
	)
	(gr_line
		(start 260.75386 -307.459126)
		(end 261.102856 -307.107336)
		(stroke
			(width 0.08255)
			(type default)
		)
		(layer "In5.Cu")
	)
	(gr_line
		(start 260.825996 -301.977044)
		(end 261.471918 -301.709328)
		(stroke
			(width 0.08255)
			(type default)
		)
		(layer "In5.Cu")
	)
	(gr_line
		(start 260.921754 -312.546492)
		(end 261.06374 -312.536586)
		(stroke
			(width 0.08255)
			(type default)
		)
		(layer "In5.Cu")
	)
	(gr_line
		(start 260.935216 -302.238156)
		(end 261.066788 -302.292766)
		(stroke
			(width 0.08255)
			(type default)
		)
		(layer "In5.Cu")
	)
	(gr_line
		(start 261.06374 -312.536586)
		(end 261.389368 -312.163206)
		(stroke
			(width 0.08255)
			(type default)
		)
		(layer "In5.Cu")
	)
	(gr_line
		(start 261.066788 -302.292766)
		(end 261.524496 -302.102774)
		(stroke
			(width 0.08255)
			(type default)
		)
		(layer "In5.Cu")
	)
	(gr_line
		(start 261.102856 -307.107336)
		(end 261.102348 -306.965096)
		(stroke
			(width 0.08255)
			(type default)
		)
		(layer "In5.Cu")
	)
	(gr_line
		(start 261.245858 -309.337456)
		(end 261.387844 -309.336694)
		(stroke
			(width 0.08255)
			(type default)
		)
		(layer "In5.Cu")
	)
	(gr_line
		(start 261.387844 -309.336694)
		(end 261.735824 -308.983888)
		(stroke
			(width 0.08255)
			(type default)
		)
		(layer "In5.Cu")
	)
	(gr_line
		(start 261.389368 -312.163206)
		(end 261.379716 -312.020966)
		(stroke
			(width 0.08255)
			(type default)
		)
		(layer "In5.Cu")
	)
	(gr_line
		(start 261.524496 -302.102774)
		(end 261.579106 -301.971456)
		(stroke
			(width 0.08255)
			(type default)
		)
		(layer "In5.Cu")
	)
	(gr_line
		(start 261.579614 -301.970186)
		(end 261.579868 -301.969932)
		(stroke
			(width 0.08255)
			(type default)
		)
		(layer "In5.Cu")
	)
	(gr_line
		(start 261.70636 -311.64657)
		(end 261.848346 -311.636664)
		(stroke
			(width 0.08255)
			(type default)
		)
		(layer "In5.Cu")
	)
	(gr_line
		(start 261.735824 -308.983888)
		(end 261.735062 -308.841648)
		(stroke
			(width 0.08255)
			(type default)
		)
		(layer "In5.Cu")
	)
	(gr_line
		(start 261.848346 -311.636664)
		(end 262.174228 -311.263284)
		(stroke
			(width 0.08255)
			(type default)
		)
		(layer "In5.Cu")
	)
	(gr_line
		(start 261.970266 -348.808548)
		(end 261.970266 -348.808294)
		(stroke
			(width 0.08255)
			(type default)
		)
		(layer "In5.Cu")
	)
	(gr_line
		(start 261.97052 -348.808548)
		(end 261.970266 -348.808548)
		(stroke
			(width 0.08255)
			(type default)
		)
		(layer "In5.Cu")
	)
	(gr_line
		(start 262.174228 -311.263284)
		(end 262.164322 -311.121298)
		(stroke
			(width 0.08255)
			(type default)
		)
		(layer "In5.Cu")
	)
	(gr_line
		(start 262.49122 -310.746648)
		(end 262.632952 -310.736996)
		(stroke
			(width 0.08255)
			(type default)
		)
		(layer "In5.Cu")
	)
	(gr_line
		(start 262.632952 -310.736996)
		(end 262.958834 -310.363362)
		(stroke
			(width 0.08255)
			(type default)
		)
		(layer "In5.Cu")
	)
	(gr_line
		(start 262.958834 -310.363362)
		(end 262.948928 -310.221376)
		(stroke
			(width 0.08255)
			(type default)
		)
		(layer "In5.Cu")
	)
	(gr_line
		(start 267.7922 -306.965858)
		(end 267.820648 -306.965858)
		(stroke
			(width 0.05715)
			(type default)
		)
		(layer "In5.Cu")
	)
	(gr_line
		(start 267.7922 -306.015898)
		(end 267.820648 -306.015898)
		(stroke
			(width 0.05715)
			(type default)
		)
		(layer "In5.Cu")
	)
	(gr_line
		(start 267.820648 -306.965858)
		(end 267.866368 -306.920138)
		(stroke
			(width 0.05715)
			(type default)
		)
		(layer "In5.Cu")
	)
	(gr_line
		(start 267.820648 -306.015898)
		(end 267.866368 -305.970178)
		(stroke
			(width 0.05715)
			(type default)
		)
		(layer "In5.Cu")
	)
	(gr_line
		(start 267.836904 -305.065938)
		(end 267.865352 -305.065938)
		(stroke
			(width 0.05715)
			(type default)
		)
		(layer "In5.Cu")
	)
	(gr_line
		(start 267.865352 -305.065938)
		(end 267.911072 -305.020218)
		(stroke
			(width 0.05715)
			(type default)
		)
		(layer "In5.Cu")
	)
	(gr_line
		(start 268.627352 -301.265844)
		(end 268.6558 -301.265844)
		(stroke
			(width 0.05715)
			(type default)
		)
		(layer "In5.Cu")
	)
	(gr_line
		(start 268.627352 -300.983904)
		(end 268.6558 -300.983904)
		(stroke
			(width 0.05715)
			(type default)
		)
		(layer "In5.Cu")
	)
	(gr_line
		(start 268.6558 -301.265844)
		(end 268.70152 -301.220124)
		(stroke
			(width 0.05715)
			(type default)
		)
		(layer "In5.Cu")
	)
	(gr_line
		(start 268.6558 -300.983904)
		(end 268.70152 -301.029624)
		(stroke
			(width 0.05715)
			(type default)
		)
		(layer "In5.Cu")
	)
	(gr_line
		(start 269.315184 -306.349908)
		(end 269.049754 -306.349908)
		(stroke
			(width 0.05715)
			(type default)
		)
		(layer "In5.Cu")
	)
	(gr_line
		(start 269.429484 -306.235608)
		(end 269.315184 -306.349908)
		(stroke
			(width 0.05715)
			(type default)
		)
		(layer "In5.Cu")
	)
	(gr_line
		(start 270.333978 -320.043048)
		(end 270.333978 -320.0146)
		(stroke
			(width 0.05715)
			(type default)
		)
		(layer "In5.Cu")
	)
	(gr_line
		(start 270.333978 -320.0146)
		(end 270.379698 -319.96888)
		(stroke
			(width 0.05715)
			(type default)
		)
		(layer "In5.Cu")
	)
	(gr_line
		(start 270.615918 -320.043048)
		(end 270.615918 -320.0146)
		(stroke
			(width 0.05715)
			(type default)
		)
		(layer "In5.Cu")
	)
	(gr_line
		(start 270.615918 -320.0146)
		(end 270.570198 -319.96888)
		(stroke
			(width 0.05715)
			(type default)
		)
		(layer "In5.Cu")
	)
	(gr_line
		(start 270.835628 -318.320166)
		(end 270.949928 -318.434466)
		(stroke
			(width 0.05715)
			(type default)
		)
		(layer "In5.Cu")
	)
	(gr_line
		(start 270.835628 -318.129666)
		(end 270.949928 -318.015366)
		(stroke
			(width 0.05715)
			(type default)
		)
		(layer "In5.Cu")
	)
	(gr_line
		(start 270.949928 -318.434466)
		(end 270.949928 -318.699896)
		(stroke
			(width 0.05715)
			(type default)
		)
		(layer "In5.Cu")
	)
	(gr_line
		(start 270.949928 -318.015366)
		(end 270.949928 -317.749936)
		(stroke
			(width 0.05715)
			(type default)
		)
		(layer "In5.Cu")
	)
	(gr_line
		(start 271.215358 -307.299868)
		(end 270.949928 -307.299868)
		(stroke
			(width 0.05715)
			(type default)
		)
		(layer "In5.Cu")
	)
	(gr_line
		(start 271.215358 -305.399948)
		(end 270.949928 -305.399948)
		(stroke
			(width 0.05715)
			(type default)
		)
		(layer "In5.Cu")
	)
	(gr_line
		(start 271.215358 -301.599854)
		(end 270.949928 -301.599854)
		(stroke
			(width 0.05715)
			(type default)
		)
		(layer "In5.Cu")
	)
	(gr_line
		(start 271.329658 -307.185568)
		(end 271.215358 -307.299868)
		(stroke
			(width 0.05715)
			(type default)
		)
		(layer "In5.Cu")
	)
	(gr_line
		(start 271.329658 -305.285648)
		(end 271.215358 -305.399948)
		(stroke
			(width 0.05715)
			(type default)
		)
		(layer "In5.Cu")
	)
	(gr_line
		(start 271.329658 -301.485554)
		(end 271.215358 -301.599854)
		(stroke
			(width 0.05715)
			(type default)
		)
		(layer "In5.Cu")
	)
	(gr_line
		(start 271.520158 -301.485554)
		(end 271.634458 -301.599854)
		(stroke
			(width 0.05715)
			(type default)
		)
		(layer "In5.Cu")
	)
	(gr_line
		(start 271.634458 -301.599854)
		(end 271.899888 -301.599854)
		(stroke
			(width 0.05715)
			(type default)
		)
		(layer "In5.Cu")
	)
	(gr_line
		(start 272.835878 -341.46744)
		(end 272.79092 -341.423752)
		(stroke
			(width 0.08255)
			(type default)
		)
		(layer "In5.Cu")
	)
	(gr_line
		(start 272.839434 -341.470996)
		(end 272.835878 -341.46744)
		(stroke
			(width 0.08255)
			(type default)
		)
		(layer "In5.Cu")
	)
	(gr_line
		(start 272.861278 -341.53475)
		(end 272.839434 -341.470996)
		(stroke
			(width 0.08255)
			(type default)
		)
		(layer "In5.Cu")
	)
	(gr_line
		(start 274.752816 -330.774294)
		(end 274.752816 -330.77404)
		(stroke
			(width 0.08255)
			(type default)
		)
		(layer "In5.Cu")
	)
	(gr_line
		(start 275.349716 -150.576026)
		(end 275.349462 -150.576026)
		(stroke
			(width 0.08255)
			(type default)
		)
		(layer "In5.Cu")
	)
	(gr_line
		(start 275.398738 -151.297386)
		(end 275.504148 -151.17699)
		(stroke
			(width 0.08255)
			(type default)
		)
		(layer "In5.Cu")
	)
	(gr_line
		(start 275.471382 -150.682452)
		(end 275.350986 -150.577296)
		(stroke
			(width 0.08255)
			(type default)
		)
		(layer "In5.Cu")
	)
	(gr_line
		(start 275.47951 -152.5143)
		(end 275.575014 -152.40508)
		(stroke
			(width 0.08255)
			(type default)
		)
		(layer "In5.Cu")
	)
	(gr_line
		(start 275.504148 -151.17699)
		(end 275.471382 -150.682452)
		(stroke
			(width 0.08255)
			(type default)
		)
		(layer "In5.Cu")
	)
	(gr_line
		(start 275.540724 -151.889206)
		(end 275.431758 -151.793702)
		(stroke
			(width 0.08255)
			(type default)
		)
		(layer "In5.Cu")
	)
	(gr_line
		(start 275.556726 -153.68016)
		(end 275.638768 -153.586688)
		(stroke
			(width 0.08255)
			(type default)
		)
		(layer "In5.Cu")
	)
	(gr_line
		(start 275.575014 -152.40508)
		(end 275.540724 -151.889206)
		(stroke
			(width 0.08255)
			(type default)
		)
		(layer "In5.Cu")
	)
	(gr_line
		(start 275.606002 -153.09215)
		(end 275.512276 -153.010362)
		(stroke
			(width 0.08255)
			(type default)
		)
		(layer "In5.Cu")
	)
	(gr_line
		(start 275.634196 -154.846274)
		(end 275.703538 -154.767026)
		(stroke
			(width 0.08255)
			(type default)
		)
		(layer "In5.Cu")
	)
	(gr_line
		(start 275.638768 -153.586688)
		(end 275.606002 -153.09215)
		(stroke
			(width 0.08255)
			(type default)
		)
		(layer "In5.Cu")
	)
	(gr_line
		(start 275.668994 -154.245564)
		(end 275.589746 -154.176222)
		(stroke
			(width 0.08255)
			(type default)
		)
		(layer "In5.Cu")
	)
	(gr_line
		(start 275.692616 -341.136986)
		(end 275.652484 -341.10168)
		(stroke
			(width 0.08255)
			(type default)
		)
		(layer "In5.Cu")
	)
	(gr_line
		(start 275.703538 -154.767026)
		(end 275.668994 -154.245564)
		(stroke
			(width 0.08255)
			(type default)
		)
		(layer "In5.Cu")
	)
	(gr_line
		(start 276.022816 -341.691468)
		(end 275.692616 -341.136986)
		(stroke
			(width 0.08255)
			(type default)
		)
		(layer "In5.Cu")
	)
	(gr_line
		(start 278.883872 -320.043048)
		(end 278.883872 -320.0146)
		(stroke
			(width 0.05715)
			(type default)
		)
		(layer "In5.Cu")
	)
	(gr_line
		(start 278.883872 -320.0146)
		(end 278.929592 -319.96888)
		(stroke
			(width 0.05715)
			(type default)
		)
		(layer "In5.Cu")
	)
	(gr_line
		(start 279.165812 -320.043048)
		(end 279.165812 -320.0146)
		(stroke
			(width 0.05715)
			(type default)
		)
		(layer "In5.Cu")
	)
	(gr_line
		(start 279.165812 -320.0146)
		(end 279.120092 -319.96888)
		(stroke
			(width 0.05715)
			(type default)
		)
		(layer "In5.Cu")
	)
	(gr_line
		(start 279.385522 -316.419992)
		(end 279.499822 -316.534292)
		(stroke
			(width 0.05715)
			(type default)
		)
		(layer "In5.Cu")
	)
	(gr_line
		(start 279.385522 -316.229492)
		(end 279.499822 -316.115192)
		(stroke
			(width 0.05715)
			(type default)
		)
		(layer "In5.Cu")
	)
	(gr_line
		(start 279.499822 -316.534292)
		(end 279.499822 -316.799722)
		(stroke
			(width 0.05715)
			(type default)
		)
		(layer "In5.Cu")
	)
	(gr_line
		(start 279.499822 -316.115192)
		(end 279.499822 -315.849762)
		(stroke
			(width 0.05715)
			(type default)
		)
		(layer "In5.Cu")
	)
	(gr_line
		(start 279.833832 -319.966848)
		(end 279.833832 -319.9384)
		(stroke
			(width 0.05715)
			(type default)
		)
		(layer "In5.Cu")
	)
	(gr_line
		(start 279.833832 -319.9384)
		(end 279.879552 -319.89268)
		(stroke
			(width 0.05715)
			(type default)
		)
		(layer "In5.Cu")
	)
	(gr_line
		(start 280.115772 -319.966848)
		(end 280.115772 -319.9384)
		(stroke
			(width 0.05715)
			(type default)
		)
		(layer "In5.Cu")
	)
	(gr_line
		(start 280.115772 -319.9384)
		(end 280.070052 -319.89268)
		(stroke
			(width 0.05715)
			(type default)
		)
		(layer "In5.Cu")
	)
	(gr_line
		(start 280.335482 -318.320166)
		(end 280.449782 -318.434466)
		(stroke
			(width 0.05715)
			(type default)
		)
		(layer "In5.Cu")
	)
	(gr_line
		(start 280.335482 -318.129666)
		(end 280.449782 -318.015366)
		(stroke
			(width 0.05715)
			(type default)
		)
		(layer "In5.Cu")
	)
	(gr_line
		(start 280.449782 -318.434466)
		(end 280.449782 -318.699896)
		(stroke
			(width 0.05715)
			(type default)
		)
		(layer "In5.Cu")
	)
	(gr_line
		(start 280.449782 -318.015366)
		(end 280.449782 -317.749936)
		(stroke
			(width 0.05715)
			(type default)
		)
		(layer "In5.Cu")
	)
	(gr_line
		(start 280.783792 -319.966848)
		(end 280.783792 -319.9384)
		(stroke
			(width 0.05715)
			(type default)
		)
		(layer "In5.Cu")
	)
	(gr_line
		(start 280.783792 -319.9384)
		(end 280.829512 -319.89268)
		(stroke
			(width 0.05715)
			(type default)
		)
		(layer "In5.Cu")
	)
	(gr_line
		(start 281.065732 -319.966848)
		(end 281.065732 -319.9384)
		(stroke
			(width 0.05715)
			(type default)
		)
		(layer "In5.Cu")
	)
	(gr_line
		(start 281.065732 -319.9384)
		(end 281.020012 -319.89268)
		(stroke
			(width 0.05715)
			(type default)
		)
		(layer "In5.Cu")
	)
	(gr_line
		(start 281.285442 -316.419992)
		(end 281.399742 -316.534292)
		(stroke
			(width 0.05715)
			(type default)
		)
		(layer "In5.Cu")
	)
	(gr_line
		(start 281.285442 -316.229492)
		(end 281.399742 -316.115192)
		(stroke
			(width 0.05715)
			(type default)
		)
		(layer "In5.Cu")
	)
	(gr_line
		(start 281.399742 -316.534292)
		(end 281.399742 -316.799722)
		(stroke
			(width 0.05715)
			(type default)
		)
		(layer "In5.Cu")
	)
	(gr_line
		(start 281.399742 -316.115192)
		(end 281.399742 -315.849762)
		(stroke
			(width 0.05715)
			(type default)
		)
		(layer "In5.Cu")
	)
	(gr_line
		(start 281.625294 -142.648178)
		(end 281.625294 -142.648432)
		(stroke
			(width 0.08255)
			(type default)
		)
		(layer "In5.Cu")
	)
	(gr_line
		(start 281.627072 -142.647416)
		(end 281.7749 -142.586202)
		(stroke
			(width 0.08255)
			(type default)
		)
		(layer "In5.Cu")
	)
	(gr_line
		(start 281.733752 -319.916048)
		(end 281.733752 -319.8876)
		(stroke
			(width 0.05715)
			(type default)
		)
		(layer "In5.Cu")
	)
	(gr_line
		(start 281.733752 -319.8876)
		(end 281.779472 -319.84188)
		(stroke
			(width 0.05715)
			(type default)
		)
		(layer "In5.Cu")
	)
	(gr_line
		(start 281.7749 -142.586202)
		(end 281.964384 -142.128494)
		(stroke
			(width 0.08255)
			(type default)
		)
		(layer "In5.Cu")
	)
	(gr_line
		(start 281.964384 -142.128494)
		(end 281.90317 -141.980666)
		(stroke
			(width 0.08255)
			(type default)
		)
		(layer "In5.Cu")
	)
	(gr_line
		(start 282.015692 -319.916048)
		(end 282.015692 -319.8876)
		(stroke
			(width 0.05715)
			(type default)
		)
		(layer "In5.Cu")
	)
	(gr_line
		(start 282.015692 -319.8876)
		(end 281.969972 -319.84188)
		(stroke
			(width 0.05715)
			(type default)
		)
		(layer "In5.Cu")
	)
	(gr_line
		(start 282.222448 -140.713206)
		(end 282.335478 -140.600176)
		(stroke
			(width 0.08255)
			(type default)
		)
		(layer "In5.Cu")
	)
	(gr_line
		(start 282.222448 -139.494006)
		(end 282.335478 -139.380976)
		(stroke
			(width 0.08255)
			(type default)
		)
		(layer "In5.Cu")
	)
	(gr_line
		(start 282.235402 -318.320166)
		(end 282.349702 -318.434466)
		(stroke
			(width 0.05715)
			(type default)
		)
		(layer "In5.Cu")
	)
	(gr_line
		(start 282.235402 -318.129666)
		(end 282.349702 -318.015366)
		(stroke
			(width 0.05715)
			(type default)
		)
		(layer "In5.Cu")
	)
	(gr_line
		(start 282.335478 -140.600176)
		(end 282.335478 -140.104876)
		(stroke
			(width 0.08255)
			(type default)
		)
		(layer "In5.Cu")
	)
	(gr_line
		(start 282.335478 -140.104876)
		(end 282.222448 -139.991846)
		(stroke
			(width 0.08255)
			(type default)
		)
		(layer "In5.Cu")
	)
	(gr_line
		(start 282.335478 -139.380976)
		(end 282.335478 -138.885676)
		(stroke
			(width 0.08255)
			(type default)
		)
		(layer "In5.Cu")
	)
	(gr_line
		(start 282.335478 -138.885676)
		(end 282.222448 -138.772646)
		(stroke
			(width 0.08255)
			(type default)
		)
		(layer "In5.Cu")
	)
	(gr_line
		(start 282.349702 -318.434466)
		(end 282.349702 -318.699896)
		(stroke
			(width 0.05715)
			(type default)
		)
		(layer "In5.Cu")
	)
	(gr_line
		(start 282.349702 -318.015366)
		(end 282.349702 -317.749936)
		(stroke
			(width 0.05715)
			(type default)
		)
		(layer "In5.Cu")
	)
	(gr_line
		(start 282.649168 -369.87353)
		(end 282.63215 -369.852702)
		(stroke
			(width 0.08255)
			(type default)
		)
		(layer "In5.Cu")
	)
	(gr_line
		(start 282.650438 -369.874038)
		(end 282.649168 -369.87353)
		(stroke
			(width 0.08255)
			(type default)
		)
		(layer "In5.Cu")
	)
	(gr_line
		(start 282.6512 -369.8748)
		(end 282.650438 -369.874038)
		(stroke
			(width 0.08255)
			(type default)
		)
		(layer "In5.Cu")
	)
	(gr_line
		(start 282.666186 -369.904518)
		(end 282.6512 -369.8748)
		(stroke
			(width 0.08255)
			(type default)
		)
		(layer "In5.Cu")
	)
	(gr_line
		(start 282.701746 -136.147048)
		(end 282.701746 -136.147302)
		(stroke
			(width 0.08255)
			(type default)
		)
		(layer "In5.Cu")
	)
	(gr_line
		(start 282.703524 -136.14654)
		(end 282.853892 -136.092438)
		(stroke
			(width 0.08255)
			(type default)
		)
		(layer "In5.Cu")
	)
	(gr_line
		(start 282.853892 -136.092438)
		(end 283.065982 -135.644382)
		(stroke
			(width 0.08255)
			(type default)
		)
		(layer "In5.Cu")
	)
	(gr_line
		(start 283.065982 -135.644382)
		(end 283.012134 -135.49376)
		(stroke
			(width 0.08255)
			(type default)
		)
		(layer "In5.Cu")
	)
	(gr_line
		(start 284.176216 -378.796296)
		(end 284.175454 -378.786898)
		(stroke
			(width 0.08255)
			(type default)
		)
		(layer "In5.Cu")
	)
	(gr_line
		(start 284.634178 -134.606792)
		(end 284.747208 -134.719822)
		(stroke
			(width 0.08255)
			(type default)
		)
		(layer "In5.Cu")
	)
	(gr_line
		(start 284.73781 -392.728958)
		(end 284.703012 -392.591036)
		(stroke
			(width 0.08255)
			(type default)
		)
		(layer "In5.Cu")
	)
	(gr_line
		(start 284.747208 -134.719822)
		(end 285.242508 -134.719822)
		(stroke
			(width 0.08255)
			(type default)
		)
		(layer "In5.Cu")
	)
	(gr_line
		(start 285.163768 -392.982196)
		(end 284.73781 -392.728958)
		(stroke
			(width 0.08255)
			(type default)
		)
		(layer "In5.Cu")
	)
	(gr_line
		(start 285.242508 -134.719822)
		(end 285.355538 -134.606792)
		(stroke
			(width 0.08255)
			(type default)
		)
		(layer "In5.Cu")
	)
	(gr_line
		(start 285.30169 -392.947144)
		(end 285.163768 -392.982196)
		(stroke
			(width 0.08255)
			(type default)
		)
		(layer "In5.Cu")
	)
	(gr_line
		(start 285.447232 -392.70432)
		(end 284.846522 -392.347196)
		(stroke
			(width 0.08255)
			(type default)
		)
		(layer "In5.Cu")
	)
	(gr_line
		(start 285.76397 -393.339066)
		(end 285.728918 -393.201398)
		(stroke
			(width 0.08255)
			(type default)
		)
		(layer "In5.Cu")
	)
	(gr_line
		(start 285.99765 -134.605522)
		(end 286.003746 -134.603236)
		(stroke
			(width 0.08255)
			(type default)
		)
		(layer "In5.Cu")
	)
	(gr_line
		(start 286.003746 -134.603236)
		(end 286.006032 -134.605522)
		(stroke
			(width 0.08255)
			(type default)
		)
		(layer "In5.Cu")
	)
	(gr_line
		(start 286.006032 -134.605522)
		(end 286.296862 -134.896352)
		(stroke
			(width 0.08255)
			(type default)
		)
		(layer "In5.Cu")
	)
	(gr_line
		(start 286.190182 -393.592558)
		(end 285.76397 -393.339066)
		(stroke
			(width 0.08255)
			(type default)
		)
		(layer "In5.Cu")
	)
	(gr_line
		(start 286.328104 -393.557506)
		(end 286.190182 -393.592558)
		(stroke
			(width 0.08255)
			(type default)
		)
		(layer "In5.Cu")
	)
	(gr_line
		(start 286.473646 -393.314682)
		(end 285.872682 -392.957304)
		(stroke
			(width 0.08255)
			(type default)
		)
		(layer "In5.Cu")
	)
	(gr_line
		(start 287.4899 -409.490164)
		(end 287.4899 -409.108148)
		(stroke
			(width 0.08255)
			(type default)
		)
		(layer "In5.Cu")
	)
	(gr_line
		(start 287.4899 -409.108148)
		(end 287.6169 -408.981148)
		(stroke
			(width 0.08255)
			(type default)
		)
		(layer "In5.Cu")
	)
	(gr_line
		(start 287.4899 -408.572208)
		(end 287.6169 -408.699208)
		(stroke
			(width 0.08255)
			(type default)
		)
		(layer "In5.Cu")
	)
	(gr_line
		(start 287.4899 -408.190192)
		(end 287.4899 -408.572208)
		(stroke
			(width 0.08255)
			(type default)
		)
		(layer "In5.Cu")
	)
	(gr_line
		(start 288.51606 -338.500974)
		(end 288.396426 -338.534756)
		(stroke
			(width 0.08255)
			(type default)
		)
		(layer "In5.Cu")
	)
	(gr_line
		(start 288.845752 -339.109812)
		(end 288.257742 -338.781644)
		(stroke
			(width 0.08255)
			(type default)
		)
		(layer "In5.Cu")
	)
	(gr_line
		(start 288.948876 -338.742528)
		(end 288.51606 -338.500974)
		(stroke
			(width 0.08255)
			(type default)
		)
		(layer "In5.Cu")
	)
	(gr_line
		(start 288.982912 -338.862162)
		(end 288.948876 -338.742528)
		(stroke
			(width 0.08255)
			(type default)
		)
		(layer "In5.Cu")
	)
	(gr_line
		(start 289.536886 -339.070442)
		(end 289.417252 -339.104224)
		(stroke
			(width 0.08255)
			(type default)
		)
		(layer "In5.Cu")
	)
	(gr_line
		(start 289.866578 -339.67928)
		(end 289.278314 -339.351112)
		(stroke
			(width 0.08255)
			(type default)
		)
		(layer "In5.Cu")
	)
	(gr_line
		(start 289.969448 -339.311996)
		(end 289.536886 -339.070442)
		(stroke
			(width 0.08255)
			(type default)
		)
		(layer "In5.Cu")
	)
	(gr_line
		(start 290.003484 -339.431376)
		(end 289.969448 -339.311996)
		(stroke
			(width 0.08255)
			(type default)
		)
		(layer "In5.Cu")
	)
	(gr_line
		(start 291.319712 -328.331322)
		(end 291.202364 -328.372724)
		(stroke
			(width 0.08255)
			(type default)
		)
		(layer "In5.Cu")
	)
	(gr_line
		(start 291.687504 -328.917808)
		(end 291.079682 -328.627994)
		(stroke
			(width 0.08255)
			(type default)
		)
		(layer "In5.Cu")
	)
	(gr_line
		(start 291.767006 -328.544682)
		(end 291.319712 -328.331322)
		(stroke
			(width 0.08255)
			(type default)
		)
		(layer "In5.Cu")
	)
	(gr_line
		(start 291.808408 -328.661776)
		(end 291.767006 -328.544682)
		(stroke
			(width 0.08255)
			(type default)
		)
		(layer "In5.Cu")
	)
	(gr_line
		(start 292.040564 -360.151172)
		(end 292.113716 -360.008932)
		(stroke
			(width 0.08255)
			(type default)
		)
		(layer "In5.Cu")
	)
	(gr_line
		(start 292.191948 -360.623104)
		(end 292.040564 -360.151172)
		(stroke
			(width 0.08255)
			(type default)
		)
		(layer "In5.Cu")
	)
	(gr_line
		(start 292.334188 -360.696002)
		(end 292.191948 -360.623104)
		(stroke
			(width 0.08255)
			(type default)
		)
		(layer "In5.Cu")
	)
	(gr_line
		(start 292.335712 -360.697018)
		(end 292.335966 -360.697018)
		(stroke
			(width 0.08255)
			(type default)
		)
		(layer "In5.Cu")
	)
	(gr_line
		(start 292.361366 -326.477376)
		(end 292.227762 -326.52589)
		(stroke
			(width 0.08255)
			(type default)
		)
		(layer "In5.Cu")
	)
	(gr_line
		(start 292.37432 -328.834496)
		(end 292.25748 -328.875898)
		(stroke
			(width 0.08255)
			(type default)
		)
		(layer "In5.Cu")
	)
	(gr_line
		(start 292.515544 -327.74382)
		(end 292.415722 -327.779888)
		(stroke
			(width 0.08255)
			(type default)
		)
		(layer "In5.Cu")
	)
	(gr_line
		(start 292.60419 -360.610912)
		(end 292.382956 -359.921302)
		(stroke
			(width 0.08255)
			(type default)
		)
		(layer "In5.Cu")
	)
	(gr_line
		(start 292.74008 -327.077832)
		(end 292.107112 -326.782176)
		(stroke
			(width 0.08255)
			(type default)
		)
		(layer "In5.Cu")
	)
	(gr_line
		(start 292.74262 -329.420982)
		(end 292.134544 -329.130914)
		(stroke
			(width 0.08255)
			(type default)
		)
		(layer "In5.Cu")
	)
	(gr_line
		(start 292.810438 -326.687434)
		(end 292.361366 -326.477376)
		(stroke
			(width 0.08255)
			(type default)
		)
		(layer "In5.Cu")
	)
	(gr_line
		(start 292.821614 -329.047856)
		(end 292.37432 -328.834496)
		(stroke
			(width 0.08255)
			(type default)
		)
		(layer "In5.Cu")
	)
	(gr_line
		(start 292.858952 -326.820784)
		(end 292.810438 -326.687434)
		(stroke
			(width 0.08255)
			(type default)
		)
		(layer "In5.Cu")
	)
	(gr_line
		(start 292.86327 -329.164696)
		(end 292.821614 -329.047856)
		(stroke
			(width 0.08255)
			(type default)
		)
		(layer "In5.Cu")
	)
	(gr_line
		(start 292.863778 -329.166474)
		(end 292.864032 -329.16622)
		(stroke
			(width 0.08255)
			(type default)
		)
		(layer "In5.Cu")
	)
	(gr_line
		(start 292.882066 -328.310494)
		(end 292.295072 -328.036174)
		(stroke
			(width 0.08255)
			(type default)
		)
		(layer "In5.Cu")
	)
	(gr_line
		(start 292.964616 -327.953624)
		(end 292.515544 -327.74382)
		(stroke
			(width 0.08255)
			(type default)
		)
		(layer "In5.Cu")
	)
	(gr_line
		(start 293.000938 -328.053446)
		(end 292.964616 -327.953624)
		(stroke
			(width 0.08255)
			(type default)
		)
		(layer "In5.Cu")
	)
	(gr_line
		(start 293.443152 -326.982836)
		(end 293.309294 -327.03135)
		(stroke
			(width 0.08255)
			(type default)
		)
		(layer "In5.Cu")
	)
	(gr_line
		(start 293.552626 -364.864142)
		(end 293.625778 -364.721648)
		(stroke
			(width 0.08255)
			(type default)
		)
		(layer "In5.Cu")
	)
	(gr_line
		(start 293.70401 -365.336074)
		(end 293.552626 -364.864142)
		(stroke
			(width 0.08255)
			(type default)
		)
		(layer "In5.Cu")
	)
	(gr_line
		(start 293.821866 -327.583292)
		(end 293.188644 -327.287636)
		(stroke
			(width 0.08255)
			(type default)
		)
		(layer "In5.Cu")
	)
	(gr_line
		(start 293.84625 -365.409226)
		(end 293.70401 -365.336074)
		(stroke
			(width 0.08255)
			(type default)
		)
		(layer "In5.Cu")
	)
	(gr_line
		(start 293.847774 -365.409988)
		(end 293.848028 -365.409988)
		(stroke
			(width 0.08255)
			(type default)
		)
		(layer "In5.Cu")
	)
	(gr_line
		(start 293.892224 -327.19264)
		(end 293.443152 -326.982836)
		(stroke
			(width 0.08255)
			(type default)
		)
		(layer "In5.Cu")
	)
	(gr_line
		(start 293.925244 -366.025176)
		(end 293.998396 -365.882936)
		(stroke
			(width 0.08255)
			(type default)
		)
		(layer "In5.Cu")
	)
	(gr_line
		(start 293.940738 -327.326244)
		(end 293.892224 -327.19264)
		(stroke
			(width 0.08255)
			(type default)
		)
		(layer "In5.Cu")
	)
	(gr_line
		(start 293.999158 -365.881412)
		(end 293.998904 -365.881412)
		(stroke
			(width 0.08255)
			(type default)
		)
		(layer "In5.Cu")
	)
	(gr_line
		(start 294.076628 -366.497108)
		(end 293.925244 -366.025176)
		(stroke
			(width 0.08255)
			(type default)
		)
		(layer "In5.Cu")
	)
	(gr_line
		(start 294.089836 -384.590036)
		(end 294.089836 -384.20802)
		(stroke
			(width 0.08255)
			(type default)
		)
		(layer "In5.Cu")
	)
	(gr_line
		(start 294.089836 -384.20802)
		(end 294.216836 -384.08102)
		(stroke
			(width 0.08255)
			(type default)
		)
		(layer "In5.Cu")
	)
	(gr_line
		(start 294.089836 -383.67208)
		(end 294.216836 -383.79908)
		(stroke
			(width 0.08255)
			(type default)
		)
		(layer "In5.Cu")
	)
	(gr_line
		(start 294.089836 -383.290064)
		(end 294.089836 -383.67208)
		(stroke
			(width 0.08255)
			(type default)
		)
		(layer "In5.Cu")
	)
	(gr_line
		(start 294.116506 -365.323882)
		(end 293.895272 -364.634272)
		(stroke
			(width 0.08255)
			(type default)
		)
		(layer "In5.Cu")
	)
	(gr_line
		(start 294.218868 -366.570006)
		(end 294.076628 -366.497108)
		(stroke
			(width 0.08255)
			(type default)
		)
		(layer "In5.Cu")
	)
	(gr_line
		(start 294.220392 -366.571022)
		(end 294.220646 -366.571022)
		(stroke
			(width 0.08255)
			(type default)
		)
		(layer "In5.Cu")
	)
	(gr_line
		(start 294.48887 -366.484916)
		(end 294.267636 -365.795306)
		(stroke
			(width 0.08255)
			(type default)
		)
		(layer "In5.Cu")
	)
	(gr_line
		(start 294.568626 -326.33412)
		(end 294.469058 -326.371204)
		(stroke
			(width 0.08255)
			(type default)
		)
		(layer "In5.Cu")
	)
	(gr_line
		(start 294.917876 -393.07008)
		(end 294.27805 -392.73099)
		(stroke
			(width 0.08255)
			(type default)
		)
		(layer "In5.Cu")
	)
	(gr_line
		(start 294.939974 -326.897492)
		(end 294.350694 -326.628506)
		(stroke
			(width 0.08255)
			(type default)
		)
		(layer "In5.Cu")
	)
	(gr_line
		(start 295.019476 -326.540114)
		(end 294.568626 -326.33412)
		(stroke
			(width 0.08255)
			(type default)
		)
		(layer "In5.Cu")
	)
	(gr_line
		(start 295.05656 -326.639428)
		(end 295.019476 -326.540114)
		(stroke
			(width 0.08255)
			(type default)
		)
		(layer "In5.Cu")
	)
	(gr_line
		(start 295.355518 -393.301728)
		(end 295.29659 -393.270486)
		(stroke
			(width 0.08255)
			(type default)
		)
		(layer "In5.Cu")
	)
	(gr_line
		(start 295.995598 -393.640564)
		(end 295.355518 -393.301728)
		(stroke
			(width 0.08255)
			(type default)
		)
		(layer "In5.Cu")
	)
	(gr_line
		(start 296.289984 -409.490164)
		(end 296.289984 -409.108148)
		(stroke
			(width 0.08255)
			(type default)
		)
		(layer "In5.Cu")
	)
	(gr_line
		(start 296.289984 -409.108148)
		(end 296.416984 -408.981148)
		(stroke
			(width 0.08255)
			(type default)
		)
		(layer "In5.Cu")
	)
	(gr_line
		(start 297.403012 -121.367296)
		(end 297.693842 -121.076466)
		(stroke
			(width 0.08255)
			(type default)
		)
		(layer "In5.Cu")
	)
	(gr_line
		(start 298.489878 -410.589984)
		(end 298.489878 -410.207968)
		(stroke
			(width 0.08255)
			(type default)
		)
		(layer "In5.Cu")
	)
	(gr_line
		(start 298.489878 -410.207968)
		(end 298.616878 -410.080968)
		(stroke
			(width 0.08255)
			(type default)
		)
		(layer "In5.Cu")
	)
	(gr_line
		(start 299.257212 -130.777234)
		(end 299.548042 -130.486404)
		(stroke
			(width 0.08255)
			(type default)
		)
		(layer "In5.Cu")
	)
	(gr_line
		(start 299.257212 -119.567198)
		(end 299.548042 -119.276368)
		(stroke
			(width 0.08255)
			(type default)
		)
		(layer "In5.Cu")
	)
	(gr_line
		(start 299.35551 -392.943842)
		(end 298.753784 -392.541252)
		(stroke
			(width 0.08255)
			(type default)
		)
		(layer "In5.Cu")
	)
	(gr_line
		(start 299.548042 -146.796506)
		(end 299.257212 -147.087336)
		(stroke
			(width 0.08255)
			(type default)
		)
		(layer "In5.Cu")
	)
	(gr_line
		(start 299.783754 -319.969896)
		(end 299.783754 -319.941448)
		(stroke
			(width 0.05715)
			(type default)
		)
		(layer "In5.Cu")
	)
	(gr_line
		(start 299.783754 -319.941448)
		(end 299.829474 -319.895728)
		(stroke
			(width 0.05715)
			(type default)
		)
		(layer "In5.Cu")
	)
	(gr_line
		(start 300.21657 -121.266712)
		(end 300.21657 -121.266966)
		(stroke
			(width 0.08255)
			(type default)
		)
		(layer "In5.Cu")
	)
	(gr_line
		(start 300.217332 -121.26849)
		(end 300.278038 -121.416572)
		(stroke
			(width 0.08255)
			(type default)
		)
		(layer "In5.Cu")
	)
	(gr_line
		(start 300.278038 -121.416572)
		(end 300.735492 -121.606818)
		(stroke
			(width 0.08255)
			(type default)
		)
		(layer "In5.Cu")
	)
	(gr_line
		(start 300.285404 -316.229492)
		(end 300.399704 -316.115192)
		(stroke
			(width 0.05715)
			(type default)
		)
		(layer "In5.Cu")
	)
	(gr_line
		(start 300.36897 -393.622276)
		(end 299.76699 -393.219432)
		(stroke
			(width 0.08255)
			(type default)
		)
		(layer "In5.Cu")
	)
	(gr_line
		(start 300.378876 -147.272248)
		(end 300.378876 -147.148296)
		(stroke
			(width 0.08255)
			(type default)
		)
		(layer "In5.Cu")
	)
	(gr_line
		(start 300.399704 -316.115192)
		(end 300.399704 -315.849762)
		(stroke
			(width 0.05715)
			(type default)
		)
		(layer "In5.Cu")
	)
	(gr_line
		(start 300.484286 -119.465598)
		(end 300.484286 -119.465852)
		(stroke
			(width 0.08255)
			(type default)
		)
		(layer "In5.Cu")
	)
	(gr_line
		(start 300.485048 -119.467376)
		(end 300.546262 -119.615204)
		(stroke
			(width 0.08255)
			(type default)
		)
		(layer "In5.Cu")
	)
	(gr_line
		(start 300.546262 -119.615204)
		(end 301.004224 -119.804688)
		(stroke
			(width 0.08255)
			(type default)
		)
		(layer "In5.Cu")
	)
	(gr_line
		(start 300.582584 -130.845052)
		(end 300.629574 -130.99796)
		(stroke
			(width 0.08255)
			(type default)
		)
		(layer "In5.Cu")
	)
	(gr_line
		(start 300.629574 -130.99796)
		(end 301.067724 -131.229608)
		(stroke
			(width 0.08255)
			(type default)
		)
		(layer "In5.Cu")
	)
	(gr_line
		(start 300.689772 -409.490164)
		(end 300.689772 -409.108148)
		(stroke
			(width 0.08255)
			(type default)
		)
		(layer "In5.Cu")
	)
	(gr_line
		(start 300.689772 -409.108148)
		(end 300.816772 -408.981148)
		(stroke
			(width 0.08255)
			(type default)
		)
		(layer "In5.Cu")
	)
	(gr_line
		(start 300.729396 -147.622768)
		(end 300.378876 -147.272248)
		(stroke
			(width 0.08255)
			(type default)
		)
		(layer "In5.Cu")
	)
	(gr_line
		(start 300.735492 -121.606818)
		(end 300.883574 -121.545858)
		(stroke
			(width 0.08255)
			(type default)
		)
		(layer "In5.Cu")
	)
	(gr_line
		(start 300.853348 -147.622768)
		(end 300.729396 -147.622768)
		(stroke
			(width 0.08255)
			(type default)
		)
		(layer "In5.Cu")
	)
	(gr_line
		(start 301.004224 -119.804688)
		(end 301.152052 -119.743474)
		(stroke
			(width 0.08255)
			(type default)
		)
		(layer "In5.Cu")
	)
	(gr_line
		(start 301.067724 -131.229608)
		(end 301.220632 -131.182364)
		(stroke
			(width 0.08255)
			(type default)
		)
		(layer "In5.Cu")
	)
	(gr_line
		(start 301.34306 -121.73712)
		(end 301.403766 -121.885202)
		(stroke
			(width 0.08255)
			(type default)
		)
		(layer "In5.Cu")
	)
	(gr_line
		(start 301.403766 -121.885202)
		(end 301.86122 -122.075702)
		(stroke
			(width 0.08255)
			(type default)
		)
		(layer "In5.Cu")
	)
	(gr_line
		(start 301.61103 -119.931942)
		(end 301.610776 -119.931942)
		(stroke
			(width 0.08255)
			(type default)
		)
		(layer "In5.Cu")
	)
	(gr_line
		(start 301.611792 -119.93372)
		(end 301.673006 -120.081548)
		(stroke
			(width 0.08255)
			(type default)
		)
		(layer "In5.Cu")
	)
	(gr_line
		(start 301.642272 -131.403598)
		(end 301.660052 -131.412996)
		(stroke
			(width 0.08255)
			(type default)
		)
		(layer "In5.Cu")
	)
	(gr_line
		(start 301.66056 -131.414774)
		(end 301.70755 -131.567682)
		(stroke
			(width 0.08255)
			(type default)
		)
		(layer "In5.Cu")
	)
	(gr_line
		(start 301.673006 -120.081548)
		(end 302.130968 -120.271032)
		(stroke
			(width 0.08255)
			(type default)
		)
		(layer "In5.Cu")
	)
	(gr_line
		(start 301.683928 -319.969896)
		(end 301.683928 -319.941448)
		(stroke
			(width 0.05715)
			(type default)
		)
		(layer "In5.Cu")
	)
	(gr_line
		(start 301.683928 -319.941448)
		(end 301.729648 -319.895728)
		(stroke
			(width 0.05715)
			(type default)
		)
		(layer "In5.Cu")
	)
	(gr_line
		(start 301.70755 -131.567682)
		(end 302.1457 -131.799076)
		(stroke
			(width 0.08255)
			(type default)
		)
		(layer "In5.Cu")
	)
	(gr_line
		(start 301.851822 -148.901658)
		(end 301.875952 -148.780246)
		(stroke
			(width 0.08255)
			(type default)
		)
		(layer "In5.Cu")
	)
	(gr_line
		(start 301.86122 -122.075702)
		(end 302.009556 -122.014742)
		(stroke
			(width 0.08255)
			(type default)
		)
		(layer "In5.Cu")
	)
	(gr_line
		(start 302.128428 -149.313138)
		(end 301.851822 -148.901658)
		(stroke
			(width 0.08255)
			(type default)
		)
		(layer "In5.Cu")
	)
	(gr_line
		(start 302.130968 -120.271032)
		(end 302.278796 -120.209818)
		(stroke
			(width 0.08255)
			(type default)
		)
		(layer "In5.Cu")
	)
	(gr_line
		(start 302.1457 -131.799076)
		(end 302.298862 -131.752086)
		(stroke
			(width 0.08255)
			(type default)
		)
		(layer "In5.Cu")
	)
	(gr_line
		(start 302.185578 -316.229492)
		(end 302.299878 -316.115192)
		(stroke
			(width 0.05715)
			(type default)
		)
		(layer "In5.Cu")
	)
	(gr_line
		(start 302.250094 -149.337014)
		(end 302.128428 -149.313138)
		(stroke
			(width 0.08255)
			(type default)
		)
		(layer "In5.Cu")
	)
	(gr_line
		(start 302.299878 -316.115192)
		(end 302.299878 -315.849762)
		(stroke
			(width 0.05715)
			(type default)
		)
		(layer "In5.Cu")
	)
	(gr_line
		(start 302.468534 -122.20575)
		(end 302.529494 -122.354086)
		(stroke
			(width 0.08255)
			(type default)
		)
		(layer "In5.Cu")
	)
	(gr_line
		(start 302.529494 -122.354086)
		(end 302.986948 -122.544586)
		(stroke
			(width 0.08255)
			(type default)
		)
		(layer "In5.Cu")
	)
	(gr_line
		(start 302.737774 -131.982464)
		(end 302.738282 -131.982718)
		(stroke
			(width 0.08255)
			(type default)
		)
		(layer "In5.Cu")
	)
	(gr_line
		(start 302.737774 -120.398286)
		(end 302.73752 -120.398286)
		(stroke
			(width 0.08255)
			(type default)
		)
		(layer "In5.Cu")
	)
	(gr_line
		(start 302.738536 -120.400064)
		(end 302.79975 -120.547892)
		(stroke
			(width 0.08255)
			(type default)
		)
		(layer "In5.Cu")
	)
	(gr_line
		(start 302.73879 -131.984496)
		(end 302.78578 -132.137404)
		(stroke
			(width 0.08255)
			(type default)
		)
		(layer "In5.Cu")
	)
	(gr_line
		(start 302.78578 -132.137404)
		(end 303.22393 -132.368798)
		(stroke
			(width 0.08255)
			(type default)
		)
		(layer "In5.Cu")
	)
	(gr_line
		(start 302.79975 -120.547892)
		(end 303.257712 -120.737376)
		(stroke
			(width 0.08255)
			(type default)
		)
		(layer "In5.Cu")
	)
	(gr_line
		(start 302.986948 -122.544586)
		(end 303.135284 -122.483372)
		(stroke
			(width 0.08255)
			(type default)
		)
		(layer "In5.Cu")
	)
	(gr_line
		(start 303.22393 -132.368798)
		(end 303.377092 -132.321808)
		(stroke
			(width 0.08255)
			(type default)
		)
		(layer "In5.Cu")
	)
	(gr_line
		(start 303.257712 -120.737376)
		(end 303.40554 -120.676162)
		(stroke
			(width 0.08255)
			(type default)
		)
		(layer "In5.Cu")
	)
	(gr_line
		(start 303.583848 -319.969896)
		(end 303.583848 -319.941448)
		(stroke
			(width 0.05715)
			(type default)
		)
		(layer "In5.Cu")
	)
	(gr_line
		(start 303.583848 -319.941448)
		(end 303.629568 -319.895728)
		(stroke
			(width 0.05715)
			(type default)
		)
		(layer "In5.Cu")
	)
	(gr_line
		(start 303.594262 -122.674634)
		(end 303.655222 -122.822716)
		(stroke
			(width 0.08255)
			(type default)
		)
		(layer "In5.Cu")
	)
	(gr_line
		(start 303.655222 -122.822716)
		(end 304.112676 -123.013216)
		(stroke
			(width 0.08255)
			(type default)
		)
		(layer "In5.Cu")
	)
	(gr_line
		(start 303.81702 -132.554218)
		(end 303.86401 -132.706872)
		(stroke
			(width 0.08255)
			(type default)
		)
		(layer "In5.Cu")
	)
	(gr_line
		(start 303.86401 -132.706872)
		(end 304.302414 -132.93852)
		(stroke
			(width 0.08255)
			(type default)
		)
		(layer "In5.Cu")
	)
	(gr_line
		(start 303.865788 -319.969896)
		(end 303.865788 -319.941448)
		(stroke
			(width 0.05715)
			(type default)
		)
		(layer "In5.Cu")
	)
	(gr_line
		(start 303.865788 -319.941448)
		(end 303.820068 -319.895728)
		(stroke
			(width 0.05715)
			(type default)
		)
		(layer "In5.Cu")
	)
	(gr_line
		(start 304.085498 -316.419992)
		(end 304.199798 -316.534292)
		(stroke
			(width 0.05715)
			(type default)
		)
		(layer "In5.Cu")
	)
	(gr_line
		(start 304.085498 -316.229492)
		(end 304.199798 -316.115192)
		(stroke
			(width 0.05715)
			(type default)
		)
		(layer "In5.Cu")
	)
	(gr_line
		(start 304.112676 -123.013216)
		(end 304.260758 -122.952002)
		(stroke
			(width 0.08255)
			(type default)
		)
		(layer "In5.Cu")
	)
	(gr_line
		(start 304.199798 -316.534292)
		(end 304.199798 -316.799722)
		(stroke
			(width 0.05715)
			(type default)
		)
		(layer "In5.Cu")
	)
	(gr_line
		(start 304.199798 -316.115192)
		(end 304.199798 -315.849762)
		(stroke
			(width 0.05715)
			(type default)
		)
		(layer "In5.Cu")
	)
	(gr_line
		(start 304.302414 -132.93852)
		(end 304.455322 -132.89153)
		(stroke
			(width 0.08255)
			(type default)
		)
		(layer "In5.Cu")
	)
	(gr_line
		(start 304.31613 -326.15505)
		(end 304.31613 -326.154796)
		(stroke
			(width 0.08255)
			(type default)
		)
		(layer "In5.Cu")
	)
	(gr_line
		(start 304.770028 -271.600168)
		(end 304.815748 -271.554448)
		(stroke
			(width 0.05715)
			(type default)
		)
		(layer "In5.Cu")
	)
	(gr_line
		(start 304.815748 -271.554448)
		(end 304.815748 -271.526)
		(stroke
			(width 0.05715)
			(type default)
		)
		(layer "In5.Cu")
	)
	(gr_line
		(start 304.815748 -271.398238)
		(end 304.815748 -271.39773)
		(stroke
			(width 0.08255)
			(type default)
		)
		(layer "In5.Cu")
	)
	(gr_line
		(start 304.815748 -271.397222)
		(end 304.815748 -271.396714)
		(stroke
			(width 0.08255)
			(type default)
		)
		(layer "In5.Cu")
	)
	(gr_line
		(start 304.89525 -133.12394)
		(end 304.94224 -133.276594)
		(stroke
			(width 0.08255)
			(type default)
		)
		(layer "In5.Cu")
	)
	(gr_line
		(start 304.94224 -133.276594)
		(end 305.380644 -133.508242)
		(stroke
			(width 0.08255)
			(type default)
		)
		(layer "In5.Cu")
	)
	(gr_line
		(start 304.946812 -326.456802)
		(end 304.31613 -326.15505)
		(stroke
			(width 0.08255)
			(type default)
		)
		(layer "In5.Cu")
	)
	(gr_line
		(start 305.149504 -273.365214)
		(end 305.035204 -273.479514)
		(stroke
			(width 0.05715)
			(type default)
		)
		(layer "In5.Cu")
	)
	(gr_line
		(start 305.149504 -273.099784)
		(end 305.149504 -273.365214)
		(stroke
			(width 0.05715)
			(type default)
		)
		(layer "In5.Cu")
	)
	(gr_line
		(start 305.380644 -133.508242)
		(end 305.533552 -133.461252)
		(stroke
			(width 0.08255)
			(type default)
		)
		(layer "In5.Cu")
	)
	(gr_line
		(start 306.02047 -324.543674)
		(end 305.388518 -324.24624)
		(stroke
			(width 0.08255)
			(type default)
		)
		(layer "In5.Cu")
	)
	(gr_line
		(start 307.084984 -134.677912)
		(end 307.092096 -134.801864)
		(stroke
			(width 0.08255)
			(type default)
		)
		(layer "In5.Cu")
	)
	(gr_line
		(start 307.092096 -134.801864)
		(end 307.461666 -135.132318)
		(stroke
			(width 0.08255)
			(type default)
		)
		(layer "In5.Cu")
	)
	(gr_line
		(start 307.461666 -135.132318)
		(end 307.585618 -135.125206)
		(stroke
			(width 0.08255)
			(type default)
		)
		(layer "In5.Cu")
	)
	(gr_line
		(start 307.517038 -322.405248)
		(end 307.383434 -322.454524)
		(stroke
			(width 0.08255)
			(type default)
		)
		(layer "In5.Cu")
	)
	(gr_line
		(start 307.547518 -126.049786)
		(end 307.871368 -126.425198)
		(stroke
			(width 0.08255)
			(type default)
		)
		(layer "In5.Cu")
	)
	(gr_line
		(start 307.556662 -125.925834)
		(end 307.547518 -126.049786)
		(stroke
			(width 0.08255)
			(type default)
		)
		(layer "In5.Cu")
	)
	(gr_line
		(start 307.584094 -123.735846)
		(end 307.601874 -123.858782)
		(stroke
			(width 0.08255)
			(type default)
		)
		(layer "In5.Cu")
	)
	(gr_line
		(start 307.601874 -123.858782)
		(end 307.999384 -124.154946)
		(stroke
			(width 0.08255)
			(type default)
		)
		(layer "In5.Cu")
	)
	(gr_line
		(start 307.649118 -158.81731)
		(end 307.649118 -158.817564)
		(stroke
			(width 0.08255)
			(type default)
		)
		(layer "In5.Cu")
	)
	(gr_line
		(start 307.871368 -126.425198)
		(end 307.995066 -126.434342)
		(stroke
			(width 0.08255)
			(type default)
		)
		(layer "In5.Cu")
	)
	(gr_line
		(start 307.8988 -323.003672)
		(end 307.264054 -322.711572)
		(stroke
			(width 0.08255)
			(type default)
		)
		(layer "In5.Cu")
	)
	(gr_line
		(start 307.956204 -135.456676)
		(end 307.963316 -135.580628)
		(stroke
			(width 0.08255)
			(type default)
		)
		(layer "In5.Cu")
	)
	(gr_line
		(start 307.963316 -135.580628)
		(end 308.332886 -135.911082)
		(stroke
			(width 0.08255)
			(type default)
		)
		(layer "In5.Cu")
	)
	(gr_line
		(start 307.967126 -322.612766)
		(end 307.517038 -322.405248)
		(stroke
			(width 0.08255)
			(type default)
		)
		(layer "In5.Cu")
	)
	(gr_line
		(start 307.999384 -124.154946)
		(end 308.12232 -124.137166)
		(stroke
			(width 0.08255)
			(type default)
		)
		(layer "In5.Cu")
	)
	(gr_line
		(start 308.016402 -322.746116)
		(end 307.967126 -322.612766)
		(stroke
			(width 0.08255)
			(type default)
		)
		(layer "In5.Cu")
	)
	(gr_line
		(start 308.310788 -126.934722)
		(end 308.634384 -127.310134)
		(stroke
			(width 0.08255)
			(type default)
		)
		(layer "In5.Cu")
	)
	(gr_line
		(start 308.319932 -126.81077)
		(end 308.310788 -126.934722)
		(stroke
			(width 0.08255)
			(type default)
		)
		(layer "In5.Cu")
	)
	(gr_line
		(start 308.332886 -135.911082)
		(end 308.456838 -135.90397)
		(stroke
			(width 0.08255)
			(type default)
		)
		(layer "In5.Cu")
	)
	(gr_line
		(start 308.448456 -334.106012)
		(end 308.44871 -334.106012)
		(stroke
			(width 0.08255)
			(type default)
		)
		(layer "In5.Cu")
	)
	(gr_line
		(start 308.520846 -124.434346)
		(end 308.538626 -124.557282)
		(stroke
			(width 0.08255)
			(type default)
		)
		(layer "In5.Cu")
	)
	(gr_line
		(start 308.538626 -124.557282)
		(end 308.935882 -124.8537)
		(stroke
			(width 0.08255)
			(type default)
		)
		(layer "In5.Cu")
	)
	(gr_line
		(start 308.634384 -127.310134)
		(end 308.758082 -127.319278)
		(stroke
			(width 0.08255)
			(type default)
		)
		(layer "In5.Cu")
	)
	(gr_line
		(start 308.935882 -124.8537)
		(end 309.059072 -124.835666)
		(stroke
			(width 0.08255)
			(type default)
		)
		(layer "In5.Cu")
	)
	(gr_line
		(start 309.074058 -127.819658)
		(end 309.397654 -128.19507)
		(stroke
			(width 0.08255)
			(type default)
		)
		(layer "In5.Cu")
	)
	(gr_line
		(start 309.083202 -127.69596)
		(end 309.074058 -127.819658)
		(stroke
			(width 0.08255)
			(type default)
		)
		(layer "In5.Cu")
	)
	(gr_line
		(start 309.397654 -128.19507)
		(end 309.521352 -128.204214)
		(stroke
			(width 0.08255)
			(type default)
		)
		(layer "In5.Cu")
	)
	(gr_line
		(start 309.457598 -125.132846)
		(end 309.475378 -125.255782)
		(stroke
			(width 0.08255)
			(type default)
		)
		(layer "In5.Cu")
	)
	(gr_line
		(start 309.475378 -125.255782)
		(end 309.872634 -125.5522)
		(stroke
			(width 0.08255)
			(type default)
		)
		(layer "In5.Cu")
	)
	(gr_line
		(start 309.872634 -125.5522)
		(end 309.99557 -125.534166)
		(stroke
			(width 0.08255)
			(type default)
		)
		(layer "In5.Cu")
	)
	(gr_line
		(start 310.39435 -125.831346)
		(end 310.41213 -125.954282)
		(stroke
			(width 0.08255)
			(type default)
		)
		(layer "In5.Cu")
	)
	(gr_line
		(start 310.41213 -125.954282)
		(end 310.809386 -126.2507)
		(stroke
			(width 0.08255)
			(type default)
		)
		(layer "In5.Cu")
	)
	(gr_line
		(start 310.809386 -126.2507)
		(end 310.932322 -126.232666)
		(stroke
			(width 0.08255)
			(type default)
		)
		(layer "In5.Cu")
	)
	(gr_line
		(start 311.183782 -271.599406)
		(end 311.183782 -271.570958)
		(stroke
			(width 0.05715)
			(type default)
		)
		(layer "In5.Cu")
	)
	(gr_line
		(start 311.229502 -271.645126)
		(end 311.183782 -271.599406)
		(stroke
			(width 0.05715)
			(type default)
		)
		(layer "In5.Cu")
	)
	(gr_line
		(start 311.799478 -275.949918)
		(end 311.799478 -275.684488)
		(stroke
			(width 0.05715)
			(type default)
		)
		(layer "In5.Cu")
	)
	(gr_line
		(start 311.799478 -275.684488)
		(end 311.685178 -275.570188)
		(stroke
			(width 0.05715)
			(type default)
		)
		(layer "In5.Cu")
	)
	(gr_line
		(start 312.065162 -288.299906)
		(end 311.799732 -288.299906)
		(stroke
			(width 0.05715)
			(type default)
		)
		(layer "In5.Cu")
	)
	(gr_line
		(start 312.065162 -284.499812)
		(end 311.799732 -284.499812)
		(stroke
			(width 0.05715)
			(type default)
		)
		(layer "In5.Cu")
	)
	(gr_line
		(start 312.179462 -288.185606)
		(end 312.065162 -288.299906)
		(stroke
			(width 0.05715)
			(type default)
		)
		(layer "In5.Cu")
	)
	(gr_line
		(start 312.179462 -284.385512)
		(end 312.065162 -284.499812)
		(stroke
			(width 0.05715)
			(type default)
		)
		(layer "In5.Cu")
	)
	(gr_line
		(start 313.965336 -287.349946)
		(end 313.699906 -287.349946)
		(stroke
			(width 0.05715)
			(type default)
		)
		(layer "In5.Cu")
	)
	(gr_line
		(start 314.079636 -287.235646)
		(end 313.965336 -287.349946)
		(stroke
			(width 0.05715)
			(type default)
		)
		(layer "In5.Cu")
	)
	(gr_line
		(start 316.096142 -287.683956)
		(end 316.050422 -287.729676)
		(stroke
			(width 0.05715)
			(type default)
		)
		(layer "In5.Cu")
	)
	(gr_line
		(start 316.096142 -283.883862)
		(end 316.050422 -283.929582)
		(stroke
			(width 0.05715)
			(type default)
		)
		(layer "In5.Cu")
	)
	(gr_line
		(start 316.121542 -286.733996)
		(end 316.075822 -286.779716)
		(stroke
			(width 0.05715)
			(type default)
		)
		(layer "In5.Cu")
	)
	(gr_line
		(start 316.12459 -287.683956)
		(end 316.096142 -287.683956)
		(stroke
			(width 0.05715)
			(type default)
		)
		(layer "In5.Cu")
	)
	(gr_line
		(start 316.12459 -283.883862)
		(end 316.096142 -283.883862)
		(stroke
			(width 0.05715)
			(type default)
		)
		(layer "In5.Cu")
	)
	(gr_line
		(start 316.14999 -286.733996)
		(end 316.121542 -286.733996)
		(stroke
			(width 0.05715)
			(type default)
		)
		(layer "In5.Cu")
	)
	(gr_line
		(start 324.156832 -377.374912)
		(end 324.217538 -377.246134)
		(stroke
			(width 0.08255)
			(type default)
		)
		(layer "In5.Cu")
	)
	(gr_line
		(start 324.32371 -377.84151)
		(end 324.156832 -377.374912)
		(stroke
			(width 0.08255)
			(type default)
		)
		(layer "In5.Cu")
	)
	(gr_line
		(start 324.376542 -372.971822)
		(end 324.376542 -372.971568)
		(stroke
			(width 0.08255)
			(type default)
		)
		(layer "In5.Cu")
	)
	(gr_line
		(start 324.452234 -377.902216)
		(end 324.32371 -377.84151)
		(stroke
			(width 0.08255)
			(type default)
		)
		(layer "In5.Cu")
	)
	(gr_line
		(start 324.453758 -377.902978)
		(end 324.45325 -377.902724)
		(stroke
			(width 0.08255)
			(type default)
		)
		(layer "In5.Cu")
	)
	(gr_line
		(start 324.559168 -378.498862)
		(end 324.619874 -378.370592)
		(stroke
			(width 0.08255)
			(type default)
		)
		(layer "In5.Cu")
	)
	(gr_line
		(start 324.719188 -377.807474)
		(end 324.48373 -377.149868)
		(stroke
			(width 0.08255)
			(type default)
		)
		(layer "In5.Cu")
	)
	(gr_line
		(start 324.719442 -377.808236)
		(end 324.719188 -377.807474)
		(stroke
			(width 0.08255)
			(type default)
		)
		(layer "In5.Cu")
	)
	(gr_line
		(start 324.726046 -378.96546)
		(end 324.559168 -378.498862)
		(stroke
			(width 0.08255)
			(type default)
		)
		(layer "In5.Cu")
	)
	(gr_line
		(start 324.85457 -379.026166)
		(end 324.726046 -378.96546)
		(stroke
			(width 0.08255)
			(type default)
		)
		(layer "In5.Cu")
	)
	(gr_line
		(start 324.856348 -379.02769)
		(end 324.856094 -379.026928)
		(stroke
			(width 0.08255)
			(type default)
		)
		(layer "In5.Cu")
	)
	(gr_line
		(start 325.121778 -378.932186)
		(end 324.886066 -378.274072)
		(stroke
			(width 0.08255)
			(type default)
		)
		(layer "In5.Cu")
	)
	(gr_line
		(start 325.121778 -378.932186)
		(end 325.122032 -378.932186)
		(stroke
			(width 0.08255)
			(type default)
		)
		(layer "In5.Cu")
	)
	(gr_line
		(start 325.122286 -378.932948)
		(end 325.122032 -378.932186)
		(stroke
			(width 0.08255)
			(type default)
		)
		(layer "In5.Cu")
	)
	(gr_line
		(start 327.309988 -376.705368)
		(end 327.309734 -376.704098)
		(stroke
			(width 0.08255)
			(type default)
		)
		(layer "In5.Cu")
	)
	(gr_line
		(start 327.552812 -378.35586)
		(end 327.621646 -378.252482)
		(stroke
			(width 0.08255)
			(type default)
		)
		(layer "In5.Cu")
	)
	(gr_line
		(start 327.581006 -376.622056)
		(end 327.580752 -376.620278)
		(stroke
			(width 0.08255)
			(type default)
		)
		(layer "In5.Cu")
	)
	(gr_line
		(start 327.65111 -378.841508)
		(end 327.552812 -378.35586)
		(stroke
			(width 0.08255)
			(type default)
		)
		(layer "In5.Cu")
	)
	(gr_line
		(start 327.754488 -378.910088)
		(end 327.65111 -378.841508)
		(stroke
			(width 0.08255)
			(type default)
		)
		(layer "In5.Cu")
	)
	(gr_line
		(start 327.755758 -378.911104)
		(end 327.756012 -378.911104)
		(stroke
			(width 0.08255)
			(type default)
		)
		(layer "In5.Cu")
	)
	(gr_line
		(start 327.784206 -379.501146)
		(end 327.85304 -379.397514)
		(stroke
			(width 0.08255)
			(type default)
		)
		(layer "In5.Cu")
	)
	(gr_line
		(start 327.882504 -379.987048)
		(end 327.784206 -379.501146)
		(stroke
			(width 0.08255)
			(type default)
		)
		(layer "In5.Cu")
	)
	(gr_line
		(start 327.986136 -380.055374)
		(end 327.882504 -379.987048)
		(stroke
			(width 0.08255)
			(type default)
		)
		(layer "In5.Cu")
	)
	(gr_line
		(start 328.032364 -378.855224)
		(end 327.899014 -378.195332)
		(stroke
			(width 0.08255)
			(type default)
		)
		(layer "In5.Cu")
	)
	(gr_line
		(start 328.240644 -379.885448)
		(end 328.130408 -379.340618)
		(stroke
			(width 0.08255)
			(type default)
		)
		(layer "In5.Cu")
	)
	(gr_line
		(start 328.240644 -379.885448)
		(end 328.240644 -379.885702)
		(stroke
			(width 0.08255)
			(type default)
		)
		(layer "In5.Cu")
	)
	(gr_line
		(start 328.263758 -380.00051)
		(end 328.240644 -379.885702)
		(stroke
			(width 0.08255)
			(type default)
		)
		(layer "In5.Cu")
	)
	(gr_line
		(start 335.890108 -370.872258)
		(end 336.017108 -370.999258)
		(stroke
			(width 0.08255)
			(type default)
		)
		(layer "In5.Cu")
	)
	(gr_line
		(start 335.890108 -370.489988)
		(end 335.890108 -370.872258)
		(stroke
			(width 0.08255)
			(type default)
		)
		(layer "In5.Cu")
	)
	(gr_line
		(start 336.135726 -360.459274)
		(end 336.218022 -360.366056)
		(stroke
			(width 0.08255)
			(type default)
		)
		(layer "In5.Cu")
	)
	(gr_line
		(start 336.164936 -360.953812)
		(end 336.135726 -360.459274)
		(stroke
			(width 0.08255)
			(type default)
		)
		(layer "In5.Cu")
	)
	(gr_line
		(start 336.204814 -361.625642)
		(end 336.287364 -361.532678)
		(stroke
			(width 0.08255)
			(type default)
		)
		(layer "In5.Cu")
	)
	(gr_line
		(start 336.234278 -362.120434)
		(end 336.204814 -361.625642)
		(stroke
			(width 0.08255)
			(type default)
		)
		(layer "In5.Cu")
	)
	(gr_line
		(start 336.2579 -361.036362)
		(end 336.164936 -360.953812)
		(stroke
			(width 0.08255)
			(type default)
		)
		(layer "In5.Cu")
	)
	(gr_line
		(start 336.327242 -362.202476)
		(end 336.234278 -362.120434)
		(stroke
			(width 0.08255)
			(type default)
		)
		(layer "In5.Cu")
	)
	(gr_line
		(start 336.404458 -364.988856)
		(end 336.487008 -364.895892)
		(stroke
			(width 0.08255)
			(type default)
		)
		(layer "In5.Cu")
	)
	(gr_line
		(start 336.433922 -365.483394)
		(end 336.404458 -364.988856)
		(stroke
			(width 0.08255)
			(type default)
		)
		(layer "In5.Cu")
	)
	(gr_line
		(start 336.4738 -366.155224)
		(end 336.55635 -366.06226)
		(stroke
			(width 0.08255)
			(type default)
		)
		(layer "In5.Cu")
	)
	(gr_line
		(start 336.503264 -366.649762)
		(end 336.4738 -366.155224)
		(stroke
			(width 0.08255)
			(type default)
		)
		(layer "In5.Cu")
	)
	(gr_line
		(start 336.526886 -365.565944)
		(end 336.433922 -365.483394)
		(stroke
			(width 0.08255)
			(type default)
		)
		(layer "In5.Cu")
	)
	(gr_line
		(start 336.543142 -367.321592)
		(end 336.625692 -367.228882)
		(stroke
			(width 0.08255)
			(type default)
		)
		(layer "In5.Cu")
	)
	(gr_line
		(start 336.572606 -367.816384)
		(end 336.543142 -367.321592)
		(stroke
			(width 0.08255)
			(type default)
		)
		(layer "In5.Cu")
	)
	(gr_line
		(start 336.596228 -366.732058)
		(end 336.503264 -366.649762)
		(stroke
			(width 0.08255)
			(type default)
		)
		(layer "In5.Cu")
	)
	(gr_line
		(start 336.603086 -366.828832)
		(end 336.597498 -366.733328)
		(stroke
			(width 0.08255)
			(type default)
		)
		(layer "In5.Cu")
	)
	(gr_line
		(start 336.665316 -367.898426)
		(end 336.572606 -367.816384)
		(stroke
			(width 0.08255)
			(type default)
		)
		(layer "In5.Cu")
	)
	(gr_line
		(start 336.666586 -367.899696)
		(end 336.66684 -367.899696)
		(stroke
			(width 0.08255)
			(type default)
		)
		(layer "In5.Cu")
	)
	(gr_line
		(start 337.337654 -392.42873)
		(end 337.31581 -392.32459)
		(stroke
			(width 0.08255)
			(type default)
		)
		(layer "In5.Cu")
	)
	(gr_line
		(start 337.752944 -392.699494)
		(end 337.337654 -392.42873)
		(stroke
			(width 0.08255)
			(type default)
		)
		(layer "In5.Cu")
	)
	(gr_line
		(start 337.857084 -392.677396)
		(end 337.752944 -392.699494)
		(stroke
			(width 0.08255)
			(type default)
		)
		(layer "In5.Cu")
	)
	(gr_line
		(start 338.012532 -392.440668)
		(end 337.469734 -392.086846)
		(stroke
			(width 0.08255)
			(type default)
		)
		(layer "In5.Cu")
	)
	(gr_line
		(start 338.235544 -391.66546)
		(end 338.203794 -391.564114)
		(stroke
			(width 0.08255)
			(type default)
		)
		(layer "In5.Cu")
	)
	(gr_line
		(start 338.295234 -393.053062)
		(end 338.27339 -392.948922)
		(stroke
			(width 0.08255)
			(type default)
		)
		(layer "In5.Cu")
	)
	(gr_line
		(start 338.675218 -391.894822)
		(end 338.235544 -391.66546)
		(stroke
			(width 0.08255)
			(type default)
		)
		(layer "In5.Cu")
	)
	(gr_line
		(start 338.710524 -393.323826)
		(end 338.295234 -393.053062)
		(stroke
			(width 0.08255)
			(type default)
		)
		(layer "In5.Cu")
	)
	(gr_line
		(start 338.776564 -391.862818)
		(end 338.675218 -391.894822)
		(stroke
			(width 0.08255)
			(type default)
		)
		(layer "In5.Cu")
	)
	(gr_line
		(start 338.81441 -393.301728)
		(end 338.710524 -393.323826)
		(stroke
			(width 0.08255)
			(type default)
		)
		(layer "In5.Cu")
	)
	(gr_line
		(start 338.90839 -391.61212)
		(end 338.333842 -391.312654)
		(stroke
			(width 0.08255)
			(type default)
		)
		(layer "In5.Cu")
	)
	(gr_line
		(start 338.970112 -393.065)
		(end 338.427314 -392.711178)
		(stroke
			(width 0.08255)
			(type default)
		)
		(layer "In5.Cu")
	)
	(gr_line
		(start 339.252814 -393.677394)
		(end 339.23097 -393.573254)
		(stroke
			(width 0.08255)
			(type default)
		)
		(layer "In5.Cu")
	)
	(gr_line
		(start 339.668104 -393.948158)
		(end 339.252814 -393.677394)
		(stroke
			(width 0.08255)
			(type default)
		)
		(layer "In5.Cu")
	)
	(gr_line
		(start 339.77199 -393.92606)
		(end 339.668104 -393.948158)
		(stroke
			(width 0.08255)
			(type default)
		)
		(layer "In5.Cu")
	)
	(gr_line
		(start 339.927692 -393.689586)
		(end 339.384894 -393.33551)
		(stroke
			(width 0.08255)
			(type default)
		)
		(layer "In5.Cu")
	)
	(gr_line
		(start 340.29015 -401.690078)
		(end 340.29015 -401.308062)
		(stroke
			(width 0.08255)
			(type default)
		)
		(layer "In5.Cu")
	)
	(gr_line
		(start 340.29015 -401.308062)
		(end 340.41715 -401.181062)
		(stroke
			(width 0.08255)
			(type default)
		)
		(layer "In5.Cu")
	)
	(gr_line
		(start 340.29015 -400.772122)
		(end 340.41715 -400.899122)
		(stroke
			(width 0.08255)
			(type default)
		)
		(layer "In5.Cu")
	)
	(gr_line
		(start 340.29015 -400.390106)
		(end 340.29015 -400.772122)
		(stroke
			(width 0.08255)
			(type default)
		)
		(layer "In5.Cu")
	)
	(gr_line
		(start 340.29015 -370.872258)
		(end 340.41715 -370.999258)
		(stroke
			(width 0.08255)
			(type default)
		)
		(layer "In5.Cu")
	)
	(gr_line
		(start 340.29015 -370.489988)
		(end 340.29015 -370.872258)
		(stroke
			(width 0.08255)
			(type default)
		)
		(layer "In5.Cu")
	)
	(gr_line
		(start 340.524846 -393.083288)
		(end 340.501224 -392.961622)
		(stroke
			(width 0.08255)
			(type default)
		)
		(layer "In5.Cu")
	)
	(gr_line
		(start 340.711536 -391.730738)
		(end 340.66734 -391.59561)
		(stroke
			(width 0.08255)
			(type default)
		)
		(layer "In5.Cu")
	)
	(gr_line
		(start 340.93531 -393.361164)
		(end 340.524846 -393.083288)
		(stroke
			(width 0.08255)
			(type default)
		)
		(layer "In5.Cu")
	)
	(gr_line
		(start 341.05723 -393.337796)
		(end 340.93531 -393.361164)
		(stroke
			(width 0.08255)
			(type default)
		)
		(layer "In5.Cu")
	)
	(gr_line
		(start 341.153496 -391.954766)
		(end 340.711536 -391.730738)
		(stroke
			(width 0.08255)
			(type default)
		)
		(layer "In5.Cu")
	)
	(gr_line
		(start 341.216742 -393.103862)
		(end 340.658958 -392.726164)
		(stroke
			(width 0.08255)
			(type default)
		)
		(layer "In5.Cu")
	)
	(gr_line
		(start 341.288624 -391.91057)
		(end 341.153496 -391.954766)
		(stroke
			(width 0.08255)
			(type default)
		)
		(layer "In5.Cu")
	)
	(gr_line
		(start 341.417656 -391.658348)
		(end 340.79434 -391.342626)
		(stroke
			(width 0.08255)
			(type default)
		)
		(layer "In5.Cu")
	)
	(gr_line
		(start 341.431626 -367.875312)
		(end 341.474806 -367.38179)
		(stroke
			(width 0.08255)
			(type default)
		)
		(layer "In5.Cu")
	)
	(gr_line
		(start 341.474806 -367.38179)
		(end 341.570056 -367.302288)
		(stroke
			(width 0.08255)
			(type default)
		)
		(layer "In5.Cu")
	)
	(gr_line
		(start 341.49665 -393.761468)
		(end 341.468964 -393.616434)
		(stroke
			(width 0.08255)
			(type default)
		)
		(layer "In5.Cu")
	)
	(gr_line
		(start 341.511382 -367.970562)
		(end 341.431626 -367.875312)
		(stroke
			(width 0.08255)
			(type default)
		)
		(layer "In5.Cu")
	)
	(gr_line
		(start 341.533734 -366.711484)
		(end 341.577168 -366.217708)
		(stroke
			(width 0.08255)
			(type default)
		)
		(layer "In5.Cu")
	)
	(gr_line
		(start 341.57158 -367.301018)
		(end 341.571326 -367.301018)
		(stroke
			(width 0.08255)
			(type default)
		)
		(layer "In5.Cu")
	)
	(gr_line
		(start 341.577168 -366.217708)
		(end 341.672418 -366.138206)
		(stroke
			(width 0.08255)
			(type default)
		)
		(layer "In5.Cu")
	)
	(gr_line
		(start 341.61349 -366.806734)
		(end 341.533734 -366.711484)
		(stroke
			(width 0.08255)
			(type default)
		)
		(layer "In5.Cu")
	)
	(gr_line
		(start 341.636096 -365.547402)
		(end 341.67953 -365.053626)
		(stroke
			(width 0.08255)
			(type default)
		)
		(layer "In5.Cu")
	)
	(gr_line
		(start 341.67953 -365.053626)
		(end 341.774526 -364.974124)
		(stroke
			(width 0.08255)
			(type default)
		)
		(layer "In5.Cu")
	)
	(gr_line
		(start 341.715852 -365.642398)
		(end 341.636096 -365.547402)
		(stroke
			(width 0.08255)
			(type default)
		)
		(layer "In5.Cu")
	)
	(gr_line
		(start 341.77605 -364.972854)
		(end 341.775796 -364.972854)
		(stroke
			(width 0.08255)
			(type default)
		)
		(layer "In5.Cu")
	)
	(gr_line
		(start 341.879682 -394.020802)
		(end 341.49665 -393.761468)
		(stroke
			(width 0.08255)
			(type default)
		)
		(layer "In5.Cu")
	)
	(gr_line
		(start 341.885778 -362.702348)
		(end 341.929212 -362.208826)
		(stroke
			(width 0.08255)
			(type default)
		)
		(layer "In5.Cu")
	)
	(gr_line
		(start 341.929212 -362.208826)
		(end 342.024208 -362.129324)
		(stroke
			(width 0.08255)
			(type default)
		)
		(layer "In5.Cu")
	)
	(gr_line
		(start 341.965534 -362.797852)
		(end 341.885778 -362.702348)
		(stroke
			(width 0.08255)
			(type default)
		)
		(layer "In5.Cu")
	)
	(gr_line
		(start 341.987886 -361.53852)
		(end 342.03132 -361.044744)
		(stroke
			(width 0.08255)
			(type default)
		)
		(layer "In5.Cu")
	)
	(gr_line
		(start 342.024716 -393.992608)
		(end 341.879682 -394.020802)
		(stroke
			(width 0.08255)
			(type default)
		)
		(layer "In5.Cu")
	)
	(gr_line
		(start 342.025732 -362.128054)
		(end 342.025478 -362.128054)
		(stroke
			(width 0.08255)
			(type default)
		)
		(layer "In5.Cu")
	)
	(gr_line
		(start 342.03132 -361.044744)
		(end 342.12657 -360.964988)
		(stroke
			(width 0.08255)
			(type default)
		)
		(layer "In5.Cu")
	)
	(gr_line
		(start 342.067896 -361.63377)
		(end 341.987886 -361.53852)
		(stroke
			(width 0.08255)
			(type default)
		)
		(layer "In5.Cu")
	)
	(gr_line
		(start 342.184482 -393.758674)
		(end 341.626698 -393.38123)
		(stroke
			(width 0.08255)
			(type default)
		)
		(layer "In5.Cu")
	)
	(gr_line
		(start 342.490044 -402.790152)
		(end 342.490044 -402.408136)
		(stroke
			(width 0.08255)
			(type default)
		)
		(layer "In5.Cu")
	)
	(gr_line
		(start 342.490044 -402.408136)
		(end 342.617044 -402.281136)
		(stroke
			(width 0.08255)
			(type default)
		)
		(layer "In5.Cu")
	)
	(gr_line
		(start 342.490044 -401.872196)
		(end 342.617044 -401.999196)
		(stroke
			(width 0.08255)
			(type default)
		)
		(layer "In5.Cu")
	)
	(gr_line
		(start 342.490044 -401.49018)
		(end 342.490044 -401.872196)
		(stroke
			(width 0.08255)
			(type default)
		)
		(layer "In5.Cu")
	)
	(gr_line
		(start 342.86825 -392.997182)
		(end 342.844628 -392.875262)
		(stroke
			(width 0.08255)
			(type default)
		)
		(layer "In5.Cu")
	)
	(gr_line
		(start 342.9127 -391.248646)
		(end 342.903302 -391.248646)
		(stroke
			(width 0.08255)
			(type default)
		)
		(layer "In5.Cu")
	)
	(gr_line
		(start 342.921082 -391.257028)
		(end 342.9127 -391.248646)
		(stroke
			(width 0.08255)
			(type default)
		)
		(layer "In5.Cu")
	)
	(gr_line
		(start 342.921082 -391.257028)
		(end 342.921336 -391.257028)
		(stroke
			(width 0.08255)
			(type default)
		)
		(layer "In5.Cu")
	)
	(gr_line
		(start 342.937846 -391.26795)
		(end 342.921336 -391.257028)
		(stroke
			(width 0.08255)
			(type default)
		)
		(layer "In5.Cu")
	)
	(gr_line
		(start 343.27846 -393.275312)
		(end 342.86825 -392.997182)
		(stroke
			(width 0.08255)
			(type default)
		)
		(layer "In5.Cu")
	)
	(gr_line
		(start 343.400634 -393.251944)
		(end 343.27846 -393.275312)
		(stroke
			(width 0.08255)
			(type default)
		)
		(layer "In5.Cu")
	)
	(gr_line
		(start 343.560146 -393.01801)
		(end 343.002616 -392.640312)
		(stroke
			(width 0.08255)
			(type default)
		)
		(layer "In5.Cu")
	)
	(gr_line
		(start 343.835482 -393.652756)
		(end 343.812114 -393.530836)
		(stroke
			(width 0.08255)
			(type default)
		)
		(layer "In5.Cu")
	)
	(gr_line
		(start 344.038936 -392.465814)
		(end 344.010996 -392.326368)
		(stroke
			(width 0.08255)
			(type default)
		)
		(layer "In5.Cu")
	)
	(gr_line
		(start 344.245692 -393.930886)
		(end 343.835482 -393.652756)
		(stroke
			(width 0.08255)
			(type default)
		)
		(layer "In5.Cu")
	)
	(gr_line
		(start 344.367866 -393.907264)
		(end 344.245692 -393.930886)
		(stroke
			(width 0.08255)
			(type default)
		)
		(layer "In5.Cu")
	)
	(gr_line
		(start 344.450924 -392.741404)
		(end 344.038936 -392.465814)
		(stroke
			(width 0.08255)
			(type default)
		)
		(layer "In5.Cu")
	)
	(gr_line
		(start 344.527378 -393.67333)
		(end 343.970102 -393.295632)
		(stroke
			(width 0.08255)
			(type default)
		)
		(layer "In5.Cu")
	)
	(gr_line
		(start 344.590116 -392.713718)
		(end 344.450924 -392.741404)
		(stroke
			(width 0.08255)
			(type default)
		)
		(layer "In5.Cu")
	)
	(gr_line
		(start 344.689938 -401.690078)
		(end 344.689938 -401.308062)
		(stroke
			(width 0.08255)
			(type default)
		)
		(layer "In5.Cu")
	)
	(gr_line
		(start 344.689938 -401.308062)
		(end 344.816938 -401.181062)
		(stroke
			(width 0.08255)
			(type default)
		)
		(layer "In5.Cu")
	)
	(gr_line
		(start 344.689938 -400.772122)
		(end 344.816938 -400.899122)
		(stroke
			(width 0.08255)
			(type default)
		)
		(layer "In5.Cu")
	)
	(gr_line
		(start 344.689938 -400.390106)
		(end 344.689938 -400.772122)
		(stroke
			(width 0.08255)
			(type default)
		)
		(layer "In5.Cu")
	)
	(gr_line
		(start 344.689938 -371.790214)
		(end 344.689938 -371.408198)
		(stroke
			(width 0.08255)
			(type default)
		)
		(layer "In5.Cu")
	)
	(gr_line
		(start 344.689938 -371.408198)
		(end 344.816938 -371.281198)
		(stroke
			(width 0.08255)
			(type default)
		)
		(layer "In5.Cu")
	)
	(gr_line
		(start 344.689938 -370.872258)
		(end 344.816938 -370.999258)
		(stroke
			(width 0.08255)
			(type default)
		)
		(layer "In5.Cu")
	)
	(gr_line
		(start 344.689938 -370.489988)
		(end 344.689938 -370.872258)
		(stroke
			(width 0.08255)
			(type default)
		)
		(layer "In5.Cu")
	)
	(gr_line
		(start 344.748358 -392.479022)
		(end 344.16746 -392.090402)
		(stroke
			(width 0.08255)
			(type default)
		)
		(layer "In5.Cu")
	)
	(gr_line
		(start 345.003374 -392.9888)
		(end 345.003374 -392.988546)
		(stroke
			(width 0.08255)
			(type default)
		)
		(layer "In5.Cu")
	)
	(gr_line
		(start 345.031314 -393.129516)
		(end 345.003628 -392.990324)
		(stroke
			(width 0.08255)
			(type default)
		)
		(layer "In5.Cu")
	)
	(gr_line
		(start 345.443302 -393.405106)
		(end 345.031314 -393.129516)
		(stroke
			(width 0.08255)
			(type default)
		)
		(layer "In5.Cu")
	)
	(gr_line
		(start 345.582748 -393.37742)
		(end 345.443302 -393.405106)
		(stroke
			(width 0.08255)
			(type default)
		)
		(layer "In5.Cu")
	)
	(gr_line
		(start 345.614244 -368.497358)
		(end 345.650312 -368.003074)
		(stroke
			(width 0.08255)
			(type default)
		)
		(layer "In5.Cu")
	)
	(gr_line
		(start 345.650312 -368.003074)
		(end 345.744292 -367.922302)
		(stroke
			(width 0.08255)
			(type default)
		)
		(layer "In5.Cu")
	)
	(gr_line
		(start 345.69527 -368.591592)
		(end 345.614244 -368.497358)
		(stroke
			(width 0.08255)
			(type default)
		)
		(layer "In5.Cu")
	)
	(gr_line
		(start 345.699334 -367.332006)
		(end 345.735402 -366.837722)
		(stroke
			(width 0.08255)
			(type default)
		)
		(layer "In5.Cu")
	)
	(gr_line
		(start 345.735402 -366.837722)
		(end 345.829382 -366.75695)
		(stroke
			(width 0.08255)
			(type default)
		)
		(layer "In5.Cu")
	)
	(gr_line
		(start 345.74099 -393.142724)
		(end 345.160092 -392.754358)
		(stroke
			(width 0.08255)
			(type default)
		)
		(layer "In5.Cu")
	)
	(gr_line
		(start 345.745562 -367.921032)
		(end 345.748102 -367.885472)
		(stroke
			(width 0.08255)
			(type default)
		)
		(layer "In5.Cu")
	)
	(gr_line
		(start 345.78036 -367.42624)
		(end 345.699334 -367.332006)
		(stroke
			(width 0.08255)
			(type default)
		)
		(layer "In5.Cu")
	)
	(gr_line
		(start 345.78417 -366.166654)
		(end 345.820238 -365.67237)
		(stroke
			(width 0.08255)
			(type default)
		)
		(layer "In5.Cu")
	)
	(gr_line
		(start 345.820238 -365.67237)
		(end 345.914472 -365.591344)
		(stroke
			(width 0.08255)
			(type default)
		)
		(layer "In5.Cu")
	)
	(gr_line
		(start 345.830398 -366.75568)
		(end 345.830652 -366.75568)
		(stroke
			(width 0.08255)
			(type default)
		)
		(layer "In5.Cu")
	)
	(gr_line
		(start 345.86545 -366.260634)
		(end 345.78417 -366.166654)
		(stroke
			(width 0.08255)
			(type default)
		)
		(layer "In5.Cu")
	)
	(gr_line
		(start 345.977718 -368.613182)
		(end 346.02674 -367.941352)
		(stroke
			(width 0.08255)
			(type default)
		)
		(layer "In5.Cu")
	)
	(gr_line
		(start 346.02674 -367.941352)
		(end 346.02928 -367.905792)
		(stroke
			(width 0.08255)
			(type default)
		)
		(layer "In5.Cu")
	)
	(gr_line
		(start 346.04071 -362.651294)
		(end 346.076778 -362.15701)
		(stroke
			(width 0.08255)
			(type default)
		)
		(layer "In5.Cu")
	)
	(gr_line
		(start 346.062808 -367.447576)
		(end 346.11183 -366.776254)
		(stroke
			(width 0.08255)
			(type default)
		)
		(layer "In5.Cu")
	)
	(gr_line
		(start 346.076778 -362.15701)
		(end 346.171012 -362.075984)
		(stroke
			(width 0.08255)
			(type default)
		)
		(layer "In5.Cu")
	)
	(gr_line
		(start 346.12199 -362.745528)
		(end 346.04071 -362.651294)
		(stroke
			(width 0.08255)
			(type default)
		)
		(layer "In5.Cu")
	)
	(gr_line
		(start 346.13088 -361.491784)
		(end 346.167964 -360.986832)
		(stroke
			(width 0.08255)
			(type default)
		)
		(layer "In5.Cu")
	)
	(gr_line
		(start 346.147898 -366.282478)
		(end 346.19692 -365.610902)
		(stroke
			(width 0.08255)
			(type default)
		)
		(layer "In5.Cu")
	)
	(gr_line
		(start 346.167964 -360.986832)
		(end 346.256102 -360.910886)
		(stroke
			(width 0.08255)
			(type default)
		)
		(layer "In5.Cu")
	)
	(gr_line
		(start 346.20708 -361.580176)
		(end 346.13088 -361.491784)
		(stroke
			(width 0.08255)
			(type default)
		)
		(layer "In5.Cu")
	)
	(gr_line
		(start 346.404438 -362.767118)
		(end 346.45346 -362.095288)
		(stroke
			(width 0.08255)
			(type default)
		)
		(layer "In5.Cu")
	)
	(gr_line
		(start 346.489528 -361.601512)
		(end 346.53855 -360.93019)
		(stroke
			(width 0.08255)
			(type default)
		)
		(layer "In5.Cu")
	)
	(gr_line
		(start 346.513404 -394.282676)
		(end 346.515182 -394.158724)
		(stroke
			(width 0.08255)
			(type default)
		)
		(layer "In5.Cu")
	)
	(gr_line
		(start 346.859606 -394.637514)
		(end 346.513404 -394.282676)
		(stroke
			(width 0.08255)
			(type default)
		)
		(layer "In5.Cu")
	)
	(gr_line
		(start 346.890086 -402.790152)
		(end 346.890086 -402.408136)
		(stroke
			(width 0.08255)
			(type default)
		)
		(layer "In5.Cu")
	)
	(gr_line
		(start 346.890086 -402.408136)
		(end 347.017086 -402.281136)
		(stroke
			(width 0.08255)
			(type default)
		)
		(layer "In5.Cu")
	)
	(gr_line
		(start 346.890086 -401.872196)
		(end 347.017086 -401.999196)
		(stroke
			(width 0.08255)
			(type default)
		)
		(layer "In5.Cu")
	)
	(gr_line
		(start 346.890086 -401.49018)
		(end 346.890086 -401.872196)
		(stroke
			(width 0.08255)
			(type default)
		)
		(layer "In5.Cu")
	)
	(gr_line
		(start 346.983812 -394.639292)
		(end 346.859606 -394.637514)
		(stroke
			(width 0.08255)
			(type default)
		)
		(layer "In5.Cu")
	)
	(gr_line
		(start 347.187266 -394.442188)
		(end 346.717112 -393.960096)
		(stroke
			(width 0.08255)
			(type default)
		)
		(layer "In5.Cu")
	)
	(gr_line
		(start 372.706392 -363.798612)
		(end 372.727474 -363.67466)
		(stroke
			(width 0.08255)
			(type default)
		)
		(layer "In5.Cu")
	)
	(gr_line
		(start 373.020844 -364.243366)
		(end 372.706392 -363.798612)
		(stroke
			(width 0.08255)
			(type default)
		)
		(layer "In5.Cu")
	)
	(gr_line
		(start 373.144288 -364.264702)
		(end 373.020844 -364.243366)
		(stroke
			(width 0.08255)
			(type default)
		)
		(layer "In5.Cu")
	)
	(gr_line
		(start 373.407432 -364.810802)
		(end 373.431308 -364.670594)
		(stroke
			(width 0.08255)
			(type default)
		)
		(layer "In5.Cu")
	)
	(gr_line
		(start 373.708168 -365.236252)
		(end 373.407432 -364.810802)
		(stroke
			(width 0.08255)
			(type default)
		)
		(layer "In5.Cu")
	)
	(gr_line
		(start 373.848122 -365.260382)
		(end 373.708168 -365.236252)
		(stroke
			(width 0.08255)
			(type default)
		)
		(layer "In5.Cu")
	)
	(gr_line
		(start 374.113298 -365.793782)
		(end 374.135142 -365.666528)
		(stroke
			(width 0.08255)
			(type default)
		)
		(layer "In5.Cu")
	)
	(gr_line
		(start 374.424702 -366.234218)
		(end 374.113298 -365.793782)
		(stroke
			(width 0.08255)
			(type default)
		)
		(layer "In5.Cu")
	)
	(gr_line
		(start 374.551702 -366.256062)
		(end 374.424702 -366.234218)
		(stroke
			(width 0.08255)
			(type default)
		)
		(layer "In5.Cu")
	)
	(gr_line
		(start 374.585738 -366.302036)
		(end 374.55348 -366.256316)
		(stroke
			(width 0.08255)
			(type default)
		)
		(layer "In5.Cu")
	)
	(gr_line
		(start 374.814338 -366.805718)
		(end 374.838722 -366.662208)
		(stroke
			(width 0.08255)
			(type default)
		)
		(layer "In5.Cu")
	)
	(gr_line
		(start 375.112534 -367.227358)
		(end 374.814338 -366.805718)
		(stroke
			(width 0.08255)
			(type default)
		)
		(layer "In5.Cu")
	)
	(gr_line
		(start 375.255536 -367.251996)
		(end 375.112534 -367.227358)
		(stroke
			(width 0.08255)
			(type default)
		)
		(layer "In5.Cu")
	)
	(gr_line
		(start 375.489978 -374.729756)
		(end 375.663206 -374.902984)
		(stroke
			(width 0.08255)
			(type default)
		)
		(layer "In5.Cu")
	)
	(gr_line
		(start 375.489978 -374.390158)
		(end 375.489978 -374.729756)
		(stroke
			(width 0.08255)
			(type default)
		)
		(layer "In5.Cu")
	)
	(gr_line
		(start 391.449814 -150.576026)
		(end 391.44956 -150.576026)
		(stroke
			(width 0.08255)
			(type default)
		)
		(layer "In5.Cu")
	)
	(gr_line
		(start 391.498836 -151.297386)
		(end 391.604246 -151.17699)
		(stroke
			(width 0.08255)
			(type default)
		)
		(layer "In5.Cu")
	)
	(gr_line
		(start 391.57148 -150.682452)
		(end 391.451084 -150.577296)
		(stroke
			(width 0.08255)
			(type default)
		)
		(layer "In5.Cu")
	)
	(gr_line
		(start 391.579608 -152.5143)
		(end 391.675112 -152.40508)
		(stroke
			(width 0.08255)
			(type default)
		)
		(layer "In5.Cu")
	)
	(gr_line
		(start 391.604246 -151.17699)
		(end 391.57148 -150.682452)
		(stroke
			(width 0.08255)
			(type default)
		)
		(layer "In5.Cu")
	)
	(gr_line
		(start 391.640822 -151.889206)
		(end 391.531856 -151.793702)
		(stroke
			(width 0.08255)
			(type default)
		)
		(layer "In5.Cu")
	)
	(gr_line
		(start 391.656824 -153.68016)
		(end 391.738866 -153.586688)
		(stroke
			(width 0.08255)
			(type default)
		)
		(layer "In5.Cu")
	)
	(gr_line
		(start 391.675112 -152.40508)
		(end 391.640822 -151.889206)
		(stroke
			(width 0.08255)
			(type default)
		)
		(layer "In5.Cu")
	)
	(gr_line
		(start 391.7061 -153.09215)
		(end 391.612374 -153.010362)
		(stroke
			(width 0.08255)
			(type default)
		)
		(layer "In5.Cu")
	)
	(gr_line
		(start 391.734294 -154.846274)
		(end 391.803636 -154.767026)
		(stroke
			(width 0.08255)
			(type default)
		)
		(layer "In5.Cu")
	)
	(gr_line
		(start 391.738866 -153.586688)
		(end 391.7061 -153.09215)
		(stroke
			(width 0.08255)
			(type default)
		)
		(layer "In5.Cu")
	)
	(gr_line
		(start 391.769092 -154.245564)
		(end 391.689844 -154.176222)
		(stroke
			(width 0.08255)
			(type default)
		)
		(layer "In5.Cu")
	)
	(gr_line
		(start 391.803636 -154.767026)
		(end 391.769092 -154.245564)
		(stroke
			(width 0.08255)
			(type default)
		)
		(layer "In5.Cu")
	)
	(gr_line
		(start 397.725392 -142.648178)
		(end 397.725392 -142.648432)
		(stroke
			(width 0.08255)
			(type default)
		)
		(layer "In5.Cu")
	)
	(gr_line
		(start 397.72717 -142.647416)
		(end 397.874998 -142.586202)
		(stroke
			(width 0.08255)
			(type default)
		)
		(layer "In5.Cu")
	)
	(gr_line
		(start 397.874998 -142.586202)
		(end 398.064482 -142.128494)
		(stroke
			(width 0.08255)
			(type default)
		)
		(layer "In5.Cu")
	)
	(gr_line
		(start 398.064482 -142.128494)
		(end 398.003268 -141.980666)
		(stroke
			(width 0.08255)
			(type default)
		)
		(layer "In5.Cu")
	)
	(gr_line
		(start 398.322546 -140.713206)
		(end 398.435576 -140.600176)
		(stroke
			(width 0.08255)
			(type default)
		)
		(layer "In5.Cu")
	)
	(gr_line
		(start 398.322546 -139.494006)
		(end 398.435576 -139.380976)
		(stroke
			(width 0.08255)
			(type default)
		)
		(layer "In5.Cu")
	)
	(gr_line
		(start 398.435576 -140.600176)
		(end 398.435576 -140.104876)
		(stroke
			(width 0.08255)
			(type default)
		)
		(layer "In5.Cu")
	)
	(gr_line
		(start 398.435576 -140.104876)
		(end 398.322546 -139.991846)
		(stroke
			(width 0.08255)
			(type default)
		)
		(layer "In5.Cu")
	)
	(gr_line
		(start 398.435576 -139.380976)
		(end 398.435576 -138.885676)
		(stroke
			(width 0.08255)
			(type default)
		)
		(layer "In5.Cu")
	)
	(gr_line
		(start 398.435576 -138.885676)
		(end 398.322546 -138.772646)
		(stroke
			(width 0.08255)
			(type default)
		)
		(layer "In5.Cu")
	)
	(gr_line
		(start 398.784064 -320.01333)
		(end 398.784064 -319.984882)
		(stroke
			(width 0.05715)
			(type default)
		)
		(layer "In5.Cu")
	)
	(gr_line
		(start 398.784064 -319.984882)
		(end 398.829784 -319.939162)
		(stroke
			(width 0.05715)
			(type default)
		)
		(layer "In5.Cu")
	)
	(gr_line
		(start 398.801844 -136.147048)
		(end 398.801844 -136.147302)
		(stroke
			(width 0.08255)
			(type default)
		)
		(layer "In5.Cu")
	)
	(gr_line
		(start 398.803622 -136.14654)
		(end 398.95399 -136.092438)
		(stroke
			(width 0.08255)
			(type default)
		)
		(layer "In5.Cu")
	)
	(gr_line
		(start 398.95399 -136.092438)
		(end 399.16608 -135.644382)
		(stroke
			(width 0.08255)
			(type default)
		)
		(layer "In5.Cu")
	)
	(gr_line
		(start 399.16608 -135.644382)
		(end 399.112232 -135.49376)
		(stroke
			(width 0.08255)
			(type default)
		)
		(layer "In5.Cu")
	)
	(gr_line
		(start 399.285714 -316.229492)
		(end 399.400014 -316.115192)
		(stroke
			(width 0.05715)
			(type default)
		)
		(layer "In5.Cu")
	)
	(gr_line
		(start 399.400014 -316.115192)
		(end 399.400014 -315.849762)
		(stroke
			(width 0.05715)
			(type default)
		)
		(layer "In5.Cu")
	)
	(gr_line
		(start 400.734276 -134.606792)
		(end 400.847306 -134.719822)
		(stroke
			(width 0.08255)
			(type default)
		)
		(layer "In5.Cu")
	)
	(gr_line
		(start 400.847306 -134.719822)
		(end 401.342606 -134.719822)
		(stroke
			(width 0.08255)
			(type default)
		)
		(layer "In5.Cu")
	)
	(gr_line
		(start 401.342606 -134.719822)
		(end 401.455636 -134.606792)
		(stroke
			(width 0.08255)
			(type default)
		)
		(layer "In5.Cu")
	)
	(gr_line
		(start 402.097748 -134.605522)
		(end 402.103844 -134.603236)
		(stroke
			(width 0.08255)
			(type default)
		)
		(layer "In5.Cu")
	)
	(gr_line
		(start 402.103844 -134.603236)
		(end 402.10613 -134.605522)
		(stroke
			(width 0.08255)
			(type default)
		)
		(layer "In5.Cu")
	)
	(gr_line
		(start 402.10613 -134.605522)
		(end 402.39696 -134.896352)
		(stroke
			(width 0.08255)
			(type default)
		)
		(layer "In5.Cu")
	)
	(gr_line
		(start 413.50311 -121.367296)
		(end 413.79394 -121.076466)
		(stroke
			(width 0.08255)
			(type default)
		)
		(layer "In5.Cu")
	)
	(gr_line
		(start 413.79394 -135.886444)
		(end 413.50311 -136.177274)
		(stroke
			(width 0.08255)
			(type default)
		)
		(layer "In5.Cu")
	)
	(gr_line
		(start 413.79394 -135.604504)
		(end 413.50311 -135.313674)
		(stroke
			(width 0.08255)
			(type default)
		)
		(layer "In5.Cu")
	)
	(gr_line
		(start 415.64814 -146.796506)
		(end 415.35731 -147.087336)
		(stroke
			(width 0.08255)
			(type default)
		)
		(layer "In5.Cu")
	)
	(gr_line
		(start 416.316668 -121.266712)
		(end 416.316668 -121.266966)
		(stroke
			(width 0.08255)
			(type default)
		)
		(layer "In5.Cu")
	)
	(gr_line
		(start 416.31743 -121.26849)
		(end 416.378136 -121.416572)
		(stroke
			(width 0.08255)
			(type default)
		)
		(layer "In5.Cu")
	)
	(gr_line
		(start 416.374834 -136.153652)
		(end 416.374834 -136.153398)
		(stroke
			(width 0.08255)
			(type default)
		)
		(layer "In5.Cu")
	)
	(gr_line
		(start 416.378136 -121.416572)
		(end 416.83559 -121.606818)
		(stroke
			(width 0.08255)
			(type default)
		)
		(layer "In5.Cu")
	)
	(gr_line
		(start 416.437572 -136.30275)
		(end 416.375596 -136.155176)
		(stroke
			(width 0.08255)
			(type default)
		)
		(layer "In5.Cu")
	)
	(gr_line
		(start 416.478974 -147.272248)
		(end 416.478974 -147.148296)
		(stroke
			(width 0.08255)
			(type default)
		)
		(layer "In5.Cu")
	)
	(gr_line
		(start 416.829494 -147.622768)
		(end 416.478974 -147.272248)
		(stroke
			(width 0.08255)
			(type default)
		)
		(layer "In5.Cu")
	)
	(gr_line
		(start 416.83559 -121.606818)
		(end 416.983672 -121.545858)
		(stroke
			(width 0.08255)
			(type default)
		)
		(layer "In5.Cu")
	)
	(gr_line
		(start 416.896804 -136.489186)
		(end 416.437572 -136.30275)
		(stroke
			(width 0.08255)
			(type default)
		)
		(layer "In5.Cu")
	)
	(gr_line
		(start 416.953446 -147.622768)
		(end 416.829494 -147.622768)
		(stroke
			(width 0.08255)
			(type default)
		)
		(layer "In5.Cu")
	)
	(gr_line
		(start 417.044124 -136.426956)
		(end 416.896804 -136.489186)
		(stroke
			(width 0.08255)
			(type default)
		)
		(layer "In5.Cu")
	)
	(gr_line
		(start 417.15182 -136.165082)
		(end 416.48126 -135.892286)
		(stroke
			(width 0.08255)
			(type default)
		)
		(layer "In5.Cu")
	)
	(gr_line
		(start 417.443158 -121.73712)
		(end 417.503864 -121.885202)
		(stroke
			(width 0.08255)
			(type default)
		)
		(layer "In5.Cu")
	)
	(gr_line
		(start 417.503864 -121.885202)
		(end 417.961318 -122.075702)
		(stroke
			(width 0.08255)
			(type default)
		)
		(layer "In5.Cu")
	)
	(gr_line
		(start 417.56711 -136.761982)
		(end 417.505134 -136.614408)
		(stroke
			(width 0.08255)
			(type default)
		)
		(layer "In5.Cu")
	)
	(gr_line
		(start 417.95192 -148.901658)
		(end 417.97605 -148.780246)
		(stroke
			(width 0.08255)
			(type default)
		)
		(layer "In5.Cu")
	)
	(gr_line
		(start 417.961318 -122.075702)
		(end 418.109654 -122.014742)
		(stroke
			(width 0.08255)
			(type default)
		)
		(layer "In5.Cu")
	)
	(gr_line
		(start 418.026088 -136.948672)
		(end 417.56711 -136.761982)
		(stroke
			(width 0.08255)
			(type default)
		)
		(layer "In5.Cu")
	)
	(gr_line
		(start 418.173916 -136.886442)
		(end 418.026088 -136.948672)
		(stroke
			(width 0.08255)
			(type default)
		)
		(layer "In5.Cu")
	)
	(gr_line
		(start 418.228526 -149.313138)
		(end 417.95192 -148.901658)
		(stroke
			(width 0.08255)
			(type default)
		)
		(layer "In5.Cu")
	)
	(gr_line
		(start 418.281358 -136.624568)
		(end 417.610544 -136.351518)
		(stroke
			(width 0.08255)
			(type default)
		)
		(layer "In5.Cu")
	)
	(gr_line
		(start 418.350192 -149.337014)
		(end 418.228526 -149.313138)
		(stroke
			(width 0.08255)
			(type default)
		)
		(layer "In5.Cu")
	)
	(gr_line
		(start 418.568632 -122.20575)
		(end 418.629592 -122.354086)
		(stroke
			(width 0.08255)
			(type default)
		)
		(layer "In5.Cu")
	)
	(gr_line
		(start 418.629592 -122.354086)
		(end 419.087046 -122.544586)
		(stroke
			(width 0.08255)
			(type default)
		)
		(layer "In5.Cu")
	)
	(gr_line
		(start 418.682678 -137.188194)
		(end 418.634418 -137.073894)
		(stroke
			(width 0.08255)
			(type default)
		)
		(layer "In5.Cu")
	)
	(gr_line
		(start 419.087046 -122.544586)
		(end 419.235382 -122.483372)
		(stroke
			(width 0.08255)
			(type default)
		)
		(layer "In5.Cu")
	)
	(gr_line
		(start 419.14191 -137.375138)
		(end 418.682678 -137.188194)
		(stroke
			(width 0.08255)
			(type default)
		)
		(layer "In5.Cu")
	)
	(gr_line
		(start 419.256464 -137.326624)
		(end 419.14191 -137.375138)
		(stroke
			(width 0.08255)
			(type default)
		)
		(layer "In5.Cu")
	)
	(gr_line
		(start 419.363906 -137.06475)
		(end 418.740082 -136.811004)
		(stroke
			(width 0.08255)
			(type default)
		)
		(layer "In5.Cu")
	)
	(gr_line
		(start 419.48989 -378.629672)
		(end 419.663118 -378.8029)
		(stroke
			(width 0.08255)
			(type default)
		)
		(layer "In5.Cu")
	)
	(gr_line
		(start 419.48989 -378.290074)
		(end 419.48989 -378.629672)
		(stroke
			(width 0.08255)
			(type default)
		)
		(layer "In5.Cu")
	)
	(gr_line
		(start 419.69436 -122.674634)
		(end 419.75532 -122.822716)
		(stroke
			(width 0.08255)
			(type default)
		)
		(layer "In5.Cu")
	)
	(gr_line
		(start 419.75532 -122.822716)
		(end 420.212774 -123.013216)
		(stroke
			(width 0.08255)
			(type default)
		)
		(layer "In5.Cu")
	)
	(gr_line
		(start 420.212774 -123.013216)
		(end 420.360856 -122.952002)
		(stroke
			(width 0.08255)
			(type default)
		)
		(layer "In5.Cu")
	)
	(gr_line
		(start 420.453312 -138.149584)
		(end 420.454328 -138.025378)
		(stroke
			(width 0.08255)
			(type default)
		)
		(layer "In5.Cu")
	)
	(gr_line
		(start 420.801546 -138.50239)
		(end 420.453312 -138.149584)
		(stroke
			(width 0.08255)
			(type default)
		)
		(layer "In5.Cu")
	)
	(gr_line
		(start 420.870126 -271.600168)
		(end 420.915846 -271.554448)
		(stroke
			(width 0.05715)
			(type default)
		)
		(layer "In5.Cu")
	)
	(gr_line
		(start 420.915846 -271.554448)
		(end 420.915846 -271.526)
		(stroke
			(width 0.05715)
			(type default)
		)
		(layer "In5.Cu")
	)
	(gr_line
		(start 420.915846 -271.398238)
		(end 420.915846 -271.39773)
		(stroke
			(width 0.08255)
			(type default)
		)
		(layer "In5.Cu")
	)
	(gr_line
		(start 420.915846 -271.397222)
		(end 420.915846 -271.396714)
		(stroke
			(width 0.08255)
			(type default)
		)
		(layer "In5.Cu")
	)
	(gr_line
		(start 420.925752 -138.503406)
		(end 420.801546 -138.50239)
		(stroke
			(width 0.08255)
			(type default)
		)
		(layer "In5.Cu")
	)
	(gr_line
		(start 421.12819 -138.305286)
		(end 420.655242 -137.825734)
		(stroke
			(width 0.08255)
			(type default)
		)
		(layer "In5.Cu")
	)
	(gr_line
		(start 421.249602 -273.365214)
		(end 421.135302 -273.479514)
		(stroke
			(width 0.05715)
			(type default)
		)
		(layer "In5.Cu")
	)
	(gr_line
		(start 421.249602 -273.099784)
		(end 421.249602 -273.365214)
		(stroke
			(width 0.05715)
			(type default)
		)
		(layer "In5.Cu")
	)
	(gr_line
		(start 421.689784 -379.729746)
		(end 421.863012 -379.902974)
		(stroke
			(width 0.08255)
			(type default)
		)
		(layer "In5.Cu")
	)
	(gr_line
		(start 421.689784 -379.390148)
		(end 421.689784 -379.729746)
		(stroke
			(width 0.08255)
			(type default)
		)
		(layer "In5.Cu")
	)
	(gr_line
		(start 422.381172 -367.20018)
		(end 422.397936 -367.040922)
		(stroke
			(width 0.08255)
			(type default)
		)
		(layer "In5.Cu")
	)
	(gr_line
		(start 422.397936 -367.040922)
		(end 422.783508 -366.729264)
		(stroke
			(width 0.08255)
			(type default)
		)
		(layer "In5.Cu")
	)
	(gr_line
		(start 422.783508 -366.729264)
		(end 422.942766 -366.746028)
		(stroke
			(width 0.08255)
			(type default)
		)
		(layer "In5.Cu")
	)
	(gr_line
		(start 423.305478 -141.708632)
		(end 423.283634 -141.671294)
		(stroke
			(width 0.08255)
			(type default)
		)
		(layer "In5.Cu")
	)
	(gr_line
		(start 423.305478 -141.708632)
		(end 423.305478 -141.708378)
		(stroke
			(width 0.08255)
			(type default)
		)
		(layer "In5.Cu")
	)
	(gr_line
		(start 423.305732 -141.708886)
		(end 423.305478 -141.708378)
		(stroke
			(width 0.08255)
			(type default)
		)
		(layer "In5.Cu")
	)
	(gr_line
		(start 423.315384 -141.751304)
		(end 423.305732 -141.708886)
		(stroke
			(width 0.08255)
			(type default)
		)
		(layer "In5.Cu")
	)
	(gr_line
		(start 423.327576 -143.590518)
		(end 423.41292 -143.454882)
		(stroke
			(width 0.08255)
			(type default)
		)
		(layer "In5.Cu")
	)
	(gr_line
		(start 423.329608 -366.433354)
		(end 423.346372 -366.27435)
		(stroke
			(width 0.08255)
			(type default)
		)
		(layer "In5.Cu")
	)
	(gr_line
		(start 423.346372 -366.27435)
		(end 423.73169 -365.962438)
		(stroke
			(width 0.08255)
			(type default)
		)
		(layer "In5.Cu")
	)
	(gr_line
		(start 423.437558 -144.073626)
		(end 423.327576 -143.590518)
		(stroke
			(width 0.08255)
			(type default)
		)
		(layer "In5.Cu")
	)
	(gr_line
		(start 423.573194 -144.158716)
		(end 423.437558 -144.073626)
		(stroke
			(width 0.08255)
			(type default)
		)
		(layer "In5.Cu")
	)
	(gr_line
		(start 423.574718 -144.159732)
		(end 423.573956 -144.159224)
		(stroke
			(width 0.08255)
			(type default)
		)
		(layer "In5.Cu")
	)
	(gr_line
		(start 423.598594 -144.779492)
		(end 423.683684 -144.643602)
		(stroke
			(width 0.08255)
			(type default)
		)
		(layer "In5.Cu")
	)
	(gr_line
		(start 423.647616 -126.049786)
		(end 423.971466 -126.425198)
		(stroke
			(width 0.08255)
			(type default)
		)
		(layer "In5.Cu")
	)
	(gr_line
		(start 423.65676 -125.925834)
		(end 423.647616 -126.049786)
		(stroke
			(width 0.08255)
			(type default)
		)
		(layer "In5.Cu")
	)
	(gr_line
		(start 423.684192 -144.643094)
		(end 423.684446 -144.642586)
		(stroke
			(width 0.08255)
			(type default)
		)
		(layer "In5.Cu")
	)
	(gr_line
		(start 423.684446 -144.642586)
		(end 423.684192 -144.64157)
		(stroke
			(width 0.08255)
			(type default)
		)
		(layer "In5.Cu")
	)
	(gr_line
		(start 423.708576 -145.2626)
		(end 423.598594 -144.779492)
		(stroke
			(width 0.08255)
			(type default)
		)
		(layer "In5.Cu")
	)
	(gr_line
		(start 423.73169 -365.962438)
		(end 423.890948 -365.979202)
		(stroke
			(width 0.08255)
			(type default)
		)
		(layer "In5.Cu")
	)
	(gr_line
		(start 423.749216 -158.81731)
		(end 423.749216 -158.817564)
		(stroke
			(width 0.08255)
			(type default)
		)
		(layer "In5.Cu")
	)
	(gr_line
		(start 423.843958 -145.34769)
		(end 423.708576 -145.2626)
		(stroke
			(width 0.08255)
			(type default)
		)
		(layer "In5.Cu")
	)
	(gr_line
		(start 423.845482 -145.348706)
		(end 423.84472 -145.348198)
		(stroke
			(width 0.08255)
			(type default)
		)
		(layer "In5.Cu")
	)
	(gr_line
		(start 423.849546 -144.096486)
		(end 423.688764 -143.390874)
		(stroke
			(width 0.08255)
			(type default)
		)
		(layer "In5.Cu")
	)
	(gr_line
		(start 423.8498 -144.097248)
		(end 423.849546 -144.096486)
		(stroke
			(width 0.08255)
			(type default)
		)
		(layer "In5.Cu")
	)
	(gr_line
		(start 423.869358 -145.968466)
		(end 423.954448 -145.832576)
		(stroke
			(width 0.08255)
			(type default)
		)
		(layer "In5.Cu")
	)
	(gr_line
		(start 423.954956 -145.832068)
		(end 423.95521 -145.83156)
		(stroke
			(width 0.08255)
			(type default)
		)
		(layer "In5.Cu")
	)
	(gr_line
		(start 423.95521 -145.83156)
		(end 423.954956 -145.830544)
		(stroke
			(width 0.08255)
			(type default)
		)
		(layer "In5.Cu")
	)
	(gr_line
		(start 423.959782 -144.580356)
		(end 423.959528 -144.57934)
		(stroke
			(width 0.08255)
			(type default)
		)
		(layer "In5.Cu")
	)
	(gr_line
		(start 423.971466 -126.425198)
		(end 424.095164 -126.434342)
		(stroke
			(width 0.08255)
			(type default)
		)
		(layer "In5.Cu")
	)
	(gr_line
		(start 423.97934 -146.451574)
		(end 423.869358 -145.968466)
		(stroke
			(width 0.08255)
			(type default)
		)
		(layer "In5.Cu")
	)
	(gr_line
		(start 424.114722 -146.536664)
		(end 423.97934 -146.451574)
		(stroke
			(width 0.08255)
			(type default)
		)
		(layer "In5.Cu")
	)
	(gr_line
		(start 424.116246 -146.53768)
		(end 424.115484 -146.537172)
		(stroke
			(width 0.08255)
			(type default)
		)
		(layer "In5.Cu")
	)
	(gr_line
		(start 424.12031 -145.28546)
		(end 423.959782 -144.580356)
		(stroke
			(width 0.08255)
			(type default)
		)
		(layer "In5.Cu")
	)
	(gr_line
		(start 424.120564 -145.286222)
		(end 424.12031 -145.28546)
		(stroke
			(width 0.08255)
			(type default)
		)
		(layer "In5.Cu")
	)
	(gr_line
		(start 424.230546 -145.76933)
		(end 424.230292 -145.768314)
		(stroke
			(width 0.08255)
			(type default)
		)
		(layer "In5.Cu")
	)
	(gr_line
		(start 424.27779 -365.666782)
		(end 424.294554 -365.507524)
		(stroke
			(width 0.08255)
			(type default)
		)
		(layer "In5.Cu")
	)
	(gr_line
		(start 424.294554 -365.507524)
		(end 424.679872 -365.195866)
		(stroke
			(width 0.08255)
			(type default)
		)
		(layer "In5.Cu")
	)
	(gr_line
		(start 424.391074 -146.474434)
		(end 424.230546 -145.76933)
		(stroke
			(width 0.08255)
			(type default)
		)
		(layer "In5.Cu")
	)
	(gr_line
		(start 424.391328 -146.474942)
		(end 424.391074 -146.474434)
		(stroke
			(width 0.08255)
			(type default)
		)
		(layer "In5.Cu")
	)
	(gr_line
		(start 424.410886 -126.934722)
		(end 424.734482 -127.310134)
		(stroke
			(width 0.08255)
			(type default)
		)
		(layer "In5.Cu")
	)
	(gr_line
		(start 424.42003 -126.81077)
		(end 424.410886 -126.934722)
		(stroke
			(width 0.08255)
			(type default)
		)
		(layer "In5.Cu")
	)
	(gr_line
		(start 424.679872 -365.195866)
		(end 424.83913 -365.21263)
		(stroke
			(width 0.08255)
			(type default)
		)
		(layer "In5.Cu")
	)
	(gr_line
		(start 424.734482 -127.310134)
		(end 424.85818 -127.319278)
		(stroke
			(width 0.08255)
			(type default)
		)
		(layer "In5.Cu")
	)
	(gr_line
		(start 425.028106 -366.679988)
		(end 425.052998 -366.521492)
		(stroke
			(width 0.08255)
			(type default)
		)
		(layer "In5.Cu")
	)
	(gr_line
		(start 425.052998 -366.521492)
		(end 425.453302 -366.229392)
		(stroke
			(width 0.08255)
			(type default)
		)
		(layer "In5.Cu")
	)
	(gr_line
		(start 425.174156 -127.819658)
		(end 425.497752 -128.19507)
		(stroke
			(width 0.08255)
			(type default)
		)
		(layer "In5.Cu")
	)
	(gr_line
		(start 425.1833 -127.69596)
		(end 425.174156 -127.819658)
		(stroke
			(width 0.08255)
			(type default)
		)
		(layer "In5.Cu")
	)
	(gr_line
		(start 425.453302 -366.229392)
		(end 425.612052 -366.25403)
		(stroke
			(width 0.08255)
			(type default)
		)
		(layer "In5.Cu")
	)
	(gr_line
		(start 425.497752 -128.19507)
		(end 425.62145 -128.204214)
		(stroke
			(width 0.08255)
			(type default)
		)
		(layer "In5.Cu")
	)
	(gr_line
		(start 426.013372 -365.961422)
		(end 426.029374 -365.858806)
		(stroke
			(width 0.08255)
			(type default)
		)
		(layer "In5.Cu")
	)
	(gr_line
		(start 426.029374 -365.858806)
		(end 426.494448 -365.519462)
		(stroke
			(width 0.08255)
			(type default)
		)
		(layer "In5.Cu")
	)
	(gr_line
		(start 426.089826 -380.69012)
		(end 426.089826 -380.358142)
		(stroke
			(width 0.08255)
			(type default)
		)
		(layer "In5.Cu")
	)
	(gr_line
		(start 426.089826 -380.358142)
		(end 426.263054 -380.184914)
		(stroke
			(width 0.08255)
			(type default)
		)
		(layer "In5.Cu")
	)
	(gr_line
		(start 426.089826 -379.729746)
		(end 426.263054 -379.902974)
		(stroke
			(width 0.08255)
			(type default)
		)
		(layer "In5.Cu")
	)
	(gr_line
		(start 426.089826 -379.390148)
		(end 426.089826 -379.729746)
		(stroke
			(width 0.08255)
			(type default)
		)
		(layer "In5.Cu")
	)
	(gr_line
		(start 426.494448 -365.519462)
		(end 426.597318 -365.535464)
		(stroke
			(width 0.08255)
			(type default)
		)
		(layer "In5.Cu")
	)
	(gr_line
		(start 426.998638 -365.242856)
		(end 427.01464 -365.139986)
		(stroke
			(width 0.08255)
			(type default)
		)
		(layer "In5.Cu")
	)
	(gr_line
		(start 427.01464 -365.139986)
		(end 427.47946 -364.800896)
		(stroke
			(width 0.08255)
			(type default)
		)
		(layer "In5.Cu")
	)
	(gr_line
		(start 427.255432 -363.258862)
		(end 427.270164 -363.117638)
		(stroke
			(width 0.08255)
			(type default)
		)
		(layer "In5.Cu")
	)
	(gr_line
		(start 427.270164 -363.117638)
		(end 427.655736 -362.80598)
		(stroke
			(width 0.08255)
			(type default)
		)
		(layer "In5.Cu")
	)
	(gr_line
		(start 427.28388 -271.599406)
		(end 427.28388 -271.570958)
		(stroke
			(width 0.05715)
			(type default)
		)
		(layer "In5.Cu")
	)
	(gr_line
		(start 427.3296 -271.645126)
		(end 427.28388 -271.599406)
		(stroke
			(width 0.05715)
			(type default)
		)
		(layer "In5.Cu")
	)
	(gr_line
		(start 427.47946 -364.800896)
		(end 427.582584 -364.816898)
		(stroke
			(width 0.08255)
			(type default)
		)
		(layer "In5.Cu")
	)
	(gr_line
		(start 427.57979 -160.476184)
		(end 427.57979 -160.455102)
		(stroke
			(width 0.08255)
			(type default)
		)
		(layer "In5.Cu")
	)
	(gr_line
		(start 427.57979 -160.455102)
		(end 427.573694 -160.449006)
		(stroke
			(width 0.08255)
			(type default)
		)
		(layer "In5.Cu")
	)
	(gr_line
		(start 427.580806 -160.503108)
		(end 427.57979 -160.476184)
		(stroke
			(width 0.08255)
			(type default)
		)
		(layer "In5.Cu")
	)
	(gr_line
		(start 427.655736 -362.80598)
		(end 427.797214 -362.820712)
		(stroke
			(width 0.08255)
			(type default)
		)
		(layer "In5.Cu")
	)
	(gr_line
		(start 427.899576 -275.949918)
		(end 427.899576 -275.684488)
		(stroke
			(width 0.05715)
			(type default)
		)
		(layer "In5.Cu")
	)
	(gr_line
		(start 427.899576 -275.684488)
		(end 427.785276 -275.570188)
		(stroke
			(width 0.05715)
			(type default)
		)
		(layer "In5.Cu")
	)
	(gr_line
		(start 428.16526 -307.299868)
		(end 427.89983 -307.299868)
		(stroke
			(width 0.05715)
			(type default)
		)
		(layer "In5.Cu")
	)
	(gr_line
		(start 428.183802 -362.508292)
		(end 428.198534 -362.366814)
		(stroke
			(width 0.08255)
			(type default)
		)
		(layer "In5.Cu")
	)
	(gr_line
		(start 428.198534 -362.366814)
		(end 428.584106 -362.055156)
		(stroke
			(width 0.08255)
			(type default)
		)
		(layer "In5.Cu")
	)
	(gr_line
		(start 428.27956 -307.414168)
		(end 428.16526 -307.299868)
		(stroke
			(width 0.05715)
			(type default)
		)
		(layer "In5.Cu")
	)
	(gr_line
		(start 428.289974 -378.629672)
		(end 428.463202 -378.8029)
		(stroke
			(width 0.08255)
			(type default)
		)
		(layer "In5.Cu")
	)
	(gr_line
		(start 428.289974 -378.290074)
		(end 428.289974 -378.629672)
		(stroke
			(width 0.08255)
			(type default)
		)
		(layer "In5.Cu")
	)
	(gr_line
		(start 428.584106 -362.055156)
		(end 428.725584 -362.070142)
		(stroke
			(width 0.08255)
			(type default)
		)
		(layer "In5.Cu")
	)
	(gr_line
		(start 429.112172 -361.757468)
		(end 429.126904 -361.61599)
		(stroke
			(width 0.08255)
			(type default)
		)
		(layer "In5.Cu")
	)
	(gr_line
		(start 429.126904 -361.61599)
		(end 429.512476 -361.304332)
		(stroke
			(width 0.08255)
			(type default)
		)
		(layer "In5.Cu")
	)
	(gr_line
		(start 429.383952 -366.97285)
		(end 429.866552 -366.649508)
		(stroke
			(width 0.08255)
			(type default)
		)
		(layer "In5.Cu")
	)
	(gr_line
		(start 429.512476 -361.304332)
		(end 429.653954 -361.319318)
		(stroke
			(width 0.08255)
			(type default)
		)
		(layer "In5.Cu")
	)
	(gr_line
		(start 429.540924 -367.207038)
		(end 430.023524 -366.883696)
		(stroke
			(width 0.08255)
			(type default)
		)
		(layer "In5.Cu")
	)
	(gr_line
		(start 429.800004 -281.649932)
		(end 430.065434 -281.649932)
		(stroke
			(width 0.05715)
			(type default)
		)
		(layer "In5.Cu")
	)
	(gr_line
		(start 429.866806 -366.64773)
		(end 429.897794 -366.490758)
		(stroke
			(width 0.08255)
			(type default)
		)
		(layer "In5.Cu")
	)
	(gr_line
		(start 429.897794 -366.490758)
		(end 430.309528 -366.214914)
		(stroke
			(width 0.08255)
			(type default)
		)
		(layer "In5.Cu")
	)
	(gr_line
		(start 429.966628 -363.078268)
		(end 429.991266 -362.920026)
		(stroke
			(width 0.08255)
			(type default)
		)
		(layer "In5.Cu")
	)
	(gr_line
		(start 429.991266 -362.920026)
		(end 430.39157 -362.627926)
		(stroke
			(width 0.08255)
			(type default)
		)
		(layer "In5.Cu")
	)
	(gr_line
		(start 430.023524 -366.883696)
		(end 430.62525 -366.480344)
		(stroke
			(width 0.08255)
			(type default)
		)
		(layer "In5.Cu")
	)
	(gr_line
		(start 430.065434 -316.799722)
		(end 429.800004 -316.799722)
		(stroke
			(width 0.05715)
			(type default)
		)
		(layer "In5.Cu")
	)
	(gr_line
		(start 430.065434 -310.149748)
		(end 429.800004 -310.149748)
		(stroke
			(width 0.05715)
			(type default)
		)
		(layer "In5.Cu")
	)
	(gr_line
		(start 430.065434 -308.249828)
		(end 429.800004 -308.249828)
		(stroke
			(width 0.05715)
			(type default)
		)
		(layer "In5.Cu")
	)
	(gr_line
		(start 430.065434 -306.349908)
		(end 429.800004 -306.349908)
		(stroke
			(width 0.05715)
			(type default)
		)
		(layer "In5.Cu")
	)
	(gr_line
		(start 430.065434 -287.349946)
		(end 429.800004 -287.349946)
		(stroke
			(width 0.05715)
			(type default)
		)
		(layer "In5.Cu")
	)
	(gr_line
		(start 430.065434 -281.649932)
		(end 430.179734 -281.535632)
		(stroke
			(width 0.05715)
			(type default)
		)
		(layer "In5.Cu")
	)
	(gr_line
		(start 430.134014 -319.027048)
		(end 430.134014 -318.9986)
		(stroke
			(width 0.05715)
			(type default)
		)
		(layer "In5.Cu")
	)
	(gr_line
		(start 430.134014 -318.9986)
		(end 430.179734 -318.95288)
		(stroke
			(width 0.05715)
			(type default)
		)
		(layer "In5.Cu")
	)
	(gr_line
		(start 430.179734 -316.914022)
		(end 430.065434 -316.799722)
		(stroke
			(width 0.05715)
			(type default)
		)
		(layer "In5.Cu")
	)
	(gr_line
		(start 430.179734 -310.264048)
		(end 430.065434 -310.149748)
		(stroke
			(width 0.05715)
			(type default)
		)
		(layer "In5.Cu")
	)
	(gr_line
		(start 430.179734 -308.364128)
		(end 430.065434 -308.249828)
		(stroke
			(width 0.05715)
			(type default)
		)
		(layer "In5.Cu")
	)
	(gr_line
		(start 430.179734 -306.464208)
		(end 430.065434 -306.349908)
		(stroke
			(width 0.05715)
			(type default)
		)
		(layer "In5.Cu")
	)
	(gr_line
		(start 430.179734 -287.235646)
		(end 430.065434 -287.349946)
		(stroke
			(width 0.05715)
			(type default)
		)
		(layer "In5.Cu")
	)
	(gr_line
		(start 430.309528 -366.214914)
		(end 430.466754 -366.245902)
		(stroke
			(width 0.08255)
			(type default)
		)
		(layer "In5.Cu")
	)
	(gr_line
		(start 430.370234 -308.364128)
		(end 430.484534 -308.249828)
		(stroke
			(width 0.05715)
			(type default)
		)
		(layer "In5.Cu")
	)
	(gr_line
		(start 430.39157 -362.627926)
		(end 430.55032 -362.652564)
		(stroke
			(width 0.08255)
			(type default)
		)
		(layer "In5.Cu")
	)
	(gr_line
		(start 430.484534 -308.249828)
		(end 430.749964 -308.249828)
		(stroke
			(width 0.05715)
			(type default)
		)
		(layer "In5.Cu")
	)
	(gr_line
		(start 430.484534 -281.649932)
		(end 430.370234 -281.535632)
		(stroke
			(width 0.05715)
			(type default)
		)
		(layer "In5.Cu")
	)
	(gr_line
		(start 430.489868 -379.729746)
		(end 430.663096 -379.902974)
		(stroke
			(width 0.08255)
			(type default)
		)
		(layer "In5.Cu")
	)
	(gr_line
		(start 430.489868 -379.390148)
		(end 430.489868 -379.729746)
		(stroke
			(width 0.08255)
			(type default)
		)
		(layer "In5.Cu")
	)
	(gr_line
		(start 430.749964 -281.649932)
		(end 430.484534 -281.649932)
		(stroke
			(width 0.05715)
			(type default)
		)
		(layer "In5.Cu")
	)
	(gr_line
		(start 430.879758 -365.969042)
		(end 430.911 -365.81207)
		(stroke
			(width 0.08255)
			(type default)
		)
		(layer "In5.Cu")
	)
	(gr_line
		(start 430.911 -365.81207)
		(end 431.322734 -365.535972)
		(stroke
			(width 0.08255)
			(type default)
		)
		(layer "In5.Cu")
	)
	(gr_line
		(start 430.95164 -362.359956)
		(end 430.976278 -362.20146)
		(stroke
			(width 0.08255)
			(type default)
		)
		(layer "In5.Cu")
	)
	(gr_line
		(start 430.976278 -362.20146)
		(end 431.376836 -361.90936)
		(stroke
			(width 0.08255)
			(type default)
		)
		(layer "In5.Cu")
	)
	(gr_line
		(start 431.036476 -366.205008)
		(end 431.638202 -365.801656)
		(stroke
			(width 0.08255)
			(type default)
		)
		(layer "In5.Cu")
	)
	(gr_line
		(start 431.09896 -367.405158)
		(end 431.098706 -367.405158)
		(stroke
			(width 0.08255)
			(type default)
		)
		(layer "In5.Cu")
	)
	(gr_line
		(start 431.099468 -367.40338)
		(end 431.132234 -367.246916)
		(stroke
			(width 0.08255)
			(type default)
		)
		(layer "In5.Cu")
	)
	(gr_line
		(start 431.132234 -367.246916)
		(end 431.547778 -366.97666)
		(stroke
			(width 0.08255)
			(type default)
		)
		(layer "In5.Cu")
	)
	(gr_line
		(start 431.322734 -365.535972)
		(end 431.479452 -365.567214)
		(stroke
			(width 0.08255)
			(type default)
		)
		(layer "In5.Cu")
	)
	(gr_line
		(start 431.376836 -361.90936)
		(end 431.535586 -361.933998)
		(stroke
			(width 0.08255)
			(type default)
		)
		(layer "In5.Cu")
	)
	(gr_line
		(start 431.547778 -366.97666)
		(end 431.704242 -367.009934)
		(stroke
			(width 0.08255)
			(type default)
		)
		(layer "In5.Cu")
	)
	(gr_line
		(start 431.89271 -365.290354)
		(end 431.923952 -365.133382)
		(stroke
			(width 0.08255)
			(type default)
		)
		(layer "In5.Cu")
	)
	(gr_line
		(start 431.904648 -306.965858)
		(end 431.858928 -306.920138)
		(stroke
			(width 0.05715)
			(type default)
		)
		(layer "In5.Cu")
	)
	(gr_line
		(start 431.923952 -365.133382)
		(end 432.335686 -364.857284)
		(stroke
			(width 0.08255)
			(type default)
		)
		(layer "In5.Cu")
	)
	(gr_line
		(start 431.933096 -306.965858)
		(end 431.904648 -306.965858)
		(stroke
			(width 0.05715)
			(type default)
		)
		(layer "In5.Cu")
	)
	(gr_line
		(start 431.936906 -361.64139)
		(end 431.961798 -361.482894)
		(stroke
			(width 0.08255)
			(type default)
		)
		(layer "In5.Cu")
	)
	(gr_line
		(start 431.9524 -310.765698)
		(end 431.90668 -310.719978)
		(stroke
			(width 0.05715)
			(type default)
		)
		(layer "In5.Cu")
	)
	(gr_line
		(start 431.960528 -308.865778)
		(end 431.914808 -308.820058)
		(stroke
			(width 0.05715)
			(type default)
		)
		(layer "In5.Cu")
	)
	(gr_line
		(start 431.960528 -308.583838)
		(end 431.914808 -308.629558)
		(stroke
			(width 0.05715)
			(type default)
		)
		(layer "In5.Cu")
	)
	(gr_line
		(start 431.961798 -361.482894)
		(end 432.362102 -361.190794)
		(stroke
			(width 0.08255)
			(type default)
		)
		(layer "In5.Cu")
	)
	(gr_line
		(start 431.980848 -310.765698)
		(end 431.9524 -310.765698)
		(stroke
			(width 0.05715)
			(type default)
		)
		(layer "In5.Cu")
	)
	(gr_line
		(start 431.988976 -308.865778)
		(end 431.960528 -308.865778)
		(stroke
			(width 0.05715)
			(type default)
		)
		(layer "In5.Cu")
	)
	(gr_line
		(start 431.988976 -308.583838)
		(end 431.960528 -308.583838)
		(stroke
			(width 0.05715)
			(type default)
		)
		(layer "In5.Cu")
	)
	(gr_line
		(start 432.022504 -307.915818)
		(end 431.976784 -307.870098)
		(stroke
			(width 0.05715)
			(type default)
		)
		(layer "In5.Cu")
	)
	(gr_line
		(start 432.049428 -365.526066)
		(end 432.651154 -365.122968)
		(stroke
			(width 0.08255)
			(type default)
		)
		(layer "In5.Cu")
	)
	(gr_line
		(start 432.050952 -307.915818)
		(end 432.022504 -307.915818)
		(stroke
			(width 0.05715)
			(type default)
		)
		(layer "In5.Cu")
	)
	(gr_line
		(start 432.121056 -366.740186)
		(end 432.120802 -366.740186)
		(stroke
			(width 0.08255)
			(type default)
		)
		(layer "In5.Cu")
	)
	(gr_line
		(start 432.121564 -366.738408)
		(end 432.154584 -366.582198)
		(stroke
			(width 0.08255)
			(type default)
		)
		(layer "In5.Cu")
	)
	(gr_line
		(start 432.154584 -366.582198)
		(end 432.569874 -366.311688)
		(stroke
			(width 0.08255)
			(type default)
		)
		(layer "In5.Cu")
	)
	(gr_line
		(start 432.17592 -281.270202)
		(end 432.22164 -281.315922)
		(stroke
			(width 0.05715)
			(type default)
		)
		(layer "In5.Cu")
	)
	(gr_line
		(start 432.17592 -281.079702)
		(end 432.22164 -281.033982)
		(stroke
			(width 0.05715)
			(type default)
		)
		(layer "In5.Cu")
	)
	(gr_line
		(start 432.22164 -286.733996)
		(end 432.17592 -286.779716)
		(stroke
			(width 0.05715)
			(type default)
		)
		(layer "In5.Cu")
	)
	(gr_line
		(start 432.22164 -281.315922)
		(end 432.250088 -281.315922)
		(stroke
			(width 0.05715)
			(type default)
		)
		(layer "In5.Cu")
	)
	(gr_line
		(start 432.22164 -281.033982)
		(end 432.250088 -281.033982)
		(stroke
			(width 0.05715)
			(type default)
		)
		(layer "In5.Cu")
	)
	(gr_line
		(start 432.250088 -286.733996)
		(end 432.22164 -286.733996)
		(stroke
			(width 0.05715)
			(type default)
		)
		(layer "In5.Cu")
	)
	(gr_line
		(start 432.335686 -364.857284)
		(end 432.492658 -364.888272)
		(stroke
			(width 0.08255)
			(type default)
		)
		(layer "In5.Cu")
	)
	(gr_line
		(start 432.362102 -361.190794)
		(end 432.520852 -361.215432)
		(stroke
			(width 0.08255)
			(type default)
		)
		(layer "In5.Cu")
	)
	(gr_line
		(start 432.569874 -366.311688)
		(end 432.726338 -366.344962)
		(stroke
			(width 0.08255)
			(type default)
		)
		(layer "In5.Cu")
	)
	(gr_line
		(start 432.905662 -364.611666)
		(end 432.923696 -364.520734)
		(stroke
			(width 0.08255)
			(type default)
		)
		(layer "In5.Cu")
	)
	(gr_line
		(start 432.923696 -364.520734)
		(end 433.414932 -364.191296)
		(stroke
			(width 0.08255)
			(type default)
		)
		(layer "In5.Cu")
	)
	(gr_line
		(start 433.062634 -364.847378)
		(end 433.66436 -364.444026)
		(stroke
			(width 0.08255)
			(type default)
		)
		(layer "In5.Cu")
	)
	(gr_line
		(start 433.078636 -367.61674)
		(end 433.10937 -367.459768)
		(stroke
			(width 0.08255)
			(type default)
		)
		(layer "In5.Cu")
	)
	(gr_line
		(start 433.10937 -367.459768)
		(end 433.520342 -367.182654)
		(stroke
			(width 0.08255)
			(type default)
		)
		(layer "In5.Cu")
	)
	(gr_line
		(start 433.143152 -366.075214)
		(end 433.142898 -366.075214)
		(stroke
			(width 0.08255)
			(type default)
		)
		(layer "In5.Cu")
	)
	(gr_line
		(start 433.143406 -366.073436)
		(end 433.17668 -365.917226)
		(stroke
			(width 0.08255)
			(type default)
		)
		(layer "In5.Cu")
	)
	(gr_line
		(start 433.17668 -365.917226)
		(end 433.59197 -365.646716)
		(stroke
			(width 0.08255)
			(type default)
		)
		(layer "In5.Cu")
	)
	(gr_line
		(start 433.414932 -364.191296)
		(end 433.505864 -364.20933)
		(stroke
			(width 0.08255)
			(type default)
		)
		(layer "In5.Cu")
	)
	(gr_line
		(start 433.520342 -367.182654)
		(end 433.677314 -367.213134)
		(stroke
			(width 0.08255)
			(type default)
		)
		(layer "In5.Cu")
	)
	(gr_line
		(start 433.59197 -365.646716)
		(end 433.748434 -365.67999)
		(stroke
			(width 0.08255)
			(type default)
		)
		(layer "In5.Cu")
	)
	(gr_line
		(start 434.089556 -366.935258)
		(end 434.12029 -366.778032)
		(stroke
			(width 0.08255)
			(type default)
		)
		(layer "In5.Cu")
	)
	(gr_line
		(start 434.12029 -366.778032)
		(end 434.531262 -366.500918)
		(stroke
			(width 0.08255)
			(type default)
		)
		(layer "In5.Cu")
	)
	(gr_line
		(start 434.531262 -366.500918)
		(end 434.688488 -366.531652)
		(stroke
			(width 0.08255)
			(type default)
		)
		(layer "In5.Cu")
	)
	(gr_line
		(start 435.10073 -366.253776)
		(end 435.131464 -366.09655)
		(stroke
			(width 0.08255)
			(type default)
		)
		(layer "In5.Cu")
	)
	(gr_line
		(start 435.131464 -366.09655)
		(end 435.542436 -365.819436)
		(stroke
			(width 0.08255)
			(type default)
		)
		(layer "In5.Cu")
	)
	(gr_line
		(start 435.542436 -365.819436)
		(end 435.699916 -365.849916)
		(stroke
			(width 0.08255)
			(type default)
		)
		(layer "In5.Cu")
	)
	(gr_line
		(start 437.225186 -363.38002)
		(end 437.224932 -363.38002)
		(stroke
			(width 0.08255)
			(type default)
		)
		(layer "In5.Cu")
	)
	(gr_line
		(start 437.22544 -363.377988)
		(end 437.247792 -363.219746)
		(stroke
			(width 0.08255)
			(type default)
		)
		(layer "In5.Cu")
	)
	(gr_line
		(start 437.247792 -363.219746)
		(end 437.644286 -362.922312)
		(stroke
			(width 0.08255)
			(type default)
		)
		(layer "In5.Cu")
	)
	(gr_line
		(start 437.422036 -361.585256)
		(end 437.453278 -361.42803)
		(stroke
			(width 0.08255)
			(type default)
		)
		(layer "In5.Cu")
	)
	(gr_line
		(start 437.453278 -361.42803)
		(end 437.865012 -361.152186)
		(stroke
			(width 0.08255)
			(type default)
		)
		(layer "In5.Cu")
	)
	(gr_line
		(start 437.579008 -361.820968)
		(end 438.180734 -361.41787)
		(stroke
			(width 0.08255)
			(type default)
		)
		(layer "In5.Cu")
	)
	(gr_line
		(start 437.644286 -362.922312)
		(end 437.802528 -362.944664)
		(stroke
			(width 0.08255)
			(type default)
		)
		(layer "In5.Cu")
	)
	(gr_line
		(start 437.865012 -361.152186)
		(end 438.022238 -361.183174)
		(stroke
			(width 0.08255)
			(type default)
		)
		(layer "In5.Cu")
	)
	(gr_line
		(start 438.200292 -362.647738)
		(end 438.200038 -362.647738)
		(stroke
			(width 0.08255)
			(type default)
		)
		(layer "In5.Cu")
	)
	(gr_line
		(start 438.200546 -362.64596)
		(end 438.222898 -362.487464)
		(stroke
			(width 0.08255)
			(type default)
		)
		(layer "In5.Cu")
	)
	(gr_line
		(start 438.222898 -362.487464)
		(end 438.619392 -362.19003)
		(stroke
			(width 0.08255)
			(type default)
		)
		(layer "In5.Cu")
	)
	(gr_line
		(start 438.22747 -364.091474)
		(end 438.244996 -363.932216)
		(stroke
			(width 0.08255)
			(type default)
		)
		(layer "In5.Cu")
	)
	(gr_line
		(start 438.244996 -363.932216)
		(end 438.631838 -363.62259)
		(stroke
			(width 0.08255)
			(type default)
		)
		(layer "In5.Cu")
	)
	(gr_line
		(start 438.434988 -360.906568)
		(end 438.46623 -360.749342)
		(stroke
			(width 0.08255)
			(type default)
		)
		(layer "In5.Cu")
	)
	(gr_line
		(start 438.46623 -360.749342)
		(end 438.877964 -360.473244)
		(stroke
			(width 0.08255)
			(type default)
		)
		(layer "In5.Cu")
	)
	(gr_line
		(start 438.59196 -361.14228)
		(end 439.193686 -360.739182)
		(stroke
			(width 0.08255)
			(type default)
		)
		(layer "In5.Cu")
	)
	(gr_line
		(start 438.619392 -362.19003)
		(end 438.777634 -362.212382)
		(stroke
			(width 0.08255)
			(type default)
		)
		(layer "In5.Cu")
	)
	(gr_line
		(start 438.631838 -363.62259)
		(end 438.791096 -363.640116)
		(stroke
			(width 0.08255)
			(type default)
		)
		(layer "In5.Cu")
	)
	(gr_line
		(start 438.877964 -360.473244)
		(end 439.03519 -360.504486)
		(stroke
			(width 0.08255)
			(type default)
		)
		(layer "In5.Cu")
	)
	(gr_line
		(start 439.175398 -361.915456)
		(end 439.175144 -361.915456)
		(stroke
			(width 0.08255)
			(type default)
		)
		(layer "In5.Cu")
	)
	(gr_line
		(start 439.175652 -361.913678)
		(end 439.198004 -361.755436)
		(stroke
			(width 0.08255)
			(type default)
		)
		(layer "In5.Cu")
	)
	(gr_line
		(start 439.179462 -363.329474)
		(end 439.191146 -363.22381)
		(stroke
			(width 0.08255)
			(type default)
		)
		(layer "In5.Cu")
	)
	(gr_line
		(start 439.191146 -363.22381)
		(end 439.577988 -362.914184)
		(stroke
			(width 0.08255)
			(type default)
		)
		(layer "In5.Cu")
	)
	(gr_line
		(start 439.198004 -361.755436)
		(end 439.594498 -361.457748)
		(stroke
			(width 0.08255)
			(type default)
		)
		(layer "In5.Cu")
	)
	(gr_line
		(start 439.577988 -362.914184)
		(end 439.683652 -362.925868)
		(stroke
			(width 0.08255)
			(type default)
		)
		(layer "In5.Cu")
	)
	(gr_line
		(start 439.594498 -361.457748)
		(end 439.752994 -361.4801)
		(stroke
			(width 0.08255)
			(type default)
		)
		(layer "In5.Cu")
	)
	(gr_line
		(start 440.072018 -362.615226)
		(end 440.083702 -362.509562)
		(stroke
			(width 0.08255)
			(type default)
		)
		(layer "In5.Cu")
	)
	(gr_line
		(start 440.083702 -362.509562)
		(end 440.470544 -362.199936)
		(stroke
			(width 0.08255)
			(type default)
		)
		(layer "In5.Cu")
	)
	(gr_line
		(start 440.470544 -362.199936)
		(end 440.575954 -362.21162)
		(stroke
			(width 0.08255)
			(type default)
		)
		(layer "In5.Cu")
	)
	(gr_line
		(start 442.111638 -358.125522)
		(end 442.111384 -358.125522)
		(stroke
			(width 0.08255)
			(type default)
		)
		(layer "In5.Cu")
	)
	(gr_line
		(start 442.664088 -317.080392)
		(end 442.664088 -316.920626)
		(stroke
			(width 0.08255)
			(type default)
		)
		(layer "In5.Cu")
	)
	(gr_line
		(start 443.014608 -317.430912)
		(end 442.664088 -317.080392)
		(stroke
			(width 0.08255)
			(type default)
		)
		(layer "In5.Cu")
	)
	(gr_line
		(start 443.174374 -317.430912)
		(end 443.014608 -317.430912)
		(stroke
			(width 0.08255)
			(type default)
		)
		(layer "In5.Cu")
	)
	(gr_poly
		(pts
			(arc
				(start 265.615928 -377.679966)
				(mid 265.635451 -377.676065)
				(end 265.651996 -377.66498)
			)
			(arc
				(start 265.851386 -377.46559)
				(mid 265.862497 -377.449056)
				(end 265.866372 -377.429522)
			)
			(arc
				(start 265.866372 -368.884962)
				(mid 265.862471 -368.865439)
				(end 265.851386 -368.848894)
			)
			(arc
				(start 265.514582 -368.51209)
				(mid 265.498048 -368.500979)
				(end 265.478514 -368.497104)
			)
			(arc
				(start 242.901216 -368.497104)
				(mid 242.881693 -368.501005)
				(end 242.865148 -368.51209)
			)
			(arc
				(start 242.760754 -368.616484)
				(mid 242.749643 -368.633018)
				(end 242.745768 -368.652552)
			)
			(arc
				(start 242.745768 -377.268994)
				(mid 242.749669 -377.288517)
				(end 242.760754 -377.305062)
			)
			(arc
				(start 243.120672 -377.66498)
				(mid 243.137206 -377.676091)
				(end 243.15674 -377.679966)
			)
		)
		(stroke
			(width 0)
			(type solid)
		)
		(fill yes)
		(layer "In6.Cu")
		(net "P12V_STBY_R2")
	)
	(gr_poly
		(pts
			(arc
				(start 37.053012 -314.899802)
				(mid 36.646612 -314.899802)
				(end 37.053012 -314.899802)
			)
		)
		(stroke
			(width 0)
			(type solid)
		)
		(fill yes)
		(layer "In6.Cu")
		(net "P5E_PEX0_STN7_TX_DN<122>")
	)
	(gr_poly
		(pts
			(arc
				(start 37.053012 -312.049922)
				(mid 36.646612 -312.049922)
				(end 37.053012 -312.049922)
			)
		)
		(stroke
			(width 0)
			(type solid)
		)
		(fill yes)
		(layer "In6.Cu")
		(net "P5E_PEX0_STN7_TX_DN<121>")
	)
	(gr_poly
		(pts
			(arc
				(start 38.002972 -314.899802)
				(mid 37.596572 -314.899802)
				(end 38.002972 -314.899802)
			)
		)
		(stroke
			(width 0)
			(type solid)
		)
		(fill yes)
		(layer "In6.Cu")
		(net "P5E_PEX0_STN7_TX_DP<122>")
	)
	(gr_poly
		(pts
			(arc
				(start 38.002972 -312.049922)
				(mid 37.596572 -312.049922)
				(end 38.002972 -312.049922)
			)
		)
		(stroke
			(width 0)
			(type solid)
		)
		(fill yes)
		(layer "In6.Cu")
		(net "P5E_PEX0_STN7_TX_DP<121>")
	)
	(gr_poly
		(pts
			(arc
				(start 38.953186 -313.949842)
				(mid 38.546786 -313.949842)
				(end 38.953186 -313.949842)
			)
		)
		(stroke
			(width 0)
			(type solid)
		)
		(fill yes)
		(layer "In6.Cu")
		(net "P5E_PEX0_STN7_TX_DN<123>")
	)
	(gr_poly
		(pts
			(arc
				(start 38.953186 -312.999882)
				(mid 38.546786 -312.999882)
				(end 38.953186 -312.999882)
			)
		)
		(stroke
			(width 0)
			(type solid)
		)
		(fill yes)
		(layer "In6.Cu")
		(net "P5E_PEX0_STN7_TX_DP<123>")
	)
	(gr_poly
		(pts
			(arc
				(start 39.903146 -312.049922)
				(mid 39.496746 -312.049922)
				(end 39.903146 -312.049922)
			)
		)
		(stroke
			(width 0)
			(type solid)
		)
		(fill yes)
		(layer "In6.Cu")
		(net "P5E_PEX0_STN7_TX_DN<124>")
	)
	(gr_poly
		(pts
			(arc
				(start 39.903146 -311.099962)
				(mid 39.496746 -311.099962)
				(end 39.903146 -311.099962)
			)
		)
		(stroke
			(width 0)
			(type solid)
		)
		(fill yes)
		(layer "In6.Cu")
		(net "P5E_PEX0_STN7_TX_DP<124>")
	)
	(gr_poly
		(pts
			(arc
				(start 40.853106 -313.949842)
				(mid 40.446706 -313.949842)
				(end 40.853106 -313.949842)
			)
		)
		(stroke
			(width 0)
			(type solid)
		)
		(fill yes)
		(layer "In6.Cu")
		(net "P5E_PEX0_STN7_TX_DN<125>")
	)
	(gr_poly
		(pts
			(arc
				(start 40.853106 -312.999882)
				(mid 40.446706 -312.999882)
				(end 40.853106 -312.999882)
			)
		)
		(stroke
			(width 0)
			(type solid)
		)
		(fill yes)
		(layer "In6.Cu")
		(net "P5E_PEX0_STN7_TX_DP<125>")
	)
	(gr_poly
		(pts
			(arc
				(start 41.803066 -312.049922)
				(mid 41.396666 -312.049922)
				(end 41.803066 -312.049922)
			)
		)
		(stroke
			(width 0)
			(type solid)
		)
		(fill yes)
		(layer "In6.Cu")
		(net "P5E_PEX0_STN7_TX_DN<126>")
	)
	(gr_poly
		(pts
			(arc
				(start 41.803066 -311.099962)
				(mid 41.396666 -311.099962)
				(end 41.803066 -311.099962)
			)
		)
		(stroke
			(width 0)
			(type solid)
		)
		(fill yes)
		(layer "In6.Cu")
		(net "P5E_PEX0_STN7_TX_DP<126>")
	)
	(gr_poly
		(pts
			(arc
				(start 41.803066 -309.199788)
				(mid 41.396666 -309.199788)
				(end 41.803066 -309.199788)
			)
		)
		(stroke
			(width 0)
			(type solid)
		)
		(fill yes)
		(layer "In6.Cu")
		(net "P5E_PEX0_STN7_TX_DN<120>")
	)
	(gr_poly
		(pts
			(arc
				(start 41.803066 -307.299868)
				(mid 41.396666 -307.299868)
				(end 41.803066 -307.299868)
			)
		)
		(stroke
			(width 0)
			(type solid)
		)
		(fill yes)
		(layer "In6.Cu")
		(net "P5E_PEX0_STN7_TX_DN<118>")
	)
	(gr_poly
		(pts
			(arc
				(start 41.803066 -305.399948)
				(mid 41.396666 -305.399948)
				(end 41.803066 -305.399948)
			)
		)
		(stroke
			(width 0)
			(type solid)
		)
		(fill yes)
		(layer "In6.Cu")
		(net "P5E_PEX0_STN7_TX_DN<116>")
	)
	(gr_poly
		(pts
			(arc
				(start 41.803066 -303.499774)
				(mid 41.396666 -303.499774)
				(end 41.803066 -303.499774)
			)
		)
		(stroke
			(width 0)
			(type solid)
		)
		(fill yes)
		(layer "In6.Cu")
		(net "P5E_PEX0_STN7_TX_DN<114>")
	)
	(gr_poly
		(pts
			(arc
				(start 41.803066 -301.599854)
				(mid 41.396666 -301.599854)
				(end 41.803066 -301.599854)
			)
		)
		(stroke
			(width 0)
			(type solid)
		)
		(fill yes)
		(layer "In6.Cu")
		(net "P5E_PEX0_STN7_TX_DN<112>")
	)
	(gr_poly
		(pts
			(arc
				(start 42.753026 -313.949842)
				(mid 42.346626 -313.949842)
				(end 42.753026 -313.949842)
			)
		)
		(stroke
			(width 0)
			(type solid)
		)
		(fill yes)
		(layer "In6.Cu")
		(net "P5E_PEX0_STN7_TX_DN<127>")
	)
	(gr_poly
		(pts
			(arc
				(start 42.753026 -312.999882)
				(mid 42.346626 -312.999882)
				(end 42.753026 -312.999882)
			)
		)
		(stroke
			(width 0)
			(type solid)
		)
		(fill yes)
		(layer "In6.Cu")
		(net "P5E_PEX0_STN7_TX_DP<127>")
	)
	(gr_poly
		(pts
			(arc
				(start 42.753026 -309.199788)
				(mid 42.346626 -309.199788)
				(end 42.753026 -309.199788)
			)
		)
		(stroke
			(width 0)
			(type solid)
		)
		(fill yes)
		(layer "In6.Cu")
		(net "P5E_PEX0_STN7_TX_DP<120>")
	)
	(gr_poly
		(pts
			(arc
				(start 42.753026 -307.299868)
				(mid 42.346626 -307.299868)
				(end 42.753026 -307.299868)
			)
		)
		(stroke
			(width 0)
			(type solid)
		)
		(fill yes)
		(layer "In6.Cu")
		(net "P5E_PEX0_STN7_TX_DP<118>")
	)
	(gr_poly
		(pts
			(arc
				(start 42.753026 -305.399948)
				(mid 42.346626 -305.399948)
				(end 42.753026 -305.399948)
			)
		)
		(stroke
			(width 0)
			(type solid)
		)
		(fill yes)
		(layer "In6.Cu")
		(net "P5E_PEX0_STN7_TX_DP<116>")
	)
	(gr_poly
		(pts
			(arc
				(start 42.753026 -303.499774)
				(mid 42.346626 -303.499774)
				(end 42.753026 -303.499774)
			)
		)
		(stroke
			(width 0)
			(type solid)
		)
		(fill yes)
		(layer "In6.Cu")
		(net "P5E_PEX0_STN7_TX_DP<114>")
	)
	(gr_poly
		(pts
			(arc
				(start 42.753026 -301.599854)
				(mid 42.346626 -301.599854)
				(end 42.753026 -301.599854)
			)
		)
		(stroke
			(width 0)
			(type solid)
		)
		(fill yes)
		(layer "In6.Cu")
		(net "P5E_PEX0_STN7_TX_DP<112>")
	)
	(gr_poly
		(pts
			(arc
				(start 43.702986 -312.049922)
				(mid 43.296586 -312.049922)
				(end 43.702986 -312.049922)
			)
		)
		(stroke
			(width 0)
			(type solid)
		)
		(fill yes)
		(layer "In6.Cu")
		(net "P5E_PEX0_STN6_TX_DN<111>")
	)
	(gr_poly
		(pts
			(arc
				(start 43.702986 -311.099962)
				(mid 43.296586 -311.099962)
				(end 43.702986 -311.099962)
			)
		)
		(stroke
			(width 0)
			(type solid)
		)
		(fill yes)
		(layer "In6.Cu")
		(net "P5E_PEX0_STN6_TX_DP<111>")
	)
	(gr_poly
		(pts
			(arc
				(start 43.702986 -308.249828)
				(mid 43.296586 -308.249828)
				(end 43.702986 -308.249828)
			)
		)
		(stroke
			(width 0)
			(type solid)
		)
		(fill yes)
		(layer "In6.Cu")
		(net "P5E_PEX0_STN7_TX_DN<119>")
	)
	(gr_poly
		(pts
			(arc
				(start 43.702986 -306.349908)
				(mid 43.296586 -306.349908)
				(end 43.702986 -306.349908)
			)
		)
		(stroke
			(width 0)
			(type solid)
		)
		(fill yes)
		(layer "In6.Cu")
		(net "P5E_PEX0_STN7_TX_DN<117>")
	)
	(gr_poly
		(pts
			(arc
				(start 43.702986 -304.449734)
				(mid 43.296586 -304.449734)
				(end 43.702986 -304.449734)
			)
		)
		(stroke
			(width 0)
			(type solid)
		)
		(fill yes)
		(layer "In6.Cu")
		(net "P5E_PEX0_STN7_TX_DN<115>")
	)
	(gr_poly
		(pts
			(arc
				(start 43.702986 -302.549814)
				(mid 43.296586 -302.549814)
				(end 43.702986 -302.549814)
			)
		)
		(stroke
			(width 0)
			(type solid)
		)
		(fill yes)
		(layer "In6.Cu")
		(net "P5E_PEX0_STN7_TX_DN<113>")
	)
	(gr_poly
		(pts
			(arc
				(start 44.652946 -313.949842)
				(mid 44.246546 -313.949842)
				(end 44.652946 -313.949842)
			)
		)
		(stroke
			(width 0)
			(type solid)
		)
		(fill yes)
		(layer "In6.Cu")
		(net "P5E_PEX0_STN6_TX_DN<110>")
	)
	(gr_poly
		(pts
			(arc
				(start 44.652946 -312.999882)
				(mid 44.246546 -312.999882)
				(end 44.652946 -312.999882)
			)
		)
		(stroke
			(width 0)
			(type solid)
		)
		(fill yes)
		(layer "In6.Cu")
		(net "P5E_PEX0_STN6_TX_DP<110>")
	)
	(gr_poly
		(pts
			(arc
				(start 44.652946 -308.249828)
				(mid 44.246546 -308.249828)
				(end 44.652946 -308.249828)
			)
		)
		(stroke
			(width 0)
			(type solid)
		)
		(fill yes)
		(layer "In6.Cu")
		(net "P5E_PEX0_STN7_TX_DP<119>")
	)
	(gr_poly
		(pts
			(arc
				(start 44.652946 -306.349908)
				(mid 44.246546 -306.349908)
				(end 44.652946 -306.349908)
			)
		)
		(stroke
			(width 0)
			(type solid)
		)
		(fill yes)
		(layer "In6.Cu")
		(net "P5E_PEX0_STN7_TX_DP<117>")
	)
	(gr_poly
		(pts
			(arc
				(start 44.652946 -304.449734)
				(mid 44.246546 -304.449734)
				(end 44.652946 -304.449734)
			)
		)
		(stroke
			(width 0)
			(type solid)
		)
		(fill yes)
		(layer "In6.Cu")
		(net "P5E_PEX0_STN7_TX_DP<115>")
	)
	(gr_poly
		(pts
			(arc
				(start 44.652946 -302.549814)
				(mid 44.246546 -302.549814)
				(end 44.652946 -302.549814)
			)
		)
		(stroke
			(width 0)
			(type solid)
		)
		(fill yes)
		(layer "In6.Cu")
		(net "P5E_PEX0_STN7_TX_DP<113>")
	)
	(gr_poly
		(pts
			(arc
				(start 44.652946 -278.799798)
				(mid 44.246546 -278.799798)
				(end 44.652946 -278.799798)
			)
		)
		(stroke
			(width 0)
			(type solid)
		)
		(fill yes)
		(layer "In6.Cu")
		(net "P5E_PEX0_STN2_TX_DP<47>")
	)
	(gr_poly
		(pts
			(arc
				(start 44.652946 -277.849838)
				(mid 44.246546 -277.849838)
				(end 44.652946 -277.849838)
			)
		)
		(stroke
			(width 0)
			(type solid)
		)
		(fill yes)
		(layer "In6.Cu")
		(net "P5E_PEX0_STN2_TX_DN<47>")
	)
	(gr_poly
		(pts
			(arc
				(start 44.652946 -274.049744)
				(mid 44.246546 -274.049744)
				(end 44.652946 -274.049744)
			)
		)
		(stroke
			(width 0)
			(type solid)
		)
		(fill yes)
		(layer "In6.Cu")
		(net "P5E_PEX0_STN2_RX_DP<47>")
	)
	(gr_poly
		(pts
			(arc
				(start 44.652946 -273.099784)
				(mid 44.246546 -273.099784)
				(end 44.652946 -273.099784)
			)
		)
		(stroke
			(width 0)
			(type solid)
		)
		(fill yes)
		(layer "In6.Cu")
		(net "P5E_PEX0_STN2_RX_DN<47>")
	)
	(gr_poly
		(pts
			(arc
				(start 45.60316 -312.049922)
				(mid 45.19676 -312.049922)
				(end 45.60316 -312.049922)
			)
		)
		(stroke
			(width 0)
			(type solid)
		)
		(fill yes)
		(layer "In6.Cu")
		(net "P5E_PEX0_STN6_TX_DN<109>")
	)
	(gr_poly
		(pts
			(arc
				(start 45.60316 -311.099962)
				(mid 45.19676 -311.099962)
				(end 45.60316 -311.099962)
			)
		)
		(stroke
			(width 0)
			(type solid)
		)
		(fill yes)
		(layer "In6.Cu")
		(net "P5E_PEX0_STN6_TX_DP<109>")
	)
	(gr_poly
		(pts
			(arc
				(start 45.60316 -280.699718)
				(mid 45.19676 -280.699718)
				(end 45.60316 -280.699718)
			)
		)
		(stroke
			(width 0)
			(type solid)
		)
		(fill yes)
		(layer "In6.Cu")
		(net "P5E_PEX0_STN2_TX_DP<46>")
	)
	(gr_poly
		(pts
			(arc
				(start 45.60316 -279.749504)
				(mid 45.19676 -279.749504)
				(end 45.60316 -279.749504)
			)
		)
		(stroke
			(width 0)
			(type solid)
		)
		(fill yes)
		(layer "In6.Cu")
		(net "P5E_PEX0_STN2_TX_DN<46>")
	)
	(gr_poly
		(pts
			(arc
				(start 45.60316 -275.949918)
				(mid 45.19676 -275.949918)
				(end 45.60316 -275.949918)
			)
		)
		(stroke
			(width 0)
			(type solid)
		)
		(fill yes)
		(layer "In6.Cu")
		(net "P5E_PEX0_STN2_RX_DP<46>")
	)
	(gr_poly
		(pts
			(arc
				(start 45.60316 -274.999958)
				(mid 45.19676 -274.999958)
				(end 45.60316 -274.999958)
			)
		)
		(stroke
			(width 0)
			(type solid)
		)
		(fill yes)
		(layer "In6.Cu")
		(net "P5E_PEX0_STN2_RX_DN<46>")
	)
	(gr_poly
		(pts
			(arc
				(start 46.55312 -313.949842)
				(mid 46.14672 -313.949842)
				(end 46.55312 -313.949842)
			)
		)
		(stroke
			(width 0)
			(type solid)
		)
		(fill yes)
		(layer "In6.Cu")
		(net "P5E_PEX0_STN6_TX_DN<108>")
	)
	(gr_poly
		(pts
			(arc
				(start 46.55312 -312.999882)
				(mid 46.14672 -312.999882)
				(end 46.55312 -312.999882)
			)
		)
		(stroke
			(width 0)
			(type solid)
		)
		(fill yes)
		(layer "In6.Cu")
		(net "P5E_PEX0_STN6_TX_DP<108>")
	)
	(gr_poly
		(pts
			(arc
				(start 46.55312 -278.799798)
				(mid 46.14672 -278.799798)
				(end 46.55312 -278.799798)
			)
		)
		(stroke
			(width 0)
			(type solid)
		)
		(fill yes)
		(layer "In6.Cu")
		(net "P5E_PEX0_STN2_TX_DP<45>")
	)
	(gr_poly
		(pts
			(arc
				(start 46.55312 -277.849838)
				(mid 46.14672 -277.849838)
				(end 46.55312 -277.849838)
			)
		)
		(stroke
			(width 0)
			(type solid)
		)
		(fill yes)
		(layer "In6.Cu")
		(net "P5E_PEX0_STN2_TX_DN<45>")
	)
	(gr_poly
		(pts
			(arc
				(start 46.55312 -274.049744)
				(mid 46.14672 -274.049744)
				(end 46.55312 -274.049744)
			)
		)
		(stroke
			(width 0)
			(type solid)
		)
		(fill yes)
		(layer "In6.Cu")
		(net "P5E_PEX0_STN2_RX_DP<45>")
	)
	(gr_poly
		(pts
			(arc
				(start 46.55312 -273.099784)
				(mid 46.14672 -273.099784)
				(end 46.55312 -273.099784)
			)
		)
		(stroke
			(width 0)
			(type solid)
		)
		(fill yes)
		(layer "In6.Cu")
		(net "P5E_PEX0_STN2_RX_DN<45>")
	)
	(gr_poly
		(pts
			(arc
				(start 47.50308 -312.049922)
				(mid 47.09668 -312.049922)
				(end 47.50308 -312.049922)
			)
		)
		(stroke
			(width 0)
			(type solid)
		)
		(fill yes)
		(layer "In6.Cu")
		(net "P5E_PEX0_STN6_TX_DN<107>")
	)
	(gr_poly
		(pts
			(arc
				(start 47.50308 -311.099962)
				(mid 47.09668 -311.099962)
				(end 47.50308 -311.099962)
			)
		)
		(stroke
			(width 0)
			(type solid)
		)
		(fill yes)
		(layer "In6.Cu")
		(net "P5E_PEX0_STN6_TX_DP<107>")
	)
	(gr_poly
		(pts
			(arc
				(start 47.50308 -280.699718)
				(mid 47.09668 -280.699718)
				(end 47.50308 -280.699718)
			)
		)
		(stroke
			(width 0)
			(type solid)
		)
		(fill yes)
		(layer "In6.Cu")
		(net "P5E_PEX0_STN2_TX_DP<44>")
	)
	(gr_poly
		(pts
			(arc
				(start 47.50308 -279.749504)
				(mid 47.09668 -279.749504)
				(end 47.50308 -279.749504)
			)
		)
		(stroke
			(width 0)
			(type solid)
		)
		(fill yes)
		(layer "In6.Cu")
		(net "P5E_PEX0_STN2_TX_DN<44>")
	)
	(gr_poly
		(pts
			(arc
				(start 47.50308 -275.949918)
				(mid 47.09668 -275.949918)
				(end 47.50308 -275.949918)
			)
		)
		(stroke
			(width 0)
			(type solid)
		)
		(fill yes)
		(layer "In6.Cu")
		(net "P5E_PEX0_STN2_RX_DP<44>")
	)
	(gr_poly
		(pts
			(arc
				(start 47.50308 -274.999958)
				(mid 47.09668 -274.999958)
				(end 47.50308 -274.999958)
			)
		)
		(stroke
			(width 0)
			(type solid)
		)
		(fill yes)
		(layer "In6.Cu")
		(net "P5E_PEX0_STN2_RX_DN<44>")
	)
	(gr_poly
		(pts
			(arc
				(start 48.45304 -313.949842)
				(mid 48.04664 -313.949842)
				(end 48.45304 -313.949842)
			)
		)
		(stroke
			(width 0)
			(type solid)
		)
		(fill yes)
		(layer "In6.Cu")
		(net "P5E_PEX0_STN6_TX_DN<106>")
	)
	(gr_poly
		(pts
			(arc
				(start 48.45304 -312.999882)
				(mid 48.04664 -312.999882)
				(end 48.45304 -312.999882)
			)
		)
		(stroke
			(width 0)
			(type solid)
		)
		(fill yes)
		(layer "In6.Cu")
		(net "P5E_PEX0_STN6_TX_DP<106>")
	)
	(gr_poly
		(pts
			(arc
				(start 48.45304 -278.799798)
				(mid 48.04664 -278.799798)
				(end 48.45304 -278.799798)
			)
		)
		(stroke
			(width 0)
			(type solid)
		)
		(fill yes)
		(layer "In6.Cu")
		(net "P5E_PEX0_STN2_TX_DP<43>")
	)
	(gr_poly
		(pts
			(arc
				(start 48.45304 -277.849838)
				(mid 48.04664 -277.849838)
				(end 48.45304 -277.849838)
			)
		)
		(stroke
			(width 0)
			(type solid)
		)
		(fill yes)
		(layer "In6.Cu")
		(net "P5E_PEX0_STN2_TX_DN<43>")
	)
	(gr_poly
		(pts
			(arc
				(start 48.45304 -274.049744)
				(mid 48.04664 -274.049744)
				(end 48.45304 -274.049744)
			)
		)
		(stroke
			(width 0)
			(type solid)
		)
		(fill yes)
		(layer "In6.Cu")
		(net "P5E_PEX0_STN2_RX_DP<43>")
	)
	(gr_poly
		(pts
			(arc
				(start 48.45304 -273.099784)
				(mid 48.04664 -273.099784)
				(end 48.45304 -273.099784)
			)
		)
		(stroke
			(width 0)
			(type solid)
		)
		(fill yes)
		(layer "In6.Cu")
		(net "P5E_PEX0_STN2_RX_DN<43>")
	)
	(gr_poly
		(pts
			(arc
				(start 49.403 -312.049922)
				(mid 48.9966 -312.049922)
				(end 49.403 -312.049922)
			)
		)
		(stroke
			(width 0)
			(type solid)
		)
		(fill yes)
		(layer "In6.Cu")
		(net "P5E_PEX0_STN6_TX_DN<105>")
	)
	(gr_poly
		(pts
			(arc
				(start 49.403 -311.099962)
				(mid 48.9966 -311.099962)
				(end 49.403 -311.099962)
			)
		)
		(stroke
			(width 0)
			(type solid)
		)
		(fill yes)
		(layer "In6.Cu")
		(net "P5E_PEX0_STN6_TX_DP<105>")
	)
	(gr_poly
		(pts
			(arc
				(start 49.403 -280.699718)
				(mid 48.9966 -280.699718)
				(end 49.403 -280.699718)
			)
		)
		(stroke
			(width 0)
			(type solid)
		)
		(fill yes)
		(layer "In6.Cu")
		(net "P5E_PEX0_STN2_TX_DP<42>")
	)
	(gr_poly
		(pts
			(arc
				(start 49.403 -279.749504)
				(mid 48.9966 -279.749504)
				(end 49.403 -279.749504)
			)
		)
		(stroke
			(width 0)
			(type solid)
		)
		(fill yes)
		(layer "In6.Cu")
		(net "P5E_PEX0_STN2_TX_DN<42>")
	)
	(gr_poly
		(pts
			(arc
				(start 49.403 -275.949918)
				(mid 48.9966 -275.949918)
				(end 49.403 -275.949918)
			)
		)
		(stroke
			(width 0)
			(type solid)
		)
		(fill yes)
		(layer "In6.Cu")
		(net "P5E_PEX0_STN2_RX_DP<42>")
	)
	(gr_poly
		(pts
			(arc
				(start 49.403 -274.999958)
				(mid 48.9966 -274.999958)
				(end 49.403 -274.999958)
			)
		)
		(stroke
			(width 0)
			(type solid)
		)
		(fill yes)
		(layer "In6.Cu")
		(net "P5E_PEX0_STN2_RX_DN<42>")
	)
	(gr_poly
		(pts
			(arc
				(start 50.35296 -313.949842)
				(mid 49.94656 -313.949842)
				(end 50.35296 -313.949842)
			)
		)
		(stroke
			(width 0)
			(type solid)
		)
		(fill yes)
		(layer "In6.Cu")
		(net "P5E_PEX0_STN6_TX_DN<104>")
	)
	(gr_poly
		(pts
			(arc
				(start 50.35296 -312.999882)
				(mid 49.94656 -312.999882)
				(end 50.35296 -312.999882)
			)
		)
		(stroke
			(width 0)
			(type solid)
		)
		(fill yes)
		(layer "In6.Cu")
		(net "P5E_PEX0_STN6_TX_DP<104>")
	)
	(gr_poly
		(pts
			(arc
				(start 50.35296 -278.799798)
				(mid 49.94656 -278.799798)
				(end 50.35296 -278.799798)
			)
		)
		(stroke
			(width 0)
			(type solid)
		)
		(fill yes)
		(layer "In6.Cu")
		(net "P5E_PEX0_STN2_TX_DP<41>")
	)
	(gr_poly
		(pts
			(arc
				(start 50.35296 -277.849838)
				(mid 49.94656 -277.849838)
				(end 50.35296 -277.849838)
			)
		)
		(stroke
			(width 0)
			(type solid)
		)
		(fill yes)
		(layer "In6.Cu")
		(net "P5E_PEX0_STN2_TX_DN<41>")
	)
	(gr_poly
		(pts
			(arc
				(start 50.35296 -274.049744)
				(mid 49.94656 -274.049744)
				(end 50.35296 -274.049744)
			)
		)
		(stroke
			(width 0)
			(type solid)
		)
		(fill yes)
		(layer "In6.Cu")
		(net "P5E_PEX0_STN2_RX_DP<41>")
	)
	(gr_poly
		(pts
			(arc
				(start 50.35296 -273.099784)
				(mid 49.94656 -273.099784)
				(end 50.35296 -273.099784)
			)
		)
		(stroke
			(width 0)
			(type solid)
		)
		(fill yes)
		(layer "In6.Cu")
		(net "P5E_PEX0_STN2_RX_DN<41>")
	)
	(gr_poly
		(pts
			(arc
				(start 51.303174 -316.799722)
				(mid 50.896774 -316.799722)
				(end 51.303174 -316.799722)
			)
		)
		(stroke
			(width 0)
			(type solid)
		)
		(fill yes)
		(layer "In6.Cu")
		(net "P5E_PEX0_STN6_RX_DN<103>")
	)
	(gr_poly
		(pts
			(arc
				(start 51.303174 -315.849762)
				(mid 50.896774 -315.849762)
				(end 51.303174 -315.849762)
			)
		)
		(stroke
			(width 0)
			(type solid)
		)
		(fill yes)
		(layer "In6.Cu")
		(net "P5E_PEX0_STN6_RX_DP<103>")
	)
	(gr_poly
		(pts
			(arc
				(start 51.303174 -312.049922)
				(mid 50.896774 -312.049922)
				(end 51.303174 -312.049922)
			)
		)
		(stroke
			(width 0)
			(type solid)
		)
		(fill yes)
		(layer "In6.Cu")
		(net "P5E_PEX0_STN6_TX_DN<103>")
	)
	(gr_poly
		(pts
			(arc
				(start 51.303174 -311.099962)
				(mid 50.896774 -311.099962)
				(end 51.303174 -311.099962)
			)
		)
		(stroke
			(width 0)
			(type solid)
		)
		(fill yes)
		(layer "In6.Cu")
		(net "P5E_PEX0_STN6_TX_DP<103>")
	)
	(gr_poly
		(pts
			(arc
				(start 51.303174 -280.699718)
				(mid 50.896774 -280.699718)
				(end 51.303174 -280.699718)
			)
		)
		(stroke
			(width 0)
			(type solid)
		)
		(fill yes)
		(layer "In6.Cu")
		(net "P5E_PEX0_STN2_TX_DP<40>")
	)
	(gr_poly
		(pts
			(arc
				(start 51.303174 -279.749504)
				(mid 50.896774 -279.749504)
				(end 51.303174 -279.749504)
			)
		)
		(stroke
			(width 0)
			(type solid)
		)
		(fill yes)
		(layer "In6.Cu")
		(net "P5E_PEX0_STN2_TX_DN<40>")
	)
	(gr_poly
		(pts
			(arc
				(start 51.303174 -275.949918)
				(mid 50.896774 -275.949918)
				(end 51.303174 -275.949918)
			)
		)
		(stroke
			(width 0)
			(type solid)
		)
		(fill yes)
		(layer "In6.Cu")
		(net "P5E_PEX0_STN2_RX_DP<40>")
	)
	(gr_poly
		(pts
			(arc
				(start 51.303174 -274.999958)
				(mid 50.896774 -274.999958)
				(end 51.303174 -274.999958)
			)
		)
		(stroke
			(width 0)
			(type solid)
		)
		(fill yes)
		(layer "In6.Cu")
		(net "P5E_PEX0_STN2_RX_DN<40>")
	)
	(gr_poly
		(pts
			(arc
				(start 52.253134 -318.699896)
				(mid 51.846734 -318.699896)
				(end 52.253134 -318.699896)
			)
		)
		(stroke
			(width 0)
			(type solid)
		)
		(fill yes)
		(layer "In6.Cu")
		(net "P5E_PEX0_STN6_RX_DN<102>")
	)
	(gr_poly
		(pts
			(arc
				(start 52.253134 -317.749936)
				(mid 51.846734 -317.749936)
				(end 52.253134 -317.749936)
			)
		)
		(stroke
			(width 0)
			(type solid)
		)
		(fill yes)
		(layer "In6.Cu")
		(net "P5E_PEX0_STN6_RX_DP<102>")
	)
	(gr_poly
		(pts
			(arc
				(start 52.253134 -313.949842)
				(mid 51.846734 -313.949842)
				(end 52.253134 -313.949842)
			)
		)
		(stroke
			(width 0)
			(type solid)
		)
		(fill yes)
		(layer "In6.Cu")
		(net "P5E_PEX0_STN6_TX_DN<102>")
	)
	(gr_poly
		(pts
			(arc
				(start 52.253134 -312.999882)
				(mid 51.846734 -312.999882)
				(end 52.253134 -312.999882)
			)
		)
		(stroke
			(width 0)
			(type solid)
		)
		(fill yes)
		(layer "In6.Cu")
		(net "P5E_PEX0_STN6_TX_DP<102>")
	)
	(gr_poly
		(pts
			(arc
				(start 52.253134 -278.799798)
				(mid 51.846734 -278.799798)
				(end 52.253134 -278.799798)
			)
		)
		(stroke
			(width 0)
			(type solid)
		)
		(fill yes)
		(layer "In6.Cu")
		(net "P5E_PEX0_STN2_TX_DP<39>")
	)
	(gr_poly
		(pts
			(arc
				(start 52.253134 -277.849838)
				(mid 51.846734 -277.849838)
				(end 52.253134 -277.849838)
			)
		)
		(stroke
			(width 0)
			(type solid)
		)
		(fill yes)
		(layer "In6.Cu")
		(net "P5E_PEX0_STN2_TX_DN<39>")
	)
	(gr_poly
		(pts
			(arc
				(start 52.253134 -274.049744)
				(mid 51.846734 -274.049744)
				(end 52.253134 -274.049744)
			)
		)
		(stroke
			(width 0)
			(type solid)
		)
		(fill yes)
		(layer "In6.Cu")
		(net "P5E_PEX0_STN2_RX_DP<39>")
	)
	(gr_poly
		(pts
			(arc
				(start 52.253134 -273.099784)
				(mid 51.846734 -273.099784)
				(end 52.253134 -273.099784)
			)
		)
		(stroke
			(width 0)
			(type solid)
		)
		(fill yes)
		(layer "In6.Cu")
		(net "P5E_PEX0_STN2_RX_DN<39>")
	)
	(gr_poly
		(pts
			(arc
				(start 53.203094 -316.799722)
				(mid 52.796694 -316.799722)
				(end 53.203094 -316.799722)
			)
		)
		(stroke
			(width 0)
			(type solid)
		)
		(fill yes)
		(layer "In6.Cu")
		(net "P5E_PEX0_STN6_RX_DN<101>")
	)
	(gr_poly
		(pts
			(arc
				(start 53.203094 -315.849762)
				(mid 52.796694 -315.849762)
				(end 53.203094 -315.849762)
			)
		)
		(stroke
			(width 0)
			(type solid)
		)
		(fill yes)
		(layer "In6.Cu")
		(net "P5E_PEX0_STN6_RX_DP<101>")
	)
	(gr_poly
		(pts
			(arc
				(start 53.203094 -312.049922)
				(mid 52.796694 -312.049922)
				(end 53.203094 -312.049922)
			)
		)
		(stroke
			(width 0)
			(type solid)
		)
		(fill yes)
		(layer "In6.Cu")
		(net "P5E_PEX0_STN6_TX_DN<101>")
	)
	(gr_poly
		(pts
			(arc
				(start 53.203094 -311.099962)
				(mid 52.796694 -311.099962)
				(end 53.203094 -311.099962)
			)
		)
		(stroke
			(width 0)
			(type solid)
		)
		(fill yes)
		(layer "In6.Cu")
		(net "P5E_PEX0_STN6_TX_DP<101>")
	)
	(gr_poly
		(pts
			(arc
				(start 53.203094 -280.699718)
				(mid 52.796694 -280.699718)
				(end 53.203094 -280.699718)
			)
		)
		(stroke
			(width 0)
			(type solid)
		)
		(fill yes)
		(layer "In6.Cu")
		(net "P5E_PEX0_STN2_TX_DP<38>")
	)
	(gr_poly
		(pts
			(arc
				(start 53.203094 -279.749504)
				(mid 52.796694 -279.749504)
				(end 53.203094 -279.749504)
			)
		)
		(stroke
			(width 0)
			(type solid)
		)
		(fill yes)
		(layer "In6.Cu")
		(net "P5E_PEX0_STN2_TX_DN<38>")
	)
	(gr_poly
		(pts
			(arc
				(start 53.203094 -275.949918)
				(mid 52.796694 -275.949918)
				(end 53.203094 -275.949918)
			)
		)
		(stroke
			(width 0)
			(type solid)
		)
		(fill yes)
		(layer "In6.Cu")
		(net "P5E_PEX0_STN2_RX_DP<38>")
	)
	(gr_poly
		(pts
			(arc
				(start 53.203094 -274.999958)
				(mid 52.796694 -274.999958)
				(end 53.203094 -274.999958)
			)
		)
		(stroke
			(width 0)
			(type solid)
		)
		(fill yes)
		(layer "In6.Cu")
		(net "P5E_PEX0_STN2_RX_DN<38>")
	)
	(gr_poly
		(pts
			(arc
				(start 54.153054 -318.699896)
				(mid 53.746654 -318.699896)
				(end 54.153054 -318.699896)
			)
		)
		(stroke
			(width 0)
			(type solid)
		)
		(fill yes)
		(layer "In6.Cu")
		(net "P5E_PEX0_STN6_RX_DN<100>")
	)
	(gr_poly
		(pts
			(arc
				(start 54.153054 -317.749936)
				(mid 53.746654 -317.749936)
				(end 54.153054 -317.749936)
			)
		)
		(stroke
			(width 0)
			(type solid)
		)
		(fill yes)
		(layer "In6.Cu")
		(net "P5E_PEX0_STN6_RX_DP<100>")
	)
	(gr_poly
		(pts
			(arc
				(start 54.153054 -313.949842)
				(mid 53.746654 -313.949842)
				(end 54.153054 -313.949842)
			)
		)
		(stroke
			(width 0)
			(type solid)
		)
		(fill yes)
		(layer "In6.Cu")
		(net "P5E_PEX0_STN6_TX_DN<100>")
	)
	(gr_poly
		(pts
			(arc
				(start 54.153054 -312.999882)
				(mid 53.746654 -312.999882)
				(end 54.153054 -312.999882)
			)
		)
		(stroke
			(width 0)
			(type solid)
		)
		(fill yes)
		(layer "In6.Cu")
		(net "P5E_PEX0_STN6_TX_DP<100>")
	)
	(gr_poly
		(pts
			(arc
				(start 54.153054 -278.799798)
				(mid 53.746654 -278.799798)
				(end 54.153054 -278.799798)
			)
		)
		(stroke
			(width 0)
			(type solid)
		)
		(fill yes)
		(layer "In6.Cu")
		(net "P5E_PEX0_STN2_TX_DP<37>")
	)
	(gr_poly
		(pts
			(arc
				(start 54.153054 -277.849838)
				(mid 53.746654 -277.849838)
				(end 54.153054 -277.849838)
			)
		)
		(stroke
			(width 0)
			(type solid)
		)
		(fill yes)
		(layer "In6.Cu")
		(net "P5E_PEX0_STN2_TX_DN<37>")
	)
	(gr_poly
		(pts
			(arc
				(start 54.153054 -274.049744)
				(mid 53.746654 -274.049744)
				(end 54.153054 -274.049744)
			)
		)
		(stroke
			(width 0)
			(type solid)
		)
		(fill yes)
		(layer "In6.Cu")
		(net "P5E_PEX0_STN2_RX_DP<37>")
	)
	(gr_poly
		(pts
			(arc
				(start 54.153054 -273.099784)
				(mid 53.746654 -273.099784)
				(end 54.153054 -273.099784)
			)
		)
		(stroke
			(width 0)
			(type solid)
		)
		(fill yes)
		(layer "In6.Cu")
		(net "P5E_PEX0_STN2_RX_DN<37>")
	)
	(gr_poly
		(pts
			(arc
				(start 55.103014 -316.799722)
				(mid 54.696614 -316.799722)
				(end 55.103014 -316.799722)
			)
		)
		(stroke
			(width 0)
			(type solid)
		)
		(fill yes)
		(layer "In6.Cu")
		(net "P5E_PEX0_STN6_RX_DN<99>")
	)
	(gr_poly
		(pts
			(arc
				(start 55.103014 -315.849762)
				(mid 54.696614 -315.849762)
				(end 55.103014 -315.849762)
			)
		)
		(stroke
			(width 0)
			(type solid)
		)
		(fill yes)
		(layer "In6.Cu")
		(net "P5E_PEX0_STN6_RX_DP<99>")
	)
	(gr_poly
		(pts
			(arc
				(start 55.103014 -312.049922)
				(mid 54.696614 -312.049922)
				(end 55.103014 -312.049922)
			)
		)
		(stroke
			(width 0)
			(type solid)
		)
		(fill yes)
		(layer "In6.Cu")
		(net "P5E_PEX0_STN6_TX_DN<99>")
	)
	(gr_poly
		(pts
			(arc
				(start 55.103014 -311.099962)
				(mid 54.696614 -311.099962)
				(end 55.103014 -311.099962)
			)
		)
		(stroke
			(width 0)
			(type solid)
		)
		(fill yes)
		(layer "In6.Cu")
		(net "P5E_PEX0_STN6_TX_DP<99>")
	)
	(gr_poly
		(pts
			(arc
				(start 55.103014 -280.699718)
				(mid 54.696614 -280.699718)
				(end 55.103014 -280.699718)
			)
		)
		(stroke
			(width 0)
			(type solid)
		)
		(fill yes)
		(layer "In6.Cu")
		(net "P5E_PEX0_STN2_TX_DP<36>")
	)
	(gr_poly
		(pts
			(arc
				(start 55.103014 -279.749504)
				(mid 54.696614 -279.749504)
				(end 55.103014 -279.749504)
			)
		)
		(stroke
			(width 0)
			(type solid)
		)
		(fill yes)
		(layer "In6.Cu")
		(net "P5E_PEX0_STN2_TX_DN<36>")
	)
	(gr_poly
		(pts
			(arc
				(start 55.103014 -275.949918)
				(mid 54.696614 -275.949918)
				(end 55.103014 -275.949918)
			)
		)
		(stroke
			(width 0)
			(type solid)
		)
		(fill yes)
		(layer "In6.Cu")
		(net "P5E_PEX0_STN2_RX_DP<36>")
	)
	(gr_poly
		(pts
			(arc
				(start 55.103014 -274.999958)
				(mid 54.696614 -274.999958)
				(end 55.103014 -274.999958)
			)
		)
		(stroke
			(width 0)
			(type solid)
		)
		(fill yes)
		(layer "In6.Cu")
		(net "P5E_PEX0_STN2_RX_DN<36>")
	)
	(gr_poly
		(pts
			(arc
				(start 56.052974 -318.699896)
				(mid 55.646574 -318.699896)
				(end 56.052974 -318.699896)
			)
		)
		(stroke
			(width 0)
			(type solid)
		)
		(fill yes)
		(layer "In6.Cu")
		(net "P5E_PEX0_STN6_RX_DN<98>")
	)
	(gr_poly
		(pts
			(arc
				(start 56.052974 -317.749936)
				(mid 55.646574 -317.749936)
				(end 56.052974 -317.749936)
			)
		)
		(stroke
			(width 0)
			(type solid)
		)
		(fill yes)
		(layer "In6.Cu")
		(net "P5E_PEX0_STN6_RX_DP<98>")
	)
	(gr_poly
		(pts
			(arc
				(start 56.052974 -313.949842)
				(mid 55.646574 -313.949842)
				(end 56.052974 -313.949842)
			)
		)
		(stroke
			(width 0)
			(type solid)
		)
		(fill yes)
		(layer "In6.Cu")
		(net "P5E_PEX0_STN6_TX_DN<98>")
	)
	(gr_poly
		(pts
			(arc
				(start 56.052974 -312.999882)
				(mid 55.646574 -312.999882)
				(end 56.052974 -312.999882)
			)
		)
		(stroke
			(width 0)
			(type solid)
		)
		(fill yes)
		(layer "In6.Cu")
		(net "P5E_PEX0_STN6_TX_DP<98>")
	)
	(gr_poly
		(pts
			(arc
				(start 56.052974 -278.799798)
				(mid 55.646574 -278.799798)
				(end 56.052974 -278.799798)
			)
		)
		(stroke
			(width 0)
			(type solid)
		)
		(fill yes)
		(layer "In6.Cu")
		(net "P5E_PEX0_STN2_TX_DP<35>")
	)
	(gr_poly
		(pts
			(arc
				(start 56.052974 -277.849838)
				(mid 55.646574 -277.849838)
				(end 56.052974 -277.849838)
			)
		)
		(stroke
			(width 0)
			(type solid)
		)
		(fill yes)
		(layer "In6.Cu")
		(net "P5E_PEX0_STN2_TX_DN<35>")
	)
	(gr_poly
		(pts
			(arc
				(start 56.052974 -274.049744)
				(mid 55.646574 -274.049744)
				(end 56.052974 -274.049744)
			)
		)
		(stroke
			(width 0)
			(type solid)
		)
		(fill yes)
		(layer "In6.Cu")
		(net "P5E_PEX0_STN2_RX_DP<35>")
	)
	(gr_poly
		(pts
			(arc
				(start 56.052974 -273.099784)
				(mid 55.646574 -273.099784)
				(end 56.052974 -273.099784)
			)
		)
		(stroke
			(width 0)
			(type solid)
		)
		(fill yes)
		(layer "In6.Cu")
		(net "P5E_PEX0_STN2_RX_DN<35>")
	)
	(gr_poly
		(pts
			(arc
				(start 57.002934 -280.699718)
				(mid 56.596534 -280.699718)
				(end 57.002934 -280.699718)
			)
		)
		(stroke
			(width 0)
			(type solid)
		)
		(fill yes)
		(layer "In6.Cu")
		(net "P5E_PEX0_STN2_TX_DP<34>")
	)
	(gr_poly
		(pts
			(arc
				(start 57.002934 -279.749504)
				(mid 56.596534 -279.749504)
				(end 57.002934 -279.749504)
			)
		)
		(stroke
			(width 0)
			(type solid)
		)
		(fill yes)
		(layer "In6.Cu")
		(net "P5E_PEX0_STN2_TX_DN<34>")
	)
	(gr_poly
		(pts
			(arc
				(start 57.003188 -316.799722)
				(mid 56.596788 -316.799722)
				(end 57.003188 -316.799722)
			)
		)
		(stroke
			(width 0)
			(type solid)
		)
		(fill yes)
		(layer "In6.Cu")
		(net "P5E_PEX0_STN6_RX_DN<97>")
	)
	(gr_poly
		(pts
			(arc
				(start 57.003188 -315.849762)
				(mid 56.596788 -315.849762)
				(end 57.003188 -315.849762)
			)
		)
		(stroke
			(width 0)
			(type solid)
		)
		(fill yes)
		(layer "In6.Cu")
		(net "P5E_PEX0_STN6_RX_DP<97>")
	)
	(gr_poly
		(pts
			(arc
				(start 57.003188 -312.049922)
				(mid 56.596788 -312.049922)
				(end 57.003188 -312.049922)
			)
		)
		(stroke
			(width 0)
			(type solid)
		)
		(fill yes)
		(layer "In6.Cu")
		(net "P5E_PEX0_STN6_TX_DN<97>")
	)
	(gr_poly
		(pts
			(arc
				(start 57.003188 -311.099962)
				(mid 56.596788 -311.099962)
				(end 57.003188 -311.099962)
			)
		)
		(stroke
			(width 0)
			(type solid)
		)
		(fill yes)
		(layer "In6.Cu")
		(net "P5E_PEX0_STN6_TX_DP<97>")
	)
	(gr_poly
		(pts
			(arc
				(start 57.003188 -275.949918)
				(mid 56.596788 -275.949918)
				(end 57.003188 -275.949918)
			)
		)
		(stroke
			(width 0)
			(type solid)
		)
		(fill yes)
		(layer "In6.Cu")
		(net "P5E_PEX0_STN2_RX_DP<34>")
	)
	(gr_poly
		(pts
			(arc
				(start 57.003188 -274.999958)
				(mid 56.596788 -274.999958)
				(end 57.003188 -274.999958)
			)
		)
		(stroke
			(width 0)
			(type solid)
		)
		(fill yes)
		(layer "In6.Cu")
		(net "P5E_PEX0_STN2_RX_DN<34>")
	)
	(gr_poly
		(pts
			(arc
				(start 57.953148 -318.699896)
				(mid 57.546748 -318.699896)
				(end 57.953148 -318.699896)
			)
		)
		(stroke
			(width 0)
			(type solid)
		)
		(fill yes)
		(layer "In6.Cu")
		(net "P5E_PEX0_STN6_RX_DN<96>")
	)
	(gr_poly
		(pts
			(arc
				(start 57.953148 -317.749936)
				(mid 57.546748 -317.749936)
				(end 57.953148 -317.749936)
			)
		)
		(stroke
			(width 0)
			(type solid)
		)
		(fill yes)
		(layer "In6.Cu")
		(net "P5E_PEX0_STN6_RX_DP<96>")
	)
	(gr_poly
		(pts
			(arc
				(start 57.953148 -313.949842)
				(mid 57.546748 -313.949842)
				(end 57.953148 -313.949842)
			)
		)
		(stroke
			(width 0)
			(type solid)
		)
		(fill yes)
		(layer "In6.Cu")
		(net "P5E_PEX0_STN6_TX_DN<96>")
	)
	(gr_poly
		(pts
			(arc
				(start 57.953148 -312.999882)
				(mid 57.546748 -312.999882)
				(end 57.953148 -312.999882)
			)
		)
		(stroke
			(width 0)
			(type solid)
		)
		(fill yes)
		(layer "In6.Cu")
		(net "P5E_PEX0_STN6_TX_DP<96>")
	)
	(gr_poly
		(pts
			(arc
				(start 57.953148 -278.799798)
				(mid 57.546748 -278.799798)
				(end 57.953148 -278.799798)
			)
		)
		(stroke
			(width 0)
			(type solid)
		)
		(fill yes)
		(layer "In6.Cu")
		(net "P5E_PEX0_STN2_TX_DP<33>")
	)
	(gr_poly
		(pts
			(arc
				(start 57.953148 -277.849838)
				(mid 57.546748 -277.849838)
				(end 57.953148 -277.849838)
			)
		)
		(stroke
			(width 0)
			(type solid)
		)
		(fill yes)
		(layer "In6.Cu")
		(net "P5E_PEX0_STN2_TX_DN<33>")
	)
	(gr_poly
		(pts
			(arc
				(start 57.953148 -274.049744)
				(mid 57.546748 -274.049744)
				(end 57.953148 -274.049744)
			)
		)
		(stroke
			(width 0)
			(type solid)
		)
		(fill yes)
		(layer "In6.Cu")
		(net "P5E_PEX0_STN2_RX_DP<33>")
	)
	(gr_poly
		(pts
			(arc
				(start 57.953148 -273.099784)
				(mid 57.546748 -273.099784)
				(end 57.953148 -273.099784)
			)
		)
		(stroke
			(width 0)
			(type solid)
		)
		(fill yes)
		(layer "In6.Cu")
		(net "P5E_PEX0_STN2_RX_DN<33>")
	)
	(gr_poly
		(pts
			(arc
				(start 58.903108 -316.799722)
				(mid 58.496708 -316.799722)
				(end 58.903108 -316.799722)
			)
		)
		(stroke
			(width 0)
			(type solid)
		)
		(fill yes)
		(layer "In6.Cu")
		(net "P5E_PEX0_STN5_RX_DN<80>")
	)
	(gr_poly
		(pts
			(arc
				(start 58.903108 -315.849762)
				(mid 58.496708 -315.849762)
				(end 58.903108 -315.849762)
			)
		)
		(stroke
			(width 0)
			(type solid)
		)
		(fill yes)
		(layer "In6.Cu")
		(net "P5E_PEX0_STN5_RX_DP<80>")
	)
	(gr_poly
		(pts
			(arc
				(start 58.903108 -312.049922)
				(mid 58.496708 -312.049922)
				(end 58.903108 -312.049922)
			)
		)
		(stroke
			(width 0)
			(type solid)
		)
		(fill yes)
		(layer "In6.Cu")
		(net "P5E_PEX0_STN5_TX_DN<80>")
	)
	(gr_poly
		(pts
			(arc
				(start 58.903108 -311.099962)
				(mid 58.496708 -311.099962)
				(end 58.903108 -311.099962)
			)
		)
		(stroke
			(width 0)
			(type solid)
		)
		(fill yes)
		(layer "In6.Cu")
		(net "P5E_PEX0_STN5_TX_DP<80>")
	)
	(gr_poly
		(pts
			(arc
				(start 58.903108 -280.699718)
				(mid 58.496708 -280.699718)
				(end 58.903108 -280.699718)
			)
		)
		(stroke
			(width 0)
			(type solid)
		)
		(fill yes)
		(layer "In6.Cu")
		(net "P5E_PEX0_STN2_TX_DP<32>")
	)
	(gr_poly
		(pts
			(arc
				(start 58.903108 -279.749504)
				(mid 58.496708 -279.749504)
				(end 58.903108 -279.749504)
			)
		)
		(stroke
			(width 0)
			(type solid)
		)
		(fill yes)
		(layer "In6.Cu")
		(net "P5E_PEX0_STN2_TX_DN<32>")
	)
	(gr_poly
		(pts
			(arc
				(start 58.903108 -275.949918)
				(mid 58.496708 -275.949918)
				(end 58.903108 -275.949918)
			)
		)
		(stroke
			(width 0)
			(type solid)
		)
		(fill yes)
		(layer "In6.Cu")
		(net "P5E_PEX0_STN2_RX_DP<32>")
	)
	(gr_poly
		(pts
			(arc
				(start 58.903108 -274.999958)
				(mid 58.496708 -274.999958)
				(end 58.903108 -274.999958)
			)
		)
		(stroke
			(width 0)
			(type solid)
		)
		(fill yes)
		(layer "In6.Cu")
		(net "P5E_PEX0_STN2_RX_DN<32>")
	)
	(gr_poly
		(pts
			(arc
				(start 59.852814 -278.799798)
				(mid 59.446414 -278.799798)
				(end 59.852814 -278.799798)
			)
		)
		(stroke
			(width 0)
			(type solid)
		)
		(fill yes)
		(layer "In6.Cu")
		(net "P5E_PEX0_STN1_TX_DP<16>")
	)
	(gr_poly
		(pts
			(arc
				(start 59.852814 -277.849838)
				(mid 59.446414 -277.849838)
				(end 59.852814 -277.849838)
			)
		)
		(stroke
			(width 0)
			(type solid)
		)
		(fill yes)
		(layer "In6.Cu")
		(net "P5E_PEX0_STN1_TX_DN<16>")
	)
	(gr_poly
		(pts
			(arc
				(start 59.853068 -318.699896)
				(mid 59.446668 -318.699896)
				(end 59.853068 -318.699896)
			)
		)
		(stroke
			(width 0)
			(type solid)
		)
		(fill yes)
		(layer "In6.Cu")
		(net "P5E_PEX0_STN5_RX_DN<81>")
	)
	(gr_poly
		(pts
			(arc
				(start 59.853068 -317.749936)
				(mid 59.446668 -317.749936)
				(end 59.853068 -317.749936)
			)
		)
		(stroke
			(width 0)
			(type solid)
		)
		(fill yes)
		(layer "In6.Cu")
		(net "P5E_PEX0_STN5_RX_DP<81>")
	)
	(gr_poly
		(pts
			(arc
				(start 59.853068 -313.949842)
				(mid 59.446668 -313.949842)
				(end 59.853068 -313.949842)
			)
		)
		(stroke
			(width 0)
			(type solid)
		)
		(fill yes)
		(layer "In6.Cu")
		(net "P5E_PEX0_STN5_TX_DN<81>")
	)
	(gr_poly
		(pts
			(arc
				(start 59.853068 -312.999882)
				(mid 59.446668 -312.999882)
				(end 59.853068 -312.999882)
			)
		)
		(stroke
			(width 0)
			(type solid)
		)
		(fill yes)
		(layer "In6.Cu")
		(net "P5E_PEX0_STN5_TX_DP<81>")
	)
	(gr_poly
		(pts
			(arc
				(start 60.803028 -316.799722)
				(mid 60.396628 -316.799722)
				(end 60.803028 -316.799722)
			)
		)
		(stroke
			(width 0)
			(type solid)
		)
		(fill yes)
		(layer "In6.Cu")
		(net "P5E_PEX0_STN5_RX_DN<82>")
	)
	(gr_poly
		(pts
			(arc
				(start 60.803028 -315.849762)
				(mid 60.396628 -315.849762)
				(end 60.803028 -315.849762)
			)
		)
		(stroke
			(width 0)
			(type solid)
		)
		(fill yes)
		(layer "In6.Cu")
		(net "P5E_PEX0_STN5_RX_DP<82>")
	)
	(gr_poly
		(pts
			(arc
				(start 60.803028 -312.049922)
				(mid 60.396628 -312.049922)
				(end 60.803028 -312.049922)
			)
		)
		(stroke
			(width 0)
			(type solid)
		)
		(fill yes)
		(layer "In6.Cu")
		(net "P5E_PEX0_STN5_TX_DN<82>")
	)
	(gr_poly
		(pts
			(arc
				(start 60.803028 -311.099962)
				(mid 60.396628 -311.099962)
				(end 60.803028 -311.099962)
			)
		)
		(stroke
			(width 0)
			(type solid)
		)
		(fill yes)
		(layer "In6.Cu")
		(net "P5E_PEX0_STN5_TX_DP<82>")
	)
	(gr_poly
		(pts
			(arc
				(start 60.803028 -280.699718)
				(mid 60.396628 -280.699718)
				(end 60.803028 -280.699718)
			)
		)
		(stroke
			(width 0)
			(type solid)
		)
		(fill yes)
		(layer "In6.Cu")
		(net "P5E_PEX0_STN1_TX_DN<17>")
	)
	(gr_poly
		(pts
			(arc
				(start 60.803028 -279.749504)
				(mid 60.396628 -279.749504)
				(end 60.803028 -279.749504)
			)
		)
		(stroke
			(width 0)
			(type solid)
		)
		(fill yes)
		(layer "In6.Cu")
		(net "P5E_PEX0_STN1_TX_DP<17>")
	)
	(gr_poly
		(pts
			(arc
				(start 61.752734 -278.799798)
				(mid 61.346334 -278.799798)
				(end 61.752734 -278.799798)
			)
		)
		(stroke
			(width 0)
			(type solid)
		)
		(fill yes)
		(layer "In6.Cu")
		(net "P5E_PEX0_STN1_TX_DP<18>")
	)
	(gr_poly
		(pts
			(arc
				(start 61.752734 -277.849838)
				(mid 61.346334 -277.849838)
				(end 61.752734 -277.849838)
			)
		)
		(stroke
			(width 0)
			(type solid)
		)
		(fill yes)
		(layer "In6.Cu")
		(net "P5E_PEX0_STN1_TX_DN<18>")
	)
	(gr_poly
		(pts
			(arc
				(start 61.752988 -318.699896)
				(mid 61.346588 -318.699896)
				(end 61.752988 -318.699896)
			)
		)
		(stroke
			(width 0)
			(type solid)
		)
		(fill yes)
		(layer "In6.Cu")
		(net "P5E_PEX0_STN5_RX_DN<83>")
	)
	(gr_poly
		(pts
			(arc
				(start 61.752988 -317.749936)
				(mid 61.346588 -317.749936)
				(end 61.752988 -317.749936)
			)
		)
		(stroke
			(width 0)
			(type solid)
		)
		(fill yes)
		(layer "In6.Cu")
		(net "P5E_PEX0_STN5_RX_DP<83>")
	)
	(gr_poly
		(pts
			(arc
				(start 61.752988 -313.949842)
				(mid 61.346588 -313.949842)
				(end 61.752988 -313.949842)
			)
		)
		(stroke
			(width 0)
			(type solid)
		)
		(fill yes)
		(layer "In6.Cu")
		(net "P5E_PEX0_STN5_TX_DN<83>")
	)
	(gr_poly
		(pts
			(arc
				(start 61.752988 -312.999882)
				(mid 61.346588 -312.999882)
				(end 61.752988 -312.999882)
			)
		)
		(stroke
			(width 0)
			(type solid)
		)
		(fill yes)
		(layer "In6.Cu")
		(net "P5E_PEX0_STN5_TX_DP<83>")
	)
	(gr_poly
		(pts
			(arc
				(start 62.702948 -316.799722)
				(mid 62.296548 -316.799722)
				(end 62.702948 -316.799722)
			)
		)
		(stroke
			(width 0)
			(type solid)
		)
		(fill yes)
		(layer "In6.Cu")
		(net "P5E_PEX0_STN5_RX_DN<84>")
	)
	(gr_poly
		(pts
			(arc
				(start 62.702948 -315.849762)
				(mid 62.296548 -315.849762)
				(end 62.702948 -315.849762)
			)
		)
		(stroke
			(width 0)
			(type solid)
		)
		(fill yes)
		(layer "In6.Cu")
		(net "P5E_PEX0_STN5_RX_DP<84>")
	)
	(gr_poly
		(pts
			(arc
				(start 62.702948 -312.049922)
				(mid 62.296548 -312.049922)
				(end 62.702948 -312.049922)
			)
		)
		(stroke
			(width 0)
			(type solid)
		)
		(fill yes)
		(layer "In6.Cu")
		(net "P5E_PEX0_STN5_TX_DN<84>")
	)
	(gr_poly
		(pts
			(arc
				(start 62.702948 -311.099962)
				(mid 62.296548 -311.099962)
				(end 62.702948 -311.099962)
			)
		)
		(stroke
			(width 0)
			(type solid)
		)
		(fill yes)
		(layer "In6.Cu")
		(net "P5E_PEX0_STN5_TX_DP<84>")
	)
	(gr_poly
		(pts
			(arc
				(start 62.702948 -280.699718)
				(mid 62.296548 -280.699718)
				(end 62.702948 -280.699718)
			)
		)
		(stroke
			(width 0)
			(type solid)
		)
		(fill yes)
		(layer "In6.Cu")
		(net "P5E_PEX0_STN1_TX_DN<19>")
	)
	(gr_poly
		(pts
			(arc
				(start 62.702948 -279.749504)
				(mid 62.296548 -279.749504)
				(end 62.702948 -279.749504)
			)
		)
		(stroke
			(width 0)
			(type solid)
		)
		(fill yes)
		(layer "In6.Cu")
		(net "P5E_PEX0_STN1_TX_DP<19>")
	)
	(gr_poly
		(pts
			(arc
				(start 63.652908 -278.799798)
				(mid 63.246508 -278.799798)
				(end 63.652908 -278.799798)
			)
		)
		(stroke
			(width 0)
			(type solid)
		)
		(fill yes)
		(layer "In6.Cu")
		(net "P5E_PEX0_STN1_TX_DP<20>")
	)
	(gr_poly
		(pts
			(arc
				(start 63.652908 -277.849838)
				(mid 63.246508 -277.849838)
				(end 63.652908 -277.849838)
			)
		)
		(stroke
			(width 0)
			(type solid)
		)
		(fill yes)
		(layer "In6.Cu")
		(net "P5E_PEX0_STN1_TX_DN<20>")
	)
	(gr_poly
		(pts
			(arc
				(start 63.653162 -318.699896)
				(mid 63.246762 -318.699896)
				(end 63.653162 -318.699896)
			)
		)
		(stroke
			(width 0)
			(type solid)
		)
		(fill yes)
		(layer "In6.Cu")
		(net "P5E_PEX0_STN5_RX_DN<85>")
	)
	(gr_poly
		(pts
			(arc
				(start 63.653162 -317.749936)
				(mid 63.246762 -317.749936)
				(end 63.653162 -317.749936)
			)
		)
		(stroke
			(width 0)
			(type solid)
		)
		(fill yes)
		(layer "In6.Cu")
		(net "P5E_PEX0_STN5_RX_DP<85>")
	)
	(gr_poly
		(pts
			(arc
				(start 63.653162 -313.949842)
				(mid 63.246762 -313.949842)
				(end 63.653162 -313.949842)
			)
		)
		(stroke
			(width 0)
			(type solid)
		)
		(fill yes)
		(layer "In6.Cu")
		(net "P5E_PEX0_STN5_TX_DN<85>")
	)
	(gr_poly
		(pts
			(arc
				(start 63.653162 -312.999882)
				(mid 63.246762 -312.999882)
				(end 63.653162 -312.999882)
			)
		)
		(stroke
			(width 0)
			(type solid)
		)
		(fill yes)
		(layer "In6.Cu")
		(net "P5E_PEX0_STN5_TX_DP<85>")
	)
	(gr_poly
		(pts
			(arc
				(start 64.603122 -316.799722)
				(mid 64.196722 -316.799722)
				(end 64.603122 -316.799722)
			)
		)
		(stroke
			(width 0)
			(type solid)
		)
		(fill yes)
		(layer "In6.Cu")
		(net "P5E_PEX0_STN5_RX_DN<86>")
	)
	(gr_poly
		(pts
			(arc
				(start 64.603122 -315.849762)
				(mid 64.196722 -315.849762)
				(end 64.603122 -315.849762)
			)
		)
		(stroke
			(width 0)
			(type solid)
		)
		(fill yes)
		(layer "In6.Cu")
		(net "P5E_PEX0_STN5_RX_DP<86>")
	)
	(gr_poly
		(pts
			(arc
				(start 64.603122 -312.049922)
				(mid 64.196722 -312.049922)
				(end 64.603122 -312.049922)
			)
		)
		(stroke
			(width 0)
			(type solid)
		)
		(fill yes)
		(layer "In6.Cu")
		(net "P5E_PEX0_STN5_TX_DN<86>")
	)
	(gr_poly
		(pts
			(arc
				(start 64.603122 -311.099962)
				(mid 64.196722 -311.099962)
				(end 64.603122 -311.099962)
			)
		)
		(stroke
			(width 0)
			(type solid)
		)
		(fill yes)
		(layer "In6.Cu")
		(net "P5E_PEX0_STN5_TX_DP<86>")
	)
	(gr_poly
		(pts
			(arc
				(start 64.603122 -280.699718)
				(mid 64.196722 -280.699718)
				(end 64.603122 -280.699718)
			)
		)
		(stroke
			(width 0)
			(type solid)
		)
		(fill yes)
		(layer "In6.Cu")
		(net "P5E_PEX0_STN1_TX_DN<21>")
	)
	(gr_poly
		(pts
			(arc
				(start 64.603122 -279.749504)
				(mid 64.196722 -279.749504)
				(end 64.603122 -279.749504)
			)
		)
		(stroke
			(width 0)
			(type solid)
		)
		(fill yes)
		(layer "In6.Cu")
		(net "P5E_PEX0_STN1_TX_DP<21>")
	)
	(gr_poly
		(pts
			(arc
				(start 65.552828 -278.799798)
				(mid 65.146428 -278.799798)
				(end 65.552828 -278.799798)
			)
		)
		(stroke
			(width 0)
			(type solid)
		)
		(fill yes)
		(layer "In6.Cu")
		(net "P5E_PEX0_STN1_TX_DP<22>")
	)
	(gr_poly
		(pts
			(arc
				(start 65.552828 -277.849838)
				(mid 65.146428 -277.849838)
				(end 65.552828 -277.849838)
			)
		)
		(stroke
			(width 0)
			(type solid)
		)
		(fill yes)
		(layer "In6.Cu")
		(net "P5E_PEX0_STN1_TX_DN<22>")
	)
	(gr_poly
		(pts
			(arc
				(start 65.553082 -318.699896)
				(mid 65.146682 -318.699896)
				(end 65.553082 -318.699896)
			)
		)
		(stroke
			(width 0)
			(type solid)
		)
		(fill yes)
		(layer "In6.Cu")
		(net "P5E_PEX0_STN5_RX_DN<87>")
	)
	(gr_poly
		(pts
			(arc
				(start 65.553082 -317.749936)
				(mid 65.146682 -317.749936)
				(end 65.553082 -317.749936)
			)
		)
		(stroke
			(width 0)
			(type solid)
		)
		(fill yes)
		(layer "In6.Cu")
		(net "P5E_PEX0_STN5_RX_DP<87>")
	)
	(gr_poly
		(pts
			(arc
				(start 65.553082 -313.949842)
				(mid 65.146682 -313.949842)
				(end 65.553082 -313.949842)
			)
		)
		(stroke
			(width 0)
			(type solid)
		)
		(fill yes)
		(layer "In6.Cu")
		(net "P5E_PEX0_STN5_TX_DN<87>")
	)
	(gr_poly
		(pts
			(arc
				(start 65.553082 -312.999882)
				(mid 65.146682 -312.999882)
				(end 65.553082 -312.999882)
			)
		)
		(stroke
			(width 0)
			(type solid)
		)
		(fill yes)
		(layer "In6.Cu")
		(net "P5E_PEX0_STN5_TX_DP<87>")
	)
	(gr_poly
		(pts
			(arc
				(start 66.503042 -312.049922)
				(mid 66.096642 -312.049922)
				(end 66.503042 -312.049922)
			)
		)
		(stroke
			(width 0)
			(type solid)
		)
		(fill yes)
		(layer "In6.Cu")
		(net "P5E_PEX0_STN5_TX_DN<88>")
	)
	(gr_poly
		(pts
			(arc
				(start 66.503042 -311.099962)
				(mid 66.096642 -311.099962)
				(end 66.503042 -311.099962)
			)
		)
		(stroke
			(width 0)
			(type solid)
		)
		(fill yes)
		(layer "In6.Cu")
		(net "P5E_PEX0_STN5_TX_DP<88>")
	)
	(gr_poly
		(pts
			(arc
				(start 66.503042 -280.699718)
				(mid 66.096642 -280.699718)
				(end 66.503042 -280.699718)
			)
		)
		(stroke
			(width 0)
			(type solid)
		)
		(fill yes)
		(layer "In6.Cu")
		(net "P5E_PEX0_STN1_TX_DN<23>")
	)
	(gr_poly
		(pts
			(arc
				(start 66.503042 -279.749504)
				(mid 66.096642 -279.749504)
				(end 66.503042 -279.749504)
			)
		)
		(stroke
			(width 0)
			(type solid)
		)
		(fill yes)
		(layer "In6.Cu")
		(net "P5E_PEX0_STN1_TX_DP<23>")
	)
	(gr_poly
		(pts
			(arc
				(start 67.452748 -278.799798)
				(mid 67.046348 -278.799798)
				(end 67.452748 -278.799798)
			)
		)
		(stroke
			(width 0)
			(type solid)
		)
		(fill yes)
		(layer "In6.Cu")
		(net "P5E_PEX0_STN1_TX_DP<24>")
	)
	(gr_poly
		(pts
			(arc
				(start 67.452748 -277.849838)
				(mid 67.046348 -277.849838)
				(end 67.452748 -277.849838)
			)
		)
		(stroke
			(width 0)
			(type solid)
		)
		(fill yes)
		(layer "In6.Cu")
		(net "P5E_PEX0_STN1_TX_DN<24>")
	)
	(gr_poly
		(pts
			(arc
				(start 67.453002 -313.949842)
				(mid 67.046602 -313.949842)
				(end 67.453002 -313.949842)
			)
		)
		(stroke
			(width 0)
			(type solid)
		)
		(fill yes)
		(layer "In6.Cu")
		(net "P5E_PEX0_STN5_TX_DN<89>")
	)
	(gr_poly
		(pts
			(arc
				(start 67.453002 -312.999882)
				(mid 67.046602 -312.999882)
				(end 67.453002 -312.999882)
			)
		)
		(stroke
			(width 0)
			(type solid)
		)
		(fill yes)
		(layer "In6.Cu")
		(net "P5E_PEX0_STN5_TX_DP<89>")
	)
	(gr_poly
		(pts
			(arc
				(start 68.402962 -312.049922)
				(mid 67.996562 -312.049922)
				(end 68.402962 -312.049922)
			)
		)
		(stroke
			(width 0)
			(type solid)
		)
		(fill yes)
		(layer "In6.Cu")
		(net "P5E_PEX0_STN5_TX_DN<90>")
	)
	(gr_poly
		(pts
			(arc
				(start 68.402962 -311.099962)
				(mid 67.996562 -311.099962)
				(end 68.402962 -311.099962)
			)
		)
		(stroke
			(width 0)
			(type solid)
		)
		(fill yes)
		(layer "In6.Cu")
		(net "P5E_PEX0_STN5_TX_DP<90>")
	)
	(gr_poly
		(pts
			(arc
				(start 68.402962 -280.699718)
				(mid 67.996562 -280.699718)
				(end 68.402962 -280.699718)
			)
		)
		(stroke
			(width 0)
			(type solid)
		)
		(fill yes)
		(layer "In6.Cu")
		(net "P5E_PEX0_STN1_TX_DN<25>")
	)
	(gr_poly
		(pts
			(arc
				(start 68.402962 -279.749504)
				(mid 67.996562 -279.749504)
				(end 68.402962 -279.749504)
			)
		)
		(stroke
			(width 0)
			(type solid)
		)
		(fill yes)
		(layer "In6.Cu")
		(net "P5E_PEX0_STN1_TX_DP<25>")
	)
	(gr_poly
		(pts
			(arc
				(start 69.352922 -278.799798)
				(mid 68.946522 -278.799798)
				(end 69.352922 -278.799798)
			)
		)
		(stroke
			(width 0)
			(type solid)
		)
		(fill yes)
		(layer "In6.Cu")
		(net "P5E_PEX0_STN1_TX_DP<26>")
	)
	(gr_poly
		(pts
			(arc
				(start 69.352922 -277.849838)
				(mid 68.946522 -277.849838)
				(end 69.352922 -277.849838)
			)
		)
		(stroke
			(width 0)
			(type solid)
		)
		(fill yes)
		(layer "In6.Cu")
		(net "P5E_PEX0_STN1_TX_DN<26>")
	)
	(gr_poly
		(pts
			(arc
				(start 69.353176 -313.949842)
				(mid 68.946776 -313.949842)
				(end 69.353176 -313.949842)
			)
		)
		(stroke
			(width 0)
			(type solid)
		)
		(fill yes)
		(layer "In6.Cu")
		(net "P5E_PEX0_STN5_TX_DN<91>")
	)
	(gr_poly
		(pts
			(arc
				(start 69.353176 -312.999882)
				(mid 68.946776 -312.999882)
				(end 69.353176 -312.999882)
			)
		)
		(stroke
			(width 0)
			(type solid)
		)
		(fill yes)
		(layer "In6.Cu")
		(net "P5E_PEX0_STN5_TX_DP<91>")
	)
	(gr_poly
		(pts
			(arc
				(start 70.303136 -312.049922)
				(mid 69.896736 -312.049922)
				(end 70.303136 -312.049922)
			)
		)
		(stroke
			(width 0)
			(type solid)
		)
		(fill yes)
		(layer "In6.Cu")
		(net "P5E_PEX0_STN5_TX_DN<92>")
	)
	(gr_poly
		(pts
			(arc
				(start 70.303136 -311.099962)
				(mid 69.896736 -311.099962)
				(end 70.303136 -311.099962)
			)
		)
		(stroke
			(width 0)
			(type solid)
		)
		(fill yes)
		(layer "In6.Cu")
		(net "P5E_PEX0_STN5_TX_DP<92>")
	)
	(gr_poly
		(pts
			(arc
				(start 70.303136 -280.699718)
				(mid 69.896736 -280.699718)
				(end 70.303136 -280.699718)
			)
		)
		(stroke
			(width 0)
			(type solid)
		)
		(fill yes)
		(layer "In6.Cu")
		(net "P5E_PEX0_STN1_TX_DN<27>")
	)
	(gr_poly
		(pts
			(arc
				(start 70.303136 -279.749504)
				(mid 69.896736 -279.749504)
				(end 70.303136 -279.749504)
			)
		)
		(stroke
			(width 0)
			(type solid)
		)
		(fill yes)
		(layer "In6.Cu")
		(net "P5E_PEX0_STN1_TX_DP<27>")
	)
	(gr_poly
		(pts
			(arc
				(start 71.252842 -278.799798)
				(mid 70.846442 -278.799798)
				(end 71.252842 -278.799798)
			)
		)
		(stroke
			(width 0)
			(type solid)
		)
		(fill yes)
		(layer "In6.Cu")
		(net "P5E_PEX0_STN1_TX_DP<28>")
	)
	(gr_poly
		(pts
			(arc
				(start 71.252842 -277.849838)
				(mid 70.846442 -277.849838)
				(end 71.252842 -277.849838)
			)
		)
		(stroke
			(width 0)
			(type solid)
		)
		(fill yes)
		(layer "In6.Cu")
		(net "P5E_PEX0_STN1_TX_DN<28>")
	)
	(gr_poly
		(pts
			(arc
				(start 71.253096 -313.949842)
				(mid 70.846696 -313.949842)
				(end 71.253096 -313.949842)
			)
		)
		(stroke
			(width 0)
			(type solid)
		)
		(fill yes)
		(layer "In6.Cu")
		(net "P5E_PEX0_STN5_TX_DN<93>")
	)
	(gr_poly
		(pts
			(arc
				(start 71.253096 -312.999882)
				(mid 70.846696 -312.999882)
				(end 71.253096 -312.999882)
			)
		)
		(stroke
			(width 0)
			(type solid)
		)
		(fill yes)
		(layer "In6.Cu")
		(net "P5E_PEX0_STN5_TX_DP<93>")
	)
	(gr_poly
		(pts
			(arc
				(start 72.203056 -312.049922)
				(mid 71.796656 -312.049922)
				(end 72.203056 -312.049922)
			)
		)
		(stroke
			(width 0)
			(type solid)
		)
		(fill yes)
		(layer "In6.Cu")
		(net "P5E_PEX0_STN5_TX_DN<94>")
	)
	(gr_poly
		(pts
			(arc
				(start 72.203056 -311.099962)
				(mid 71.796656 -311.099962)
				(end 72.203056 -311.099962)
			)
		)
		(stroke
			(width 0)
			(type solid)
		)
		(fill yes)
		(layer "In6.Cu")
		(net "P5E_PEX0_STN5_TX_DP<94>")
	)
	(gr_poly
		(pts
			(arc
				(start 72.203056 -280.699718)
				(mid 71.796656 -280.699718)
				(end 72.203056 -280.699718)
			)
		)
		(stroke
			(width 0)
			(type solid)
		)
		(fill yes)
		(layer "In6.Cu")
		(net "P5E_PEX0_STN1_TX_DN<29>")
	)
	(gr_poly
		(pts
			(arc
				(start 72.203056 -279.749504)
				(mid 71.796656 -279.749504)
				(end 72.203056 -279.749504)
			)
		)
		(stroke
			(width 0)
			(type solid)
		)
		(fill yes)
		(layer "In6.Cu")
		(net "P5E_PEX0_STN1_TX_DP<29>")
	)
	(gr_poly
		(pts
			(arc
				(start 73.152762 -278.799798)
				(mid 72.746362 -278.799798)
				(end 73.152762 -278.799798)
			)
		)
		(stroke
			(width 0)
			(type solid)
		)
		(fill yes)
		(layer "In6.Cu")
		(net "P5E_PEX0_STN1_TX_DP<30>")
	)
	(gr_poly
		(pts
			(arc
				(start 73.152762 -277.849838)
				(mid 72.746362 -277.849838)
				(end 73.152762 -277.849838)
			)
		)
		(stroke
			(width 0)
			(type solid)
		)
		(fill yes)
		(layer "In6.Cu")
		(net "P5E_PEX0_STN1_TX_DN<30>")
	)
	(gr_poly
		(pts
			(arc
				(start 73.153016 -313.949842)
				(mid 72.746616 -313.949842)
				(end 73.153016 -313.949842)
			)
		)
		(stroke
			(width 0)
			(type solid)
		)
		(fill yes)
		(layer "In6.Cu")
		(net "P5E_PEX0_STN5_TX_DN<95>")
	)
	(gr_poly
		(pts
			(arc
				(start 73.153016 -312.999882)
				(mid 72.746616 -312.999882)
				(end 73.153016 -312.999882)
			)
		)
		(stroke
			(width 0)
			(type solid)
		)
		(fill yes)
		(layer "In6.Cu")
		(net "P5E_PEX0_STN5_TX_DP<95>")
	)
	(gr_poly
		(pts
			(arc
				(start 74.102976 -316.799722)
				(mid 73.696576 -316.799722)
				(end 74.102976 -316.799722)
			)
		)
		(stroke
			(width 0)
			(type solid)
		)
		(fill yes)
		(layer "In6.Cu")
		(net "P5E_PEX0_STN4_RX_DN<79>")
	)
	(gr_poly
		(pts
			(arc
				(start 74.102976 -315.849762)
				(mid 73.696576 -315.849762)
				(end 74.102976 -315.849762)
			)
		)
		(stroke
			(width 0)
			(type solid)
		)
		(fill yes)
		(layer "In6.Cu")
		(net "P5E_PEX0_STN4_RX_DP<79>")
	)
	(gr_poly
		(pts
			(arc
				(start 74.102976 -312.049922)
				(mid 73.696576 -312.049922)
				(end 74.102976 -312.049922)
			)
		)
		(stroke
			(width 0)
			(type solid)
		)
		(fill yes)
		(layer "In6.Cu")
		(net "P5E_PEX0_STN4_TX_DN<79>")
	)
	(gr_poly
		(pts
			(arc
				(start 74.102976 -311.099962)
				(mid 73.696576 -311.099962)
				(end 74.102976 -311.099962)
			)
		)
		(stroke
			(width 0)
			(type solid)
		)
		(fill yes)
		(layer "In6.Cu")
		(net "P5E_PEX0_STN4_TX_DP<79>")
	)
	(gr_poly
		(pts
			(arc
				(start 74.102976 -280.699718)
				(mid 73.696576 -280.699718)
				(end 74.102976 -280.699718)
			)
		)
		(stroke
			(width 0)
			(type solid)
		)
		(fill yes)
		(layer "In6.Cu")
		(net "P5E_PEX0_STN1_TX_DN<31>")
	)
	(gr_poly
		(pts
			(arc
				(start 74.102976 -279.749504)
				(mid 73.696576 -279.749504)
				(end 74.102976 -279.749504)
			)
		)
		(stroke
			(width 0)
			(type solid)
		)
		(fill yes)
		(layer "In6.Cu")
		(net "P5E_PEX0_STN1_TX_DP<31>")
	)
	(gr_poly
		(pts
			(arc
				(start 75.052936 -287.349946)
				(mid 74.646536 -287.349946)
				(end 75.052936 -287.349946)
			)
		)
		(stroke
			(width 0)
			(type solid)
		)
		(fill yes)
		(layer "In6.Cu")
		(net "P5E_PEX0_STN0_TX_DP<1>")
	)
	(gr_poly
		(pts
			(arc
				(start 75.052936 -285.449772)
				(mid 74.646536 -285.449772)
				(end 75.052936 -285.449772)
			)
		)
		(stroke
			(width 0)
			(type solid)
		)
		(fill yes)
		(layer "In6.Cu")
		(net "P5E_PEX0_STN0_TX_DP<3>")
	)
	(gr_poly
		(pts
			(arc
				(start 75.052936 -283.549852)
				(mid 74.646536 -283.549852)
				(end 75.052936 -283.549852)
			)
		)
		(stroke
			(width 0)
			(type solid)
		)
		(fill yes)
		(layer "In6.Cu")
		(net "P5E_PEX0_STN0_TX_DP<5>")
	)
	(gr_poly
		(pts
			(arc
				(start 75.052936 -278.799798)
				(mid 74.646536 -278.799798)
				(end 75.052936 -278.799798)
			)
		)
		(stroke
			(width 0)
			(type solid)
		)
		(fill yes)
		(layer "In6.Cu")
		(net "P5E_PEX0_STN0_TX_DP<15>")
	)
	(gr_poly
		(pts
			(arc
				(start 75.052936 -277.849838)
				(mid 74.646536 -277.849838)
				(end 75.052936 -277.849838)
			)
		)
		(stroke
			(width 0)
			(type solid)
		)
		(fill yes)
		(layer "In6.Cu")
		(net "P5E_PEX0_STN0_TX_DN<15>")
	)
	(gr_poly
		(pts
			(arc
				(start 75.05319 -318.699896)
				(mid 74.64679 -318.699896)
				(end 75.05319 -318.699896)
			)
		)
		(stroke
			(width 0)
			(type solid)
		)
		(fill yes)
		(layer "In6.Cu")
		(net "P5E_PEX0_STN4_RX_DN<78>")
	)
	(gr_poly
		(pts
			(arc
				(start 75.05319 -317.749936)
				(mid 74.64679 -317.749936)
				(end 75.05319 -317.749936)
			)
		)
		(stroke
			(width 0)
			(type solid)
		)
		(fill yes)
		(layer "In6.Cu")
		(net "P5E_PEX0_STN4_RX_DP<78>")
	)
	(gr_poly
		(pts
			(arc
				(start 75.05319 -313.949842)
				(mid 74.64679 -313.949842)
				(end 75.05319 -313.949842)
			)
		)
		(stroke
			(width 0)
			(type solid)
		)
		(fill yes)
		(layer "In6.Cu")
		(net "P5E_PEX0_STN4_TX_DN<78>")
	)
	(gr_poly
		(pts
			(arc
				(start 75.05319 -312.999882)
				(mid 74.64679 -312.999882)
				(end 75.05319 -312.999882)
			)
		)
		(stroke
			(width 0)
			(type solid)
		)
		(fill yes)
		(layer "In6.Cu")
		(net "P5E_PEX0_STN4_TX_DP<78>")
	)
	(gr_poly
		(pts
			(arc
				(start 75.05319 -308.249828)
				(mid 74.64679 -308.249828)
				(end 75.05319 -308.249828)
			)
		)
		(stroke
			(width 0)
			(type solid)
		)
		(fill yes)
		(layer "In6.Cu")
		(net "P5E_PEX0_STN4_TX_DP<68>")
	)
	(gr_poly
		(pts
			(arc
				(start 75.05319 -306.349908)
				(mid 74.64679 -306.349908)
				(end 75.05319 -306.349908)
			)
		)
		(stroke
			(width 0)
			(type solid)
		)
		(fill yes)
		(layer "In6.Cu")
		(net "P5E_PEX0_STN4_TX_DP<66>")
	)
	(gr_poly
		(pts
			(arc
				(start 75.05319 -304.449734)
				(mid 74.64679 -304.449734)
				(end 75.05319 -304.449734)
			)
		)
		(stroke
			(width 0)
			(type solid)
		)
		(fill yes)
		(layer "In6.Cu")
		(net "P5E_PEX0_STN4_TX_DP<64>")
	)
	(gr_poly
		(pts
			(arc
				(start 76.00315 -316.799722)
				(mid 75.59675 -316.799722)
				(end 76.00315 -316.799722)
			)
		)
		(stroke
			(width 0)
			(type solid)
		)
		(fill yes)
		(layer "In6.Cu")
		(net "P5E_PEX0_STN4_RX_DN<77>")
	)
	(gr_poly
		(pts
			(arc
				(start 76.00315 -315.849762)
				(mid 75.59675 -315.849762)
				(end 76.00315 -315.849762)
			)
		)
		(stroke
			(width 0)
			(type solid)
		)
		(fill yes)
		(layer "In6.Cu")
		(net "P5E_PEX0_STN4_RX_DP<77>")
	)
	(gr_poly
		(pts
			(arc
				(start 76.00315 -312.049922)
				(mid 75.59675 -312.049922)
				(end 76.00315 -312.049922)
			)
		)
		(stroke
			(width 0)
			(type solid)
		)
		(fill yes)
		(layer "In6.Cu")
		(net "P5E_PEX0_STN4_TX_DN<77>")
	)
	(gr_poly
		(pts
			(arc
				(start 76.00315 -311.099962)
				(mid 75.59675 -311.099962)
				(end 76.00315 -311.099962)
			)
		)
		(stroke
			(width 0)
			(type solid)
		)
		(fill yes)
		(layer "In6.Cu")
		(net "P5E_PEX0_STN4_TX_DP<77>")
	)
	(gr_poly
		(pts
			(arc
				(start 76.00315 -308.249828)
				(mid 75.59675 -308.249828)
				(end 76.00315 -308.249828)
			)
		)
		(stroke
			(width 0)
			(type solid)
		)
		(fill yes)
		(layer "In6.Cu")
		(net "P5E_PEX0_STN4_TX_DN<68>")
	)
	(gr_poly
		(pts
			(arc
				(start 76.00315 -306.349908)
				(mid 75.59675 -306.349908)
				(end 76.00315 -306.349908)
			)
		)
		(stroke
			(width 0)
			(type solid)
		)
		(fill yes)
		(layer "In6.Cu")
		(net "P5E_PEX0_STN4_TX_DN<66>")
	)
	(gr_poly
		(pts
			(arc
				(start 76.00315 -304.449734)
				(mid 75.59675 -304.449734)
				(end 76.00315 -304.449734)
			)
		)
		(stroke
			(width 0)
			(type solid)
		)
		(fill yes)
		(layer "In6.Cu")
		(net "P5E_PEX0_STN4_TX_DN<64>")
	)
	(gr_poly
		(pts
			(arc
				(start 76.00315 -287.349946)
				(mid 75.59675 -287.349946)
				(end 76.00315 -287.349946)
			)
		)
		(stroke
			(width 0)
			(type solid)
		)
		(fill yes)
		(layer "In6.Cu")
		(net "P5E_PEX0_STN0_TX_DN<1>")
	)
	(gr_poly
		(pts
			(arc
				(start 76.00315 -285.449772)
				(mid 75.59675 -285.449772)
				(end 76.00315 -285.449772)
			)
		)
		(stroke
			(width 0)
			(type solid)
		)
		(fill yes)
		(layer "In6.Cu")
		(net "P5E_PEX0_STN0_TX_DN<3>")
	)
	(gr_poly
		(pts
			(arc
				(start 76.00315 -283.549852)
				(mid 75.59675 -283.549852)
				(end 76.00315 -283.549852)
			)
		)
		(stroke
			(width 0)
			(type solid)
		)
		(fill yes)
		(layer "In6.Cu")
		(net "P5E_PEX0_STN0_TX_DN<5>")
	)
	(gr_poly
		(pts
			(arc
				(start 76.00315 -280.699718)
				(mid 75.59675 -280.699718)
				(end 76.00315 -280.699718)
			)
		)
		(stroke
			(width 0)
			(type solid)
		)
		(fill yes)
		(layer "In6.Cu")
		(net "P5E_PEX0_STN0_TX_DN<14>")
	)
	(gr_poly
		(pts
			(arc
				(start 76.00315 -279.749504)
				(mid 75.59675 -279.749504)
				(end 76.00315 -279.749504)
			)
		)
		(stroke
			(width 0)
			(type solid)
		)
		(fill yes)
		(layer "In6.Cu")
		(net "P5E_PEX0_STN0_TX_DP<14>")
	)
	(gr_poly
		(pts
			(arc
				(start 76.952856 -278.799798)
				(mid 76.546456 -278.799798)
				(end 76.952856 -278.799798)
			)
		)
		(stroke
			(width 0)
			(type solid)
		)
		(fill yes)
		(layer "In6.Cu")
		(net "P5E_PEX0_STN0_TX_DP<13>")
	)
	(gr_poly
		(pts
			(arc
				(start 76.952856 -277.849838)
				(mid 76.546456 -277.849838)
				(end 76.952856 -277.849838)
			)
		)
		(stroke
			(width 0)
			(type solid)
		)
		(fill yes)
		(layer "In6.Cu")
		(net "P5E_PEX0_STN0_TX_DN<13>")
	)
	(gr_poly
		(pts
			(arc
				(start 76.95311 -318.699896)
				(mid 76.54671 -318.699896)
				(end 76.95311 -318.699896)
			)
		)
		(stroke
			(width 0)
			(type solid)
		)
		(fill yes)
		(layer "In6.Cu")
		(net "P5E_PEX0_STN4_RX_DN<76>")
	)
	(gr_poly
		(pts
			(arc
				(start 76.95311 -317.749936)
				(mid 76.54671 -317.749936)
				(end 76.95311 -317.749936)
			)
		)
		(stroke
			(width 0)
			(type solid)
		)
		(fill yes)
		(layer "In6.Cu")
		(net "P5E_PEX0_STN4_RX_DP<76>")
	)
	(gr_poly
		(pts
			(arc
				(start 76.95311 -313.949842)
				(mid 76.54671 -313.949842)
				(end 76.95311 -313.949842)
			)
		)
		(stroke
			(width 0)
			(type solid)
		)
		(fill yes)
		(layer "In6.Cu")
		(net "P5E_PEX0_STN4_TX_DN<76>")
	)
	(gr_poly
		(pts
			(arc
				(start 76.95311 -312.999882)
				(mid 76.54671 -312.999882)
				(end 76.95311 -312.999882)
			)
		)
		(stroke
			(width 0)
			(type solid)
		)
		(fill yes)
		(layer "In6.Cu")
		(net "P5E_PEX0_STN4_TX_DP<76>")
	)
	(gr_poly
		(pts
			(arc
				(start 76.95311 -309.199788)
				(mid 76.54671 -309.199788)
				(end 76.95311 -309.199788)
			)
		)
		(stroke
			(width 0)
			(type solid)
		)
		(fill yes)
		(layer "In6.Cu")
		(net "P5E_PEX0_STN4_TX_DP<69>")
	)
	(gr_poly
		(pts
			(arc
				(start 76.95311 -307.299868)
				(mid 76.54671 -307.299868)
				(end 76.95311 -307.299868)
			)
		)
		(stroke
			(width 0)
			(type solid)
		)
		(fill yes)
		(layer "In6.Cu")
		(net "P5E_PEX0_STN4_TX_DP<67>")
	)
	(gr_poly
		(pts
			(arc
				(start 76.95311 -305.399948)
				(mid 76.54671 -305.399948)
				(end 76.95311 -305.399948)
			)
		)
		(stroke
			(width 0)
			(type solid)
		)
		(fill yes)
		(layer "In6.Cu")
		(net "P5E_PEX0_STN4_TX_DP<65>")
	)
	(gr_poly
		(pts
			(arc
				(start 76.95311 -288.299906)
				(mid 76.54671 -288.299906)
				(end 76.95311 -288.299906)
			)
		)
		(stroke
			(width 0)
			(type solid)
		)
		(fill yes)
		(layer "In6.Cu")
		(net "P5E_PEX0_STN0_TX_DP<0>")
	)
	(gr_poly
		(pts
			(arc
				(start 76.95311 -286.399986)
				(mid 76.54671 -286.399986)
				(end 76.95311 -286.399986)
			)
		)
		(stroke
			(width 0)
			(type solid)
		)
		(fill yes)
		(layer "In6.Cu")
		(net "P5E_PEX0_STN0_TX_DP<2>")
	)
	(gr_poly
		(pts
			(arc
				(start 76.95311 -284.499812)
				(mid 76.54671 -284.499812)
				(end 76.95311 -284.499812)
			)
		)
		(stroke
			(width 0)
			(type solid)
		)
		(fill yes)
		(layer "In6.Cu")
		(net "P5E_PEX0_STN0_TX_DP<4>")
	)
	(gr_poly
		(pts
			(arc
				(start 76.95311 -282.599892)
				(mid 76.54671 -282.599892)
				(end 76.95311 -282.599892)
			)
		)
		(stroke
			(width 0)
			(type solid)
		)
		(fill yes)
		(layer "In6.Cu")
		(net "P5E_PEX0_STN0_TX_DP<6>")
	)
	(gr_poly
		(pts
			(arc
				(start 77.90307 -316.799722)
				(mid 77.49667 -316.799722)
				(end 77.90307 -316.799722)
			)
		)
		(stroke
			(width 0)
			(type solid)
		)
		(fill yes)
		(layer "In6.Cu")
		(net "P5E_PEX0_STN4_RX_DN<75>")
	)
	(gr_poly
		(pts
			(arc
				(start 77.90307 -315.849762)
				(mid 77.49667 -315.849762)
				(end 77.90307 -315.849762)
			)
		)
		(stroke
			(width 0)
			(type solid)
		)
		(fill yes)
		(layer "In6.Cu")
		(net "P5E_PEX0_STN4_RX_DP<75>")
	)
	(gr_poly
		(pts
			(arc
				(start 77.90307 -312.049922)
				(mid 77.49667 -312.049922)
				(end 77.90307 -312.049922)
			)
		)
		(stroke
			(width 0)
			(type solid)
		)
		(fill yes)
		(layer "In6.Cu")
		(net "P5E_PEX0_STN4_TX_DN<75>")
	)
	(gr_poly
		(pts
			(arc
				(start 77.90307 -311.099962)
				(mid 77.49667 -311.099962)
				(end 77.90307 -311.099962)
			)
		)
		(stroke
			(width 0)
			(type solid)
		)
		(fill yes)
		(layer "In6.Cu")
		(net "P5E_PEX0_STN4_TX_DP<75>")
	)
	(gr_poly
		(pts
			(arc
				(start 77.90307 -309.199788)
				(mid 77.49667 -309.199788)
				(end 77.90307 -309.199788)
			)
		)
		(stroke
			(width 0)
			(type solid)
		)
		(fill yes)
		(layer "In6.Cu")
		(net "P5E_PEX0_STN4_TX_DN<69>")
	)
	(gr_poly
		(pts
			(arc
				(start 77.90307 -307.299868)
				(mid 77.49667 -307.299868)
				(end 77.90307 -307.299868)
			)
		)
		(stroke
			(width 0)
			(type solid)
		)
		(fill yes)
		(layer "In6.Cu")
		(net "P5E_PEX0_STN4_TX_DN<67>")
	)
	(gr_poly
		(pts
			(arc
				(start 77.90307 -305.399948)
				(mid 77.49667 -305.399948)
				(end 77.90307 -305.399948)
			)
		)
		(stroke
			(width 0)
			(type solid)
		)
		(fill yes)
		(layer "In6.Cu")
		(net "P5E_PEX0_STN4_TX_DN<65>")
	)
	(gr_poly
		(pts
			(arc
				(start 77.90307 -288.299906)
				(mid 77.49667 -288.299906)
				(end 77.90307 -288.299906)
			)
		)
		(stroke
			(width 0)
			(type solid)
		)
		(fill yes)
		(layer "In6.Cu")
		(net "P5E_PEX0_STN0_TX_DN<0>")
	)
	(gr_poly
		(pts
			(arc
				(start 77.90307 -286.399986)
				(mid 77.49667 -286.399986)
				(end 77.90307 -286.399986)
			)
		)
		(stroke
			(width 0)
			(type solid)
		)
		(fill yes)
		(layer "In6.Cu")
		(net "P5E_PEX0_STN0_TX_DN<2>")
	)
	(gr_poly
		(pts
			(arc
				(start 77.90307 -284.499812)
				(mid 77.49667 -284.499812)
				(end 77.90307 -284.499812)
			)
		)
		(stroke
			(width 0)
			(type solid)
		)
		(fill yes)
		(layer "In6.Cu")
		(net "P5E_PEX0_STN0_TX_DN<4>")
	)
	(gr_poly
		(pts
			(arc
				(start 77.90307 -282.599892)
				(mid 77.49667 -282.599892)
				(end 77.90307 -282.599892)
			)
		)
		(stroke
			(width 0)
			(type solid)
		)
		(fill yes)
		(layer "In6.Cu")
		(net "P5E_PEX0_STN0_TX_DN<6>")
	)
	(gr_poly
		(pts
			(arc
				(start 77.90307 -280.699718)
				(mid 77.49667 -280.699718)
				(end 77.90307 -280.699718)
			)
		)
		(stroke
			(width 0)
			(type solid)
		)
		(fill yes)
		(layer "In6.Cu")
		(net "P5E_PEX0_STN0_TX_DN<12>")
	)
	(gr_poly
		(pts
			(arc
				(start 77.90307 -279.749504)
				(mid 77.49667 -279.749504)
				(end 77.90307 -279.749504)
			)
		)
		(stroke
			(width 0)
			(type solid)
		)
		(fill yes)
		(layer "In6.Cu")
		(net "P5E_PEX0_STN0_TX_DP<12>")
	)
	(gr_poly
		(pts
			(arc
				(start 78.852776 -278.799798)
				(mid 78.446376 -278.799798)
				(end 78.852776 -278.799798)
			)
		)
		(stroke
			(width 0)
			(type solid)
		)
		(fill yes)
		(layer "In6.Cu")
		(net "P5E_PEX0_STN0_TX_DP<11>")
	)
	(gr_poly
		(pts
			(arc
				(start 78.852776 -277.849838)
				(mid 78.446376 -277.849838)
				(end 78.852776 -277.849838)
			)
		)
		(stroke
			(width 0)
			(type solid)
		)
		(fill yes)
		(layer "In6.Cu")
		(net "P5E_PEX0_STN0_TX_DN<11>")
	)
	(gr_poly
		(pts
			(arc
				(start 78.85303 -318.699896)
				(mid 78.44663 -318.699896)
				(end 78.85303 -318.699896)
			)
		)
		(stroke
			(width 0)
			(type solid)
		)
		(fill yes)
		(layer "In6.Cu")
		(net "P5E_PEX0_STN4_RX_DN<74>")
	)
	(gr_poly
		(pts
			(arc
				(start 78.85303 -317.749936)
				(mid 78.44663 -317.749936)
				(end 78.85303 -317.749936)
			)
		)
		(stroke
			(width 0)
			(type solid)
		)
		(fill yes)
		(layer "In6.Cu")
		(net "P5E_PEX0_STN4_RX_DP<74>")
	)
	(gr_poly
		(pts
			(arc
				(start 78.85303 -313.949842)
				(mid 78.44663 -313.949842)
				(end 78.85303 -313.949842)
			)
		)
		(stroke
			(width 0)
			(type solid)
		)
		(fill yes)
		(layer "In6.Cu")
		(net "P5E_PEX0_STN4_TX_DN<74>")
	)
	(gr_poly
		(pts
			(arc
				(start 78.85303 -312.999882)
				(mid 78.44663 -312.999882)
				(end 78.85303 -312.999882)
			)
		)
		(stroke
			(width 0)
			(type solid)
		)
		(fill yes)
		(layer "In6.Cu")
		(net "P5E_PEX0_STN4_TX_DP<74>")
	)
	(gr_poly
		(pts
			(arc
				(start 79.80299 -316.799722)
				(mid 79.39659 -316.799722)
				(end 79.80299 -316.799722)
			)
		)
		(stroke
			(width 0)
			(type solid)
		)
		(fill yes)
		(layer "In6.Cu")
		(net "P5E_PEX0_STN4_RX_DN<73>")
	)
	(gr_poly
		(pts
			(arc
				(start 79.80299 -315.849762)
				(mid 79.39659 -315.849762)
				(end 79.80299 -315.849762)
			)
		)
		(stroke
			(width 0)
			(type solid)
		)
		(fill yes)
		(layer "In6.Cu")
		(net "P5E_PEX0_STN4_RX_DP<73>")
	)
	(gr_poly
		(pts
			(arc
				(start 79.80299 -312.049922)
				(mid 79.39659 -312.049922)
				(end 79.80299 -312.049922)
			)
		)
		(stroke
			(width 0)
			(type solid)
		)
		(fill yes)
		(layer "In6.Cu")
		(net "P5E_PEX0_STN4_TX_DN<73>")
	)
	(gr_poly
		(pts
			(arc
				(start 79.80299 -311.099962)
				(mid 79.39659 -311.099962)
				(end 79.80299 -311.099962)
			)
		)
		(stroke
			(width 0)
			(type solid)
		)
		(fill yes)
		(layer "In6.Cu")
		(net "P5E_PEX0_STN4_TX_DP<73>")
	)
	(gr_poly
		(pts
			(arc
				(start 79.80299 -309.199788)
				(mid 79.39659 -309.199788)
				(end 79.80299 -309.199788)
			)
		)
		(stroke
			(width 0)
			(type solid)
		)
		(fill yes)
		(layer "In6.Cu")
		(net "P5E_PEX0_STN4_RX_DP<69>")
	)
	(gr_poly
		(pts
			(arc
				(start 79.80299 -307.299868)
				(mid 79.39659 -307.299868)
				(end 79.80299 -307.299868)
			)
		)
		(stroke
			(width 0)
			(type solid)
		)
		(fill yes)
		(layer "In6.Cu")
		(net "P5E_PEX0_STN4_RX_DP<67>")
	)
	(gr_poly
		(pts
			(arc
				(start 79.80299 -305.399948)
				(mid 79.39659 -305.399948)
				(end 79.80299 -305.399948)
			)
		)
		(stroke
			(width 0)
			(type solid)
		)
		(fill yes)
		(layer "In6.Cu")
		(net "P5E_PEX0_STN4_RX_DP<65>")
	)
	(gr_poly
		(pts
			(arc
				(start 79.80299 -280.699718)
				(mid 79.39659 -280.699718)
				(end 79.80299 -280.699718)
			)
		)
		(stroke
			(width 0)
			(type solid)
		)
		(fill yes)
		(layer "In6.Cu")
		(net "P5E_PEX0_STN0_TX_DP<10>")
	)
	(gr_poly
		(pts
			(arc
				(start 79.80299 -279.749758)
				(mid 79.39659 -279.749758)
				(end 79.80299 -279.749758)
			)
		)
		(stroke
			(width 0)
			(type solid)
		)
		(fill yes)
		(layer "In6.Cu")
		(net "P5E_PEX0_STN0_TX_DN<10>")
	)
	(gr_poly
		(pts
			(arc
				(start 80.75295 -318.699896)
				(mid 80.34655 -318.699896)
				(end 80.75295 -318.699896)
			)
		)
		(stroke
			(width 0)
			(type solid)
		)
		(fill yes)
		(layer "In6.Cu")
		(net "P5E_PEX0_STN4_RX_DN<72>")
	)
	(gr_poly
		(pts
			(arc
				(start 80.75295 -317.749936)
				(mid 80.34655 -317.749936)
				(end 80.75295 -317.749936)
			)
		)
		(stroke
			(width 0)
			(type solid)
		)
		(fill yes)
		(layer "In6.Cu")
		(net "P5E_PEX0_STN4_RX_DP<72>")
	)
	(gr_poly
		(pts
			(arc
				(start 80.75295 -313.949842)
				(mid 80.34655 -313.949842)
				(end 80.75295 -313.949842)
			)
		)
		(stroke
			(width 0)
			(type solid)
		)
		(fill yes)
		(layer "In6.Cu")
		(net "P5E_PEX0_STN4_TX_DN<72>")
	)
	(gr_poly
		(pts
			(arc
				(start 80.75295 -312.999882)
				(mid 80.34655 -312.999882)
				(end 80.75295 -312.999882)
			)
		)
		(stroke
			(width 0)
			(type solid)
		)
		(fill yes)
		(layer "In6.Cu")
		(net "P5E_PEX0_STN4_TX_DP<72>")
	)
	(gr_poly
		(pts
			(arc
				(start 80.75295 -309.199788)
				(mid 80.34655 -309.199788)
				(end 80.75295 -309.199788)
			)
		)
		(stroke
			(width 0)
			(type solid)
		)
		(fill yes)
		(layer "In6.Cu")
		(net "P5E_PEX0_STN4_RX_DN<69>")
	)
	(gr_poly
		(pts
			(arc
				(start 80.75295 -307.299868)
				(mid 80.34655 -307.299868)
				(end 80.75295 -307.299868)
			)
		)
		(stroke
			(width 0)
			(type solid)
		)
		(fill yes)
		(layer "In6.Cu")
		(net "P5E_PEX0_STN4_RX_DN<67>")
	)
	(gr_poly
		(pts
			(arc
				(start 80.75295 -305.399948)
				(mid 80.34655 -305.399948)
				(end 80.75295 -305.399948)
			)
		)
		(stroke
			(width 0)
			(type solid)
		)
		(fill yes)
		(layer "In6.Cu")
		(net "P5E_PEX0_STN4_RX_DN<65>")
	)
	(gr_poly
		(pts
			(arc
				(start 80.75295 -278.799798)
				(mid 80.34655 -278.799798)
				(end 80.75295 -278.799798)
			)
		)
		(stroke
			(width 0)
			(type solid)
		)
		(fill yes)
		(layer "In6.Cu")
		(net "P5E_PEX0_STN0_TX_DP<9>")
	)
	(gr_poly
		(pts
			(arc
				(start 80.75295 -277.849838)
				(mid 80.34655 -277.849838)
				(end 80.75295 -277.849838)
			)
		)
		(stroke
			(width 0)
			(type solid)
		)
		(fill yes)
		(layer "In6.Cu")
		(net "P5E_PEX0_STN0_TX_DN<9>")
	)
	(gr_poly
		(pts
			(arc
				(start 81.703164 -316.799722)
				(mid 81.296764 -316.799722)
				(end 81.703164 -316.799722)
			)
		)
		(stroke
			(width 0)
			(type solid)
		)
		(fill yes)
		(layer "In6.Cu")
		(net "P5E_PEX0_STN4_RX_DP<71>")
	)
	(gr_poly
		(pts
			(arc
				(start 81.703164 -314.899802)
				(mid 81.296764 -314.899802)
				(end 81.703164 -314.899802)
			)
		)
		(stroke
			(width 0)
			(type solid)
		)
		(fill yes)
		(layer "In6.Cu")
		(net "P5E_PEX0_STN4_TX_DP<71>")
	)
	(gr_poly
		(pts
			(arc
				(start 81.703164 -312.049922)
				(mid 81.296764 -312.049922)
				(end 81.703164 -312.049922)
			)
		)
		(stroke
			(width 0)
			(type solid)
		)
		(fill yes)
		(layer "In6.Cu")
		(net "P5E_PEX0_STN4_TX_DP<70>")
	)
	(gr_poly
		(pts
			(arc
				(start 81.703164 -310.149748)
				(mid 81.296764 -310.149748)
				(end 81.703164 -310.149748)
			)
		)
		(stroke
			(width 0)
			(type solid)
		)
		(fill yes)
		(layer "In6.Cu")
		(net "P5E_PEX0_STN4_RX_DP<70>")
	)
	(gr_poly
		(pts
			(arc
				(start 81.703164 -308.249828)
				(mid 81.296764 -308.249828)
				(end 81.703164 -308.249828)
			)
		)
		(stroke
			(width 0)
			(type solid)
		)
		(fill yes)
		(layer "In6.Cu")
		(net "P5E_PEX0_STN4_RX_DP<68>")
	)
	(gr_poly
		(pts
			(arc
				(start 81.703164 -306.349908)
				(mid 81.296764 -306.349908)
				(end 81.703164 -306.349908)
			)
		)
		(stroke
			(width 0)
			(type solid)
		)
		(fill yes)
		(layer "In6.Cu")
		(net "P5E_PEX0_STN4_RX_DP<66>")
	)
	(gr_poly
		(pts
			(arc
				(start 81.703164 -304.449734)
				(mid 81.296764 -304.449734)
				(end 81.703164 -304.449734)
			)
		)
		(stroke
			(width 0)
			(type solid)
		)
		(fill yes)
		(layer "In6.Cu")
		(net "P5E_PEX0_STN4_RX_DP<64>")
	)
	(gr_poly
		(pts
			(arc
				(start 81.703164 -279.749758)
				(mid 81.296764 -279.749758)
				(end 81.703164 -279.749758)
			)
		)
		(stroke
			(width 0)
			(type solid)
		)
		(fill yes)
		(layer "In6.Cu")
		(net "P5E_PEX0_STN0_TX_DP<7>")
	)
	(gr_poly
		(pts
			(arc
				(start 81.703164 -276.899878)
				(mid 81.296764 -276.899878)
				(end 81.703164 -276.899878)
			)
		)
		(stroke
			(width 0)
			(type solid)
		)
		(fill yes)
		(layer "In6.Cu")
		(net "P5E_PEX0_STN0_TX_DP<8>")
	)
	(gr_poly
		(pts
			(arc
				(start 82.653124 -316.799722)
				(mid 82.246724 -316.799722)
				(end 82.653124 -316.799722)
			)
		)
		(stroke
			(width 0)
			(type solid)
		)
		(fill yes)
		(layer "In6.Cu")
		(net "P5E_PEX0_STN4_RX_DN<71>")
	)
	(gr_poly
		(pts
			(arc
				(start 82.653124 -314.899802)
				(mid 82.246724 -314.899802)
				(end 82.653124 -314.899802)
			)
		)
		(stroke
			(width 0)
			(type solid)
		)
		(fill yes)
		(layer "In6.Cu")
		(net "P5E_PEX0_STN4_TX_DN<71>")
	)
	(gr_poly
		(pts
			(arc
				(start 82.653124 -312.049922)
				(mid 82.246724 -312.049922)
				(end 82.653124 -312.049922)
			)
		)
		(stroke
			(width 0)
			(type solid)
		)
		(fill yes)
		(layer "In6.Cu")
		(net "P5E_PEX0_STN4_TX_DN<70>")
	)
	(gr_poly
		(pts
			(arc
				(start 82.653124 -310.149748)
				(mid 82.246724 -310.149748)
				(end 82.653124 -310.149748)
			)
		)
		(stroke
			(width 0)
			(type solid)
		)
		(fill yes)
		(layer "In6.Cu")
		(net "P5E_PEX0_STN4_RX_DN<70>")
	)
	(gr_poly
		(pts
			(arc
				(start 82.653124 -308.249828)
				(mid 82.246724 -308.249828)
				(end 82.653124 -308.249828)
			)
		)
		(stroke
			(width 0)
			(type solid)
		)
		(fill yes)
		(layer "In6.Cu")
		(net "P5E_PEX0_STN4_RX_DN<68>")
	)
	(gr_poly
		(pts
			(arc
				(start 82.653124 -306.349908)
				(mid 82.246724 -306.349908)
				(end 82.653124 -306.349908)
			)
		)
		(stroke
			(width 0)
			(type solid)
		)
		(fill yes)
		(layer "In6.Cu")
		(net "P5E_PEX0_STN4_RX_DN<66>")
	)
	(gr_poly
		(pts
			(arc
				(start 82.653124 -304.449734)
				(mid 82.246724 -304.449734)
				(end 82.653124 -304.449734)
			)
		)
		(stroke
			(width 0)
			(type solid)
		)
		(fill yes)
		(layer "In6.Cu")
		(net "P5E_PEX0_STN4_RX_DN<64>")
	)
	(gr_poly
		(pts
			(arc
				(start 82.653124 -279.749758)
				(mid 82.246724 -279.749758)
				(end 82.653124 -279.749758)
			)
		)
		(stroke
			(width 0)
			(type solid)
		)
		(fill yes)
		(layer "In6.Cu")
		(net "P5E_PEX0_STN0_TX_DN<7>")
	)
	(gr_poly
		(pts
			(arc
				(start 82.653124 -276.899878)
				(mid 82.246724 -276.899878)
				(end 82.653124 -276.899878)
			)
		)
		(stroke
			(width 0)
			(type solid)
		)
		(fill yes)
		(layer "In6.Cu")
		(net "P5E_PEX0_STN0_TX_DN<8>")
	)
	(gr_poly
		(pts
			(arc
				(start 153.15311 -316.799722)
				(mid 152.74671 -316.799722)
				(end 153.15311 -316.799722)
			)
		)
		(stroke
			(width 0)
			(type solid)
		)
		(fill yes)
		(layer "In6.Cu")
		(net "P5E_PEX1_STN7_RX_DN<122>")
	)
	(gr_poly
		(pts
			(arc
				(start 153.15311 -314.899802)
				(mid 152.74671 -314.899802)
				(end 153.15311 -314.899802)
			)
		)
		(stroke
			(width 0)
			(type solid)
		)
		(fill yes)
		(layer "In6.Cu")
		(net "P5E_PEX1_STN7_TX_DN<122>")
	)
	(gr_poly
		(pts
			(arc
				(start 153.15311 -312.049922)
				(mid 152.74671 -312.049922)
				(end 153.15311 -312.049922)
			)
		)
		(stroke
			(width 0)
			(type solid)
		)
		(fill yes)
		(layer "In6.Cu")
		(net "P5E_PEX1_STN7_TX_DN<121>")
	)
	(gr_poly
		(pts
			(arc
				(start 153.15311 -310.149748)
				(mid 152.74671 -310.149748)
				(end 153.15311 -310.149748)
			)
		)
		(stroke
			(width 0)
			(type solid)
		)
		(fill yes)
		(layer "In6.Cu")
		(net "P5E_PEX1_STN7_RX_DN<121>")
	)
	(gr_poly
		(pts
			(arc
				(start 153.15311 -308.249828)
				(mid 152.74671 -308.249828)
				(end 153.15311 -308.249828)
			)
		)
		(stroke
			(width 0)
			(type solid)
		)
		(fill yes)
		(layer "In6.Cu")
		(net "P5E_PEX1_STN7_RX_DN<119>")
	)
	(gr_poly
		(pts
			(arc
				(start 153.15311 -306.349908)
				(mid 152.74671 -306.349908)
				(end 153.15311 -306.349908)
			)
		)
		(stroke
			(width 0)
			(type solid)
		)
		(fill yes)
		(layer "In6.Cu")
		(net "P5E_PEX1_STN7_RX_DN<117>")
	)
	(gr_poly
		(pts
			(arc
				(start 153.15311 -304.449734)
				(mid 152.74671 -304.449734)
				(end 153.15311 -304.449734)
			)
		)
		(stroke
			(width 0)
			(type solid)
		)
		(fill yes)
		(layer "In6.Cu")
		(net "P5E_PEX1_STN7_RX_DN<115>")
	)
	(gr_poly
		(pts
			(arc
				(start 153.15311 -302.549814)
				(mid 152.74671 -302.549814)
				(end 153.15311 -302.549814)
			)
		)
		(stroke
			(width 0)
			(type solid)
		)
		(fill yes)
		(layer "In6.Cu")
		(net "P5E_PEX1_STN7_RX_DN<113>")
	)
	(gr_poly
		(pts
			(arc
				(start 154.10307 -316.799722)
				(mid 153.69667 -316.799722)
				(end 154.10307 -316.799722)
			)
		)
		(stroke
			(width 0)
			(type solid)
		)
		(fill yes)
		(layer "In6.Cu")
		(net "P5E_PEX1_STN7_RX_DP<122>")
	)
	(gr_poly
		(pts
			(arc
				(start 154.10307 -314.899802)
				(mid 153.69667 -314.899802)
				(end 154.10307 -314.899802)
			)
		)
		(stroke
			(width 0)
			(type solid)
		)
		(fill yes)
		(layer "In6.Cu")
		(net "P5E_PEX1_STN7_TX_DP<122>")
	)
	(gr_poly
		(pts
			(arc
				(start 154.10307 -312.049922)
				(mid 153.69667 -312.049922)
				(end 154.10307 -312.049922)
			)
		)
		(stroke
			(width 0)
			(type solid)
		)
		(fill yes)
		(layer "In6.Cu")
		(net "P5E_PEX1_STN7_TX_DP<121>")
	)
	(gr_poly
		(pts
			(arc
				(start 154.10307 -310.149748)
				(mid 153.69667 -310.149748)
				(end 154.10307 -310.149748)
			)
		)
		(stroke
			(width 0)
			(type solid)
		)
		(fill yes)
		(layer "In6.Cu")
		(net "P5E_PEX1_STN7_RX_DP<121>")
	)
	(gr_poly
		(pts
			(arc
				(start 154.10307 -308.249828)
				(mid 153.69667 -308.249828)
				(end 154.10307 -308.249828)
			)
		)
		(stroke
			(width 0)
			(type solid)
		)
		(fill yes)
		(layer "In6.Cu")
		(net "P5E_PEX1_STN7_RX_DP<119>")
	)
	(gr_poly
		(pts
			(arc
				(start 154.10307 -306.349908)
				(mid 153.69667 -306.349908)
				(end 154.10307 -306.349908)
			)
		)
		(stroke
			(width 0)
			(type solid)
		)
		(fill yes)
		(layer "In6.Cu")
		(net "P5E_PEX1_STN7_RX_DP<117>")
	)
	(gr_poly
		(pts
			(arc
				(start 154.10307 -304.449734)
				(mid 153.69667 -304.449734)
				(end 154.10307 -304.449734)
			)
		)
		(stroke
			(width 0)
			(type solid)
		)
		(fill yes)
		(layer "In6.Cu")
		(net "P5E_PEX1_STN7_RX_DP<115>")
	)
	(gr_poly
		(pts
			(arc
				(start 154.10307 -302.549814)
				(mid 153.69667 -302.549814)
				(end 154.10307 -302.549814)
			)
		)
		(stroke
			(width 0)
			(type solid)
		)
		(fill yes)
		(layer "In6.Cu")
		(net "P5E_PEX1_STN7_RX_DP<113>")
	)
	(gr_poly
		(pts
			(arc
				(start 155.053284 -318.699896)
				(mid 154.646884 -318.699896)
				(end 155.053284 -318.699896)
			)
		)
		(stroke
			(width 0)
			(type solid)
		)
		(fill yes)
		(layer "In6.Cu")
		(net "P5E_PEX1_STN7_RX_DN<123>")
	)
	(gr_poly
		(pts
			(arc
				(start 155.053284 -317.749936)
				(mid 154.646884 -317.749936)
				(end 155.053284 -317.749936)
			)
		)
		(stroke
			(width 0)
			(type solid)
		)
		(fill yes)
		(layer "In6.Cu")
		(net "P5E_PEX1_STN7_RX_DP<123>")
	)
	(gr_poly
		(pts
			(arc
				(start 155.053284 -313.949842)
				(mid 154.646884 -313.949842)
				(end 155.053284 -313.949842)
			)
		)
		(stroke
			(width 0)
			(type solid)
		)
		(fill yes)
		(layer "In6.Cu")
		(net "P5E_PEX1_STN7_TX_DN<123>")
	)
	(gr_poly
		(pts
			(arc
				(start 155.053284 -312.999882)
				(mid 154.646884 -312.999882)
				(end 155.053284 -312.999882)
			)
		)
		(stroke
			(width 0)
			(type solid)
		)
		(fill yes)
		(layer "In6.Cu")
		(net "P5E_PEX1_STN7_TX_DP<123>")
	)
	(gr_poly
		(pts
			(arc
				(start 155.053284 -309.199788)
				(mid 154.646884 -309.199788)
				(end 155.053284 -309.199788)
			)
		)
		(stroke
			(width 0)
			(type solid)
		)
		(fill yes)
		(layer "In6.Cu")
		(net "P5E_PEX1_STN7_RX_DN<120>")
	)
	(gr_poly
		(pts
			(arc
				(start 155.053284 -307.299868)
				(mid 154.646884 -307.299868)
				(end 155.053284 -307.299868)
			)
		)
		(stroke
			(width 0)
			(type solid)
		)
		(fill yes)
		(layer "In6.Cu")
		(net "P5E_PEX1_STN7_RX_DN<118>")
	)
	(gr_poly
		(pts
			(arc
				(start 155.053284 -305.399948)
				(mid 154.646884 -305.399948)
				(end 155.053284 -305.399948)
			)
		)
		(stroke
			(width 0)
			(type solid)
		)
		(fill yes)
		(layer "In6.Cu")
		(net "P5E_PEX1_STN7_RX_DN<116>")
	)
	(gr_poly
		(pts
			(arc
				(start 155.053284 -303.499774)
				(mid 154.646884 -303.499774)
				(end 155.053284 -303.499774)
			)
		)
		(stroke
			(width 0)
			(type solid)
		)
		(fill yes)
		(layer "In6.Cu")
		(net "P5E_PEX1_STN7_RX_DN<114>")
	)
	(gr_poly
		(pts
			(arc
				(start 155.053284 -301.599854)
				(mid 154.646884 -301.599854)
				(end 155.053284 -301.599854)
			)
		)
		(stroke
			(width 0)
			(type solid)
		)
		(fill yes)
		(layer "In6.Cu")
		(net "P5E_PEX1_STN7_RX_DN<112>")
	)
	(gr_poly
		(pts
			(arc
				(start 156.003244 -316.799722)
				(mid 155.596844 -316.799722)
				(end 156.003244 -316.799722)
			)
		)
		(stroke
			(width 0)
			(type solid)
		)
		(fill yes)
		(layer "In6.Cu")
		(net "P5E_PEX1_STN7_RX_DN<124>")
	)
	(gr_poly
		(pts
			(arc
				(start 156.003244 -315.849762)
				(mid 155.596844 -315.849762)
				(end 156.003244 -315.849762)
			)
		)
		(stroke
			(width 0)
			(type solid)
		)
		(fill yes)
		(layer "In6.Cu")
		(net "P5E_PEX1_STN7_RX_DP<124>")
	)
	(gr_poly
		(pts
			(arc
				(start 156.003244 -312.049922)
				(mid 155.596844 -312.049922)
				(end 156.003244 -312.049922)
			)
		)
		(stroke
			(width 0)
			(type solid)
		)
		(fill yes)
		(layer "In6.Cu")
		(net "P5E_PEX1_STN7_TX_DN<124>")
	)
	(gr_poly
		(pts
			(arc
				(start 156.003244 -311.099962)
				(mid 155.596844 -311.099962)
				(end 156.003244 -311.099962)
			)
		)
		(stroke
			(width 0)
			(type solid)
		)
		(fill yes)
		(layer "In6.Cu")
		(net "P5E_PEX1_STN7_TX_DP<124>")
	)
	(gr_poly
		(pts
			(arc
				(start 156.003244 -309.199788)
				(mid 155.596844 -309.199788)
				(end 156.003244 -309.199788)
			)
		)
		(stroke
			(width 0)
			(type solid)
		)
		(fill yes)
		(layer "In6.Cu")
		(net "P5E_PEX1_STN7_RX_DP<120>")
	)
	(gr_poly
		(pts
			(arc
				(start 156.003244 -307.299868)
				(mid 155.596844 -307.299868)
				(end 156.003244 -307.299868)
			)
		)
		(stroke
			(width 0)
			(type solid)
		)
		(fill yes)
		(layer "In6.Cu")
		(net "P5E_PEX1_STN7_RX_DP<118>")
	)
	(gr_poly
		(pts
			(arc
				(start 156.003244 -305.399948)
				(mid 155.596844 -305.399948)
				(end 156.003244 -305.399948)
			)
		)
		(stroke
			(width 0)
			(type solid)
		)
		(fill yes)
		(layer "In6.Cu")
		(net "P5E_PEX1_STN7_RX_DP<116>")
	)
	(gr_poly
		(pts
			(arc
				(start 156.003244 -303.499774)
				(mid 155.596844 -303.499774)
				(end 156.003244 -303.499774)
			)
		)
		(stroke
			(width 0)
			(type solid)
		)
		(fill yes)
		(layer "In6.Cu")
		(net "P5E_PEX1_STN7_RX_DP<114>")
	)
	(gr_poly
		(pts
			(arc
				(start 156.003244 -301.599854)
				(mid 155.596844 -301.599854)
				(end 156.003244 -301.599854)
			)
		)
		(stroke
			(width 0)
			(type solid)
		)
		(fill yes)
		(layer "In6.Cu")
		(net "P5E_PEX1_STN7_RX_DP<112>")
	)
	(gr_poly
		(pts
			(arc
				(start 156.953204 -318.699896)
				(mid 156.546804 -318.699896)
				(end 156.953204 -318.699896)
			)
		)
		(stroke
			(width 0)
			(type solid)
		)
		(fill yes)
		(layer "In6.Cu")
		(net "P5E_PEX1_STN7_RX_DN<125>")
	)
	(gr_poly
		(pts
			(arc
				(start 156.953204 -317.749936)
				(mid 156.546804 -317.749936)
				(end 156.953204 -317.749936)
			)
		)
		(stroke
			(width 0)
			(type solid)
		)
		(fill yes)
		(layer "In6.Cu")
		(net "P5E_PEX1_STN7_RX_DP<125>")
	)
	(gr_poly
		(pts
			(arc
				(start 156.953204 -313.949842)
				(mid 156.546804 -313.949842)
				(end 156.953204 -313.949842)
			)
		)
		(stroke
			(width 0)
			(type solid)
		)
		(fill yes)
		(layer "In6.Cu")
		(net "P5E_PEX1_STN7_TX_DN<125>")
	)
	(gr_poly
		(pts
			(arc
				(start 156.953204 -312.999882)
				(mid 156.546804 -312.999882)
				(end 156.953204 -312.999882)
			)
		)
		(stroke
			(width 0)
			(type solid)
		)
		(fill yes)
		(layer "In6.Cu")
		(net "P5E_PEX1_STN7_TX_DP<125>")
	)
	(gr_poly
		(pts
			(arc
				(start 157.903164 -316.799722)
				(mid 157.496764 -316.799722)
				(end 157.903164 -316.799722)
			)
		)
		(stroke
			(width 0)
			(type solid)
		)
		(fill yes)
		(layer "In6.Cu")
		(net "P5E_PEX1_STN7_RX_DN<126>")
	)
	(gr_poly
		(pts
			(arc
				(start 157.903164 -315.849762)
				(mid 157.496764 -315.849762)
				(end 157.903164 -315.849762)
			)
		)
		(stroke
			(width 0)
			(type solid)
		)
		(fill yes)
		(layer "In6.Cu")
		(net "P5E_PEX1_STN7_RX_DP<126>")
	)
	(gr_poly
		(pts
			(arc
				(start 157.903164 -312.049922)
				(mid 157.496764 -312.049922)
				(end 157.903164 -312.049922)
			)
		)
		(stroke
			(width 0)
			(type solid)
		)
		(fill yes)
		(layer "In6.Cu")
		(net "P5E_PEX1_STN7_TX_DN<126>")
	)
	(gr_poly
		(pts
			(arc
				(start 157.903164 -311.099962)
				(mid 157.496764 -311.099962)
				(end 157.903164 -311.099962)
			)
		)
		(stroke
			(width 0)
			(type solid)
		)
		(fill yes)
		(layer "In6.Cu")
		(net "P5E_PEX1_STN7_TX_DP<126>")
	)
	(gr_poly
		(pts
			(arc
				(start 157.903164 -309.199788)
				(mid 157.496764 -309.199788)
				(end 157.903164 -309.199788)
			)
		)
		(stroke
			(width 0)
			(type solid)
		)
		(fill yes)
		(layer "In6.Cu")
		(net "P5E_PEX1_STN7_TX_DN<120>")
	)
	(gr_poly
		(pts
			(arc
				(start 157.903164 -307.299868)
				(mid 157.496764 -307.299868)
				(end 157.903164 -307.299868)
			)
		)
		(stroke
			(width 0)
			(type solid)
		)
		(fill yes)
		(layer "In6.Cu")
		(net "P5E_PEX1_STN7_TX_DN<118>")
	)
	(gr_poly
		(pts
			(arc
				(start 157.903164 -305.399948)
				(mid 157.496764 -305.399948)
				(end 157.903164 -305.399948)
			)
		)
		(stroke
			(width 0)
			(type solid)
		)
		(fill yes)
		(layer "In6.Cu")
		(net "P5E_PEX1_STN7_TX_DN<116>")
	)
	(gr_poly
		(pts
			(arc
				(start 157.903164 -303.499774)
				(mid 157.496764 -303.499774)
				(end 157.903164 -303.499774)
			)
		)
		(stroke
			(width 0)
			(type solid)
		)
		(fill yes)
		(layer "In6.Cu")
		(net "P5E_PEX1_STN7_TX_DN<114>")
	)
	(gr_poly
		(pts
			(arc
				(start 157.903164 -301.599854)
				(mid 157.496764 -301.599854)
				(end 157.903164 -301.599854)
			)
		)
		(stroke
			(width 0)
			(type solid)
		)
		(fill yes)
		(layer "In6.Cu")
		(net "P5E_PEX1_STN7_TX_DN<112>")
	)
	(gr_poly
		(pts
			(arc
				(start 158.853124 -318.699896)
				(mid 158.446724 -318.699896)
				(end 158.853124 -318.699896)
			)
		)
		(stroke
			(width 0)
			(type solid)
		)
		(fill yes)
		(layer "In6.Cu")
		(net "P5E_PEX1_STN7_RX_DN<127>")
	)
	(gr_poly
		(pts
			(arc
				(start 158.853124 -317.749936)
				(mid 158.446724 -317.749936)
				(end 158.853124 -317.749936)
			)
		)
		(stroke
			(width 0)
			(type solid)
		)
		(fill yes)
		(layer "In6.Cu")
		(net "P5E_PEX1_STN7_RX_DP<127>")
	)
	(gr_poly
		(pts
			(arc
				(start 158.853124 -313.949842)
				(mid 158.446724 -313.949842)
				(end 158.853124 -313.949842)
			)
		)
		(stroke
			(width 0)
			(type solid)
		)
		(fill yes)
		(layer "In6.Cu")
		(net "P5E_PEX1_STN7_TX_DN<127>")
	)
	(gr_poly
		(pts
			(arc
				(start 158.853124 -312.999882)
				(mid 158.446724 -312.999882)
				(end 158.853124 -312.999882)
			)
		)
		(stroke
			(width 0)
			(type solid)
		)
		(fill yes)
		(layer "In6.Cu")
		(net "P5E_PEX1_STN7_TX_DP<127>")
	)
	(gr_poly
		(pts
			(arc
				(start 158.853124 -309.199788)
				(mid 158.446724 -309.199788)
				(end 158.853124 -309.199788)
			)
		)
		(stroke
			(width 0)
			(type solid)
		)
		(fill yes)
		(layer "In6.Cu")
		(net "P5E_PEX1_STN7_TX_DP<120>")
	)
	(gr_poly
		(pts
			(arc
				(start 158.853124 -307.299868)
				(mid 158.446724 -307.299868)
				(end 158.853124 -307.299868)
			)
		)
		(stroke
			(width 0)
			(type solid)
		)
		(fill yes)
		(layer "In6.Cu")
		(net "P5E_PEX1_STN7_TX_DP<118>")
	)
	(gr_poly
		(pts
			(arc
				(start 158.853124 -305.399948)
				(mid 158.446724 -305.399948)
				(end 158.853124 -305.399948)
			)
		)
		(stroke
			(width 0)
			(type solid)
		)
		(fill yes)
		(layer "In6.Cu")
		(net "P5E_PEX1_STN7_TX_DP<116>")
	)
	(gr_poly
		(pts
			(arc
				(start 158.853124 -303.499774)
				(mid 158.446724 -303.499774)
				(end 158.853124 -303.499774)
			)
		)
		(stroke
			(width 0)
			(type solid)
		)
		(fill yes)
		(layer "In6.Cu")
		(net "P5E_PEX1_STN7_TX_DP<114>")
	)
	(gr_poly
		(pts
			(arc
				(start 158.853124 -301.599854)
				(mid 158.446724 -301.599854)
				(end 158.853124 -301.599854)
			)
		)
		(stroke
			(width 0)
			(type solid)
		)
		(fill yes)
		(layer "In6.Cu")
		(net "P5E_PEX1_STN7_TX_DP<112>")
	)
	(gr_poly
		(pts
			(arc
				(start 159.803084 -316.799722)
				(mid 159.396684 -316.799722)
				(end 159.803084 -316.799722)
			)
		)
		(stroke
			(width 0)
			(type solid)
		)
		(fill yes)
		(layer "In6.Cu")
		(net "P5E_PEX1_STN6_RX_DN<111>")
	)
	(gr_poly
		(pts
			(arc
				(start 159.803084 -315.849762)
				(mid 159.396684 -315.849762)
				(end 159.803084 -315.849762)
			)
		)
		(stroke
			(width 0)
			(type solid)
		)
		(fill yes)
		(layer "In6.Cu")
		(net "P5E_PEX1_STN6_RX_DP<111>")
	)
	(gr_poly
		(pts
			(arc
				(start 159.803084 -312.049922)
				(mid 159.396684 -312.049922)
				(end 159.803084 -312.049922)
			)
		)
		(stroke
			(width 0)
			(type solid)
		)
		(fill yes)
		(layer "In6.Cu")
		(net "P5E_PEX1_STN6_TX_DN<111>")
	)
	(gr_poly
		(pts
			(arc
				(start 159.803084 -311.099962)
				(mid 159.396684 -311.099962)
				(end 159.803084 -311.099962)
			)
		)
		(stroke
			(width 0)
			(type solid)
		)
		(fill yes)
		(layer "In6.Cu")
		(net "P5E_PEX1_STN6_TX_DP<111>")
	)
	(gr_poly
		(pts
			(arc
				(start 159.803084 -308.249828)
				(mid 159.396684 -308.249828)
				(end 159.803084 -308.249828)
			)
		)
		(stroke
			(width 0)
			(type solid)
		)
		(fill yes)
		(layer "In6.Cu")
		(net "P5E_PEX1_STN7_TX_DN<119>")
	)
	(gr_poly
		(pts
			(arc
				(start 159.803084 -306.349908)
				(mid 159.396684 -306.349908)
				(end 159.803084 -306.349908)
			)
		)
		(stroke
			(width 0)
			(type solid)
		)
		(fill yes)
		(layer "In6.Cu")
		(net "P5E_PEX1_STN7_TX_DN<117>")
	)
	(gr_poly
		(pts
			(arc
				(start 159.803084 -304.449734)
				(mid 159.396684 -304.449734)
				(end 159.803084 -304.449734)
			)
		)
		(stroke
			(width 0)
			(type solid)
		)
		(fill yes)
		(layer "In6.Cu")
		(net "P5E_PEX1_STN7_TX_DN<115>")
	)
	(gr_poly
		(pts
			(arc
				(start 159.803084 -302.549814)
				(mid 159.396684 -302.549814)
				(end 159.803084 -302.549814)
			)
		)
		(stroke
			(width 0)
			(type solid)
		)
		(fill yes)
		(layer "In6.Cu")
		(net "P5E_PEX1_STN7_TX_DN<113>")
	)
	(gr_poly
		(pts
			(arc
				(start 160.753044 -318.699896)
				(mid 160.346644 -318.699896)
				(end 160.753044 -318.699896)
			)
		)
		(stroke
			(width 0)
			(type solid)
		)
		(fill yes)
		(layer "In6.Cu")
		(net "P5E_PEX1_STN6_RX_DN<110>")
	)
	(gr_poly
		(pts
			(arc
				(start 160.753044 -317.749936)
				(mid 160.346644 -317.749936)
				(end 160.753044 -317.749936)
			)
		)
		(stroke
			(width 0)
			(type solid)
		)
		(fill yes)
		(layer "In6.Cu")
		(net "P5E_PEX1_STN6_RX_DP<110>")
	)
	(gr_poly
		(pts
			(arc
				(start 160.753044 -313.949842)
				(mid 160.346644 -313.949842)
				(end 160.753044 -313.949842)
			)
		)
		(stroke
			(width 0)
			(type solid)
		)
		(fill yes)
		(layer "In6.Cu")
		(net "P5E_PEX1_STN6_TX_DN<110>")
	)
	(gr_poly
		(pts
			(arc
				(start 160.753044 -312.999882)
				(mid 160.346644 -312.999882)
				(end 160.753044 -312.999882)
			)
		)
		(stroke
			(width 0)
			(type solid)
		)
		(fill yes)
		(layer "In6.Cu")
		(net "P5E_PEX1_STN6_TX_DP<110>")
	)
	(gr_poly
		(pts
			(arc
				(start 160.753044 -308.249828)
				(mid 160.346644 -308.249828)
				(end 160.753044 -308.249828)
			)
		)
		(stroke
			(width 0)
			(type solid)
		)
		(fill yes)
		(layer "In6.Cu")
		(net "P5E_PEX1_STN7_TX_DP<119>")
	)
	(gr_poly
		(pts
			(arc
				(start 160.753044 -306.349908)
				(mid 160.346644 -306.349908)
				(end 160.753044 -306.349908)
			)
		)
		(stroke
			(width 0)
			(type solid)
		)
		(fill yes)
		(layer "In6.Cu")
		(net "P5E_PEX1_STN7_TX_DP<117>")
	)
	(gr_poly
		(pts
			(arc
				(start 160.753044 -304.449734)
				(mid 160.346644 -304.449734)
				(end 160.753044 -304.449734)
			)
		)
		(stroke
			(width 0)
			(type solid)
		)
		(fill yes)
		(layer "In6.Cu")
		(net "P5E_PEX1_STN7_TX_DP<115>")
	)
	(gr_poly
		(pts
			(arc
				(start 160.753044 -302.549814)
				(mid 160.346644 -302.549814)
				(end 160.753044 -302.549814)
			)
		)
		(stroke
			(width 0)
			(type solid)
		)
		(fill yes)
		(layer "In6.Cu")
		(net "P5E_PEX1_STN7_TX_DP<113>")
	)
	(gr_poly
		(pts
			(arc
				(start 160.753044 -278.799798)
				(mid 160.346644 -278.799798)
				(end 160.753044 -278.799798)
			)
		)
		(stroke
			(width 0)
			(type solid)
		)
		(fill yes)
		(layer "In6.Cu")
		(net "P5E_PEX1_STN2_TX_DP<47>")
	)
	(gr_poly
		(pts
			(arc
				(start 160.753044 -277.849838)
				(mid 160.346644 -277.849838)
				(end 160.753044 -277.849838)
			)
		)
		(stroke
			(width 0)
			(type solid)
		)
		(fill yes)
		(layer "In6.Cu")
		(net "P5E_PEX1_STN2_TX_DN<47>")
	)
	(gr_poly
		(pts
			(arc
				(start 160.753044 -274.049744)
				(mid 160.346644 -274.049744)
				(end 160.753044 -274.049744)
			)
		)
		(stroke
			(width 0)
			(type solid)
		)
		(fill yes)
		(layer "In6.Cu")
		(net "P5E_PEX1_STN2_RX_DP<47>")
	)
	(gr_poly
		(pts
			(arc
				(start 160.753044 -273.099784)
				(mid 160.346644 -273.099784)
				(end 160.753044 -273.099784)
			)
		)
		(stroke
			(width 0)
			(type solid)
		)
		(fill yes)
		(layer "In6.Cu")
		(net "P5E_PEX1_STN2_RX_DN<47>")
	)
	(gr_poly
		(pts
			(arc
				(start 161.703258 -316.799722)
				(mid 161.296858 -316.799722)
				(end 161.703258 -316.799722)
			)
		)
		(stroke
			(width 0)
			(type solid)
		)
		(fill yes)
		(layer "In6.Cu")
		(net "P5E_PEX1_STN6_RX_DN<109>")
	)
	(gr_poly
		(pts
			(arc
				(start 161.703258 -315.849762)
				(mid 161.296858 -315.849762)
				(end 161.703258 -315.849762)
			)
		)
		(stroke
			(width 0)
			(type solid)
		)
		(fill yes)
		(layer "In6.Cu")
		(net "P5E_PEX1_STN6_RX_DP<109>")
	)
	(gr_poly
		(pts
			(arc
				(start 161.703258 -312.049922)
				(mid 161.296858 -312.049922)
				(end 161.703258 -312.049922)
			)
		)
		(stroke
			(width 0)
			(type solid)
		)
		(fill yes)
		(layer "In6.Cu")
		(net "P5E_PEX1_STN6_TX_DN<109>")
	)
	(gr_poly
		(pts
			(arc
				(start 161.703258 -311.099962)
				(mid 161.296858 -311.099962)
				(end 161.703258 -311.099962)
			)
		)
		(stroke
			(width 0)
			(type solid)
		)
		(fill yes)
		(layer "In6.Cu")
		(net "P5E_PEX1_STN6_TX_DP<109>")
	)
	(gr_poly
		(pts
			(arc
				(start 161.703258 -280.699718)
				(mid 161.296858 -280.699718)
				(end 161.703258 -280.699718)
			)
		)
		(stroke
			(width 0)
			(type solid)
		)
		(fill yes)
		(layer "In6.Cu")
		(net "P5E_PEX1_STN2_TX_DP<46>")
	)
	(gr_poly
		(pts
			(arc
				(start 161.703258 -279.749504)
				(mid 161.296858 -279.749504)
				(end 161.703258 -279.749504)
			)
		)
		(stroke
			(width 0)
			(type solid)
		)
		(fill yes)
		(layer "In6.Cu")
		(net "P5E_PEX1_STN2_TX_DN<46>")
	)
	(gr_poly
		(pts
			(arc
				(start 161.703258 -275.949918)
				(mid 161.296858 -275.949918)
				(end 161.703258 -275.949918)
			)
		)
		(stroke
			(width 0)
			(type solid)
		)
		(fill yes)
		(layer "In6.Cu")
		(net "P5E_PEX1_STN2_RX_DP<46>")
	)
	(gr_poly
		(pts
			(arc
				(start 161.703258 -274.999958)
				(mid 161.296858 -274.999958)
				(end 161.703258 -274.999958)
			)
		)
		(stroke
			(width 0)
			(type solid)
		)
		(fill yes)
		(layer "In6.Cu")
		(net "P5E_PEX1_STN2_RX_DN<46>")
	)
	(gr_poly
		(pts
			(arc
				(start 162.653218 -318.699896)
				(mid 162.246818 -318.699896)
				(end 162.653218 -318.699896)
			)
		)
		(stroke
			(width 0)
			(type solid)
		)
		(fill yes)
		(layer "In6.Cu")
		(net "P5E_PEX1_STN6_RX_DN<108>")
	)
	(gr_poly
		(pts
			(arc
				(start 162.653218 -317.749936)
				(mid 162.246818 -317.749936)
				(end 162.653218 -317.749936)
			)
		)
		(stroke
			(width 0)
			(type solid)
		)
		(fill yes)
		(layer "In6.Cu")
		(net "P5E_PEX1_STN6_RX_DP<108>")
	)
	(gr_poly
		(pts
			(arc
				(start 162.653218 -313.949842)
				(mid 162.246818 -313.949842)
				(end 162.653218 -313.949842)
			)
		)
		(stroke
			(width 0)
			(type solid)
		)
		(fill yes)
		(layer "In6.Cu")
		(net "P5E_PEX1_STN6_TX_DN<108>")
	)
	(gr_poly
		(pts
			(arc
				(start 162.653218 -312.999882)
				(mid 162.246818 -312.999882)
				(end 162.653218 -312.999882)
			)
		)
		(stroke
			(width 0)
			(type solid)
		)
		(fill yes)
		(layer "In6.Cu")
		(net "P5E_PEX1_STN6_TX_DP<108>")
	)
	(gr_poly
		(pts
			(arc
				(start 162.653218 -278.799798)
				(mid 162.246818 -278.799798)
				(end 162.653218 -278.799798)
			)
		)
		(stroke
			(width 0)
			(type solid)
		)
		(fill yes)
		(layer "In6.Cu")
		(net "P5E_PEX1_STN2_TX_DP<45>")
	)
	(gr_poly
		(pts
			(arc
				(start 162.653218 -277.849838)
				(mid 162.246818 -277.849838)
				(end 162.653218 -277.849838)
			)
		)
		(stroke
			(width 0)
			(type solid)
		)
		(fill yes)
		(layer "In6.Cu")
		(net "P5E_PEX1_STN2_TX_DN<45>")
	)
	(gr_poly
		(pts
			(arc
				(start 162.653218 -274.049744)
				(mid 162.246818 -274.049744)
				(end 162.653218 -274.049744)
			)
		)
		(stroke
			(width 0)
			(type solid)
		)
		(fill yes)
		(layer "In6.Cu")
		(net "P5E_PEX1_STN2_RX_DP<45>")
	)
	(gr_poly
		(pts
			(arc
				(start 162.653218 -273.099784)
				(mid 162.246818 -273.099784)
				(end 162.653218 -273.099784)
			)
		)
		(stroke
			(width 0)
			(type solid)
		)
		(fill yes)
		(layer "In6.Cu")
		(net "P5E_PEX1_STN2_RX_DN<45>")
	)
	(gr_poly
		(pts
			(arc
				(start 163.603178 -316.799722)
				(mid 163.196778 -316.799722)
				(end 163.603178 -316.799722)
			)
		)
		(stroke
			(width 0)
			(type solid)
		)
		(fill yes)
		(layer "In6.Cu")
		(net "P5E_PEX1_STN6_RX_DN<107>")
	)
	(gr_poly
		(pts
			(arc
				(start 163.603178 -315.849762)
				(mid 163.196778 -315.849762)
				(end 163.603178 -315.849762)
			)
		)
		(stroke
			(width 0)
			(type solid)
		)
		(fill yes)
		(layer "In6.Cu")
		(net "P5E_PEX1_STN6_RX_DP<107>")
	)
	(gr_poly
		(pts
			(arc
				(start 163.603178 -312.049922)
				(mid 163.196778 -312.049922)
				(end 163.603178 -312.049922)
			)
		)
		(stroke
			(width 0)
			(type solid)
		)
		(fill yes)
		(layer "In6.Cu")
		(net "P5E_PEX1_STN6_TX_DN<107>")
	)
	(gr_poly
		(pts
			(arc
				(start 163.603178 -311.099962)
				(mid 163.196778 -311.099962)
				(end 163.603178 -311.099962)
			)
		)
		(stroke
			(width 0)
			(type solid)
		)
		(fill yes)
		(layer "In6.Cu")
		(net "P5E_PEX1_STN6_TX_DP<107>")
	)
	(gr_poly
		(pts
			(arc
				(start 163.603178 -280.699718)
				(mid 163.196778 -280.699718)
				(end 163.603178 -280.699718)
			)
		)
		(stroke
			(width 0)
			(type solid)
		)
		(fill yes)
		(layer "In6.Cu")
		(net "P5E_PEX1_STN2_TX_DP<44>")
	)
	(gr_poly
		(pts
			(arc
				(start 163.603178 -279.749504)
				(mid 163.196778 -279.749504)
				(end 163.603178 -279.749504)
			)
		)
		(stroke
			(width 0)
			(type solid)
		)
		(fill yes)
		(layer "In6.Cu")
		(net "P5E_PEX1_STN2_TX_DN<44>")
	)
	(gr_poly
		(pts
			(arc
				(start 163.603178 -275.949918)
				(mid 163.196778 -275.949918)
				(end 163.603178 -275.949918)
			)
		)
		(stroke
			(width 0)
			(type solid)
		)
		(fill yes)
		(layer "In6.Cu")
		(net "P5E_PEX1_STN2_RX_DP<44>")
	)
	(gr_poly
		(pts
			(arc
				(start 163.603178 -274.999958)
				(mid 163.196778 -274.999958)
				(end 163.603178 -274.999958)
			)
		)
		(stroke
			(width 0)
			(type solid)
		)
		(fill yes)
		(layer "In6.Cu")
		(net "P5E_PEX1_STN2_RX_DN<44>")
	)
	(gr_poly
		(pts
			(arc
				(start 164.553138 -318.699896)
				(mid 164.146738 -318.699896)
				(end 164.553138 -318.699896)
			)
		)
		(stroke
			(width 0)
			(type solid)
		)
		(fill yes)
		(layer "In6.Cu")
		(net "P5E_PEX1_STN6_RX_DN<106>")
	)
	(gr_poly
		(pts
			(arc
				(start 164.553138 -317.749936)
				(mid 164.146738 -317.749936)
				(end 164.553138 -317.749936)
			)
		)
		(stroke
			(width 0)
			(type solid)
		)
		(fill yes)
		(layer "In6.Cu")
		(net "P5E_PEX1_STN6_RX_DP<106>")
	)
	(gr_poly
		(pts
			(arc
				(start 164.553138 -313.949842)
				(mid 164.146738 -313.949842)
				(end 164.553138 -313.949842)
			)
		)
		(stroke
			(width 0)
			(type solid)
		)
		(fill yes)
		(layer "In6.Cu")
		(net "P5E_PEX1_STN6_TX_DN<106>")
	)
	(gr_poly
		(pts
			(arc
				(start 164.553138 -312.999882)
				(mid 164.146738 -312.999882)
				(end 164.553138 -312.999882)
			)
		)
		(stroke
			(width 0)
			(type solid)
		)
		(fill yes)
		(layer "In6.Cu")
		(net "P5E_PEX1_STN6_TX_DP<106>")
	)
	(gr_poly
		(pts
			(arc
				(start 164.553138 -278.799798)
				(mid 164.146738 -278.799798)
				(end 164.553138 -278.799798)
			)
		)
		(stroke
			(width 0)
			(type solid)
		)
		(fill yes)
		(layer "In6.Cu")
		(net "P5E_PEX1_STN2_TX_DP<43>")
	)
	(gr_poly
		(pts
			(arc
				(start 164.553138 -277.849838)
				(mid 164.146738 -277.849838)
				(end 164.553138 -277.849838)
			)
		)
		(stroke
			(width 0)
			(type solid)
		)
		(fill yes)
		(layer "In6.Cu")
		(net "P5E_PEX1_STN2_TX_DN<43>")
	)
	(gr_poly
		(pts
			(arc
				(start 164.553138 -274.049744)
				(mid 164.146738 -274.049744)
				(end 164.553138 -274.049744)
			)
		)
		(stroke
			(width 0)
			(type solid)
		)
		(fill yes)
		(layer "In6.Cu")
		(net "P5E_PEX1_STN2_RX_DP<43>")
	)
	(gr_poly
		(pts
			(arc
				(start 164.553138 -273.099784)
				(mid 164.146738 -273.099784)
				(end 164.553138 -273.099784)
			)
		)
		(stroke
			(width 0)
			(type solid)
		)
		(fill yes)
		(layer "In6.Cu")
		(net "P5E_PEX1_STN2_RX_DN<43>")
	)
	(gr_poly
		(pts
			(arc
				(start 165.503098 -316.799722)
				(mid 165.096698 -316.799722)
				(end 165.503098 -316.799722)
			)
		)
		(stroke
			(width 0)
			(type solid)
		)
		(fill yes)
		(layer "In6.Cu")
		(net "P5E_PEX1_STN6_RX_DN<105>")
	)
	(gr_poly
		(pts
			(arc
				(start 165.503098 -315.849762)
				(mid 165.096698 -315.849762)
				(end 165.503098 -315.849762)
			)
		)
		(stroke
			(width 0)
			(type solid)
		)
		(fill yes)
		(layer "In6.Cu")
		(net "P5E_PEX1_STN6_RX_DP<105>")
	)
	(gr_poly
		(pts
			(arc
				(start 165.503098 -312.049922)
				(mid 165.096698 -312.049922)
				(end 165.503098 -312.049922)
			)
		)
		(stroke
			(width 0)
			(type solid)
		)
		(fill yes)
		(layer "In6.Cu")
		(net "P5E_PEX1_STN6_TX_DN<105>")
	)
	(gr_poly
		(pts
			(arc
				(start 165.503098 -311.099962)
				(mid 165.096698 -311.099962)
				(end 165.503098 -311.099962)
			)
		)
		(stroke
			(width 0)
			(type solid)
		)
		(fill yes)
		(layer "In6.Cu")
		(net "P5E_PEX1_STN6_TX_DP<105>")
	)
	(gr_poly
		(pts
			(arc
				(start 165.503098 -280.699718)
				(mid 165.096698 -280.699718)
				(end 165.503098 -280.699718)
			)
		)
		(stroke
			(width 0)
			(type solid)
		)
		(fill yes)
		(layer "In6.Cu")
		(net "P5E_PEX1_STN2_TX_DP<42>")
	)
	(gr_poly
		(pts
			(arc
				(start 165.503098 -279.749504)
				(mid 165.096698 -279.749504)
				(end 165.503098 -279.749504)
			)
		)
		(stroke
			(width 0)
			(type solid)
		)
		(fill yes)
		(layer "In6.Cu")
		(net "P5E_PEX1_STN2_TX_DN<42>")
	)
	(gr_poly
		(pts
			(arc
				(start 165.503098 -275.949918)
				(mid 165.096698 -275.949918)
				(end 165.503098 -275.949918)
			)
		)
		(stroke
			(width 0)
			(type solid)
		)
		(fill yes)
		(layer "In6.Cu")
		(net "P5E_PEX1_STN2_RX_DP<42>")
	)
	(gr_poly
		(pts
			(arc
				(start 165.503098 -274.999958)
				(mid 165.096698 -274.999958)
				(end 165.503098 -274.999958)
			)
		)
		(stroke
			(width 0)
			(type solid)
		)
		(fill yes)
		(layer "In6.Cu")
		(net "P5E_PEX1_STN2_RX_DN<42>")
	)
	(gr_poly
		(pts
			(arc
				(start 166.453058 -318.699896)
				(mid 166.046658 -318.699896)
				(end 166.453058 -318.699896)
			)
		)
		(stroke
			(width 0)
			(type solid)
		)
		(fill yes)
		(layer "In6.Cu")
		(net "P5E_PEX1_STN6_RX_DN<104>")
	)
	(gr_poly
		(pts
			(arc
				(start 166.453058 -317.749936)
				(mid 166.046658 -317.749936)
				(end 166.453058 -317.749936)
			)
		)
		(stroke
			(width 0)
			(type solid)
		)
		(fill yes)
		(layer "In6.Cu")
		(net "P5E_PEX1_STN6_RX_DP<104>")
	)
	(gr_poly
		(pts
			(arc
				(start 166.453058 -313.949842)
				(mid 166.046658 -313.949842)
				(end 166.453058 -313.949842)
			)
		)
		(stroke
			(width 0)
			(type solid)
		)
		(fill yes)
		(layer "In6.Cu")
		(net "P5E_PEX1_STN6_TX_DN<104>")
	)
	(gr_poly
		(pts
			(arc
				(start 166.453058 -312.999882)
				(mid 166.046658 -312.999882)
				(end 166.453058 -312.999882)
			)
		)
		(stroke
			(width 0)
			(type solid)
		)
		(fill yes)
		(layer "In6.Cu")
		(net "P5E_PEX1_STN6_TX_DP<104>")
	)
	(gr_poly
		(pts
			(arc
				(start 166.453058 -278.799798)
				(mid 166.046658 -278.799798)
				(end 166.453058 -278.799798)
			)
		)
		(stroke
			(width 0)
			(type solid)
		)
		(fill yes)
		(layer "In6.Cu")
		(net "P5E_PEX1_STN2_TX_DP<41>")
	)
	(gr_poly
		(pts
			(arc
				(start 166.453058 -277.849838)
				(mid 166.046658 -277.849838)
				(end 166.453058 -277.849838)
			)
		)
		(stroke
			(width 0)
			(type solid)
		)
		(fill yes)
		(layer "In6.Cu")
		(net "P5E_PEX1_STN2_TX_DN<41>")
	)
	(gr_poly
		(pts
			(arc
				(start 166.453058 -274.049744)
				(mid 166.046658 -274.049744)
				(end 166.453058 -274.049744)
			)
		)
		(stroke
			(width 0)
			(type solid)
		)
		(fill yes)
		(layer "In6.Cu")
		(net "P5E_PEX1_STN2_RX_DP<41>")
	)
	(gr_poly
		(pts
			(arc
				(start 166.453058 -273.099784)
				(mid 166.046658 -273.099784)
				(end 166.453058 -273.099784)
			)
		)
		(stroke
			(width 0)
			(type solid)
		)
		(fill yes)
		(layer "In6.Cu")
		(net "P5E_PEX1_STN2_RX_DN<41>")
	)
	(gr_poly
		(pts
			(arc
				(start 167.403272 -312.049922)
				(mid 166.996872 -312.049922)
				(end 167.403272 -312.049922)
			)
		)
		(stroke
			(width 0)
			(type solid)
		)
		(fill yes)
		(layer "In6.Cu")
		(net "P5E_PEX1_STN6_TX_DN<103>")
	)
	(gr_poly
		(pts
			(arc
				(start 167.403272 -311.099962)
				(mid 166.996872 -311.099962)
				(end 167.403272 -311.099962)
			)
		)
		(stroke
			(width 0)
			(type solid)
		)
		(fill yes)
		(layer "In6.Cu")
		(net "P5E_PEX1_STN6_TX_DP<103>")
	)
	(gr_poly
		(pts
			(arc
				(start 167.403272 -280.699718)
				(mid 166.996872 -280.699718)
				(end 167.403272 -280.699718)
			)
		)
		(stroke
			(width 0)
			(type solid)
		)
		(fill yes)
		(layer "In6.Cu")
		(net "P5E_PEX1_STN2_TX_DP<40>")
	)
	(gr_poly
		(pts
			(arc
				(start 167.403272 -279.749504)
				(mid 166.996872 -279.749504)
				(end 167.403272 -279.749504)
			)
		)
		(stroke
			(width 0)
			(type solid)
		)
		(fill yes)
		(layer "In6.Cu")
		(net "P5E_PEX1_STN2_TX_DN<40>")
	)
	(gr_poly
		(pts
			(arc
				(start 167.403272 -275.949918)
				(mid 166.996872 -275.949918)
				(end 167.403272 -275.949918)
			)
		)
		(stroke
			(width 0)
			(type solid)
		)
		(fill yes)
		(layer "In6.Cu")
		(net "P5E_PEX1_STN2_RX_DP<40>")
	)
	(gr_poly
		(pts
			(arc
				(start 167.403272 -274.999958)
				(mid 166.996872 -274.999958)
				(end 167.403272 -274.999958)
			)
		)
		(stroke
			(width 0)
			(type solid)
		)
		(fill yes)
		(layer "In6.Cu")
		(net "P5E_PEX1_STN2_RX_DN<40>")
	)
	(gr_poly
		(pts
			(arc
				(start 168.353232 -313.949842)
				(mid 167.946832 -313.949842)
				(end 168.353232 -313.949842)
			)
		)
		(stroke
			(width 0)
			(type solid)
		)
		(fill yes)
		(layer "In6.Cu")
		(net "P5E_PEX1_STN6_TX_DN<102>")
	)
	(gr_poly
		(pts
			(arc
				(start 168.353232 -312.999882)
				(mid 167.946832 -312.999882)
				(end 168.353232 -312.999882)
			)
		)
		(stroke
			(width 0)
			(type solid)
		)
		(fill yes)
		(layer "In6.Cu")
		(net "P5E_PEX1_STN6_TX_DP<102>")
	)
	(gr_poly
		(pts
			(arc
				(start 168.353232 -278.799798)
				(mid 167.946832 -278.799798)
				(end 168.353232 -278.799798)
			)
		)
		(stroke
			(width 0)
			(type solid)
		)
		(fill yes)
		(layer "In6.Cu")
		(net "P5E_PEX1_STN2_TX_DP<39>")
	)
	(gr_poly
		(pts
			(arc
				(start 168.353232 -277.849838)
				(mid 167.946832 -277.849838)
				(end 168.353232 -277.849838)
			)
		)
		(stroke
			(width 0)
			(type solid)
		)
		(fill yes)
		(layer "In6.Cu")
		(net "P5E_PEX1_STN2_TX_DN<39>")
	)
	(gr_poly
		(pts
			(arc
				(start 168.353232 -274.049744)
				(mid 167.946832 -274.049744)
				(end 168.353232 -274.049744)
			)
		)
		(stroke
			(width 0)
			(type solid)
		)
		(fill yes)
		(layer "In6.Cu")
		(net "P5E_PEX1_STN2_RX_DP<39>")
	)
	(gr_poly
		(pts
			(arc
				(start 168.353232 -273.099784)
				(mid 167.946832 -273.099784)
				(end 168.353232 -273.099784)
			)
		)
		(stroke
			(width 0)
			(type solid)
		)
		(fill yes)
		(layer "In6.Cu")
		(net "P5E_PEX1_STN2_RX_DN<39>")
	)
	(gr_poly
		(pts
			(arc
				(start 169.303192 -312.049922)
				(mid 168.896792 -312.049922)
				(end 169.303192 -312.049922)
			)
		)
		(stroke
			(width 0)
			(type solid)
		)
		(fill yes)
		(layer "In6.Cu")
		(net "P5E_PEX1_STN6_TX_DN<101>")
	)
	(gr_poly
		(pts
			(arc
				(start 169.303192 -311.099962)
				(mid 168.896792 -311.099962)
				(end 169.303192 -311.099962)
			)
		)
		(stroke
			(width 0)
			(type solid)
		)
		(fill yes)
		(layer "In6.Cu")
		(net "P5E_PEX1_STN6_TX_DP<101>")
	)
	(gr_poly
		(pts
			(arc
				(start 169.303192 -280.699718)
				(mid 168.896792 -280.699718)
				(end 169.303192 -280.699718)
			)
		)
		(stroke
			(width 0)
			(type solid)
		)
		(fill yes)
		(layer "In6.Cu")
		(net "P5E_PEX1_STN2_TX_DP<38>")
	)
	(gr_poly
		(pts
			(arc
				(start 169.303192 -279.749504)
				(mid 168.896792 -279.749504)
				(end 169.303192 -279.749504)
			)
		)
		(stroke
			(width 0)
			(type solid)
		)
		(fill yes)
		(layer "In6.Cu")
		(net "P5E_PEX1_STN2_TX_DN<38>")
	)
	(gr_poly
		(pts
			(arc
				(start 169.303192 -275.949918)
				(mid 168.896792 -275.949918)
				(end 169.303192 -275.949918)
			)
		)
		(stroke
			(width 0)
			(type solid)
		)
		(fill yes)
		(layer "In6.Cu")
		(net "P5E_PEX1_STN2_RX_DP<38>")
	)
	(gr_poly
		(pts
			(arc
				(start 169.303192 -274.999958)
				(mid 168.896792 -274.999958)
				(end 169.303192 -274.999958)
			)
		)
		(stroke
			(width 0)
			(type solid)
		)
		(fill yes)
		(layer "In6.Cu")
		(net "P5E_PEX1_STN2_RX_DN<38>")
	)
	(gr_poly
		(pts
			(arc
				(start 170.253152 -313.949842)
				(mid 169.846752 -313.949842)
				(end 170.253152 -313.949842)
			)
		)
		(stroke
			(width 0)
			(type solid)
		)
		(fill yes)
		(layer "In6.Cu")
		(net "P5E_PEX1_STN6_TX_DN<100>")
	)
	(gr_poly
		(pts
			(arc
				(start 170.253152 -312.999882)
				(mid 169.846752 -312.999882)
				(end 170.253152 -312.999882)
			)
		)
		(stroke
			(width 0)
			(type solid)
		)
		(fill yes)
		(layer "In6.Cu")
		(net "P5E_PEX1_STN6_TX_DP<100>")
	)
	(gr_poly
		(pts
			(arc
				(start 170.253152 -278.799798)
				(mid 169.846752 -278.799798)
				(end 170.253152 -278.799798)
			)
		)
		(stroke
			(width 0)
			(type solid)
		)
		(fill yes)
		(layer "In6.Cu")
		(net "P5E_PEX1_STN2_TX_DP<37>")
	)
	(gr_poly
		(pts
			(arc
				(start 170.253152 -277.849838)
				(mid 169.846752 -277.849838)
				(end 170.253152 -277.849838)
			)
		)
		(stroke
			(width 0)
			(type solid)
		)
		(fill yes)
		(layer "In6.Cu")
		(net "P5E_PEX1_STN2_TX_DN<37>")
	)
	(gr_poly
		(pts
			(arc
				(start 170.253152 -274.049744)
				(mid 169.846752 -274.049744)
				(end 170.253152 -274.049744)
			)
		)
		(stroke
			(width 0)
			(type solid)
		)
		(fill yes)
		(layer "In6.Cu")
		(net "P5E_PEX1_STN2_RX_DP<37>")
	)
	(gr_poly
		(pts
			(arc
				(start 170.253152 -273.099784)
				(mid 169.846752 -273.099784)
				(end 170.253152 -273.099784)
			)
		)
		(stroke
			(width 0)
			(type solid)
		)
		(fill yes)
		(layer "In6.Cu")
		(net "P5E_PEX1_STN2_RX_DN<37>")
	)
	(gr_poly
		(pts
			(arc
				(start 171.203112 -312.049922)
				(mid 170.796712 -312.049922)
				(end 171.203112 -312.049922)
			)
		)
		(stroke
			(width 0)
			(type solid)
		)
		(fill yes)
		(layer "In6.Cu")
		(net "P5E_PEX1_STN6_TX_DN<99>")
	)
	(gr_poly
		(pts
			(arc
				(start 171.203112 -311.099962)
				(mid 170.796712 -311.099962)
				(end 171.203112 -311.099962)
			)
		)
		(stroke
			(width 0)
			(type solid)
		)
		(fill yes)
		(layer "In6.Cu")
		(net "P5E_PEX1_STN6_TX_DP<99>")
	)
	(gr_poly
		(pts
			(arc
				(start 171.203112 -280.699718)
				(mid 170.796712 -280.699718)
				(end 171.203112 -280.699718)
			)
		)
		(stroke
			(width 0)
			(type solid)
		)
		(fill yes)
		(layer "In6.Cu")
		(net "P5E_PEX1_STN2_TX_DP<36>")
	)
	(gr_poly
		(pts
			(arc
				(start 171.203112 -279.749504)
				(mid 170.796712 -279.749504)
				(end 171.203112 -279.749504)
			)
		)
		(stroke
			(width 0)
			(type solid)
		)
		(fill yes)
		(layer "In6.Cu")
		(net "P5E_PEX1_STN2_TX_DN<36>")
	)
	(gr_poly
		(pts
			(arc
				(start 171.203112 -275.949918)
				(mid 170.796712 -275.949918)
				(end 171.203112 -275.949918)
			)
		)
		(stroke
			(width 0)
			(type solid)
		)
		(fill yes)
		(layer "In6.Cu")
		(net "P5E_PEX1_STN2_RX_DP<36>")
	)
	(gr_poly
		(pts
			(arc
				(start 171.203112 -274.999958)
				(mid 170.796712 -274.999958)
				(end 171.203112 -274.999958)
			)
		)
		(stroke
			(width 0)
			(type solid)
		)
		(fill yes)
		(layer "In6.Cu")
		(net "P5E_PEX1_STN2_RX_DN<36>")
	)
	(gr_poly
		(pts
			(arc
				(start 172.153072 -313.949842)
				(mid 171.746672 -313.949842)
				(end 172.153072 -313.949842)
			)
		)
		(stroke
			(width 0)
			(type solid)
		)
		(fill yes)
		(layer "In6.Cu")
		(net "P5E_PEX1_STN6_TX_DN<98>")
	)
	(gr_poly
		(pts
			(arc
				(start 172.153072 -312.999882)
				(mid 171.746672 -312.999882)
				(end 172.153072 -312.999882)
			)
		)
		(stroke
			(width 0)
			(type solid)
		)
		(fill yes)
		(layer "In6.Cu")
		(net "P5E_PEX1_STN6_TX_DP<98>")
	)
	(gr_poly
		(pts
			(arc
				(start 172.153072 -278.799798)
				(mid 171.746672 -278.799798)
				(end 172.153072 -278.799798)
			)
		)
		(stroke
			(width 0)
			(type solid)
		)
		(fill yes)
		(layer "In6.Cu")
		(net "P5E_PEX1_STN2_TX_DP<35>")
	)
	(gr_poly
		(pts
			(arc
				(start 172.153072 -277.849838)
				(mid 171.746672 -277.849838)
				(end 172.153072 -277.849838)
			)
		)
		(stroke
			(width 0)
			(type solid)
		)
		(fill yes)
		(layer "In6.Cu")
		(net "P5E_PEX1_STN2_TX_DN<35>")
	)
	(gr_poly
		(pts
			(arc
				(start 172.153072 -274.049744)
				(mid 171.746672 -274.049744)
				(end 172.153072 -274.049744)
			)
		)
		(stroke
			(width 0)
			(type solid)
		)
		(fill yes)
		(layer "In6.Cu")
		(net "P5E_PEX1_STN2_RX_DP<35>")
	)
	(gr_poly
		(pts
			(arc
				(start 172.153072 -273.099784)
				(mid 171.746672 -273.099784)
				(end 172.153072 -273.099784)
			)
		)
		(stroke
			(width 0)
			(type solid)
		)
		(fill yes)
		(layer "In6.Cu")
		(net "P5E_PEX1_STN2_RX_DN<35>")
	)
	(gr_poly
		(pts
			(arc
				(start 173.103032 -280.699718)
				(mid 172.696632 -280.699718)
				(end 173.103032 -280.699718)
			)
		)
		(stroke
			(width 0)
			(type solid)
		)
		(fill yes)
		(layer "In6.Cu")
		(net "P5E_PEX1_STN2_TX_DP<34>")
	)
	(gr_poly
		(pts
			(arc
				(start 173.103032 -279.749504)
				(mid 172.696632 -279.749504)
				(end 173.103032 -279.749504)
			)
		)
		(stroke
			(width 0)
			(type solid)
		)
		(fill yes)
		(layer "In6.Cu")
		(net "P5E_PEX1_STN2_TX_DN<34>")
	)
	(gr_poly
		(pts
			(arc
				(start 173.103286 -312.049922)
				(mid 172.696886 -312.049922)
				(end 173.103286 -312.049922)
			)
		)
		(stroke
			(width 0)
			(type solid)
		)
		(fill yes)
		(layer "In6.Cu")
		(net "P5E_PEX1_STN6_TX_DN<97>")
	)
	(gr_poly
		(pts
			(arc
				(start 173.103286 -311.099962)
				(mid 172.696886 -311.099962)
				(end 173.103286 -311.099962)
			)
		)
		(stroke
			(width 0)
			(type solid)
		)
		(fill yes)
		(layer "In6.Cu")
		(net "P5E_PEX1_STN6_TX_DP<97>")
	)
	(gr_poly
		(pts
			(arc
				(start 173.103286 -275.949918)
				(mid 172.696886 -275.949918)
				(end 173.103286 -275.949918)
			)
		)
		(stroke
			(width 0)
			(type solid)
		)
		(fill yes)
		(layer "In6.Cu")
		(net "P5E_PEX1_STN2_RX_DP<34>")
	)
	(gr_poly
		(pts
			(arc
				(start 173.103286 -274.999958)
				(mid 172.696886 -274.999958)
				(end 173.103286 -274.999958)
			)
		)
		(stroke
			(width 0)
			(type solid)
		)
		(fill yes)
		(layer "In6.Cu")
		(net "P5E_PEX1_STN2_RX_DN<34>")
	)
	(gr_poly
		(pts
			(arc
				(start 174.053246 -313.949842)
				(mid 173.646846 -313.949842)
				(end 174.053246 -313.949842)
			)
		)
		(stroke
			(width 0)
			(type solid)
		)
		(fill yes)
		(layer "In6.Cu")
		(net "P5E_PEX1_STN6_TX_DN<96>")
	)
	(gr_poly
		(pts
			(arc
				(start 174.053246 -312.999882)
				(mid 173.646846 -312.999882)
				(end 174.053246 -312.999882)
			)
		)
		(stroke
			(width 0)
			(type solid)
		)
		(fill yes)
		(layer "In6.Cu")
		(net "P5E_PEX1_STN6_TX_DP<96>")
	)
	(gr_poly
		(pts
			(arc
				(start 174.053246 -278.799798)
				(mid 173.646846 -278.799798)
				(end 174.053246 -278.799798)
			)
		)
		(stroke
			(width 0)
			(type solid)
		)
		(fill yes)
		(layer "In6.Cu")
		(net "P5E_PEX1_STN2_TX_DP<33>")
	)
	(gr_poly
		(pts
			(arc
				(start 174.053246 -277.849838)
				(mid 173.646846 -277.849838)
				(end 174.053246 -277.849838)
			)
		)
		(stroke
			(width 0)
			(type solid)
		)
		(fill yes)
		(layer "In6.Cu")
		(net "P5E_PEX1_STN2_TX_DN<33>")
	)
	(gr_poly
		(pts
			(arc
				(start 174.053246 -274.049744)
				(mid 173.646846 -274.049744)
				(end 174.053246 -274.049744)
			)
		)
		(stroke
			(width 0)
			(type solid)
		)
		(fill yes)
		(layer "In6.Cu")
		(net "P5E_PEX1_STN2_RX_DP<33>")
	)
	(gr_poly
		(pts
			(arc
				(start 174.053246 -273.099784)
				(mid 173.646846 -273.099784)
				(end 174.053246 -273.099784)
			)
		)
		(stroke
			(width 0)
			(type solid)
		)
		(fill yes)
		(layer "In6.Cu")
		(net "P5E_PEX1_STN2_RX_DN<33>")
	)
	(gr_poly
		(pts
			(arc
				(start 175.003206 -312.049922)
				(mid 174.596806 -312.049922)
				(end 175.003206 -312.049922)
			)
		)
		(stroke
			(width 0)
			(type solid)
		)
		(fill yes)
		(layer "In6.Cu")
		(net "P5E_PEX1_STN5_TX_DN<80>")
	)
	(gr_poly
		(pts
			(arc
				(start 175.003206 -311.099962)
				(mid 174.596806 -311.099962)
				(end 175.003206 -311.099962)
			)
		)
		(stroke
			(width 0)
			(type solid)
		)
		(fill yes)
		(layer "In6.Cu")
		(net "P5E_PEX1_STN5_TX_DP<80>")
	)
	(gr_poly
		(pts
			(arc
				(start 175.003206 -280.699718)
				(mid 174.596806 -280.699718)
				(end 175.003206 -280.699718)
			)
		)
		(stroke
			(width 0)
			(type solid)
		)
		(fill yes)
		(layer "In6.Cu")
		(net "P5E_PEX1_STN2_TX_DP<32>")
	)
	(gr_poly
		(pts
			(arc
				(start 175.003206 -279.749504)
				(mid 174.596806 -279.749504)
				(end 175.003206 -279.749504)
			)
		)
		(stroke
			(width 0)
			(type solid)
		)
		(fill yes)
		(layer "In6.Cu")
		(net "P5E_PEX1_STN2_TX_DN<32>")
	)
	(gr_poly
		(pts
			(arc
				(start 175.003206 -275.949918)
				(mid 174.596806 -275.949918)
				(end 175.003206 -275.949918)
			)
		)
		(stroke
			(width 0)
			(type solid)
		)
		(fill yes)
		(layer "In6.Cu")
		(net "P5E_PEX1_STN2_RX_DP<32>")
	)
	(gr_poly
		(pts
			(arc
				(start 175.003206 -274.999958)
				(mid 174.596806 -274.999958)
				(end 175.003206 -274.999958)
			)
		)
		(stroke
			(width 0)
			(type solid)
		)
		(fill yes)
		(layer "In6.Cu")
		(net "P5E_PEX1_STN2_RX_DN<32>")
	)
	(gr_poly
		(pts
			(arc
				(start 175.952912 -278.799798)
				(mid 175.546512 -278.799798)
				(end 175.952912 -278.799798)
			)
		)
		(stroke
			(width 0)
			(type solid)
		)
		(fill yes)
		(layer "In6.Cu")
		(net "P5E_PEX1_STN1_TX_DP<16>")
	)
	(gr_poly
		(pts
			(arc
				(start 175.952912 -277.849838)
				(mid 175.546512 -277.849838)
				(end 175.952912 -277.849838)
			)
		)
		(stroke
			(width 0)
			(type solid)
		)
		(fill yes)
		(layer "In6.Cu")
		(net "P5E_PEX1_STN1_TX_DN<16>")
	)
	(gr_poly
		(pts
			(arc
				(start 175.953166 -313.949842)
				(mid 175.546766 -313.949842)
				(end 175.953166 -313.949842)
			)
		)
		(stroke
			(width 0)
			(type solid)
		)
		(fill yes)
		(layer "In6.Cu")
		(net "P5E_PEX1_STN5_TX_DN<81>")
	)
	(gr_poly
		(pts
			(arc
				(start 175.953166 -312.999882)
				(mid 175.546766 -312.999882)
				(end 175.953166 -312.999882)
			)
		)
		(stroke
			(width 0)
			(type solid)
		)
		(fill yes)
		(layer "In6.Cu")
		(net "P5E_PEX1_STN5_TX_DP<81>")
	)
	(gr_poly
		(pts
			(arc
				(start 176.903126 -312.049922)
				(mid 176.496726 -312.049922)
				(end 176.903126 -312.049922)
			)
		)
		(stroke
			(width 0)
			(type solid)
		)
		(fill yes)
		(layer "In6.Cu")
		(net "P5E_PEX1_STN5_TX_DN<82>")
	)
	(gr_poly
		(pts
			(arc
				(start 176.903126 -311.099962)
				(mid 176.496726 -311.099962)
				(end 176.903126 -311.099962)
			)
		)
		(stroke
			(width 0)
			(type solid)
		)
		(fill yes)
		(layer "In6.Cu")
		(net "P5E_PEX1_STN5_TX_DP<82>")
	)
	(gr_poly
		(pts
			(arc
				(start 176.903126 -280.699718)
				(mid 176.496726 -280.699718)
				(end 176.903126 -280.699718)
			)
		)
		(stroke
			(width 0)
			(type solid)
		)
		(fill yes)
		(layer "In6.Cu")
		(net "P5E_PEX1_STN1_TX_DN<17>")
	)
	(gr_poly
		(pts
			(arc
				(start 176.903126 -279.749504)
				(mid 176.496726 -279.749504)
				(end 176.903126 -279.749504)
			)
		)
		(stroke
			(width 0)
			(type solid)
		)
		(fill yes)
		(layer "In6.Cu")
		(net "P5E_PEX1_STN1_TX_DP<17>")
	)
	(gr_poly
		(pts
			(arc
				(start 177.852832 -278.799798)
				(mid 177.446432 -278.799798)
				(end 177.852832 -278.799798)
			)
		)
		(stroke
			(width 0)
			(type solid)
		)
		(fill yes)
		(layer "In6.Cu")
		(net "P5E_PEX1_STN1_TX_DP<18>")
	)
	(gr_poly
		(pts
			(arc
				(start 177.852832 -277.849838)
				(mid 177.446432 -277.849838)
				(end 177.852832 -277.849838)
			)
		)
		(stroke
			(width 0)
			(type solid)
		)
		(fill yes)
		(layer "In6.Cu")
		(net "P5E_PEX1_STN1_TX_DN<18>")
	)
	(gr_poly
		(pts
			(arc
				(start 177.853086 -313.949842)
				(mid 177.446686 -313.949842)
				(end 177.853086 -313.949842)
			)
		)
		(stroke
			(width 0)
			(type solid)
		)
		(fill yes)
		(layer "In6.Cu")
		(net "P5E_PEX1_STN5_TX_DN<83>")
	)
	(gr_poly
		(pts
			(arc
				(start 177.853086 -312.999882)
				(mid 177.446686 -312.999882)
				(end 177.853086 -312.999882)
			)
		)
		(stroke
			(width 0)
			(type solid)
		)
		(fill yes)
		(layer "In6.Cu")
		(net "P5E_PEX1_STN5_TX_DP<83>")
	)
	(gr_poly
		(pts
			(arc
				(start 178.803046 -312.049922)
				(mid 178.396646 -312.049922)
				(end 178.803046 -312.049922)
			)
		)
		(stroke
			(width 0)
			(type solid)
		)
		(fill yes)
		(layer "In6.Cu")
		(net "P5E_PEX1_STN5_TX_DN<84>")
	)
	(gr_poly
		(pts
			(arc
				(start 178.803046 -311.099962)
				(mid 178.396646 -311.099962)
				(end 178.803046 -311.099962)
			)
		)
		(stroke
			(width 0)
			(type solid)
		)
		(fill yes)
		(layer "In6.Cu")
		(net "P5E_PEX1_STN5_TX_DP<84>")
	)
	(gr_poly
		(pts
			(arc
				(start 178.803046 -280.699718)
				(mid 178.396646 -280.699718)
				(end 178.803046 -280.699718)
			)
		)
		(stroke
			(width 0)
			(type solid)
		)
		(fill yes)
		(layer "In6.Cu")
		(net "P5E_PEX1_STN1_TX_DN<19>")
	)
	(gr_poly
		(pts
			(arc
				(start 178.803046 -279.749504)
				(mid 178.396646 -279.749504)
				(end 178.803046 -279.749504)
			)
		)
		(stroke
			(width 0)
			(type solid)
		)
		(fill yes)
		(layer "In6.Cu")
		(net "P5E_PEX1_STN1_TX_DP<19>")
	)
	(gr_poly
		(pts
			(arc
				(start 179.753006 -278.799798)
				(mid 179.346606 -278.799798)
				(end 179.753006 -278.799798)
			)
		)
		(stroke
			(width 0)
			(type solid)
		)
		(fill yes)
		(layer "In6.Cu")
		(net "P5E_PEX1_STN1_TX_DP<20>")
	)
	(gr_poly
		(pts
			(arc
				(start 179.753006 -277.849838)
				(mid 179.346606 -277.849838)
				(end 179.753006 -277.849838)
			)
		)
		(stroke
			(width 0)
			(type solid)
		)
		(fill yes)
		(layer "In6.Cu")
		(net "P5E_PEX1_STN1_TX_DN<20>")
	)
	(gr_poly
		(pts
			(arc
				(start 179.75326 -313.949842)
				(mid 179.34686 -313.949842)
				(end 179.75326 -313.949842)
			)
		)
		(stroke
			(width 0)
			(type solid)
		)
		(fill yes)
		(layer "In6.Cu")
		(net "P5E_PEX1_STN5_TX_DN<85>")
	)
	(gr_poly
		(pts
			(arc
				(start 179.75326 -312.999882)
				(mid 179.34686 -312.999882)
				(end 179.75326 -312.999882)
			)
		)
		(stroke
			(width 0)
			(type solid)
		)
		(fill yes)
		(layer "In6.Cu")
		(net "P5E_PEX1_STN5_TX_DP<85>")
	)
	(gr_poly
		(pts
			(arc
				(start 180.70322 -312.049922)
				(mid 180.29682 -312.049922)
				(end 180.70322 -312.049922)
			)
		)
		(stroke
			(width 0)
			(type solid)
		)
		(fill yes)
		(layer "In6.Cu")
		(net "P5E_PEX1_STN5_TX_DN<86>")
	)
	(gr_poly
		(pts
			(arc
				(start 180.70322 -311.099962)
				(mid 180.29682 -311.099962)
				(end 180.70322 -311.099962)
			)
		)
		(stroke
			(width 0)
			(type solid)
		)
		(fill yes)
		(layer "In6.Cu")
		(net "P5E_PEX1_STN5_TX_DP<86>")
	)
	(gr_poly
		(pts
			(arc
				(start 180.70322 -280.699718)
				(mid 180.29682 -280.699718)
				(end 180.70322 -280.699718)
			)
		)
		(stroke
			(width 0)
			(type solid)
		)
		(fill yes)
		(layer "In6.Cu")
		(net "P5E_PEX1_STN1_TX_DN<21>")
	)
	(gr_poly
		(pts
			(arc
				(start 180.70322 -279.749504)
				(mid 180.29682 -279.749504)
				(end 180.70322 -279.749504)
			)
		)
		(stroke
			(width 0)
			(type solid)
		)
		(fill yes)
		(layer "In6.Cu")
		(net "P5E_PEX1_STN1_TX_DP<21>")
	)
	(gr_poly
		(pts
			(arc
				(start 181.652926 -278.799798)
				(mid 181.246526 -278.799798)
				(end 181.652926 -278.799798)
			)
		)
		(stroke
			(width 0)
			(type solid)
		)
		(fill yes)
		(layer "In6.Cu")
		(net "P5E_PEX1_STN1_TX_DP<22>")
	)
	(gr_poly
		(pts
			(arc
				(start 181.652926 -277.849838)
				(mid 181.246526 -277.849838)
				(end 181.652926 -277.849838)
			)
		)
		(stroke
			(width 0)
			(type solid)
		)
		(fill yes)
		(layer "In6.Cu")
		(net "P5E_PEX1_STN1_TX_DN<22>")
	)
	(gr_poly
		(pts
			(arc
				(start 181.65318 -313.949842)
				(mid 181.24678 -313.949842)
				(end 181.65318 -313.949842)
			)
		)
		(stroke
			(width 0)
			(type solid)
		)
		(fill yes)
		(layer "In6.Cu")
		(net "P5E_PEX1_STN5_TX_DN<87>")
	)
	(gr_poly
		(pts
			(arc
				(start 181.65318 -312.999882)
				(mid 181.24678 -312.999882)
				(end 181.65318 -312.999882)
			)
		)
		(stroke
			(width 0)
			(type solid)
		)
		(fill yes)
		(layer "In6.Cu")
		(net "P5E_PEX1_STN5_TX_DP<87>")
	)
	(gr_poly
		(pts
			(arc
				(start 182.60314 -316.799722)
				(mid 182.19674 -316.799722)
				(end 182.60314 -316.799722)
			)
		)
		(stroke
			(width 0)
			(type solid)
		)
		(fill yes)
		(layer "In6.Cu")
		(net "P5E_PEX1_STN5_RX_DN<88>")
	)
	(gr_poly
		(pts
			(arc
				(start 182.60314 -315.849762)
				(mid 182.19674 -315.849762)
				(end 182.60314 -315.849762)
			)
		)
		(stroke
			(width 0)
			(type solid)
		)
		(fill yes)
		(layer "In6.Cu")
		(net "P5E_PEX1_STN5_RX_DP<88>")
	)
	(gr_poly
		(pts
			(arc
				(start 182.60314 -312.049922)
				(mid 182.19674 -312.049922)
				(end 182.60314 -312.049922)
			)
		)
		(stroke
			(width 0)
			(type solid)
		)
		(fill yes)
		(layer "In6.Cu")
		(net "P5E_PEX1_STN5_TX_DN<88>")
	)
	(gr_poly
		(pts
			(arc
				(start 182.60314 -311.099962)
				(mid 182.19674 -311.099962)
				(end 182.60314 -311.099962)
			)
		)
		(stroke
			(width 0)
			(type solid)
		)
		(fill yes)
		(layer "In6.Cu")
		(net "P5E_PEX1_STN5_TX_DP<88>")
	)
	(gr_poly
		(pts
			(arc
				(start 182.60314 -280.699718)
				(mid 182.19674 -280.699718)
				(end 182.60314 -280.699718)
			)
		)
		(stroke
			(width 0)
			(type solid)
		)
		(fill yes)
		(layer "In6.Cu")
		(net "P5E_PEX1_STN1_TX_DN<23>")
	)
	(gr_poly
		(pts
			(arc
				(start 182.60314 -279.749504)
				(mid 182.19674 -279.749504)
				(end 182.60314 -279.749504)
			)
		)
		(stroke
			(width 0)
			(type solid)
		)
		(fill yes)
		(layer "In6.Cu")
		(net "P5E_PEX1_STN1_TX_DP<23>")
	)
	(gr_poly
		(pts
			(arc
				(start 183.552846 -278.799798)
				(mid 183.146446 -278.799798)
				(end 183.552846 -278.799798)
			)
		)
		(stroke
			(width 0)
			(type solid)
		)
		(fill yes)
		(layer "In6.Cu")
		(net "P5E_PEX1_STN1_TX_DP<24>")
	)
	(gr_poly
		(pts
			(arc
				(start 183.552846 -277.849838)
				(mid 183.146446 -277.849838)
				(end 183.552846 -277.849838)
			)
		)
		(stroke
			(width 0)
			(type solid)
		)
		(fill yes)
		(layer "In6.Cu")
		(net "P5E_PEX1_STN1_TX_DN<24>")
	)
	(gr_poly
		(pts
			(arc
				(start 183.5531 -318.699896)
				(mid 183.1467 -318.699896)
				(end 183.5531 -318.699896)
			)
		)
		(stroke
			(width 0)
			(type solid)
		)
		(fill yes)
		(layer "In6.Cu")
		(net "P5E_PEX1_STN5_RX_DN<89>")
	)
	(gr_poly
		(pts
			(arc
				(start 183.5531 -317.749936)
				(mid 183.1467 -317.749936)
				(end 183.5531 -317.749936)
			)
		)
		(stroke
			(width 0)
			(type solid)
		)
		(fill yes)
		(layer "In6.Cu")
		(net "P5E_PEX1_STN5_RX_DP<89>")
	)
	(gr_poly
		(pts
			(arc
				(start 183.5531 -313.949842)
				(mid 183.1467 -313.949842)
				(end 183.5531 -313.949842)
			)
		)
		(stroke
			(width 0)
			(type solid)
		)
		(fill yes)
		(layer "In6.Cu")
		(net "P5E_PEX1_STN5_TX_DN<89>")
	)
	(gr_poly
		(pts
			(arc
				(start 183.5531 -312.999882)
				(mid 183.1467 -312.999882)
				(end 183.5531 -312.999882)
			)
		)
		(stroke
			(width 0)
			(type solid)
		)
		(fill yes)
		(layer "In6.Cu")
		(net "P5E_PEX1_STN5_TX_DP<89>")
	)
	(gr_poly
		(pts
			(arc
				(start 184.50306 -316.799722)
				(mid 184.09666 -316.799722)
				(end 184.50306 -316.799722)
			)
		)
		(stroke
			(width 0)
			(type solid)
		)
		(fill yes)
		(layer "In6.Cu")
		(net "P5E_PEX1_STN5_RX_DN<90>")
	)
	(gr_poly
		(pts
			(arc
				(start 184.50306 -315.849762)
				(mid 184.09666 -315.849762)
				(end 184.50306 -315.849762)
			)
		)
		(stroke
			(width 0)
			(type solid)
		)
		(fill yes)
		(layer "In6.Cu")
		(net "P5E_PEX1_STN5_RX_DP<90>")
	)
	(gr_poly
		(pts
			(arc
				(start 184.50306 -312.049922)
				(mid 184.09666 -312.049922)
				(end 184.50306 -312.049922)
			)
		)
		(stroke
			(width 0)
			(type solid)
		)
		(fill yes)
		(layer "In6.Cu")
		(net "P5E_PEX1_STN5_TX_DN<90>")
	)
	(gr_poly
		(pts
			(arc
				(start 184.50306 -311.099962)
				(mid 184.09666 -311.099962)
				(end 184.50306 -311.099962)
			)
		)
		(stroke
			(width 0)
			(type solid)
		)
		(fill yes)
		(layer "In6.Cu")
		(net "P5E_PEX1_STN5_TX_DP<90>")
	)
	(gr_poly
		(pts
			(arc
				(start 184.50306 -280.699718)
				(mid 184.09666 -280.699718)
				(end 184.50306 -280.699718)
			)
		)
		(stroke
			(width 0)
			(type solid)
		)
		(fill yes)
		(layer "In6.Cu")
		(net "P5E_PEX1_STN1_TX_DN<25>")
	)
	(gr_poly
		(pts
			(arc
				(start 184.50306 -279.749504)
				(mid 184.09666 -279.749504)
				(end 184.50306 -279.749504)
			)
		)
		(stroke
			(width 0)
			(type solid)
		)
		(fill yes)
		(layer "In6.Cu")
		(net "P5E_PEX1_STN1_TX_DP<25>")
	)
	(gr_poly
		(pts
			(arc
				(start 185.45302 -278.799798)
				(mid 185.04662 -278.799798)
				(end 185.45302 -278.799798)
			)
		)
		(stroke
			(width 0)
			(type solid)
		)
		(fill yes)
		(layer "In6.Cu")
		(net "P5E_PEX1_STN1_TX_DP<26>")
	)
	(gr_poly
		(pts
			(arc
				(start 185.45302 -277.849838)
				(mid 185.04662 -277.849838)
				(end 185.45302 -277.849838)
			)
		)
		(stroke
			(width 0)
			(type solid)
		)
		(fill yes)
		(layer "In6.Cu")
		(net "P5E_PEX1_STN1_TX_DN<26>")
	)
	(gr_poly
		(pts
			(arc
				(start 185.453274 -318.699896)
				(mid 185.046874 -318.699896)
				(end 185.453274 -318.699896)
			)
		)
		(stroke
			(width 0)
			(type solid)
		)
		(fill yes)
		(layer "In6.Cu")
		(net "P5E_PEX1_STN5_RX_DN<91>")
	)
	(gr_poly
		(pts
			(arc
				(start 185.453274 -317.749936)
				(mid 185.046874 -317.749936)
				(end 185.453274 -317.749936)
			)
		)
		(stroke
			(width 0)
			(type solid)
		)
		(fill yes)
		(layer "In6.Cu")
		(net "P5E_PEX1_STN5_RX_DP<91>")
	)
	(gr_poly
		(pts
			(arc
				(start 185.453274 -313.949842)
				(mid 185.046874 -313.949842)
				(end 185.453274 -313.949842)
			)
		)
		(stroke
			(width 0)
			(type solid)
		)
		(fill yes)
		(layer "In6.Cu")
		(net "P5E_PEX1_STN5_TX_DN<91>")
	)
	(gr_poly
		(pts
			(arc
				(start 185.453274 -312.999882)
				(mid 185.046874 -312.999882)
				(end 185.453274 -312.999882)
			)
		)
		(stroke
			(width 0)
			(type solid)
		)
		(fill yes)
		(layer "In6.Cu")
		(net "P5E_PEX1_STN5_TX_DP<91>")
	)
	(gr_poly
		(pts
			(arc
				(start 186.403234 -316.799722)
				(mid 185.996834 -316.799722)
				(end 186.403234 -316.799722)
			)
		)
		(stroke
			(width 0)
			(type solid)
		)
		(fill yes)
		(layer "In6.Cu")
		(net "P5E_PEX1_STN5_RX_DN<92>")
	)
	(gr_poly
		(pts
			(arc
				(start 186.403234 -315.849762)
				(mid 185.996834 -315.849762)
				(end 186.403234 -315.849762)
			)
		)
		(stroke
			(width 0)
			(type solid)
		)
		(fill yes)
		(layer "In6.Cu")
		(net "P5E_PEX1_STN5_RX_DP<92>")
	)
	(gr_poly
		(pts
			(arc
				(start 186.403234 -312.049922)
				(mid 185.996834 -312.049922)
				(end 186.403234 -312.049922)
			)
		)
		(stroke
			(width 0)
			(type solid)
		)
		(fill yes)
		(layer "In6.Cu")
		(net "P5E_PEX1_STN5_TX_DN<92>")
	)
	(gr_poly
		(pts
			(arc
				(start 186.403234 -311.099962)
				(mid 185.996834 -311.099962)
				(end 186.403234 -311.099962)
			)
		)
		(stroke
			(width 0)
			(type solid)
		)
		(fill yes)
		(layer "In6.Cu")
		(net "P5E_PEX1_STN5_TX_DP<92>")
	)
	(gr_poly
		(pts
			(arc
				(start 186.403234 -280.699718)
				(mid 185.996834 -280.699718)
				(end 186.403234 -280.699718)
			)
		)
		(stroke
			(width 0)
			(type solid)
		)
		(fill yes)
		(layer "In6.Cu")
		(net "P5E_PEX1_STN1_TX_DN<27>")
	)
	(gr_poly
		(pts
			(arc
				(start 186.403234 -279.749504)
				(mid 185.996834 -279.749504)
				(end 186.403234 -279.749504)
			)
		)
		(stroke
			(width 0)
			(type solid)
		)
		(fill yes)
		(layer "In6.Cu")
		(net "P5E_PEX1_STN1_TX_DP<27>")
	)
	(gr_poly
		(pts
			(arc
				(start 187.35294 -278.799798)
				(mid 186.94654 -278.799798)
				(end 187.35294 -278.799798)
			)
		)
		(stroke
			(width 0)
			(type solid)
		)
		(fill yes)
		(layer "In6.Cu")
		(net "P5E_PEX1_STN1_TX_DP<28>")
	)
	(gr_poly
		(pts
			(arc
				(start 187.35294 -277.849838)
				(mid 186.94654 -277.849838)
				(end 187.35294 -277.849838)
			)
		)
		(stroke
			(width 0)
			(type solid)
		)
		(fill yes)
		(layer "In6.Cu")
		(net "P5E_PEX1_STN1_TX_DN<28>")
	)
	(gr_poly
		(pts
			(arc
				(start 187.353194 -318.699896)
				(mid 186.946794 -318.699896)
				(end 187.353194 -318.699896)
			)
		)
		(stroke
			(width 0)
			(type solid)
		)
		(fill yes)
		(layer "In6.Cu")
		(net "P5E_PEX1_STN5_RX_DN<93>")
	)
	(gr_poly
		(pts
			(arc
				(start 187.353194 -317.749936)
				(mid 186.946794 -317.749936)
				(end 187.353194 -317.749936)
			)
		)
		(stroke
			(width 0)
			(type solid)
		)
		(fill yes)
		(layer "In6.Cu")
		(net "P5E_PEX1_STN5_RX_DP<93>")
	)
	(gr_poly
		(pts
			(arc
				(start 187.353194 -313.949842)
				(mid 186.946794 -313.949842)
				(end 187.353194 -313.949842)
			)
		)
		(stroke
			(width 0)
			(type solid)
		)
		(fill yes)
		(layer "In6.Cu")
		(net "P5E_PEX1_STN5_TX_DN<93>")
	)
	(gr_poly
		(pts
			(arc
				(start 187.353194 -312.999882)
				(mid 186.946794 -312.999882)
				(end 187.353194 -312.999882)
			)
		)
		(stroke
			(width 0)
			(type solid)
		)
		(fill yes)
		(layer "In6.Cu")
		(net "P5E_PEX1_STN5_TX_DP<93>")
	)
	(gr_poly
		(pts
			(arc
				(start 188.303154 -316.799722)
				(mid 187.896754 -316.799722)
				(end 188.303154 -316.799722)
			)
		)
		(stroke
			(width 0)
			(type solid)
		)
		(fill yes)
		(layer "In6.Cu")
		(net "P5E_PEX1_STN5_RX_DN<94>")
	)
	(gr_poly
		(pts
			(arc
				(start 188.303154 -315.849762)
				(mid 187.896754 -315.849762)
				(end 188.303154 -315.849762)
			)
		)
		(stroke
			(width 0)
			(type solid)
		)
		(fill yes)
		(layer "In6.Cu")
		(net "P5E_PEX1_STN5_RX_DP<94>")
	)
	(gr_poly
		(pts
			(arc
				(start 188.303154 -312.049922)
				(mid 187.896754 -312.049922)
				(end 188.303154 -312.049922)
			)
		)
		(stroke
			(width 0)
			(type solid)
		)
		(fill yes)
		(layer "In6.Cu")
		(net "P5E_PEX1_STN5_TX_DN<94>")
	)
	(gr_poly
		(pts
			(arc
				(start 188.303154 -311.099962)
				(mid 187.896754 -311.099962)
				(end 188.303154 -311.099962)
			)
		)
		(stroke
			(width 0)
			(type solid)
		)
		(fill yes)
		(layer "In6.Cu")
		(net "P5E_PEX1_STN5_TX_DP<94>")
	)
	(gr_poly
		(pts
			(arc
				(start 188.303154 -280.699718)
				(mid 187.896754 -280.699718)
				(end 188.303154 -280.699718)
			)
		)
		(stroke
			(width 0)
			(type solid)
		)
		(fill yes)
		(layer "In6.Cu")
		(net "P5E_PEX1_STN1_TX_DN<29>")
	)
	(gr_poly
		(pts
			(arc
				(start 188.303154 -279.749504)
				(mid 187.896754 -279.749504)
				(end 188.303154 -279.749504)
			)
		)
		(stroke
			(width 0)
			(type solid)
		)
		(fill yes)
		(layer "In6.Cu")
		(net "P5E_PEX1_STN1_TX_DP<29>")
	)
	(gr_poly
		(pts
			(arc
				(start 189.25286 -278.799798)
				(mid 188.84646 -278.799798)
				(end 189.25286 -278.799798)
			)
		)
		(stroke
			(width 0)
			(type solid)
		)
		(fill yes)
		(layer "In6.Cu")
		(net "P5E_PEX1_STN1_TX_DP<30>")
	)
	(gr_poly
		(pts
			(arc
				(start 189.25286 -277.849838)
				(mid 188.84646 -277.849838)
				(end 189.25286 -277.849838)
			)
		)
		(stroke
			(width 0)
			(type solid)
		)
		(fill yes)
		(layer "In6.Cu")
		(net "P5E_PEX1_STN1_TX_DN<30>")
	)
	(gr_poly
		(pts
			(arc
				(start 189.253114 -318.699896)
				(mid 188.846714 -318.699896)
				(end 189.253114 -318.699896)
			)
		)
		(stroke
			(width 0)
			(type solid)
		)
		(fill yes)
		(layer "In6.Cu")
		(net "P5E_PEX1_STN5_RX_DN<95>")
	)
	(gr_poly
		(pts
			(arc
				(start 189.253114 -317.749936)
				(mid 188.846714 -317.749936)
				(end 189.253114 -317.749936)
			)
		)
		(stroke
			(width 0)
			(type solid)
		)
		(fill yes)
		(layer "In6.Cu")
		(net "P5E_PEX1_STN5_RX_DP<95>")
	)
	(gr_poly
		(pts
			(arc
				(start 189.253114 -313.949842)
				(mid 188.846714 -313.949842)
				(end 189.253114 -313.949842)
			)
		)
		(stroke
			(width 0)
			(type solid)
		)
		(fill yes)
		(layer "In6.Cu")
		(net "P5E_PEX1_STN5_TX_DN<95>")
	)
	(gr_poly
		(pts
			(arc
				(start 189.253114 -312.999882)
				(mid 188.846714 -312.999882)
				(end 189.253114 -312.999882)
			)
		)
		(stroke
			(width 0)
			(type solid)
		)
		(fill yes)
		(layer "In6.Cu")
		(net "P5E_PEX1_STN5_TX_DP<95>")
	)
	(gr_poly
		(pts
			(arc
				(start 190.203074 -312.049922)
				(mid 189.796674 -312.049922)
				(end 190.203074 -312.049922)
			)
		)
		(stroke
			(width 0)
			(type solid)
		)
		(fill yes)
		(layer "In6.Cu")
		(net "P5E_PEX1_STN4_TX_DN<79>")
	)
	(gr_poly
		(pts
			(arc
				(start 190.203074 -311.099962)
				(mid 189.796674 -311.099962)
				(end 190.203074 -311.099962)
			)
		)
		(stroke
			(width 0)
			(type solid)
		)
		(fill yes)
		(layer "In6.Cu")
		(net "P5E_PEX1_STN4_TX_DP<79>")
	)
	(gr_poly
		(pts
			(arc
				(start 190.203074 -280.699718)
				(mid 189.796674 -280.699718)
				(end 190.203074 -280.699718)
			)
		)
		(stroke
			(width 0)
			(type solid)
		)
		(fill yes)
		(layer "In6.Cu")
		(net "P5E_PEX1_STN1_TX_DN<31>")
	)
	(gr_poly
		(pts
			(arc
				(start 190.203074 -279.749504)
				(mid 189.796674 -279.749504)
				(end 190.203074 -279.749504)
			)
		)
		(stroke
			(width 0)
			(type solid)
		)
		(fill yes)
		(layer "In6.Cu")
		(net "P5E_PEX1_STN1_TX_DP<31>")
	)
	(gr_poly
		(pts
			(arc
				(start 191.153034 -287.349946)
				(mid 190.746634 -287.349946)
				(end 191.153034 -287.349946)
			)
		)
		(stroke
			(width 0)
			(type solid)
		)
		(fill yes)
		(layer "In6.Cu")
		(net "P5E_PEX1_STN0_TX_DP<1>")
	)
	(gr_poly
		(pts
			(arc
				(start 191.153034 -285.449772)
				(mid 190.746634 -285.449772)
				(end 191.153034 -285.449772)
			)
		)
		(stroke
			(width 0)
			(type solid)
		)
		(fill yes)
		(layer "In6.Cu")
		(net "P5E_PEX1_STN0_TX_DP<3>")
	)
	(gr_poly
		(pts
			(arc
				(start 191.153034 -283.549852)
				(mid 190.746634 -283.549852)
				(end 191.153034 -283.549852)
			)
		)
		(stroke
			(width 0)
			(type solid)
		)
		(fill yes)
		(layer "In6.Cu")
		(net "P5E_PEX1_STN0_TX_DP<5>")
	)
	(gr_poly
		(pts
			(arc
				(start 191.153034 -278.799798)
				(mid 190.746634 -278.799798)
				(end 191.153034 -278.799798)
			)
		)
		(stroke
			(width 0)
			(type solid)
		)
		(fill yes)
		(layer "In6.Cu")
		(net "P5E_PEX1_STN0_TX_DP<15>")
	)
	(gr_poly
		(pts
			(arc
				(start 191.153034 -277.849838)
				(mid 190.746634 -277.849838)
				(end 191.153034 -277.849838)
			)
		)
		(stroke
			(width 0)
			(type solid)
		)
		(fill yes)
		(layer "In6.Cu")
		(net "P5E_PEX1_STN0_TX_DN<15>")
	)
	(gr_poly
		(pts
			(arc
				(start 191.153288 -313.949842)
				(mid 190.746888 -313.949842)
				(end 191.153288 -313.949842)
			)
		)
		(stroke
			(width 0)
			(type solid)
		)
		(fill yes)
		(layer "In6.Cu")
		(net "P5E_PEX1_STN4_TX_DN<78>")
	)
	(gr_poly
		(pts
			(arc
				(start 191.153288 -312.999882)
				(mid 190.746888 -312.999882)
				(end 191.153288 -312.999882)
			)
		)
		(stroke
			(width 0)
			(type solid)
		)
		(fill yes)
		(layer "In6.Cu")
		(net "P5E_PEX1_STN4_TX_DP<78>")
	)
	(gr_poly
		(pts
			(arc
				(start 191.153288 -308.249828)
				(mid 190.746888 -308.249828)
				(end 191.153288 -308.249828)
			)
		)
		(stroke
			(width 0)
			(type solid)
		)
		(fill yes)
		(layer "In6.Cu")
		(net "P5E_PEX1_STN4_TX_DP<68>")
	)
	(gr_poly
		(pts
			(arc
				(start 191.153288 -306.349908)
				(mid 190.746888 -306.349908)
				(end 191.153288 -306.349908)
			)
		)
		(stroke
			(width 0)
			(type solid)
		)
		(fill yes)
		(layer "In6.Cu")
		(net "P5E_PEX1_STN4_TX_DP<66>")
	)
	(gr_poly
		(pts
			(arc
				(start 191.153288 -304.449734)
				(mid 190.746888 -304.449734)
				(end 191.153288 -304.449734)
			)
		)
		(stroke
			(width 0)
			(type solid)
		)
		(fill yes)
		(layer "In6.Cu")
		(net "P5E_PEX1_STN4_TX_DP<64>")
	)
	(gr_poly
		(pts
			(arc
				(start 192.103248 -312.049922)
				(mid 191.696848 -312.049922)
				(end 192.103248 -312.049922)
			)
		)
		(stroke
			(width 0)
			(type solid)
		)
		(fill yes)
		(layer "In6.Cu")
		(net "P5E_PEX1_STN4_TX_DN<77>")
	)
	(gr_poly
		(pts
			(arc
				(start 192.103248 -311.099962)
				(mid 191.696848 -311.099962)
				(end 192.103248 -311.099962)
			)
		)
		(stroke
			(width 0)
			(type solid)
		)
		(fill yes)
		(layer "In6.Cu")
		(net "P5E_PEX1_STN4_TX_DP<77>")
	)
	(gr_poly
		(pts
			(arc
				(start 192.103248 -308.249828)
				(mid 191.696848 -308.249828)
				(end 192.103248 -308.249828)
			)
		)
		(stroke
			(width 0)
			(type solid)
		)
		(fill yes)
		(layer "In6.Cu")
		(net "P5E_PEX1_STN4_TX_DN<68>")
	)
	(gr_poly
		(pts
			(arc
				(start 192.103248 -306.349908)
				(mid 191.696848 -306.349908)
				(end 192.103248 -306.349908)
			)
		)
		(stroke
			(width 0)
			(type solid)
		)
		(fill yes)
		(layer "In6.Cu")
		(net "P5E_PEX1_STN4_TX_DN<66>")
	)
	(gr_poly
		(pts
			(arc
				(start 192.103248 -304.449734)
				(mid 191.696848 -304.449734)
				(end 192.103248 -304.449734)
			)
		)
		(stroke
			(width 0)
			(type solid)
		)
		(fill yes)
		(layer "In6.Cu")
		(net "P5E_PEX1_STN4_TX_DN<64>")
	)
	(gr_poly
		(pts
			(arc
				(start 192.103248 -287.349946)
				(mid 191.696848 -287.349946)
				(end 192.103248 -287.349946)
			)
		)
		(stroke
			(width 0)
			(type solid)
		)
		(fill yes)
		(layer "In6.Cu")
		(net "P5E_PEX1_STN0_TX_DN<1>")
	)
	(gr_poly
		(pts
			(arc
				(start 192.103248 -285.449772)
				(mid 191.696848 -285.449772)
				(end 192.103248 -285.449772)
			)
		)
		(stroke
			(width 0)
			(type solid)
		)
		(fill yes)
		(layer "In6.Cu")
		(net "P5E_PEX1_STN0_TX_DN<3>")
	)
	(gr_poly
		(pts
			(arc
				(start 192.103248 -283.549852)
				(mid 191.696848 -283.549852)
				(end 192.103248 -283.549852)
			)
		)
		(stroke
			(width 0)
			(type solid)
		)
		(fill yes)
		(layer "In6.Cu")
		(net "P5E_PEX1_STN0_TX_DN<5>")
	)
	(gr_poly
		(pts
			(arc
				(start 192.103248 -280.699718)
				(mid 191.696848 -280.699718)
				(end 192.103248 -280.699718)
			)
		)
		(stroke
			(width 0)
			(type solid)
		)
		(fill yes)
		(layer "In6.Cu")
		(net "P5E_PEX1_STN0_TX_DN<14>")
	)
	(gr_poly
		(pts
			(arc
				(start 192.103248 -279.749504)
				(mid 191.696848 -279.749504)
				(end 192.103248 -279.749504)
			)
		)
		(stroke
			(width 0)
			(type solid)
		)
		(fill yes)
		(layer "In6.Cu")
		(net "P5E_PEX1_STN0_TX_DP<14>")
	)
	(gr_poly
		(pts
			(arc
				(start 193.052954 -278.799798)
				(mid 192.646554 -278.799798)
				(end 193.052954 -278.799798)
			)
		)
		(stroke
			(width 0)
			(type solid)
		)
		(fill yes)
		(layer "In6.Cu")
		(net "P5E_PEX1_STN0_TX_DP<13>")
	)
	(gr_poly
		(pts
			(arc
				(start 193.052954 -277.849838)
				(mid 192.646554 -277.849838)
				(end 193.052954 -277.849838)
			)
		)
		(stroke
			(width 0)
			(type solid)
		)
		(fill yes)
		(layer "In6.Cu")
		(net "P5E_PEX1_STN0_TX_DN<13>")
	)
	(gr_poly
		(pts
			(arc
				(start 193.053208 -313.949842)
				(mid 192.646808 -313.949842)
				(end 193.053208 -313.949842)
			)
		)
		(stroke
			(width 0)
			(type solid)
		)
		(fill yes)
		(layer "In6.Cu")
		(net "P5E_PEX1_STN4_TX_DN<76>")
	)
	(gr_poly
		(pts
			(arc
				(start 193.053208 -312.999882)
				(mid 192.646808 -312.999882)
				(end 193.053208 -312.999882)
			)
		)
		(stroke
			(width 0)
			(type solid)
		)
		(fill yes)
		(layer "In6.Cu")
		(net "P5E_PEX1_STN4_TX_DP<76>")
	)
	(gr_poly
		(pts
			(arc
				(start 193.053208 -309.199788)
				(mid 192.646808 -309.199788)
				(end 193.053208 -309.199788)
			)
		)
		(stroke
			(width 0)
			(type solid)
		)
		(fill yes)
		(layer "In6.Cu")
		(net "P5E_PEX1_STN4_TX_DP<69>")
	)
	(gr_poly
		(pts
			(arc
				(start 193.053208 -307.299868)
				(mid 192.646808 -307.299868)
				(end 193.053208 -307.299868)
			)
		)
		(stroke
			(width 0)
			(type solid)
		)
		(fill yes)
		(layer "In6.Cu")
		(net "P5E_PEX1_STN4_TX_DP<67>")
	)
	(gr_poly
		(pts
			(arc
				(start 193.053208 -305.399948)
				(mid 192.646808 -305.399948)
				(end 193.053208 -305.399948)
			)
		)
		(stroke
			(width 0)
			(type solid)
		)
		(fill yes)
		(layer "In6.Cu")
		(net "P5E_PEX1_STN4_TX_DP<65>")
	)
	(gr_poly
		(pts
			(arc
				(start 193.053208 -288.299906)
				(mid 192.646808 -288.299906)
				(end 193.053208 -288.299906)
			)
		)
		(stroke
			(width 0)
			(type solid)
		)
		(fill yes)
		(layer "In6.Cu")
		(net "P5E_PEX1_STN0_TX_DP<0>")
	)
	(gr_poly
		(pts
			(arc
				(start 193.053208 -286.399986)
				(mid 192.646808 -286.399986)
				(end 193.053208 -286.399986)
			)
		)
		(stroke
			(width 0)
			(type solid)
		)
		(fill yes)
		(layer "In6.Cu")
		(net "P5E_PEX1_STN0_TX_DP<2>")
	)
	(gr_poly
		(pts
			(arc
				(start 193.053208 -284.499812)
				(mid 192.646808 -284.499812)
				(end 193.053208 -284.499812)
			)
		)
		(stroke
			(width 0)
			(type solid)
		)
		(fill yes)
		(layer "In6.Cu")
		(net "P5E_PEX1_STN0_TX_DP<4>")
	)
	(gr_poly
		(pts
			(arc
				(start 193.053208 -282.599892)
				(mid 192.646808 -282.599892)
				(end 193.053208 -282.599892)
			)
		)
		(stroke
			(width 0)
			(type solid)
		)
		(fill yes)
		(layer "In6.Cu")
		(net "P5E_PEX1_STN0_TX_DP<6>")
	)
	(gr_poly
		(pts
			(arc
				(start 194.003168 -312.049922)
				(mid 193.596768 -312.049922)
				(end 194.003168 -312.049922)
			)
		)
		(stroke
			(width 0)
			(type solid)
		)
		(fill yes)
		(layer "In6.Cu")
		(net "P5E_PEX1_STN4_TX_DN<75>")
	)
	(gr_poly
		(pts
			(arc
				(start 194.003168 -311.099962)
				(mid 193.596768 -311.099962)
				(end 194.003168 -311.099962)
			)
		)
		(stroke
			(width 0)
			(type solid)
		)
		(fill yes)
		(layer "In6.Cu")
		(net "P5E_PEX1_STN4_TX_DP<75>")
	)
	(gr_poly
		(pts
			(arc
				(start 194.003168 -309.199788)
				(mid 193.596768 -309.199788)
				(end 194.003168 -309.199788)
			)
		)
		(stroke
			(width 0)
			(type solid)
		)
		(fill yes)
		(layer "In6.Cu")
		(net "P5E_PEX1_STN4_TX_DN<69>")
	)
	(gr_poly
		(pts
			(arc
				(start 194.003168 -307.299868)
				(mid 193.596768 -307.299868)
				(end 194.003168 -307.299868)
			)
		)
		(stroke
			(width 0)
			(type solid)
		)
		(fill yes)
		(layer "In6.Cu")
		(net "P5E_PEX1_STN4_TX_DN<67>")
	)
	(gr_poly
		(pts
			(arc
				(start 194.003168 -305.399948)
				(mid 193.596768 -305.399948)
				(end 194.003168 -305.399948)
			)
		)
		(stroke
			(width 0)
			(type solid)
		)
		(fill yes)
		(layer "In6.Cu")
		(net "P5E_PEX1_STN4_TX_DN<65>")
	)
	(gr_poly
		(pts
			(arc
				(start 194.003168 -288.299906)
				(mid 193.596768 -288.299906)
				(end 194.003168 -288.299906)
			)
		)
		(stroke
			(width 0)
			(type solid)
		)
		(fill yes)
		(layer "In6.Cu")
		(net "P5E_PEX1_STN0_TX_DN<0>")
	)
	(gr_poly
		(pts
			(arc
				(start 194.003168 -286.399986)
				(mid 193.596768 -286.399986)
				(end 194.003168 -286.399986)
			)
		)
		(stroke
			(width 0)
			(type solid)
		)
		(fill yes)
		(layer "In6.Cu")
		(net "P5E_PEX1_STN0_TX_DN<2>")
	)
	(gr_poly
		(pts
			(arc
				(start 194.003168 -284.499812)
				(mid 193.596768 -284.499812)
				(end 194.003168 -284.499812)
			)
		)
		(stroke
			(width 0)
			(type solid)
		)
		(fill yes)
		(layer "In6.Cu")
		(net "P5E_PEX1_STN0_TX_DN<4>")
	)
	(gr_poly
		(pts
			(arc
				(start 194.003168 -282.599892)
				(mid 193.596768 -282.599892)
				(end 194.003168 -282.599892)
			)
		)
		(stroke
			(width 0)
			(type solid)
		)
		(fill yes)
		(layer "In6.Cu")
		(net "P5E_PEX1_STN0_TX_DN<6>")
	)
	(gr_poly
		(pts
			(arc
				(start 194.003168 -280.699718)
				(mid 193.596768 -280.699718)
				(end 194.003168 -280.699718)
			)
		)
		(stroke
			(width 0)
			(type solid)
		)
		(fill yes)
		(layer "In6.Cu")
		(net "P5E_PEX1_STN0_TX_DN<12>")
	)
	(gr_poly
		(pts
			(arc
				(start 194.003168 -279.749504)
				(mid 193.596768 -279.749504)
				(end 194.003168 -279.749504)
			)
		)
		(stroke
			(width 0)
			(type solid)
		)
		(fill yes)
		(layer "In6.Cu")
		(net "P5E_PEX1_STN0_TX_DP<12>")
	)
	(gr_poly
		(pts
			(arc
				(start 194.952874 -278.799798)
				(mid 194.546474 -278.799798)
				(end 194.952874 -278.799798)
			)
		)
		(stroke
			(width 0)
			(type solid)
		)
		(fill yes)
		(layer "In6.Cu")
		(net "P5E_PEX1_STN0_TX_DP<11>")
	)
	(gr_poly
		(pts
			(arc
				(start 194.952874 -277.849838)
				(mid 194.546474 -277.849838)
				(end 194.952874 -277.849838)
			)
		)
		(stroke
			(width 0)
			(type solid)
		)
		(fill yes)
		(layer "In6.Cu")
		(net "P5E_PEX1_STN0_TX_DN<11>")
	)
	(gr_poly
		(pts
			(arc
				(start 194.953128 -313.949842)
				(mid 194.546728 -313.949842)
				(end 194.953128 -313.949842)
			)
		)
		(stroke
			(width 0)
			(type solid)
		)
		(fill yes)
		(layer "In6.Cu")
		(net "P5E_PEX1_STN4_TX_DN<74>")
	)
	(gr_poly
		(pts
			(arc
				(start 194.953128 -312.999882)
				(mid 194.546728 -312.999882)
				(end 194.953128 -312.999882)
			)
		)
		(stroke
			(width 0)
			(type solid)
		)
		(fill yes)
		(layer "In6.Cu")
		(net "P5E_PEX1_STN4_TX_DP<74>")
	)
	(gr_poly
		(pts
			(arc
				(start 195.903088 -312.049922)
				(mid 195.496688 -312.049922)
				(end 195.903088 -312.049922)
			)
		)
		(stroke
			(width 0)
			(type solid)
		)
		(fill yes)
		(layer "In6.Cu")
		(net "P5E_PEX1_STN4_TX_DN<73>")
	)
	(gr_poly
		(pts
			(arc
				(start 195.903088 -311.099962)
				(mid 195.496688 -311.099962)
				(end 195.903088 -311.099962)
			)
		)
		(stroke
			(width 0)
			(type solid)
		)
		(fill yes)
		(layer "In6.Cu")
		(net "P5E_PEX1_STN4_TX_DP<73>")
	)
	(gr_poly
		(pts
			(arc
				(start 195.903088 -280.699718)
				(mid 195.496688 -280.699718)
				(end 195.903088 -280.699718)
			)
		)
		(stroke
			(width 0)
			(type solid)
		)
		(fill yes)
		(layer "In6.Cu")
		(net "P5E_PEX1_STN0_TX_DP<10>")
	)
	(gr_poly
		(pts
			(arc
				(start 195.903088 -279.749758)
				(mid 195.496688 -279.749758)
				(end 195.903088 -279.749758)
			)
		)
		(stroke
			(width 0)
			(type solid)
		)
		(fill yes)
		(layer "In6.Cu")
		(net "P5E_PEX1_STN0_TX_DN<10>")
	)
	(gr_poly
		(pts
			(arc
				(start 196.853048 -313.949842)
				(mid 196.446648 -313.949842)
				(end 196.853048 -313.949842)
			)
		)
		(stroke
			(width 0)
			(type solid)
		)
		(fill yes)
		(layer "In6.Cu")
		(net "P5E_PEX1_STN4_TX_DN<72>")
	)
	(gr_poly
		(pts
			(arc
				(start 196.853048 -312.999882)
				(mid 196.446648 -312.999882)
				(end 196.853048 -312.999882)
			)
		)
		(stroke
			(width 0)
			(type solid)
		)
		(fill yes)
		(layer "In6.Cu")
		(net "P5E_PEX1_STN4_TX_DP<72>")
	)
	(gr_poly
		(pts
			(arc
				(start 196.853048 -278.799798)
				(mid 196.446648 -278.799798)
				(end 196.853048 -278.799798)
			)
		)
		(stroke
			(width 0)
			(type solid)
		)
		(fill yes)
		(layer "In6.Cu")
		(net "P5E_PEX1_STN0_TX_DP<9>")
	)
	(gr_poly
		(pts
			(arc
				(start 196.853048 -277.849838)
				(mid 196.446648 -277.849838)
				(end 196.853048 -277.849838)
			)
		)
		(stroke
			(width 0)
			(type solid)
		)
		(fill yes)
		(layer "In6.Cu")
		(net "P5E_PEX1_STN0_TX_DN<9>")
	)
	(gr_poly
		(pts
			(arc
				(start 197.803262 -314.899802)
				(mid 197.396862 -314.899802)
				(end 197.803262 -314.899802)
			)
		)
		(stroke
			(width 0)
			(type solid)
		)
		(fill yes)
		(layer "In6.Cu")
		(net "P5E_PEX1_STN4_TX_DP<71>")
	)
	(gr_poly
		(pts
			(arc
				(start 197.803262 -312.049922)
				(mid 197.396862 -312.049922)
				(end 197.803262 -312.049922)
			)
		)
		(stroke
			(width 0)
			(type solid)
		)
		(fill yes)
		(layer "In6.Cu")
		(net "P5E_PEX1_STN4_TX_DP<70>")
	)
	(gr_poly
		(pts
			(arc
				(start 197.803262 -279.749758)
				(mid 197.396862 -279.749758)
				(end 197.803262 -279.749758)
			)
		)
		(stroke
			(width 0)
			(type solid)
		)
		(fill yes)
		(layer "In6.Cu")
		(net "P5E_PEX1_STN0_TX_DP<7>")
	)
	(gr_poly
		(pts
			(arc
				(start 197.803262 -276.899878)
				(mid 197.396862 -276.899878)
				(end 197.803262 -276.899878)
			)
		)
		(stroke
			(width 0)
			(type solid)
		)
		(fill yes)
		(layer "In6.Cu")
		(net "P5E_PEX1_STN0_TX_DP<8>")
	)
	(gr_poly
		(pts
			(arc
				(start 198.753222 -314.899802)
				(mid 198.346822 -314.899802)
				(end 198.753222 -314.899802)
			)
		)
		(stroke
			(width 0)
			(type solid)
		)
		(fill yes)
		(layer "In6.Cu")
		(net "P5E_PEX1_STN4_TX_DN<71>")
	)
	(gr_poly
		(pts
			(arc
				(start 198.753222 -312.049922)
				(mid 198.346822 -312.049922)
				(end 198.753222 -312.049922)
			)
		)
		(stroke
			(width 0)
			(type solid)
		)
		(fill yes)
		(layer "In6.Cu")
		(net "P5E_PEX1_STN4_TX_DN<70>")
	)
	(gr_poly
		(pts
			(arc
				(start 198.753222 -279.749758)
				(mid 198.346822 -279.749758)
				(end 198.753222 -279.749758)
			)
		)
		(stroke
			(width 0)
			(type solid)
		)
		(fill yes)
		(layer "In6.Cu")
		(net "P5E_PEX1_STN0_TX_DN<7>")
	)
	(gr_poly
		(pts
			(arc
				(start 198.753222 -276.899878)
				(mid 198.346822 -276.899878)
				(end 198.753222 -276.899878)
			)
		)
		(stroke
			(width 0)
			(type solid)
		)
		(fill yes)
		(layer "In6.Cu")
		(net "P5E_PEX1_STN0_TX_DN<8>")
	)
	(gr_poly
		(pts
			(arc
				(start 269.252954 -314.899802)
				(mid 268.846554 -314.899802)
				(end 269.252954 -314.899802)
			)
		)
		(stroke
			(width 0)
			(type solid)
		)
		(fill yes)
		(layer "In6.Cu")
		(net "P5E_PEX2_STN7_TX_DN<122>")
	)
	(gr_poly
		(pts
			(arc
				(start 269.252954 -312.049922)
				(mid 268.846554 -312.049922)
				(end 269.252954 -312.049922)
			)
		)
		(stroke
			(width 0)
			(type solid)
		)
		(fill yes)
		(layer "In6.Cu")
		(net "P5E_PEX2_STN7_TX_DN<121>")
	)
	(gr_poly
		(pts
			(arc
				(start 270.202914 -314.899802)
				(mid 269.796514 -314.899802)
				(end 270.202914 -314.899802)
			)
		)
		(stroke
			(width 0)
			(type solid)
		)
		(fill yes)
		(layer "In6.Cu")
		(net "P5E_PEX2_STN7_TX_DP<122>")
	)
	(gr_poly
		(pts
			(arc
				(start 270.202914 -312.049922)
				(mid 269.796514 -312.049922)
				(end 270.202914 -312.049922)
			)
		)
		(stroke
			(width 0)
			(type solid)
		)
		(fill yes)
		(layer "In6.Cu")
		(net "P5E_PEX2_STN7_TX_DP<121>")
	)
	(gr_poly
		(pts
			(arc
				(start 271.153128 -313.949842)
				(mid 270.746728 -313.949842)
				(end 271.153128 -313.949842)
			)
		)
		(stroke
			(width 0)
			(type solid)
		)
		(fill yes)
		(layer "In6.Cu")
		(net "P5E_PEX2_STN7_TX_DN<123>")
	)
	(gr_poly
		(pts
			(arc
				(start 271.153128 -312.999882)
				(mid 270.746728 -312.999882)
				(end 271.153128 -312.999882)
			)
		)
		(stroke
			(width 0)
			(type solid)
		)
		(fill yes)
		(layer "In6.Cu")
		(net "P5E_PEX2_STN7_TX_DP<123>")
	)
	(gr_poly
		(pts
			(arc
				(start 272.103088 -312.049922)
				(mid 271.696688 -312.049922)
				(end 272.103088 -312.049922)
			)
		)
		(stroke
			(width 0)
			(type solid)
		)
		(fill yes)
		(layer "In6.Cu")
		(net "P5E_PEX2_STN7_TX_DN<124>")
	)
	(gr_poly
		(pts
			(arc
				(start 272.103088 -311.099962)
				(mid 271.696688 -311.099962)
				(end 272.103088 -311.099962)
			)
		)
		(stroke
			(width 0)
			(type solid)
		)
		(fill yes)
		(layer "In6.Cu")
		(net "P5E_PEX2_STN7_TX_DP<124>")
	)
	(gr_poly
		(pts
			(arc
				(start 273.053048 -313.949842)
				(mid 272.646648 -313.949842)
				(end 273.053048 -313.949842)
			)
		)
		(stroke
			(width 0)
			(type solid)
		)
		(fill yes)
		(layer "In6.Cu")
		(net "P5E_PEX2_STN7_TX_DN<125>")
	)
	(gr_poly
		(pts
			(arc
				(start 273.053048 -312.999882)
				(mid 272.646648 -312.999882)
				(end 273.053048 -312.999882)
			)
		)
		(stroke
			(width 0)
			(type solid)
		)
		(fill yes)
		(layer "In6.Cu")
		(net "P5E_PEX2_STN7_TX_DP<125>")
	)
	(gr_poly
		(pts
			(arc
				(start 274.003008 -312.049922)
				(mid 273.596608 -312.049922)
				(end 274.003008 -312.049922)
			)
		)
		(stroke
			(width 0)
			(type solid)
		)
		(fill yes)
		(layer "In6.Cu")
		(net "P5E_PEX2_STN7_TX_DN<126>")
	)
	(gr_poly
		(pts
			(arc
				(start 274.003008 -311.099962)
				(mid 273.596608 -311.099962)
				(end 274.003008 -311.099962)
			)
		)
		(stroke
			(width 0)
			(type solid)
		)
		(fill yes)
		(layer "In6.Cu")
		(net "P5E_PEX2_STN7_TX_DP<126>")
	)
	(gr_poly
		(pts
			(arc
				(start 274.003008 -309.199788)
				(mid 273.596608 -309.199788)
				(end 274.003008 -309.199788)
			)
		)
		(stroke
			(width 0)
			(type solid)
		)
		(fill yes)
		(layer "In6.Cu")
		(net "P5E_PEX2_STN7_TX_DN<120>")
	)
	(gr_poly
		(pts
			(arc
				(start 274.003008 -307.299868)
				(mid 273.596608 -307.299868)
				(end 274.003008 -307.299868)
			)
		)
		(stroke
			(width 0)
			(type solid)
		)
		(fill yes)
		(layer "In6.Cu")
		(net "P5E_PEX2_STN7_TX_DN<118>")
	)
	(gr_poly
		(pts
			(arc
				(start 274.003008 -305.399948)
				(mid 273.596608 -305.399948)
				(end 274.003008 -305.399948)
			)
		)
		(stroke
			(width 0)
			(type solid)
		)
		(fill yes)
		(layer "In6.Cu")
		(net "P5E_PEX2_STN7_TX_DN<116>")
	)
	(gr_poly
		(pts
			(arc
				(start 274.003008 -303.499774)
				(mid 273.596608 -303.499774)
				(end 274.003008 -303.499774)
			)
		)
		(stroke
			(width 0)
			(type solid)
		)
		(fill yes)
		(layer "In6.Cu")
		(net "P5E_PEX2_STN7_TX_DN<114>")
	)
	(gr_poly
		(pts
			(arc
				(start 274.003008 -301.599854)
				(mid 273.596608 -301.599854)
				(end 274.003008 -301.599854)
			)
		)
		(stroke
			(width 0)
			(type solid)
		)
		(fill yes)
		(layer "In6.Cu")
		(net "P5E_PEX2_STN7_TX_DN<112>")
	)
	(gr_poly
		(pts
			(arc
				(start 274.952968 -313.949842)
				(mid 274.546568 -313.949842)
				(end 274.952968 -313.949842)
			)
		)
		(stroke
			(width 0)
			(type solid)
		)
		(fill yes)
		(layer "In6.Cu")
		(net "P5E_PEX2_STN7_TX_DN<127>")
	)
	(gr_poly
		(pts
			(arc
				(start 274.952968 -312.999882)
				(mid 274.546568 -312.999882)
				(end 274.952968 -312.999882)
			)
		)
		(stroke
			(width 0)
			(type solid)
		)
		(fill yes)
		(layer "In6.Cu")
		(net "P5E_PEX2_STN7_TX_DP<127>")
	)
	(gr_poly
		(pts
			(arc
				(start 274.952968 -309.199788)
				(mid 274.546568 -309.199788)
				(end 274.952968 -309.199788)
			)
		)
		(stroke
			(width 0)
			(type solid)
		)
		(fill yes)
		(layer "In6.Cu")
		(net "P5E_PEX2_STN7_TX_DP<120>")
	)
	(gr_poly
		(pts
			(arc
				(start 274.952968 -307.299868)
				(mid 274.546568 -307.299868)
				(end 274.952968 -307.299868)
			)
		)
		(stroke
			(width 0)
			(type solid)
		)
		(fill yes)
		(layer "In6.Cu")
		(net "P5E_PEX2_STN7_TX_DP<118>")
	)
	(gr_poly
		(pts
			(arc
				(start 274.952968 -305.399948)
				(mid 274.546568 -305.399948)
				(end 274.952968 -305.399948)
			)
		)
		(stroke
			(width 0)
			(type solid)
		)
		(fill yes)
		(layer "In6.Cu")
		(net "P5E_PEX2_STN7_TX_DP<116>")
	)
	(gr_poly
		(pts
			(arc
				(start 274.952968 -303.499774)
				(mid 274.546568 -303.499774)
				(end 274.952968 -303.499774)
			)
		)
		(stroke
			(width 0)
			(type solid)
		)
		(fill yes)
		(layer "In6.Cu")
		(net "P5E_PEX2_STN7_TX_DP<114>")
	)
	(gr_poly
		(pts
			(arc
				(start 274.952968 -301.599854)
				(mid 274.546568 -301.599854)
				(end 274.952968 -301.599854)
			)
		)
		(stroke
			(width 0)
			(type solid)
		)
		(fill yes)
		(layer "In6.Cu")
		(net "P5E_PEX2_STN7_TX_DP<112>")
	)
	(gr_poly
		(pts
			(arc
				(start 275.902928 -312.049922)
				(mid 275.496528 -312.049922)
				(end 275.902928 -312.049922)
			)
		)
		(stroke
			(width 0)
			(type solid)
		)
		(fill yes)
		(layer "In6.Cu")
		(net "P5E_PEX2_STN6_TX_DN<111>")
	)
	(gr_poly
		(pts
			(arc
				(start 275.902928 -311.099962)
				(mid 275.496528 -311.099962)
				(end 275.902928 -311.099962)
			)
		)
		(stroke
			(width 0)
			(type solid)
		)
		(fill yes)
		(layer "In6.Cu")
		(net "P5E_PEX2_STN6_TX_DP<111>")
	)
	(gr_poly
		(pts
			(arc
				(start 275.902928 -308.249828)
				(mid 275.496528 -308.249828)
				(end 275.902928 -308.249828)
			)
		)
		(stroke
			(width 0)
			(type solid)
		)
		(fill yes)
		(layer "In6.Cu")
		(net "P5E_PEX2_STN7_TX_DN<119>")
	)
	(gr_poly
		(pts
			(arc
				(start 275.902928 -306.349908)
				(mid 275.496528 -306.349908)
				(end 275.902928 -306.349908)
			)
		)
		(stroke
			(width 0)
			(type solid)
		)
		(fill yes)
		(layer "In6.Cu")
		(net "P5E_PEX2_STN7_TX_DN<117>")
	)
	(gr_poly
		(pts
			(arc
				(start 275.902928 -304.449734)
				(mid 275.496528 -304.449734)
				(end 275.902928 -304.449734)
			)
		)
		(stroke
			(width 0)
			(type solid)
		)
		(fill yes)
		(layer "In6.Cu")
		(net "P5E_PEX2_STN7_TX_DN<115>")
	)
	(gr_poly
		(pts
			(arc
				(start 275.902928 -302.549814)
				(mid 275.496528 -302.549814)
				(end 275.902928 -302.549814)
			)
		)
		(stroke
			(width 0)
			(type solid)
		)
		(fill yes)
		(layer "In6.Cu")
		(net "P5E_PEX2_STN7_TX_DN<113>")
	)
	(gr_poly
		(pts
			(arc
				(start 276.852888 -313.949842)
				(mid 276.446488 -313.949842)
				(end 276.852888 -313.949842)
			)
		)
		(stroke
			(width 0)
			(type solid)
		)
		(fill yes)
		(layer "In6.Cu")
		(net "P5E_PEX2_STN6_TX_DN<110>")
	)
	(gr_poly
		(pts
			(arc
				(start 276.852888 -312.999882)
				(mid 276.446488 -312.999882)
				(end 276.852888 -312.999882)
			)
		)
		(stroke
			(width 0)
			(type solid)
		)
		(fill yes)
		(layer "In6.Cu")
		(net "P5E_PEX2_STN6_TX_DP<110>")
	)
	(gr_poly
		(pts
			(arc
				(start 276.852888 -308.249828)
				(mid 276.446488 -308.249828)
				(end 276.852888 -308.249828)
			)
		)
		(stroke
			(width 0)
			(type solid)
		)
		(fill yes)
		(layer "In6.Cu")
		(net "P5E_PEX2_STN7_TX_DP<119>")
	)
	(gr_poly
		(pts
			(arc
				(start 276.852888 -306.349908)
				(mid 276.446488 -306.349908)
				(end 276.852888 -306.349908)
			)
		)
		(stroke
			(width 0)
			(type solid)
		)
		(fill yes)
		(layer "In6.Cu")
		(net "P5E_PEX2_STN7_TX_DP<117>")
	)
	(gr_poly
		(pts
			(arc
				(start 276.852888 -304.449734)
				(mid 276.446488 -304.449734)
				(end 276.852888 -304.449734)
			)
		)
		(stroke
			(width 0)
			(type solid)
		)
		(fill yes)
		(layer "In6.Cu")
		(net "P5E_PEX2_STN7_TX_DP<115>")
	)
	(gr_poly
		(pts
			(arc
				(start 276.852888 -302.549814)
				(mid 276.446488 -302.549814)
				(end 276.852888 -302.549814)
			)
		)
		(stroke
			(width 0)
			(type solid)
		)
		(fill yes)
		(layer "In6.Cu")
		(net "P5E_PEX2_STN7_TX_DP<113>")
	)
	(gr_poly
		(pts
			(arc
				(start 276.852888 -278.799798)
				(mid 276.446488 -278.799798)
				(end 276.852888 -278.799798)
			)
		)
		(stroke
			(width 0)
			(type solid)
		)
		(fill yes)
		(layer "In6.Cu")
		(net "P5E_PEX2_STN2_TX_DP<47>")
	)
	(gr_poly
		(pts
			(arc
				(start 276.852888 -277.849838)
				(mid 276.446488 -277.849838)
				(end 276.852888 -277.849838)
			)
		)
		(stroke
			(width 0)
			(type solid)
		)
		(fill yes)
		(layer "In6.Cu")
		(net "P5E_PEX2_STN2_TX_DN<47>")
	)
	(gr_poly
		(pts
			(arc
				(start 276.852888 -274.049744)
				(mid 276.446488 -274.049744)
				(end 276.852888 -274.049744)
			)
		)
		(stroke
			(width 0)
			(type solid)
		)
		(fill yes)
		(layer "In6.Cu")
		(net "P5E_PEX2_STN2_RX_DP<47>")
	)
	(gr_poly
		(pts
			(arc
				(start 276.852888 -273.099784)
				(mid 276.446488 -273.099784)
				(end 276.852888 -273.099784)
			)
		)
		(stroke
			(width 0)
			(type solid)
		)
		(fill yes)
		(layer "In6.Cu")
		(net "P5E_PEX2_STN2_RX_DN<47>")
	)
	(gr_poly
		(pts
			(arc
				(start 277.803102 -312.049922)
				(mid 277.396702 -312.049922)
				(end 277.803102 -312.049922)
			)
		)
		(stroke
			(width 0)
			(type solid)
		)
		(fill yes)
		(layer "In6.Cu")
		(net "P5E_PEX2_STN6_TX_DN<109>")
	)
	(gr_poly
		(pts
			(arc
				(start 277.803102 -311.099962)
				(mid 277.396702 -311.099962)
				(end 277.803102 -311.099962)
			)
		)
		(stroke
			(width 0)
			(type solid)
		)
		(fill yes)
		(layer "In6.Cu")
		(net "P5E_PEX2_STN6_TX_DP<109>")
	)
	(gr_poly
		(pts
			(arc
				(start 277.803102 -280.699464)
				(mid 277.396702 -280.699464)
				(end 277.803102 -280.699464)
			)
		)
		(stroke
			(width 0)
			(type solid)
		)
		(fill yes)
		(layer "In6.Cu")
		(net "P5E_PEX2_STN2_TX_DP<46>")
	)
	(gr_poly
		(pts
			(arc
				(start 277.803102 -279.749504)
				(mid 277.396702 -279.749504)
				(end 277.803102 -279.749504)
			)
		)
		(stroke
			(width 0)
			(type solid)
		)
		(fill yes)
		(layer "In6.Cu")
		(net "P5E_PEX2_STN2_TX_DN<46>")
	)
	(gr_poly
		(pts
			(arc
				(start 277.803102 -275.949918)
				(mid 277.396702 -275.949918)
				(end 277.803102 -275.949918)
			)
		)
		(stroke
			(width 0)
			(type solid)
		)
		(fill yes)
		(layer "In6.Cu")
		(net "P5E_PEX2_STN2_RX_DP<46>")
	)
	(gr_poly
		(pts
			(arc
				(start 277.803102 -274.999958)
				(mid 277.396702 -274.999958)
				(end 277.803102 -274.999958)
			)
		)
		(stroke
			(width 0)
			(type solid)
		)
		(fill yes)
		(layer "In6.Cu")
		(net "P5E_PEX2_STN2_RX_DN<46>")
	)
	(gr_poly
		(pts
			(arc
				(start 278.753062 -313.949842)
				(mid 278.346662 -313.949842)
				(end 278.753062 -313.949842)
			)
		)
		(stroke
			(width 0)
			(type solid)
		)
		(fill yes)
		(layer "In6.Cu")
		(net "P5E_PEX2_STN6_TX_DN<108>")
	)
	(gr_poly
		(pts
			(arc
				(start 278.753062 -312.999882)
				(mid 278.346662 -312.999882)
				(end 278.753062 -312.999882)
			)
		)
		(stroke
			(width 0)
			(type solid)
		)
		(fill yes)
		(layer "In6.Cu")
		(net "P5E_PEX2_STN6_TX_DP<108>")
	)
	(gr_poly
		(pts
			(arc
				(start 278.753062 -278.799798)
				(mid 278.346662 -278.799798)
				(end 278.753062 -278.799798)
			)
		)
		(stroke
			(width 0)
			(type solid)
		)
		(fill yes)
		(layer "In6.Cu")
		(net "P5E_PEX2_STN2_TX_DP<45>")
	)
	(gr_poly
		(pts
			(arc
				(start 278.753062 -277.849838)
				(mid 278.346662 -277.849838)
				(end 278.753062 -277.849838)
			)
		)
		(stroke
			(width 0)
			(type solid)
		)
		(fill yes)
		(layer "In6.Cu")
		(net "P5E_PEX2_STN2_TX_DN<45>")
	)
	(gr_poly
		(pts
			(arc
				(start 278.753062 -274.049744)
				(mid 278.346662 -274.049744)
				(end 278.753062 -274.049744)
			)
		)
		(stroke
			(width 0)
			(type solid)
		)
		(fill yes)
		(layer "In6.Cu")
		(net "P5E_PEX2_STN2_RX_DP<45>")
	)
	(gr_poly
		(pts
			(arc
				(start 278.753062 -273.099784)
				(mid 278.346662 -273.099784)
				(end 278.753062 -273.099784)
			)
		)
		(stroke
			(width 0)
			(type solid)
		)
		(fill yes)
		(layer "In6.Cu")
		(net "P5E_PEX2_STN2_RX_DN<45>")
	)
	(gr_poly
		(pts
			(arc
				(start 279.703022 -312.049922)
				(mid 279.296622 -312.049922)
				(end 279.703022 -312.049922)
			)
		)
		(stroke
			(width 0)
			(type solid)
		)
		(fill yes)
		(layer "In6.Cu")
		(net "P5E_PEX2_STN6_TX_DN<107>")
	)
	(gr_poly
		(pts
			(arc
				(start 279.703022 -311.099962)
				(mid 279.296622 -311.099962)
				(end 279.703022 -311.099962)
			)
		)
		(stroke
			(width 0)
			(type solid)
		)
		(fill yes)
		(layer "In6.Cu")
		(net "P5E_PEX2_STN6_TX_DP<107>")
	)
	(gr_poly
		(pts
			(arc
				(start 279.703022 -280.699464)
				(mid 279.296622 -280.699464)
				(end 279.703022 -280.699464)
			)
		)
		(stroke
			(width 0)
			(type solid)
		)
		(fill yes)
		(layer "In6.Cu")
		(net "P5E_PEX2_STN2_TX_DP<44>")
	)
	(gr_poly
		(pts
			(arc
				(start 279.703022 -279.749504)
				(mid 279.296622 -279.749504)
				(end 279.703022 -279.749504)
			)
		)
		(stroke
			(width 0)
			(type solid)
		)
		(fill yes)
		(layer "In6.Cu")
		(net "P5E_PEX2_STN2_TX_DN<44>")
	)
	(gr_poly
		(pts
			(arc
				(start 279.703022 -275.949918)
				(mid 279.296622 -275.949918)
				(end 279.703022 -275.949918)
			)
		)
		(stroke
			(width 0)
			(type solid)
		)
		(fill yes)
		(layer "In6.Cu")
		(net "P5E_PEX2_STN2_RX_DP<44>")
	)
	(gr_poly
		(pts
			(arc
				(start 279.703022 -274.999958)
				(mid 279.296622 -274.999958)
				(end 279.703022 -274.999958)
			)
		)
		(stroke
			(width 0)
			(type solid)
		)
		(fill yes)
		(layer "In6.Cu")
		(net "P5E_PEX2_STN2_RX_DN<44>")
	)
	(gr_poly
		(pts
			(arc
				(start 280.652982 -313.949842)
				(mid 280.246582 -313.949842)
				(end 280.652982 -313.949842)
			)
		)
		(stroke
			(width 0)
			(type solid)
		)
		(fill yes)
		(layer "In6.Cu")
		(net "P5E_PEX2_STN6_TX_DN<106>")
	)
	(gr_poly
		(pts
			(arc
				(start 280.652982 -312.999882)
				(mid 280.246582 -312.999882)
				(end 280.652982 -312.999882)
			)
		)
		(stroke
			(width 0)
			(type solid)
		)
		(fill yes)
		(layer "In6.Cu")
		(net "P5E_PEX2_STN6_TX_DP<106>")
	)
	(gr_poly
		(pts
			(arc
				(start 280.652982 -278.799798)
				(mid 280.246582 -278.799798)
				(end 280.652982 -278.799798)
			)
		)
		(stroke
			(width 0)
			(type solid)
		)
		(fill yes)
		(layer "In6.Cu")
		(net "P5E_PEX2_STN2_TX_DP<43>")
	)
	(gr_poly
		(pts
			(arc
				(start 280.652982 -277.849838)
				(mid 280.246582 -277.849838)
				(end 280.652982 -277.849838)
			)
		)
		(stroke
			(width 0)
			(type solid)
		)
		(fill yes)
		(layer "In6.Cu")
		(net "P5E_PEX2_STN2_TX_DN<43>")
	)
	(gr_poly
		(pts
			(arc
				(start 280.652982 -274.049744)
				(mid 280.246582 -274.049744)
				(end 280.652982 -274.049744)
			)
		)
		(stroke
			(width 0)
			(type solid)
		)
		(fill yes)
		(layer "In6.Cu")
		(net "P5E_PEX2_STN2_RX_DP<43>")
	)
	(gr_poly
		(pts
			(arc
				(start 280.652982 -273.099784)
				(mid 280.246582 -273.099784)
				(end 280.652982 -273.099784)
			)
		)
		(stroke
			(width 0)
			(type solid)
		)
		(fill yes)
		(layer "In6.Cu")
		(net "P5E_PEX2_STN2_RX_DN<43>")
	)
	(gr_poly
		(pts
			(arc
				(start 281.602942 -312.049922)
				(mid 281.196542 -312.049922)
				(end 281.602942 -312.049922)
			)
		)
		(stroke
			(width 0)
			(type solid)
		)
		(fill yes)
		(layer "In6.Cu")
		(net "P5E_PEX2_STN6_TX_DN<105>")
	)
	(gr_poly
		(pts
			(arc
				(start 281.602942 -311.099962)
				(mid 281.196542 -311.099962)
				(end 281.602942 -311.099962)
			)
		)
		(stroke
			(width 0)
			(type solid)
		)
		(fill yes)
		(layer "In6.Cu")
		(net "P5E_PEX2_STN6_TX_DP<105>")
	)
	(gr_poly
		(pts
			(arc
				(start 281.602942 -280.699464)
				(mid 281.196542 -280.699464)
				(end 281.602942 -280.699464)
			)
		)
		(stroke
			(width 0)
			(type solid)
		)
		(fill yes)
		(layer "In6.Cu")
		(net "P5E_PEX2_STN2_TX_DP<42>")
	)
	(gr_poly
		(pts
			(arc
				(start 281.602942 -279.749504)
				(mid 281.196542 -279.749504)
				(end 281.602942 -279.749504)
			)
		)
		(stroke
			(width 0)
			(type solid)
		)
		(fill yes)
		(layer "In6.Cu")
		(net "P5E_PEX2_STN2_TX_DN<42>")
	)
	(gr_poly
		(pts
			(arc
				(start 281.602942 -275.949918)
				(mid 281.196542 -275.949918)
				(end 281.602942 -275.949918)
			)
		)
		(stroke
			(width 0)
			(type solid)
		)
		(fill yes)
		(layer "In6.Cu")
		(net "P5E_PEX2_STN2_RX_DP<42>")
	)
	(gr_poly
		(pts
			(arc
				(start 281.602942 -274.999958)
				(mid 281.196542 -274.999958)
				(end 281.602942 -274.999958)
			)
		)
		(stroke
			(width 0)
			(type solid)
		)
		(fill yes)
		(layer "In6.Cu")
		(net "P5E_PEX2_STN2_RX_DN<42>")
	)
	(gr_poly
		(pts
			(arc
				(start 282.552902 -313.949842)
				(mid 282.146502 -313.949842)
				(end 282.552902 -313.949842)
			)
		)
		(stroke
			(width 0)
			(type solid)
		)
		(fill yes)
		(layer "In6.Cu")
		(net "P5E_PEX2_STN6_TX_DN<104>")
	)
	(gr_poly
		(pts
			(arc
				(start 282.552902 -312.999882)
				(mid 282.146502 -312.999882)
				(end 282.552902 -312.999882)
			)
		)
		(stroke
			(width 0)
			(type solid)
		)
		(fill yes)
		(layer "In6.Cu")
		(net "P5E_PEX2_STN6_TX_DP<104>")
	)
	(gr_poly
		(pts
			(arc
				(start 282.552902 -278.799798)
				(mid 282.146502 -278.799798)
				(end 282.552902 -278.799798)
			)
		)
		(stroke
			(width 0)
			(type solid)
		)
		(fill yes)
		(layer "In6.Cu")
		(net "P5E_PEX2_STN2_TX_DP<41>")
	)
	(gr_poly
		(pts
			(arc
				(start 282.552902 -277.849838)
				(mid 282.146502 -277.849838)
				(end 282.552902 -277.849838)
			)
		)
		(stroke
			(width 0)
			(type solid)
		)
		(fill yes)
		(layer "In6.Cu")
		(net "P5E_PEX2_STN2_TX_DN<41>")
	)
	(gr_poly
		(pts
			(arc
				(start 282.552902 -274.049744)
				(mid 282.146502 -274.049744)
				(end 282.552902 -274.049744)
			)
		)
		(stroke
			(width 0)
			(type solid)
		)
		(fill yes)
		(layer "In6.Cu")
		(net "P5E_PEX2_STN2_RX_DP<41>")
	)
	(gr_poly
		(pts
			(arc
				(start 282.552902 -273.099784)
				(mid 282.146502 -273.099784)
				(end 282.552902 -273.099784)
			)
		)
		(stroke
			(width 0)
			(type solid)
		)
		(fill yes)
		(layer "In6.Cu")
		(net "P5E_PEX2_STN2_RX_DN<41>")
	)
	(gr_poly
		(pts
			(arc
				(start 283.503116 -316.799722)
				(mid 283.096716 -316.799722)
				(end 283.503116 -316.799722)
			)
		)
		(stroke
			(width 0)
			(type solid)
		)
		(fill yes)
		(layer "In6.Cu")
		(net "P5E_PEX2_STN6_RX_DN<103>")
	)
	(gr_poly
		(pts
			(arc
				(start 283.503116 -315.849762)
				(mid 283.096716 -315.849762)
				(end 283.503116 -315.849762)
			)
		)
		(stroke
			(width 0)
			(type solid)
		)
		(fill yes)
		(layer "In6.Cu")
		(net "P5E_PEX2_STN6_RX_DP<103>")
	)
	(gr_poly
		(pts
			(arc
				(start 283.503116 -312.049922)
				(mid 283.096716 -312.049922)
				(end 283.503116 -312.049922)
			)
		)
		(stroke
			(width 0)
			(type solid)
		)
		(fill yes)
		(layer "In6.Cu")
		(net "P5E_PEX2_STN6_TX_DN<103>")
	)
	(gr_poly
		(pts
			(arc
				(start 283.503116 -311.099962)
				(mid 283.096716 -311.099962)
				(end 283.503116 -311.099962)
			)
		)
		(stroke
			(width 0)
			(type solid)
		)
		(fill yes)
		(layer "In6.Cu")
		(net "P5E_PEX2_STN6_TX_DP<103>")
	)
	(gr_poly
		(pts
			(arc
				(start 283.503116 -280.699464)
				(mid 283.096716 -280.699464)
				(end 283.503116 -280.699464)
			)
		)
		(stroke
			(width 0)
			(type solid)
		)
		(fill yes)
		(layer "In6.Cu")
		(net "P5E_PEX2_STN2_TX_DP<40>")
	)
	(gr_poly
		(pts
			(arc
				(start 283.503116 -279.749504)
				(mid 283.096716 -279.749504)
				(end 283.503116 -279.749504)
			)
		)
		(stroke
			(width 0)
			(type solid)
		)
		(fill yes)
		(layer "In6.Cu")
		(net "P5E_PEX2_STN2_TX_DN<40>")
	)
	(gr_poly
		(pts
			(arc
				(start 283.503116 -275.949918)
				(mid 283.096716 -275.949918)
				(end 283.503116 -275.949918)
			)
		)
		(stroke
			(width 0)
			(type solid)
		)
		(fill yes)
		(layer "In6.Cu")
		(net "P5E_PEX2_STN2_RX_DP<40>")
	)
	(gr_poly
		(pts
			(arc
				(start 283.503116 -274.999958)
				(mid 283.096716 -274.999958)
				(end 283.503116 -274.999958)
			)
		)
		(stroke
			(width 0)
			(type solid)
		)
		(fill yes)
		(layer "In6.Cu")
		(net "P5E_PEX2_STN2_RX_DN<40>")
	)
	(gr_poly
		(pts
			(arc
				(start 284.453076 -318.699896)
				(mid 284.046676 -318.699896)
				(end 284.453076 -318.699896)
			)
		)
		(stroke
			(width 0)
			(type solid)
		)
		(fill yes)
		(layer "In6.Cu")
		(net "P5E_PEX2_STN6_RX_DN<102>")
	)
	(gr_poly
		(pts
			(arc
				(start 284.453076 -317.749936)
				(mid 284.046676 -317.749936)
				(end 284.453076 -317.749936)
			)
		)
		(stroke
			(width 0)
			(type solid)
		)
		(fill yes)
		(layer "In6.Cu")
		(net "P5E_PEX2_STN6_RX_DP<102>")
	)
	(gr_poly
		(pts
			(arc
				(start 284.453076 -313.949842)
				(mid 284.046676 -313.949842)
				(end 284.453076 -313.949842)
			)
		)
		(stroke
			(width 0)
			(type solid)
		)
		(fill yes)
		(layer "In6.Cu")
		(net "P5E_PEX2_STN6_TX_DN<102>")
	)
	(gr_poly
		(pts
			(arc
				(start 284.453076 -312.999882)
				(mid 284.046676 -312.999882)
				(end 284.453076 -312.999882)
			)
		)
		(stroke
			(width 0)
			(type solid)
		)
		(fill yes)
		(layer "In6.Cu")
		(net "P5E_PEX2_STN6_TX_DP<102>")
	)
	(gr_poly
		(pts
			(arc
				(start 284.453076 -278.799798)
				(mid 284.046676 -278.799798)
				(end 284.453076 -278.799798)
			)
		)
		(stroke
			(width 0)
			(type solid)
		)
		(fill yes)
		(layer "In6.Cu")
		(net "P5E_PEX2_STN2_TX_DP<39>")
	)
	(gr_poly
		(pts
			(arc
				(start 284.453076 -277.849838)
				(mid 284.046676 -277.849838)
				(end 284.453076 -277.849838)
			)
		)
		(stroke
			(width 0)
			(type solid)
		)
		(fill yes)
		(layer "In6.Cu")
		(net "P5E_PEX2_STN2_TX_DN<39>")
	)
	(gr_poly
		(pts
			(arc
				(start 284.453076 -274.049744)
				(mid 284.046676 -274.049744)
				(end 284.453076 -274.049744)
			)
		)
		(stroke
			(width 0)
			(type solid)
		)
		(fill yes)
		(layer "In6.Cu")
		(net "P5E_PEX2_STN2_RX_DP<39>")
	)
	(gr_poly
		(pts
			(arc
				(start 284.453076 -273.099784)
				(mid 284.046676 -273.099784)
				(end 284.453076 -273.099784)
			)
		)
		(stroke
			(width 0)
			(type solid)
		)
		(fill yes)
		(layer "In6.Cu")
		(net "P5E_PEX2_STN2_RX_DN<39>")
	)
	(gr_poly
		(pts
			(arc
				(start 285.403036 -316.799722)
				(mid 284.996636 -316.799722)
				(end 285.403036 -316.799722)
			)
		)
		(stroke
			(width 0)
			(type solid)
		)
		(fill yes)
		(layer "In6.Cu")
		(net "P5E_PEX2_STN6_RX_DN<101>")
	)
	(gr_poly
		(pts
			(arc
				(start 285.403036 -315.849762)
				(mid 284.996636 -315.849762)
				(end 285.403036 -315.849762)
			)
		)
		(stroke
			(width 0)
			(type solid)
		)
		(fill yes)
		(layer "In6.Cu")
		(net "P5E_PEX2_STN6_RX_DP<101>")
	)
	(gr_poly
		(pts
			(arc
				(start 285.403036 -312.049922)
				(mid 284.996636 -312.049922)
				(end 285.403036 -312.049922)
			)
		)
		(stroke
			(width 0)
			(type solid)
		)
		(fill yes)
		(layer "In6.Cu")
		(net "P5E_PEX2_STN6_TX_DN<101>")
	)
	(gr_poly
		(pts
			(arc
				(start 285.403036 -311.099962)
				(mid 284.996636 -311.099962)
				(end 285.403036 -311.099962)
			)
		)
		(stroke
			(width 0)
			(type solid)
		)
		(fill yes)
		(layer "In6.Cu")
		(net "P5E_PEX2_STN6_TX_DP<101>")
	)
	(gr_poly
		(pts
			(arc
				(start 285.403036 -280.699464)
				(mid 284.996636 -280.699464)
				(end 285.403036 -280.699464)
			)
		)
		(stroke
			(width 0)
			(type solid)
		)
		(fill yes)
		(layer "In6.Cu")
		(net "P5E_PEX2_STN2_TX_DP<38>")
	)
	(gr_poly
		(pts
			(arc
				(start 285.403036 -279.749504)
				(mid 284.996636 -279.749504)
				(end 285.403036 -279.749504)
			)
		)
		(stroke
			(width 0)
			(type solid)
		)
		(fill yes)
		(layer "In6.Cu")
		(net "P5E_PEX2_STN2_TX_DN<38>")
	)
	(gr_poly
		(pts
			(arc
				(start 285.403036 -275.949918)
				(mid 284.996636 -275.949918)
				(end 285.403036 -275.949918)
			)
		)
		(stroke
			(width 0)
			(type solid)
		)
		(fill yes)
		(layer "In6.Cu")
		(net "P5E_PEX2_STN2_RX_DP<38>")
	)
	(gr_poly
		(pts
			(arc
				(start 285.403036 -274.999958)
				(mid 284.996636 -274.999958)
				(end 285.403036 -274.999958)
			)
		)
		(stroke
			(width 0)
			(type solid)
		)
		(fill yes)
		(layer "In6.Cu")
		(net "P5E_PEX2_STN2_RX_DN<38>")
	)
	(gr_poly
		(pts
			(arc
				(start 286.352996 -318.699896)
				(mid 285.946596 -318.699896)
				(end 286.352996 -318.699896)
			)
		)
		(stroke
			(width 0)
			(type solid)
		)
		(fill yes)
		(layer "In6.Cu")
		(net "P5E_PEX2_STN6_RX_DN<100>")
	)
	(gr_poly
		(pts
			(arc
				(start 286.352996 -317.749936)
				(mid 285.946596 -317.749936)
				(end 286.352996 -317.749936)
			)
		)
		(stroke
			(width 0)
			(type solid)
		)
		(fill yes)
		(layer "In6.Cu")
		(net "P5E_PEX2_STN6_RX_DP<100>")
	)
	(gr_poly
		(pts
			(arc
				(start 286.352996 -313.949842)
				(mid 285.946596 -313.949842)
				(end 286.352996 -313.949842)
			)
		)
		(stroke
			(width 0)
			(type solid)
		)
		(fill yes)
		(layer "In6.Cu")
		(net "P5E_PEX2_STN6_TX_DN<100>")
	)
	(gr_poly
		(pts
			(arc
				(start 286.352996 -312.999882)
				(mid 285.946596 -312.999882)
				(end 286.352996 -312.999882)
			)
		)
		(stroke
			(width 0)
			(type solid)
		)
		(fill yes)
		(layer "In6.Cu")
		(net "P5E_PEX2_STN6_TX_DP<100>")
	)
	(gr_poly
		(pts
			(arc
				(start 286.352996 -278.799798)
				(mid 285.946596 -278.799798)
				(end 286.352996 -278.799798)
			)
		)
		(stroke
			(width 0)
			(type solid)
		)
		(fill yes)
		(layer "In6.Cu")
		(net "P5E_PEX2_STN2_TX_DP<37>")
	)
	(gr_poly
		(pts
			(arc
				(start 286.352996 -277.849838)
				(mid 285.946596 -277.849838)
				(end 286.352996 -277.849838)
			)
		)
		(stroke
			(width 0)
			(type solid)
		)
		(fill yes)
		(layer "In6.Cu")
		(net "P5E_PEX2_STN2_TX_DN<37>")
	)
	(gr_poly
		(pts
			(arc
				(start 286.352996 -274.049744)
				(mid 285.946596 -274.049744)
				(end 286.352996 -274.049744)
			)
		)
		(stroke
			(width 0)
			(type solid)
		)
		(fill yes)
		(layer "In6.Cu")
		(net "P5E_PEX2_STN2_RX_DP<37>")
	)
	(gr_poly
		(pts
			(arc
				(start 286.352996 -273.099784)
				(mid 285.946596 -273.099784)
				(end 286.352996 -273.099784)
			)
		)
		(stroke
			(width 0)
			(type solid)
		)
		(fill yes)
		(layer "In6.Cu")
		(net "P5E_PEX2_STN2_RX_DN<37>")
	)
	(gr_poly
		(pts
			(arc
				(start 287.302956 -316.799722)
				(mid 286.896556 -316.799722)
				(end 287.302956 -316.799722)
			)
		)
		(stroke
			(width 0)
			(type solid)
		)
		(fill yes)
		(layer "In6.Cu")
		(net "P5E_PEX2_STN6_RX_DN<99>")
	)
	(gr_poly
		(pts
			(arc
				(start 287.302956 -315.849762)
				(mid 286.896556 -315.849762)
				(end 287.302956 -315.849762)
			)
		)
		(stroke
			(width 0)
			(type solid)
		)
		(fill yes)
		(layer "In6.Cu")
		(net "P5E_PEX2_STN6_RX_DP<99>")
	)
	(gr_poly
		(pts
			(arc
				(start 287.302956 -312.049922)
				(mid 286.896556 -312.049922)
				(end 287.302956 -312.049922)
			)
		)
		(stroke
			(width 0)
			(type solid)
		)
		(fill yes)
		(layer "In6.Cu")
		(net "P5E_PEX2_STN6_TX_DN<99>")
	)
	(gr_poly
		(pts
			(arc
				(start 287.302956 -311.099962)
				(mid 286.896556 -311.099962)
				(end 287.302956 -311.099962)
			)
		)
		(stroke
			(width 0)
			(type solid)
		)
		(fill yes)
		(layer "In6.Cu")
		(net "P5E_PEX2_STN6_TX_DP<99>")
	)
	(gr_poly
		(pts
			(arc
				(start 287.302956 -280.699464)
				(mid 286.896556 -280.699464)
				(end 287.302956 -280.699464)
			)
		)
		(stroke
			(width 0)
			(type solid)
		)
		(fill yes)
		(layer "In6.Cu")
		(net "P5E_PEX2_STN2_TX_DP<36>")
	)
	(gr_poly
		(pts
			(arc
				(start 287.302956 -279.749504)
				(mid 286.896556 -279.749504)
				(end 287.302956 -279.749504)
			)
		)
		(stroke
			(width 0)
			(type solid)
		)
		(fill yes)
		(layer "In6.Cu")
		(net "P5E_PEX2_STN2_TX_DN<36>")
	)
	(gr_poly
		(pts
			(arc
				(start 287.302956 -275.949918)
				(mid 286.896556 -275.949918)
				(end 287.302956 -275.949918)
			)
		)
		(stroke
			(width 0)
			(type solid)
		)
		(fill yes)
		(layer "In6.Cu")
		(net "P5E_PEX2_STN2_RX_DP<36>")
	)
	(gr_poly
		(pts
			(arc
				(start 287.302956 -274.999958)
				(mid 286.896556 -274.999958)
				(end 287.302956 -274.999958)
			)
		)
		(stroke
			(width 0)
			(type solid)
		)
		(fill yes)
		(layer "In6.Cu")
		(net "P5E_PEX2_STN2_RX_DN<36>")
	)
	(gr_poly
		(pts
			(arc
				(start 288.252916 -318.699896)
				(mid 287.846516 -318.699896)
				(end 288.252916 -318.699896)
			)
		)
		(stroke
			(width 0)
			(type solid)
		)
		(fill yes)
		(layer "In6.Cu")
		(net "P5E_PEX2_STN6_RX_DN<98>")
	)
	(gr_poly
		(pts
			(arc
				(start 288.252916 -317.749936)
				(mid 287.846516 -317.749936)
				(end 288.252916 -317.749936)
			)
		)
		(stroke
			(width 0)
			(type solid)
		)
		(fill yes)
		(layer "In6.Cu")
		(net "P5E_PEX2_STN6_RX_DP<98>")
	)
	(gr_poly
		(pts
			(arc
				(start 288.252916 -313.949842)
				(mid 287.846516 -313.949842)
				(end 288.252916 -313.949842)
			)
		)
		(stroke
			(width 0)
			(type solid)
		)
		(fill yes)
		(layer "In6.Cu")
		(net "P5E_PEX2_STN6_TX_DN<98>")
	)
	(gr_poly
		(pts
			(arc
				(start 288.252916 -312.999882)
				(mid 287.846516 -312.999882)
				(end 288.252916 -312.999882)
			)
		)
		(stroke
			(width 0)
			(type solid)
		)
		(fill yes)
		(layer "In6.Cu")
		(net "P5E_PEX2_STN6_TX_DP<98>")
	)
	(gr_poly
		(pts
			(arc
				(start 288.252916 -278.799798)
				(mid 287.846516 -278.799798)
				(end 288.252916 -278.799798)
			)
		)
		(stroke
			(width 0)
			(type solid)
		)
		(fill yes)
		(layer "In6.Cu")
		(net "P5E_PEX2_STN2_TX_DP<35>")
	)
	(gr_poly
		(pts
			(arc
				(start 288.252916 -277.849838)
				(mid 287.846516 -277.849838)
				(end 288.252916 -277.849838)
			)
		)
		(stroke
			(width 0)
			(type solid)
		)
		(fill yes)
		(layer "In6.Cu")
		(net "P5E_PEX2_STN2_TX_DN<35>")
	)
	(gr_poly
		(pts
			(arc
				(start 288.252916 -274.049744)
				(mid 287.846516 -274.049744)
				(end 288.252916 -274.049744)
			)
		)
		(stroke
			(width 0)
			(type solid)
		)
		(fill yes)
		(layer "In6.Cu")
		(net "P5E_PEX2_STN2_RX_DP<35>")
	)
	(gr_poly
		(pts
			(arc
				(start 288.252916 -273.099784)
				(mid 287.846516 -273.099784)
				(end 288.252916 -273.099784)
			)
		)
		(stroke
			(width 0)
			(type solid)
		)
		(fill yes)
		(layer "In6.Cu")
		(net "P5E_PEX2_STN2_RX_DN<35>")
	)
	(gr_poly
		(pts
			(arc
				(start 289.202876 -280.699464)
				(mid 288.796476 -280.699464)
				(end 289.202876 -280.699464)
			)
		)
		(stroke
			(width 0)
			(type solid)
		)
		(fill yes)
		(layer "In6.Cu")
		(net "P5E_PEX2_STN2_TX_DP<34>")
	)
	(gr_poly
		(pts
			(arc
				(start 289.202876 -279.749504)
				(mid 288.796476 -279.749504)
				(end 289.202876 -279.749504)
			)
		)
		(stroke
			(width 0)
			(type solid)
		)
		(fill yes)
		(layer "In6.Cu")
		(net "P5E_PEX2_STN2_TX_DN<34>")
	)
	(gr_poly
		(pts
			(arc
				(start 289.20313 -316.799722)
				(mid 288.79673 -316.799722)
				(end 289.20313 -316.799722)
			)
		)
		(stroke
			(width 0)
			(type solid)
		)
		(fill yes)
		(layer "In6.Cu")
		(net "P5E_PEX2_STN6_RX_DN<97>")
	)
	(gr_poly
		(pts
			(arc
				(start 289.20313 -315.849762)
				(mid 288.79673 -315.849762)
				(end 289.20313 -315.849762)
			)
		)
		(stroke
			(width 0)
			(type solid)
		)
		(fill yes)
		(layer "In6.Cu")
		(net "P5E_PEX2_STN6_RX_DP<97>")
	)
	(gr_poly
		(pts
			(arc
				(start 289.20313 -312.049922)
				(mid 288.79673 -312.049922)
				(end 289.20313 -312.049922)
			)
		)
		(stroke
			(width 0)
			(type solid)
		)
		(fill yes)
		(layer "In6.Cu")
		(net "P5E_PEX2_STN6_TX_DN<97>")
	)
	(gr_poly
		(pts
			(arc
				(start 289.20313 -311.099962)
				(mid 288.79673 -311.099962)
				(end 289.20313 -311.099962)
			)
		)
		(stroke
			(width 0)
			(type solid)
		)
		(fill yes)
		(layer "In6.Cu")
		(net "P5E_PEX2_STN6_TX_DP<97>")
	)
	(gr_poly
		(pts
			(arc
				(start 289.20313 -275.949918)
				(mid 288.79673 -275.949918)
				(end 289.20313 -275.949918)
			)
		)
		(stroke
			(width 0)
			(type solid)
		)
		(fill yes)
		(layer "In6.Cu")
		(net "P5E_PEX2_STN2_RX_DP<34>")
	)
	(gr_poly
		(pts
			(arc
				(start 289.20313 -274.999958)
				(mid 288.79673 -274.999958)
				(end 289.20313 -274.999958)
			)
		)
		(stroke
			(width 0)
			(type solid)
		)
		(fill yes)
		(layer "In6.Cu")
		(net "P5E_PEX2_STN2_RX_DN<34>")
	)
	(gr_poly
		(pts
			(arc
				(start 290.15309 -318.699896)
				(mid 289.74669 -318.699896)
				(end 290.15309 -318.699896)
			)
		)
		(stroke
			(width 0)
			(type solid)
		)
		(fill yes)
		(layer "In6.Cu")
		(net "P5E_PEX2_STN6_RX_DN<96>")
	)
	(gr_poly
		(pts
			(arc
				(start 290.15309 -317.749936)
				(mid 289.74669 -317.749936)
				(end 290.15309 -317.749936)
			)
		)
		(stroke
			(width 0)
			(type solid)
		)
		(fill yes)
		(layer "In6.Cu")
		(net "P5E_PEX2_STN6_RX_DP<96>")
	)
	(gr_poly
		(pts
			(arc
				(start 290.15309 -313.949842)
				(mid 289.74669 -313.949842)
				(end 290.15309 -313.949842)
			)
		)
		(stroke
			(width 0)
			(type solid)
		)
		(fill yes)
		(layer "In6.Cu")
		(net "P5E_PEX2_STN6_TX_DN<96>")
	)
	(gr_poly
		(pts
			(arc
				(start 290.15309 -312.999882)
				(mid 289.74669 -312.999882)
				(end 290.15309 -312.999882)
			)
		)
		(stroke
			(width 0)
			(type solid)
		)
		(fill yes)
		(layer "In6.Cu")
		(net "P5E_PEX2_STN6_TX_DP<96>")
	)
	(gr_poly
		(pts
			(arc
				(start 290.15309 -278.799798)
				(mid 289.74669 -278.799798)
				(end 290.15309 -278.799798)
			)
		)
		(stroke
			(width 0)
			(type solid)
		)
		(fill yes)
		(layer "In6.Cu")
		(net "P5E_PEX2_STN2_TX_DP<33>")
	)
	(gr_poly
		(pts
			(arc
				(start 290.15309 -277.849838)
				(mid 289.74669 -277.849838)
				(end 290.15309 -277.849838)
			)
		)
		(stroke
			(width 0)
			(type solid)
		)
		(fill yes)
		(layer "In6.Cu")
		(net "P5E_PEX2_STN2_TX_DN<33>")
	)
	(gr_poly
		(pts
			(arc
				(start 290.15309 -274.049744)
				(mid 289.74669 -274.049744)
				(end 290.15309 -274.049744)
			)
		)
		(stroke
			(width 0)
			(type solid)
		)
		(fill yes)
		(layer "In6.Cu")
		(net "P5E_PEX2_STN2_RX_DP<33>")
	)
	(gr_poly
		(pts
			(arc
				(start 290.15309 -273.099784)
				(mid 289.74669 -273.099784)
				(end 290.15309 -273.099784)
			)
		)
		(stroke
			(width 0)
			(type solid)
		)
		(fill yes)
		(layer "In6.Cu")
		(net "P5E_PEX2_STN2_RX_DN<33>")
	)
	(gr_poly
		(pts
			(arc
				(start 291.10305 -316.799722)
				(mid 290.69665 -316.799722)
				(end 291.10305 -316.799722)
			)
		)
		(stroke
			(width 0)
			(type solid)
		)
		(fill yes)
		(layer "In6.Cu")
		(net "P5E_PEX2_STN5_RX_DN<80>")
	)
	(gr_poly
		(pts
			(arc
				(start 291.10305 -315.849762)
				(mid 290.69665 -315.849762)
				(end 291.10305 -315.849762)
			)
		)
		(stroke
			(width 0)
			(type solid)
		)
		(fill yes)
		(layer "In6.Cu")
		(net "P5E_PEX2_STN5_RX_DP<80>")
	)
	(gr_poly
		(pts
			(arc
				(start 291.10305 -312.049922)
				(mid 290.69665 -312.049922)
				(end 291.10305 -312.049922)
			)
		)
		(stroke
			(width 0)
			(type solid)
		)
		(fill yes)
		(layer "In6.Cu")
		(net "P5E_PEX2_STN5_TX_DN<80>")
	)
	(gr_poly
		(pts
			(arc
				(start 291.10305 -311.099962)
				(mid 290.69665 -311.099962)
				(end 291.10305 -311.099962)
			)
		)
		(stroke
			(width 0)
			(type solid)
		)
		(fill yes)
		(layer "In6.Cu")
		(net "P5E_PEX2_STN5_TX_DP<80>")
	)
	(gr_poly
		(pts
			(arc
				(start 291.10305 -280.699464)
				(mid 290.69665 -280.699464)
				(end 291.10305 -280.699464)
			)
		)
		(stroke
			(width 0)
			(type solid)
		)
		(fill yes)
		(layer "In6.Cu")
		(net "P5E_PEX2_STN2_TX_DP<32>")
	)
	(gr_poly
		(pts
			(arc
				(start 291.10305 -279.749504)
				(mid 290.69665 -279.749504)
				(end 291.10305 -279.749504)
			)
		)
		(stroke
			(width 0)
			(type solid)
		)
		(fill yes)
		(layer "In6.Cu")
		(net "P5E_PEX2_STN2_TX_DN<32>")
	)
	(gr_poly
		(pts
			(arc
				(start 291.10305 -275.949918)
				(mid 290.69665 -275.949918)
				(end 291.10305 -275.949918)
			)
		)
		(stroke
			(width 0)
			(type solid)
		)
		(fill yes)
		(layer "In6.Cu")
		(net "P5E_PEX2_STN2_RX_DP<32>")
	)
	(gr_poly
		(pts
			(arc
				(start 291.10305 -274.999958)
				(mid 290.69665 -274.999958)
				(end 291.10305 -274.999958)
			)
		)
		(stroke
			(width 0)
			(type solid)
		)
		(fill yes)
		(layer "In6.Cu")
		(net "P5E_PEX2_STN2_RX_DN<32>")
	)
	(gr_poly
		(pts
			(arc
				(start 292.052756 -278.799798)
				(mid 291.646356 -278.799798)
				(end 292.052756 -278.799798)
			)
		)
		(stroke
			(width 0)
			(type solid)
		)
		(fill yes)
		(layer "In6.Cu")
		(net "P5E_PEX2_STN1_TX_DP<16>")
	)
	(gr_poly
		(pts
			(arc
				(start 292.052756 -277.849838)
				(mid 291.646356 -277.849838)
				(end 292.052756 -277.849838)
			)
		)
		(stroke
			(width 0)
			(type solid)
		)
		(fill yes)
		(layer "In6.Cu")
		(net "P5E_PEX2_STN1_TX_DN<16>")
	)
	(gr_poly
		(pts
			(arc
				(start 292.05301 -318.699896)
				(mid 291.64661 -318.699896)
				(end 292.05301 -318.699896)
			)
		)
		(stroke
			(width 0)
			(type solid)
		)
		(fill yes)
		(layer "In6.Cu")
		(net "P5E_PEX2_STN5_RX_DN<81>")
	)
	(gr_poly
		(pts
			(arc
				(start 292.05301 -317.749936)
				(mid 291.64661 -317.749936)
				(end 292.05301 -317.749936)
			)
		)
		(stroke
			(width 0)
			(type solid)
		)
		(fill yes)
		(layer "In6.Cu")
		(net "P5E_PEX2_STN5_RX_DP<81>")
	)
	(gr_poly
		(pts
			(arc
				(start 292.05301 -313.949842)
				(mid 291.64661 -313.949842)
				(end 292.05301 -313.949842)
			)
		)
		(stroke
			(width 0)
			(type solid)
		)
		(fill yes)
		(layer "In6.Cu")
		(net "P5E_PEX2_STN5_TX_DN<81>")
	)
	(gr_poly
		(pts
			(arc
				(start 292.05301 -312.999882)
				(mid 291.64661 -312.999882)
				(end 292.05301 -312.999882)
			)
		)
		(stroke
			(width 0)
			(type solid)
		)
		(fill yes)
		(layer "In6.Cu")
		(net "P5E_PEX2_STN5_TX_DP<81>")
	)
	(gr_poly
		(pts
			(arc
				(start 293.00297 -316.799722)
				(mid 292.59657 -316.799722)
				(end 293.00297 -316.799722)
			)
		)
		(stroke
			(width 0)
			(type solid)
		)
		(fill yes)
		(layer "In6.Cu")
		(net "P5E_PEX2_STN5_RX_DN<82>")
	)
	(gr_poly
		(pts
			(arc
				(start 293.00297 -315.849762)
				(mid 292.59657 -315.849762)
				(end 293.00297 -315.849762)
			)
		)
		(stroke
			(width 0)
			(type solid)
		)
		(fill yes)
		(layer "In6.Cu")
		(net "P5E_PEX2_STN5_RX_DP<82>")
	)
	(gr_poly
		(pts
			(arc
				(start 293.00297 -312.049922)
				(mid 292.59657 -312.049922)
				(end 293.00297 -312.049922)
			)
		)
		(stroke
			(width 0)
			(type solid)
		)
		(fill yes)
		(layer "In6.Cu")
		(net "P5E_PEX2_STN5_TX_DN<82>")
	)
	(gr_poly
		(pts
			(arc
				(start 293.00297 -311.099962)
				(mid 292.59657 -311.099962)
				(end 293.00297 -311.099962)
			)
		)
		(stroke
			(width 0)
			(type solid)
		)
		(fill yes)
		(layer "In6.Cu")
		(net "P5E_PEX2_STN5_TX_DP<82>")
	)
	(gr_poly
		(pts
			(arc
				(start 293.00297 -280.699464)
				(mid 292.59657 -280.699464)
				(end 293.00297 -280.699464)
			)
		)
		(stroke
			(width 0)
			(type solid)
		)
		(fill yes)
		(layer "In6.Cu")
		(net "P5E_PEX2_STN1_TX_DN<17>")
	)
	(gr_poly
		(pts
			(arc
				(start 293.00297 -279.749504)
				(mid 292.59657 -279.749504)
				(end 293.00297 -279.749504)
			)
		)
		(stroke
			(width 0)
			(type solid)
		)
		(fill yes)
		(layer "In6.Cu")
		(net "P5E_PEX2_STN1_TX_DP<17>")
	)
	(gr_poly
		(pts
			(arc
				(start 293.952676 -278.799798)
				(mid 293.546276 -278.799798)
				(end 293.952676 -278.799798)
			)
		)
		(stroke
			(width 0)
			(type solid)
		)
		(fill yes)
		(layer "In6.Cu")
		(net "P5E_PEX2_STN1_TX_DP<18>")
	)
	(gr_poly
		(pts
			(arc
				(start 293.952676 -277.849838)
				(mid 293.546276 -277.849838)
				(end 293.952676 -277.849838)
			)
		)
		(stroke
			(width 0)
			(type solid)
		)
		(fill yes)
		(layer "In6.Cu")
		(net "P5E_PEX2_STN1_TX_DN<18>")
	)
	(gr_poly
		(pts
			(arc
				(start 293.95293 -318.699896)
				(mid 293.54653 -318.699896)
				(end 293.95293 -318.699896)
			)
		)
		(stroke
			(width 0)
			(type solid)
		)
		(fill yes)
		(layer "In6.Cu")
		(net "P5E_PEX2_STN5_RX_DN<83>")
	)
	(gr_poly
		(pts
			(arc
				(start 293.95293 -317.749936)
				(mid 293.54653 -317.749936)
				(end 293.95293 -317.749936)
			)
		)
		(stroke
			(width 0)
			(type solid)
		)
		(fill yes)
		(layer "In6.Cu")
		(net "P5E_PEX2_STN5_RX_DP<83>")
	)
	(gr_poly
		(pts
			(arc
				(start 293.95293 -313.949842)
				(mid 293.54653 -313.949842)
				(end 293.95293 -313.949842)
			)
		)
		(stroke
			(width 0)
			(type solid)
		)
		(fill yes)
		(layer "In6.Cu")
		(net "P5E_PEX2_STN5_TX_DN<83>")
	)
	(gr_poly
		(pts
			(arc
				(start 293.95293 -312.999882)
				(mid 293.54653 -312.999882)
				(end 293.95293 -312.999882)
			)
		)
		(stroke
			(width 0)
			(type solid)
		)
		(fill yes)
		(layer "In6.Cu")
		(net "P5E_PEX2_STN5_TX_DP<83>")
	)
	(gr_poly
		(pts
			(arc
				(start 294.90289 -316.799722)
				(mid 294.49649 -316.799722)
				(end 294.90289 -316.799722)
			)
		)
		(stroke
			(width 0)
			(type solid)
		)
		(fill yes)
		(layer "In6.Cu")
		(net "P5E_PEX2_STN5_RX_DN<84>")
	)
	(gr_poly
		(pts
			(arc
				(start 294.90289 -315.849762)
				(mid 294.49649 -315.849762)
				(end 294.90289 -315.849762)
			)
		)
		(stroke
			(width 0)
			(type solid)
		)
		(fill yes)
		(layer "In6.Cu")
		(net "P5E_PEX2_STN5_RX_DP<84>")
	)
	(gr_poly
		(pts
			(arc
				(start 294.90289 -312.049922)
				(mid 294.49649 -312.049922)
				(end 294.90289 -312.049922)
			)
		)
		(stroke
			(width 0)
			(type solid)
		)
		(fill yes)
		(layer "In6.Cu")
		(net "P5E_PEX2_STN5_TX_DN<84>")
	)
	(gr_poly
		(pts
			(arc
				(start 294.90289 -311.099962)
				(mid 294.49649 -311.099962)
				(end 294.90289 -311.099962)
			)
		)
		(stroke
			(width 0)
			(type solid)
		)
		(fill yes)
		(layer "In6.Cu")
		(net "P5E_PEX2_STN5_TX_DP<84>")
	)
	(gr_poly
		(pts
			(arc
				(start 294.90289 -280.699464)
				(mid 294.49649 -280.699464)
				(end 294.90289 -280.699464)
			)
		)
		(stroke
			(width 0)
			(type solid)
		)
		(fill yes)
		(layer "In6.Cu")
		(net "P5E_PEX2_STN1_TX_DN<19>")
	)
	(gr_poly
		(pts
			(arc
				(start 294.90289 -279.749504)
				(mid 294.49649 -279.749504)
				(end 294.90289 -279.749504)
			)
		)
		(stroke
			(width 0)
			(type solid)
		)
		(fill yes)
		(layer "In6.Cu")
		(net "P5E_PEX2_STN1_TX_DP<19>")
	)
	(gr_poly
		(pts
			(arc
				(start 295.85285 -278.799798)
				(mid 295.44645 -278.799798)
				(end 295.85285 -278.799798)
			)
		)
		(stroke
			(width 0)
			(type solid)
		)
		(fill yes)
		(layer "In6.Cu")
		(net "P5E_PEX2_STN1_TX_DP<20>")
	)
	(gr_poly
		(pts
			(arc
				(start 295.85285 -277.849838)
				(mid 295.44645 -277.849838)
				(end 295.85285 -277.849838)
			)
		)
		(stroke
			(width 0)
			(type solid)
		)
		(fill yes)
		(layer "In6.Cu")
		(net "P5E_PEX2_STN1_TX_DN<20>")
	)
	(gr_poly
		(pts
			(arc
				(start 295.853104 -318.699896)
				(mid 295.446704 -318.699896)
				(end 295.853104 -318.699896)
			)
		)
		(stroke
			(width 0)
			(type solid)
		)
		(fill yes)
		(layer "In6.Cu")
		(net "P5E_PEX2_STN5_RX_DN<85>")
	)
	(gr_poly
		(pts
			(arc
				(start 295.853104 -317.749936)
				(mid 295.446704 -317.749936)
				(end 295.853104 -317.749936)
			)
		)
		(stroke
			(width 0)
			(type solid)
		)
		(fill yes)
		(layer "In6.Cu")
		(net "P5E_PEX2_STN5_RX_DP<85>")
	)
	(gr_poly
		(pts
			(arc
				(start 295.853104 -313.949842)
				(mid 295.446704 -313.949842)
				(end 295.853104 -313.949842)
			)
		)
		(stroke
			(width 0)
			(type solid)
		)
		(fill yes)
		(layer "In6.Cu")
		(net "P5E_PEX2_STN5_TX_DN<85>")
	)
	(gr_poly
		(pts
			(arc
				(start 295.853104 -312.999882)
				(mid 295.446704 -312.999882)
				(end 295.853104 -312.999882)
			)
		)
		(stroke
			(width 0)
			(type solid)
		)
		(fill yes)
		(layer "In6.Cu")
		(net "P5E_PEX2_STN5_TX_DP<85>")
	)
	(gr_poly
		(pts
			(arc
				(start 296.803064 -316.799722)
				(mid 296.396664 -316.799722)
				(end 296.803064 -316.799722)
			)
		)
		(stroke
			(width 0)
			(type solid)
		)
		(fill yes)
		(layer "In6.Cu")
		(net "P5E_PEX2_STN5_RX_DN<86>")
	)
	(gr_poly
		(pts
			(arc
				(start 296.803064 -315.849762)
				(mid 296.396664 -315.849762)
				(end 296.803064 -315.849762)
			)
		)
		(stroke
			(width 0)
			(type solid)
		)
		(fill yes)
		(layer "In6.Cu")
		(net "P5E_PEX2_STN5_RX_DP<86>")
	)
	(gr_poly
		(pts
			(arc
				(start 296.803064 -312.049922)
				(mid 296.396664 -312.049922)
				(end 296.803064 -312.049922)
			)
		)
		(stroke
			(width 0)
			(type solid)
		)
		(fill yes)
		(layer "In6.Cu")
		(net "P5E_PEX2_STN5_TX_DN<86>")
	)
	(gr_poly
		(pts
			(arc
				(start 296.803064 -311.099962)
				(mid 296.396664 -311.099962)
				(end 296.803064 -311.099962)
			)
		)
		(stroke
			(width 0)
			(type solid)
		)
		(fill yes)
		(layer "In6.Cu")
		(net "P5E_PEX2_STN5_TX_DP<86>")
	)
	(gr_poly
		(pts
			(arc
				(start 296.803064 -280.699464)
				(mid 296.396664 -280.699464)
				(end 296.803064 -280.699464)
			)
		)
		(stroke
			(width 0)
			(type solid)
		)
		(fill yes)
		(layer "In6.Cu")
		(net "P5E_PEX2_STN1_TX_DN<21>")
	)
	(gr_poly
		(pts
			(arc
				(start 296.803064 -279.749504)
				(mid 296.396664 -279.749504)
				(end 296.803064 -279.749504)
			)
		)
		(stroke
			(width 0)
			(type solid)
		)
		(fill yes)
		(layer "In6.Cu")
		(net "P5E_PEX2_STN1_TX_DP<21>")
	)
	(gr_poly
		(pts
			(arc
				(start 297.75277 -278.799798)
				(mid 297.34637 -278.799798)
				(end 297.75277 -278.799798)
			)
		)
		(stroke
			(width 0)
			(type solid)
		)
		(fill yes)
		(layer "In6.Cu")
		(net "P5E_PEX2_STN1_TX_DP<22>")
	)
	(gr_poly
		(pts
			(arc
				(start 297.75277 -277.849838)
				(mid 297.34637 -277.849838)
				(end 297.75277 -277.849838)
			)
		)
		(stroke
			(width 0)
			(type solid)
		)
		(fill yes)
		(layer "In6.Cu")
		(net "P5E_PEX2_STN1_TX_DN<22>")
	)
	(gr_poly
		(pts
			(arc
				(start 297.753024 -318.699896)
				(mid 297.346624 -318.699896)
				(end 297.753024 -318.699896)
			)
		)
		(stroke
			(width 0)
			(type solid)
		)
		(fill yes)
		(layer "In6.Cu")
		(net "P5E_PEX2_STN5_RX_DN<87>")
	)
	(gr_poly
		(pts
			(arc
				(start 297.753024 -317.749936)
				(mid 297.346624 -317.749936)
				(end 297.753024 -317.749936)
			)
		)
		(stroke
			(width 0)
			(type solid)
		)
		(fill yes)
		(layer "In6.Cu")
		(net "P5E_PEX2_STN5_RX_DP<87>")
	)
	(gr_poly
		(pts
			(arc
				(start 297.753024 -313.949842)
				(mid 297.346624 -313.949842)
				(end 297.753024 -313.949842)
			)
		)
		(stroke
			(width 0)
			(type solid)
		)
		(fill yes)
		(layer "In6.Cu")
		(net "P5E_PEX2_STN5_TX_DN<87>")
	)
	(gr_poly
		(pts
			(arc
				(start 297.753024 -312.999882)
				(mid 297.346624 -312.999882)
				(end 297.753024 -312.999882)
			)
		)
		(stroke
			(width 0)
			(type solid)
		)
		(fill yes)
		(layer "In6.Cu")
		(net "P5E_PEX2_STN5_TX_DP<87>")
	)
	(gr_poly
		(pts
			(arc
				(start 298.702984 -312.049922)
				(mid 298.296584 -312.049922)
				(end 298.702984 -312.049922)
			)
		)
		(stroke
			(width 0)
			(type solid)
		)
		(fill yes)
		(layer "In6.Cu")
		(net "P5E_PEX2_STN5_TX_DN<88>")
	)
	(gr_poly
		(pts
			(arc
				(start 298.702984 -311.099962)
				(mid 298.296584 -311.099962)
				(end 298.702984 -311.099962)
			)
		)
		(stroke
			(width 0)
			(type solid)
		)
		(fill yes)
		(layer "In6.Cu")
		(net "P5E_PEX2_STN5_TX_DP<88>")
	)
	(gr_poly
		(pts
			(arc
				(start 298.702984 -280.699464)
				(mid 298.296584 -280.699464)
				(end 298.702984 -280.699464)
			)
		)
		(stroke
			(width 0)
			(type solid)
		)
		(fill yes)
		(layer "In6.Cu")
		(net "P5E_PEX2_STN1_TX_DN<23>")
	)
	(gr_poly
		(pts
			(arc
				(start 298.702984 -279.749504)
				(mid 298.296584 -279.749504)
				(end 298.702984 -279.749504)
			)
		)
		(stroke
			(width 0)
			(type solid)
		)
		(fill yes)
		(layer "In6.Cu")
		(net "P5E_PEX2_STN1_TX_DP<23>")
	)
	(gr_poly
		(pts
			(arc
				(start 299.65269 -278.799798)
				(mid 299.24629 -278.799798)
				(end 299.65269 -278.799798)
			)
		)
		(stroke
			(width 0)
			(type solid)
		)
		(fill yes)
		(layer "In6.Cu")
		(net "P5E_PEX2_STN1_TX_DP<24>")
	)
	(gr_poly
		(pts
			(arc
				(start 299.65269 -277.849838)
				(mid 299.24629 -277.849838)
				(end 299.65269 -277.849838)
			)
		)
		(stroke
			(width 0)
			(type solid)
		)
		(fill yes)
		(layer "In6.Cu")
		(net "P5E_PEX2_STN1_TX_DN<24>")
	)
	(gr_poly
		(pts
			(arc
				(start 299.652944 -313.949842)
				(mid 299.246544 -313.949842)
				(end 299.652944 -313.949842)
			)
		)
		(stroke
			(width 0)
			(type solid)
		)
		(fill yes)
		(layer "In6.Cu")
		(net "P5E_PEX2_STN5_TX_DN<89>")
	)
	(gr_poly
		(pts
			(arc
				(start 299.652944 -312.999882)
				(mid 299.246544 -312.999882)
				(end 299.652944 -312.999882)
			)
		)
		(stroke
			(width 0)
			(type solid)
		)
		(fill yes)
		(layer "In6.Cu")
		(net "P5E_PEX2_STN5_TX_DP<89>")
	)
	(gr_poly
		(pts
			(arc
				(start 300.602904 -312.049922)
				(mid 300.196504 -312.049922)
				(end 300.602904 -312.049922)
			)
		)
		(stroke
			(width 0)
			(type solid)
		)
		(fill yes)
		(layer "In6.Cu")
		(net "P5E_PEX2_STN5_TX_DN<90>")
	)
	(gr_poly
		(pts
			(arc
				(start 300.602904 -311.099962)
				(mid 300.196504 -311.099962)
				(end 300.602904 -311.099962)
			)
		)
		(stroke
			(width 0)
			(type solid)
		)
		(fill yes)
		(layer "In6.Cu")
		(net "P5E_PEX2_STN5_TX_DP<90>")
	)
	(gr_poly
		(pts
			(arc
				(start 300.602904 -280.699464)
				(mid 300.196504 -280.699464)
				(end 300.602904 -280.699464)
			)
		)
		(stroke
			(width 0)
			(type solid)
		)
		(fill yes)
		(layer "In6.Cu")
		(net "P5E_PEX2_STN1_TX_DN<25>")
	)
	(gr_poly
		(pts
			(arc
				(start 300.602904 -279.749504)
				(mid 300.196504 -279.749504)
				(end 300.602904 -279.749504)
			)
		)
		(stroke
			(width 0)
			(type solid)
		)
		(fill yes)
		(layer "In6.Cu")
		(net "P5E_PEX2_STN1_TX_DP<25>")
	)
	(gr_poly
		(pts
			(arc
				(start 301.552864 -278.799798)
				(mid 301.146464 -278.799798)
				(end 301.552864 -278.799798)
			)
		)
		(stroke
			(width 0)
			(type solid)
		)
		(fill yes)
		(layer "In6.Cu")
		(net "P5E_PEX2_STN1_TX_DP<26>")
	)
	(gr_poly
		(pts
			(arc
				(start 301.552864 -277.849838)
				(mid 301.146464 -277.849838)
				(end 301.552864 -277.849838)
			)
		)
		(stroke
			(width 0)
			(type solid)
		)
		(fill yes)
		(layer "In6.Cu")
		(net "P5E_PEX2_STN1_TX_DN<26>")
	)
	(gr_poly
		(pts
			(arc
				(start 301.553118 -313.949842)
				(mid 301.146718 -313.949842)
				(end 301.553118 -313.949842)
			)
		)
		(stroke
			(width 0)
			(type solid)
		)
		(fill yes)
		(layer "In6.Cu")
		(net "P5E_PEX2_STN5_TX_DN<91>")
	)
	(gr_poly
		(pts
			(arc
				(start 301.553118 -312.999882)
				(mid 301.146718 -312.999882)
				(end 301.553118 -312.999882)
			)
		)
		(stroke
			(width 0)
			(type solid)
		)
		(fill yes)
		(layer "In6.Cu")
		(net "P5E_PEX2_STN5_TX_DP<91>")
	)
	(gr_poly
		(pts
			(arc
				(start 302.503078 -312.049922)
				(mid 302.096678 -312.049922)
				(end 302.503078 -312.049922)
			)
		)
		(stroke
			(width 0)
			(type solid)
		)
		(fill yes)
		(layer "In6.Cu")
		(net "P5E_PEX2_STN5_TX_DN<92>")
	)
	(gr_poly
		(pts
			(arc
				(start 302.503078 -311.099962)
				(mid 302.096678 -311.099962)
				(end 302.503078 -311.099962)
			)
		)
		(stroke
			(width 0)
			(type solid)
		)
		(fill yes)
		(layer "In6.Cu")
		(net "P5E_PEX2_STN5_TX_DP<92>")
	)
	(gr_poly
		(pts
			(arc
				(start 302.503078 -280.699464)
				(mid 302.096678 -280.699464)
				(end 302.503078 -280.699464)
			)
		)
		(stroke
			(width 0)
			(type solid)
		)
		(fill yes)
		(layer "In6.Cu")
		(net "P5E_PEX2_STN1_TX_DN<27>")
	)
	(gr_poly
		(pts
			(arc
				(start 302.503078 -279.749504)
				(mid 302.096678 -279.749504)
				(end 302.503078 -279.749504)
			)
		)
		(stroke
			(width 0)
			(type solid)
		)
		(fill yes)
		(layer "In6.Cu")
		(net "P5E_PEX2_STN1_TX_DP<27>")
	)
	(gr_poly
		(pts
			(arc
				(start 303.452784 -278.799798)
				(mid 303.046384 -278.799798)
				(end 303.452784 -278.799798)
			)
		)
		(stroke
			(width 0)
			(type solid)
		)
		(fill yes)
		(layer "In6.Cu")
		(net "P5E_PEX2_STN1_TX_DP<28>")
	)
	(gr_poly
		(pts
			(arc
				(start 303.452784 -277.849838)
				(mid 303.046384 -277.849838)
				(end 303.452784 -277.849838)
			)
		)
		(stroke
			(width 0)
			(type solid)
		)
		(fill yes)
		(layer "In6.Cu")
		(net "P5E_PEX2_STN1_TX_DN<28>")
	)
	(gr_poly
		(pts
			(arc
				(start 303.453038 -313.949842)
				(mid 303.046638 -313.949842)
				(end 303.453038 -313.949842)
			)
		)
		(stroke
			(width 0)
			(type solid)
		)
		(fill yes)
		(layer "In6.Cu")
		(net "P5E_PEX2_STN5_TX_DN<93>")
	)
	(gr_poly
		(pts
			(arc
				(start 303.453038 -312.999882)
				(mid 303.046638 -312.999882)
				(end 303.453038 -312.999882)
			)
		)
		(stroke
			(width 0)
			(type solid)
		)
		(fill yes)
		(layer "In6.Cu")
		(net "P5E_PEX2_STN5_TX_DP<93>")
	)
	(gr_poly
		(pts
			(arc
				(start 304.402998 -312.049922)
				(mid 303.996598 -312.049922)
				(end 304.402998 -312.049922)
			)
		)
		(stroke
			(width 0)
			(type solid)
		)
		(fill yes)
		(layer "In6.Cu")
		(net "P5E_PEX2_STN5_TX_DN<94>")
	)
	(gr_poly
		(pts
			(arc
				(start 304.402998 -311.099962)
				(mid 303.996598 -311.099962)
				(end 304.402998 -311.099962)
			)
		)
		(stroke
			(width 0)
			(type solid)
		)
		(fill yes)
		(layer "In6.Cu")
		(net "P5E_PEX2_STN5_TX_DP<94>")
	)
	(gr_poly
		(pts
			(arc
				(start 304.402998 -280.699464)
				(mid 303.996598 -280.699464)
				(end 304.402998 -280.699464)
			)
		)
		(stroke
			(width 0)
			(type solid)
		)
		(fill yes)
		(layer "In6.Cu")
		(net "P5E_PEX2_STN1_TX_DN<29>")
	)
	(gr_poly
		(pts
			(arc
				(start 304.402998 -279.749504)
				(mid 303.996598 -279.749504)
				(end 304.402998 -279.749504)
			)
		)
		(stroke
			(width 0)
			(type solid)
		)
		(fill yes)
		(layer "In6.Cu")
		(net "P5E_PEX2_STN1_TX_DP<29>")
	)
	(gr_poly
		(pts
			(arc
				(start 305.352704 -278.799798)
				(mid 304.946304 -278.799798)
				(end 305.352704 -278.799798)
			)
		)
		(stroke
			(width 0)
			(type solid)
		)
		(fill yes)
		(layer "In6.Cu")
		(net "P5E_PEX2_STN1_TX_DP<30>")
	)
	(gr_poly
		(pts
			(arc
				(start 305.352704 -277.849838)
				(mid 304.946304 -277.849838)
				(end 305.352704 -277.849838)
			)
		)
		(stroke
			(width 0)
			(type solid)
		)
		(fill yes)
		(layer "In6.Cu")
		(net "P5E_PEX2_STN1_TX_DN<30>")
	)
	(gr_poly
		(pts
			(arc
				(start 305.352958 -313.949842)
				(mid 304.946558 -313.949842)
				(end 305.352958 -313.949842)
			)
		)
		(stroke
			(width 0)
			(type solid)
		)
		(fill yes)
		(layer "In6.Cu")
		(net "P5E_PEX2_STN5_TX_DN<95>")
	)
	(gr_poly
		(pts
			(arc
				(start 305.352958 -312.999882)
				(mid 304.946558 -312.999882)
				(end 305.352958 -312.999882)
			)
		)
		(stroke
			(width 0)
			(type solid)
		)
		(fill yes)
		(layer "In6.Cu")
		(net "P5E_PEX2_STN5_TX_DP<95>")
	)
	(gr_poly
		(pts
			(arc
				(start 306.302918 -316.799722)
				(mid 305.896518 -316.799722)
				(end 306.302918 -316.799722)
			)
		)
		(stroke
			(width 0)
			(type solid)
		)
		(fill yes)
		(layer "In6.Cu")
		(net "P5E_PEX2_STN4_RX_DN<79>")
	)
	(gr_poly
		(pts
			(arc
				(start 306.302918 -315.849762)
				(mid 305.896518 -315.849762)
				(end 306.302918 -315.849762)
			)
		)
		(stroke
			(width 0)
			(type solid)
		)
		(fill yes)
		(layer "In6.Cu")
		(net "P5E_PEX2_STN4_RX_DP<79>")
	)
	(gr_poly
		(pts
			(arc
				(start 306.302918 -312.049922)
				(mid 305.896518 -312.049922)
				(end 306.302918 -312.049922)
			)
		)
		(stroke
			(width 0)
			(type solid)
		)
		(fill yes)
		(layer "In6.Cu")
		(net "P5E_PEX2_STN4_TX_DN<79>")
	)
	(gr_poly
		(pts
			(arc
				(start 306.302918 -311.099962)
				(mid 305.896518 -311.099962)
				(end 306.302918 -311.099962)
			)
		)
		(stroke
			(width 0)
			(type solid)
		)
		(fill yes)
		(layer "In6.Cu")
		(net "P5E_PEX2_STN4_TX_DP<79>")
	)
	(gr_poly
		(pts
			(arc
				(start 306.302918 -280.699464)
				(mid 305.896518 -280.699464)
				(end 306.302918 -280.699464)
			)
		)
		(stroke
			(width 0)
			(type solid)
		)
		(fill yes)
		(layer "In6.Cu")
		(net "P5E_PEX2_STN1_TX_DN<31>")
	)
	(gr_poly
		(pts
			(arc
				(start 306.302918 -279.749504)
				(mid 305.896518 -279.749504)
				(end 306.302918 -279.749504)
			)
		)
		(stroke
			(width 0)
			(type solid)
		)
		(fill yes)
		(layer "In6.Cu")
		(net "P5E_PEX2_STN1_TX_DP<31>")
	)
	(gr_poly
		(pts
			(arc
				(start 307.252878 -278.799798)
				(mid 306.846478 -278.799798)
				(end 307.252878 -278.799798)
			)
		)
		(stroke
			(width 0)
			(type solid)
		)
		(fill yes)
		(layer "In6.Cu")
		(net "P5E_PEX2_STN0_TX_DP<15>")
	)
	(gr_poly
		(pts
			(arc
				(start 307.252878 -277.849838)
				(mid 306.846478 -277.849838)
				(end 307.252878 -277.849838)
			)
		)
		(stroke
			(width 0)
			(type solid)
		)
		(fill yes)
		(layer "In6.Cu")
		(net "P5E_PEX2_STN0_TX_DN<15>")
	)
	(gr_poly
		(pts
			(arc
				(start 307.253132 -318.699896)
				(mid 306.846732 -318.699896)
				(end 307.253132 -318.699896)
			)
		)
		(stroke
			(width 0)
			(type solid)
		)
		(fill yes)
		(layer "In6.Cu")
		(net "P5E_PEX2_STN4_RX_DN<78>")
	)
	(gr_poly
		(pts
			(arc
				(start 307.253132 -317.749936)
				(mid 306.846732 -317.749936)
				(end 307.253132 -317.749936)
			)
		)
		(stroke
			(width 0)
			(type solid)
		)
		(fill yes)
		(layer "In6.Cu")
		(net "P5E_PEX2_STN4_RX_DP<78>")
	)
	(gr_poly
		(pts
			(arc
				(start 307.253132 -313.949842)
				(mid 306.846732 -313.949842)
				(end 307.253132 -313.949842)
			)
		)
		(stroke
			(width 0)
			(type solid)
		)
		(fill yes)
		(layer "In6.Cu")
		(net "P5E_PEX2_STN4_TX_DN<78>")
	)
	(gr_poly
		(pts
			(arc
				(start 307.253132 -312.999882)
				(mid 306.846732 -312.999882)
				(end 307.253132 -312.999882)
			)
		)
		(stroke
			(width 0)
			(type solid)
		)
		(fill yes)
		(layer "In6.Cu")
		(net "P5E_PEX2_STN4_TX_DP<78>")
	)
	(gr_poly
		(pts
			(arc
				(start 307.253132 -308.249828)
				(mid 306.846732 -308.249828)
				(end 307.253132 -308.249828)
			)
		)
		(stroke
			(width 0)
			(type solid)
		)
		(fill yes)
		(layer "In6.Cu")
		(net "P5E_PEX2_STN4_TX_DP<68>")
	)
	(gr_poly
		(pts
			(arc
				(start 307.253132 -306.349908)
				(mid 306.846732 -306.349908)
				(end 307.253132 -306.349908)
			)
		)
		(stroke
			(width 0)
			(type solid)
		)
		(fill yes)
		(layer "In6.Cu")
		(net "P5E_PEX2_STN4_TX_DP<66>")
	)
	(gr_poly
		(pts
			(arc
				(start 307.253132 -304.449734)
				(mid 306.846732 -304.449734)
				(end 307.253132 -304.449734)
			)
		)
		(stroke
			(width 0)
			(type solid)
		)
		(fill yes)
		(layer "In6.Cu")
		(net "P5E_PEX2_STN4_TX_DP<64>")
	)
	(gr_poly
		(pts
			(arc
				(start 307.253132 -287.349946)
				(mid 306.846732 -287.349946)
				(end 307.253132 -287.349946)
			)
		)
		(stroke
			(width 0)
			(type solid)
		)
		(fill yes)
		(layer "In6.Cu")
		(net "P5E_PEX2_STN0_TX_DP<1>")
	)
	(gr_poly
		(pts
			(arc
				(start 307.253132 -285.449772)
				(mid 306.846732 -285.449772)
				(end 307.253132 -285.449772)
			)
		)
		(stroke
			(width 0)
			(type solid)
		)
		(fill yes)
		(layer "In6.Cu")
		(net "P5E_PEX2_STN0_TX_DP<3>")
	)
	(gr_poly
		(pts
			(arc
				(start 307.253132 -283.549852)
				(mid 306.846732 -283.549852)
				(end 307.253132 -283.549852)
			)
		)
		(stroke
			(width 0)
			(type solid)
		)
		(fill yes)
		(layer "In6.Cu")
		(net "P5E_PEX2_STN0_TX_DP<5>")
	)
	(gr_poly
		(pts
			(arc
				(start 308.203092 -316.799722)
				(mid 307.796692 -316.799722)
				(end 308.203092 -316.799722)
			)
		)
		(stroke
			(width 0)
			(type solid)
		)
		(fill yes)
		(layer "In6.Cu")
		(net "P5E_PEX2_STN4_RX_DN<77>")
	)
	(gr_poly
		(pts
			(arc
				(start 308.203092 -315.849762)
				(mid 307.796692 -315.849762)
				(end 308.203092 -315.849762)
			)
		)
		(stroke
			(width 0)
			(type solid)
		)
		(fill yes)
		(layer "In6.Cu")
		(net "P5E_PEX2_STN4_RX_DP<77>")
	)
	(gr_poly
		(pts
			(arc
				(start 308.203092 -312.049922)
				(mid 307.796692 -312.049922)
				(end 308.203092 -312.049922)
			)
		)
		(stroke
			(width 0)
			(type solid)
		)
		(fill yes)
		(layer "In6.Cu")
		(net "P5E_PEX2_STN4_TX_DN<77>")
	)
	(gr_poly
		(pts
			(arc
				(start 308.203092 -311.099962)
				(mid 307.796692 -311.099962)
				(end 308.203092 -311.099962)
			)
		)
		(stroke
			(width 0)
			(type solid)
		)
		(fill yes)
		(layer "In6.Cu")
		(net "P5E_PEX2_STN4_TX_DP<77>")
	)
	(gr_poly
		(pts
			(arc
				(start 308.203092 -308.249828)
				(mid 307.796692 -308.249828)
				(end 308.203092 -308.249828)
			)
		)
		(stroke
			(width 0)
			(type solid)
		)
		(fill yes)
		(layer "In6.Cu")
		(net "P5E_PEX2_STN4_TX_DN<68>")
	)
	(gr_poly
		(pts
			(arc
				(start 308.203092 -306.349908)
				(mid 307.796692 -306.349908)
				(end 308.203092 -306.349908)
			)
		)
		(stroke
			(width 0)
			(type solid)
		)
		(fill yes)
		(layer "In6.Cu")
		(net "P5E_PEX2_STN4_TX_DN<66>")
	)
	(gr_poly
		(pts
			(arc
				(start 308.203092 -304.449734)
				(mid 307.796692 -304.449734)
				(end 308.203092 -304.449734)
			)
		)
		(stroke
			(width 0)
			(type solid)
		)
		(fill yes)
		(layer "In6.Cu")
		(net "P5E_PEX2_STN4_TX_DN<64>")
	)
	(gr_poly
		(pts
			(arc
				(start 308.203092 -287.349946)
				(mid 307.796692 -287.349946)
				(end 308.203092 -287.349946)
			)
		)
		(stroke
			(width 0)
			(type solid)
		)
		(fill yes)
		(layer "In6.Cu")
		(net "P5E_PEX2_STN0_TX_DN<1>")
	)
	(gr_poly
		(pts
			(arc
				(start 308.203092 -285.449772)
				(mid 307.796692 -285.449772)
				(end 308.203092 -285.449772)
			)
		)
		(stroke
			(width 0)
			(type solid)
		)
		(fill yes)
		(layer "In6.Cu")
		(net "P5E_PEX2_STN0_TX_DN<3>")
	)
	(gr_poly
		(pts
			(arc
				(start 308.203092 -283.549852)
				(mid 307.796692 -283.549852)
				(end 308.203092 -283.549852)
			)
		)
		(stroke
			(width 0)
			(type solid)
		)
		(fill yes)
		(layer "In6.Cu")
		(net "P5E_PEX2_STN0_TX_DN<5>")
	)
	(gr_poly
		(pts
			(arc
				(start 308.203092 -280.699464)
				(mid 307.796692 -280.699464)
				(end 308.203092 -280.699464)
			)
		)
		(stroke
			(width 0)
			(type solid)
		)
		(fill yes)
		(layer "In6.Cu")
		(net "P5E_PEX2_STN0_TX_DN<14>")
	)
	(gr_poly
		(pts
			(arc
				(start 308.203092 -279.749504)
				(mid 307.796692 -279.749504)
				(end 308.203092 -279.749504)
			)
		)
		(stroke
			(width 0)
			(type solid)
		)
		(fill yes)
		(layer "In6.Cu")
		(net "P5E_PEX2_STN0_TX_DP<14>")
	)
	(gr_poly
		(pts
			(arc
				(start 309.152798 -278.799798)
				(mid 308.746398 -278.799798)
				(end 309.152798 -278.799798)
			)
		)
		(stroke
			(width 0)
			(type solid)
		)
		(fill yes)
		(layer "In6.Cu")
		(net "P5E_PEX2_STN0_TX_DP<13>")
	)
	(gr_poly
		(pts
			(arc
				(start 309.152798 -277.849838)
				(mid 308.746398 -277.849838)
				(end 309.152798 -277.849838)
			)
		)
		(stroke
			(width 0)
			(type solid)
		)
		(fill yes)
		(layer "In6.Cu")
		(net "P5E_PEX2_STN0_TX_DN<13>")
	)
	(gr_poly
		(pts
			(arc
				(start 309.153052 -318.699896)
				(mid 308.746652 -318.699896)
				(end 309.153052 -318.699896)
			)
		)
		(stroke
			(width 0)
			(type solid)
		)
		(fill yes)
		(layer "In6.Cu")
		(net "P5E_PEX2_STN4_RX_DN<76>")
	)
	(gr_poly
		(pts
			(arc
				(start 309.153052 -317.749936)
				(mid 308.746652 -317.749936)
				(end 309.153052 -317.749936)
			)
		)
		(stroke
			(width 0)
			(type solid)
		)
		(fill yes)
		(layer "In6.Cu")
		(net "P5E_PEX2_STN4_RX_DP<76>")
	)
	(gr_poly
		(pts
			(arc
				(start 309.153052 -313.949842)
				(mid 308.746652 -313.949842)
				(end 309.153052 -313.949842)
			)
		)
		(stroke
			(width 0)
			(type solid)
		)
		(fill yes)
		(layer "In6.Cu")
		(net "P5E_PEX2_STN4_TX_DN<76>")
	)
	(gr_poly
		(pts
			(arc
				(start 309.153052 -312.999882)
				(mid 308.746652 -312.999882)
				(end 309.153052 -312.999882)
			)
		)
		(stroke
			(width 0)
			(type solid)
		)
		(fill yes)
		(layer "In6.Cu")
		(net "P5E_PEX2_STN4_TX_DP<76>")
	)
	(gr_poly
		(pts
			(arc
				(start 309.153052 -309.199788)
				(mid 308.746652 -309.199788)
				(end 309.153052 -309.199788)
			)
		)
		(stroke
			(width 0)
			(type solid)
		)
		(fill yes)
		(layer "In6.Cu")
		(net "P5E_PEX2_STN4_TX_DP<69>")
	)
	(gr_poly
		(pts
			(arc
				(start 309.153052 -307.299868)
				(mid 308.746652 -307.299868)
				(end 309.153052 -307.299868)
			)
		)
		(stroke
			(width 0)
			(type solid)
		)
		(fill yes)
		(layer "In6.Cu")
		(net "P5E_PEX2_STN4_TX_DP<67>")
	)
	(gr_poly
		(pts
			(arc
				(start 309.153052 -305.399948)
				(mid 308.746652 -305.399948)
				(end 309.153052 -305.399948)
			)
		)
		(stroke
			(width 0)
			(type solid)
		)
		(fill yes)
		(layer "In6.Cu")
		(net "P5E_PEX2_STN4_TX_DP<65>")
	)
	(gr_poly
		(pts
			(arc
				(start 309.153052 -288.299906)
				(mid 308.746652 -288.299906)
				(end 309.153052 -288.299906)
			)
		)
		(stroke
			(width 0)
			(type solid)
		)
		(fill yes)
		(layer "In6.Cu")
		(net "P5E_PEX2_STN0_TX_DP<0>")
	)
	(gr_poly
		(pts
			(arc
				(start 309.153052 -286.399986)
				(mid 308.746652 -286.399986)
				(end 309.153052 -286.399986)
			)
		)
		(stroke
			(width 0)
			(type solid)
		)
		(fill yes)
		(layer "In6.Cu")
		(net "P5E_PEX2_STN0_TX_DP<2>")
	)
	(gr_poly
		(pts
			(arc
				(start 309.153052 -284.499812)
				(mid 308.746652 -284.499812)
				(end 309.153052 -284.499812)
			)
		)
		(stroke
			(width 0)
			(type solid)
		)
		(fill yes)
		(layer "In6.Cu")
		(net "P5E_PEX2_STN0_TX_DP<4>")
	)
	(gr_poly
		(pts
			(arc
				(start 309.153052 -282.599892)
				(mid 308.746652 -282.599892)
				(end 309.153052 -282.599892)
			)
		)
		(stroke
			(width 0)
			(type solid)
		)
		(fill yes)
		(layer "In6.Cu")
		(net "P5E_PEX2_STN0_TX_DP<6>")
	)
	(gr_poly
		(pts
			(arc
				(start 310.103012 -316.799722)
				(mid 309.696612 -316.799722)
				(end 310.103012 -316.799722)
			)
		)
		(stroke
			(width 0)
			(type solid)
		)
		(fill yes)
		(layer "In6.Cu")
		(net "P5E_PEX2_STN4_RX_DN<75>")
	)
	(gr_poly
		(pts
			(arc
				(start 310.103012 -315.849762)
				(mid 309.696612 -315.849762)
				(end 310.103012 -315.849762)
			)
		)
		(stroke
			(width 0)
			(type solid)
		)
		(fill yes)
		(layer "In6.Cu")
		(net "P5E_PEX2_STN4_RX_DP<75>")
	)
	(gr_poly
		(pts
			(arc
				(start 310.103012 -312.049922)
				(mid 309.696612 -312.049922)
				(end 310.103012 -312.049922)
			)
		)
		(stroke
			(width 0)
			(type solid)
		)
		(fill yes)
		(layer "In6.Cu")
		(net "P5E_PEX2_STN4_TX_DN<75>")
	)
	(gr_poly
		(pts
			(arc
				(start 310.103012 -311.099962)
				(mid 309.696612 -311.099962)
				(end 310.103012 -311.099962)
			)
		)
		(stroke
			(width 0)
			(type solid)
		)
		(fill yes)
		(layer "In6.Cu")
		(net "P5E_PEX2_STN4_TX_DP<75>")
	)
	(gr_poly
		(pts
			(arc
				(start 310.103012 -309.199788)
				(mid 309.696612 -309.199788)
				(end 310.103012 -309.199788)
			)
		)
		(stroke
			(width 0)
			(type solid)
		)
		(fill yes)
		(layer "In6.Cu")
		(net "P5E_PEX2_STN4_TX_DN<69>")
	)
	(gr_poly
		(pts
			(arc
				(start 310.103012 -307.299868)
				(mid 309.696612 -307.299868)
				(end 310.103012 -307.299868)
			)
		)
		(stroke
			(width 0)
			(type solid)
		)
		(fill yes)
		(layer "In6.Cu")
		(net "P5E_PEX2_STN4_TX_DN<67>")
	)
	(gr_poly
		(pts
			(arc
				(start 310.103012 -305.399948)
				(mid 309.696612 -305.399948)
				(end 310.103012 -305.399948)
			)
		)
		(stroke
			(width 0)
			(type solid)
		)
		(fill yes)
		(layer "In6.Cu")
		(net "P5E_PEX2_STN4_TX_DN<65>")
	)
	(gr_poly
		(pts
			(arc
				(start 310.103012 -288.299906)
				(mid 309.696612 -288.299906)
				(end 310.103012 -288.299906)
			)
		)
		(stroke
			(width 0)
			(type solid)
		)
		(fill yes)
		(layer "In6.Cu")
		(net "P5E_PEX2_STN0_TX_DN<0>")
	)
	(gr_poly
		(pts
			(arc
				(start 310.103012 -286.399986)
				(mid 309.696612 -286.399986)
				(end 310.103012 -286.399986)
			)
		)
		(stroke
			(width 0)
			(type solid)
		)
		(fill yes)
		(layer "In6.Cu")
		(net "P5E_PEX2_STN0_TX_DN<2>")
	)
	(gr_poly
		(pts
			(arc
				(start 310.103012 -284.499812)
				(mid 309.696612 -284.499812)
				(end 310.103012 -284.499812)
			)
		)
		(stroke
			(width 0)
			(type solid)
		)
		(fill yes)
		(layer "In6.Cu")
		(net "P5E_PEX2_STN0_TX_DN<4>")
	)
	(gr_poly
		(pts
			(arc
				(start 310.103012 -282.599892)
				(mid 309.696612 -282.599892)
				(end 310.103012 -282.599892)
			)
		)
		(stroke
			(width 0)
			(type solid)
		)
		(fill yes)
		(layer "In6.Cu")
		(net "P5E_PEX2_STN0_TX_DN<6>")
	)
	(gr_poly
		(pts
			(arc
				(start 310.103012 -280.699464)
				(mid 309.696612 -280.699464)
				(end 310.103012 -280.699464)
			)
		)
		(stroke
			(width 0)
			(type solid)
		)
		(fill yes)
		(layer "In6.Cu")
		(net "P5E_PEX2_STN0_TX_DN<12>")
	)
	(gr_poly
		(pts
			(arc
				(start 310.103012 -279.749504)
				(mid 309.696612 -279.749504)
				(end 310.103012 -279.749504)
			)
		)
		(stroke
			(width 0)
			(type solid)
		)
		(fill yes)
		(layer "In6.Cu")
		(net "P5E_PEX2_STN0_TX_DP<12>")
	)
	(gr_poly
		(pts
			(arc
				(start 311.052718 -278.799798)
				(mid 310.646318 -278.799798)
				(end 311.052718 -278.799798)
			)
		)
		(stroke
			(width 0)
			(type solid)
		)
		(fill yes)
		(layer "In6.Cu")
		(net "P5E_PEX2_STN0_TX_DP<11>")
	)
	(gr_poly
		(pts
			(arc
				(start 311.052718 -277.849838)
				(mid 310.646318 -277.849838)
				(end 311.052718 -277.849838)
			)
		)
		(stroke
			(width 0)
			(type solid)
		)
		(fill yes)
		(layer "In6.Cu")
		(net "P5E_PEX2_STN0_TX_DN<11>")
	)
	(gr_poly
		(pts
			(arc
				(start 311.052972 -318.699896)
				(mid 310.646572 -318.699896)
				(end 311.052972 -318.699896)
			)
		)
		(stroke
			(width 0)
			(type solid)
		)
		(fill yes)
		(layer "In6.Cu")
		(net "P5E_PEX2_STN4_RX_DN<74>")
	)
	(gr_poly
		(pts
			(arc
				(start 311.052972 -317.749936)
				(mid 310.646572 -317.749936)
				(end 311.052972 -317.749936)
			)
		)
		(stroke
			(width 0)
			(type solid)
		)
		(fill yes)
		(layer "In6.Cu")
		(net "P5E_PEX2_STN4_RX_DP<74>")
	)
	(gr_poly
		(pts
			(arc
				(start 311.052972 -313.949842)
				(mid 310.646572 -313.949842)
				(end 311.052972 -313.949842)
			)
		)
		(stroke
			(width 0)
			(type solid)
		)
		(fill yes)
		(layer "In6.Cu")
		(net "P5E_PEX2_STN4_TX_DN<74>")
	)
	(gr_poly
		(pts
			(arc
				(start 311.052972 -312.999882)
				(mid 310.646572 -312.999882)
				(end 311.052972 -312.999882)
			)
		)
		(stroke
			(width 0)
			(type solid)
		)
		(fill yes)
		(layer "In6.Cu")
		(net "P5E_PEX2_STN4_TX_DP<74>")
	)
	(gr_poly
		(pts
			(arc
				(start 312.002932 -316.799722)
				(mid 311.596532 -316.799722)
				(end 312.002932 -316.799722)
			)
		)
		(stroke
			(width 0)
			(type solid)
		)
		(fill yes)
		(layer "In6.Cu")
		(net "P5E_PEX2_STN4_RX_DN<73>")
	)
	(gr_poly
		(pts
			(arc
				(start 312.002932 -315.849762)
				(mid 311.596532 -315.849762)
				(end 312.002932 -315.849762)
			)
		)
		(stroke
			(width 0)
			(type solid)
		)
		(fill yes)
		(layer "In6.Cu")
		(net "P5E_PEX2_STN4_RX_DP<73>")
	)
	(gr_poly
		(pts
			(arc
				(start 312.002932 -312.049922)
				(mid 311.596532 -312.049922)
				(end 312.002932 -312.049922)
			)
		)
		(stroke
			(width 0)
			(type solid)
		)
		(fill yes)
		(layer "In6.Cu")
		(net "P5E_PEX2_STN4_TX_DN<73>")
	)
	(gr_poly
		(pts
			(arc
				(start 312.002932 -311.099962)
				(mid 311.596532 -311.099962)
				(end 312.002932 -311.099962)
			)
		)
		(stroke
			(width 0)
			(type solid)
		)
		(fill yes)
		(layer "In6.Cu")
		(net "P5E_PEX2_STN4_TX_DP<73>")
	)
	(gr_poly
		(pts
			(arc
				(start 312.002932 -309.199788)
				(mid 311.596532 -309.199788)
				(end 312.002932 -309.199788)
			)
		)
		(stroke
			(width 0)
			(type solid)
		)
		(fill yes)
		(layer "In6.Cu")
		(net "P5E_PEX2_STN4_RX_DP<69>")
	)
	(gr_poly
		(pts
			(arc
				(start 312.002932 -307.299868)
				(mid 311.596532 -307.299868)
				(end 312.002932 -307.299868)
			)
		)
		(stroke
			(width 0)
			(type solid)
		)
		(fill yes)
		(layer "In6.Cu")
		(net "P5E_PEX2_STN4_RX_DP<67>")
	)
	(gr_poly
		(pts
			(arc
				(start 312.002932 -305.399948)
				(mid 311.596532 -305.399948)
				(end 312.002932 -305.399948)
			)
		)
		(stroke
			(width 0)
			(type solid)
		)
		(fill yes)
		(layer "In6.Cu")
		(net "P5E_PEX2_STN4_RX_DP<65>")
	)
	(gr_poly
		(pts
			(arc
				(start 312.002932 -280.699718)
				(mid 311.596532 -280.699718)
				(end 312.002932 -280.699718)
			)
		)
		(stroke
			(width 0)
			(type solid)
		)
		(fill yes)
		(layer "In6.Cu")
		(net "P5E_PEX2_STN0_TX_DP<10>")
	)
	(gr_poly
		(pts
			(arc
				(start 312.002932 -279.749758)
				(mid 311.596532 -279.749758)
				(end 312.002932 -279.749758)
			)
		)
		(stroke
			(width 0)
			(type solid)
		)
		(fill yes)
		(layer "In6.Cu")
		(net "P5E_PEX2_STN0_TX_DN<10>")
	)
	(gr_poly
		(pts
			(arc
				(start 312.952892 -318.699896)
				(mid 312.546492 -318.699896)
				(end 312.952892 -318.699896)
			)
		)
		(stroke
			(width 0)
			(type solid)
		)
		(fill yes)
		(layer "In6.Cu")
		(net "P5E_PEX2_STN4_RX_DN<72>")
	)
	(gr_poly
		(pts
			(arc
				(start 312.952892 -317.749936)
				(mid 312.546492 -317.749936)
				(end 312.952892 -317.749936)
			)
		)
		(stroke
			(width 0)
			(type solid)
		)
		(fill yes)
		(layer "In6.Cu")
		(net "P5E_PEX2_STN4_RX_DP<72>")
	)
	(gr_poly
		(pts
			(arc
				(start 312.952892 -313.949842)
				(mid 312.546492 -313.949842)
				(end 312.952892 -313.949842)
			)
		)
		(stroke
			(width 0)
			(type solid)
		)
		(fill yes)
		(layer "In6.Cu")
		(net "P5E_PEX2_STN4_TX_DN<72>")
	)
	(gr_poly
		(pts
			(arc
				(start 312.952892 -312.999882)
				(mid 312.546492 -312.999882)
				(end 312.952892 -312.999882)
			)
		)
		(stroke
			(width 0)
			(type solid)
		)
		(fill yes)
		(layer "In6.Cu")
		(net "P5E_PEX2_STN4_TX_DP<72>")
	)
	(gr_poly
		(pts
			(arc
				(start 312.952892 -309.199788)
				(mid 312.546492 -309.199788)
				(end 312.952892 -309.199788)
			)
		)
		(stroke
			(width 0)
			(type solid)
		)
		(fill yes)
		(layer "In6.Cu")
		(net "P5E_PEX2_STN4_RX_DN<69>")
	)
	(gr_poly
		(pts
			(arc
				(start 312.952892 -307.299868)
				(mid 312.546492 -307.299868)
				(end 312.952892 -307.299868)
			)
		)
		(stroke
			(width 0)
			(type solid)
		)
		(fill yes)
		(layer "In6.Cu")
		(net "P5E_PEX2_STN4_RX_DN<67>")
	)
	(gr_poly
		(pts
			(arc
				(start 312.952892 -305.399948)
				(mid 312.546492 -305.399948)
				(end 312.952892 -305.399948)
			)
		)
		(stroke
			(width 0)
			(type solid)
		)
		(fill yes)
		(layer "In6.Cu")
		(net "P5E_PEX2_STN4_RX_DN<65>")
	)
	(gr_poly
		(pts
			(arc
				(start 312.952892 -278.799798)
				(mid 312.546492 -278.799798)
				(end 312.952892 -278.799798)
			)
		)
		(stroke
			(width 0)
			(type solid)
		)
		(fill yes)
		(layer "In6.Cu")
		(net "P5E_PEX2_STN0_TX_DP<9>")
	)
	(gr_poly
		(pts
			(arc
				(start 312.952892 -277.849838)
				(mid 312.546492 -277.849838)
				(end 312.952892 -277.849838)
			)
		)
		(stroke
			(width 0)
			(type solid)
		)
		(fill yes)
		(layer "In6.Cu")
		(net "P5E_PEX2_STN0_TX_DN<9>")
	)
	(gr_poly
		(pts
			(arc
				(start 313.903106 -316.799722)
				(mid 313.496706 -316.799722)
				(end 313.903106 -316.799722)
			)
		)
		(stroke
			(width 0)
			(type solid)
		)
		(fill yes)
		(layer "In6.Cu")
		(net "P5E_PEX2_STN4_RX_DP<71>")
	)
	(gr_poly
		(pts
			(arc
				(start 313.903106 -314.899802)
				(mid 313.496706 -314.899802)
				(end 313.903106 -314.899802)
			)
		)
		(stroke
			(width 0)
			(type solid)
		)
		(fill yes)
		(layer "In6.Cu")
		(net "P5E_PEX2_STN4_TX_DP<71>")
	)
	(gr_poly
		(pts
			(arc
				(start 313.903106 -312.049922)
				(mid 313.496706 -312.049922)
				(end 313.903106 -312.049922)
			)
		)
		(stroke
			(width 0)
			(type solid)
		)
		(fill yes)
		(layer "In6.Cu")
		(net "P5E_PEX2_STN4_TX_DP<70>")
	)
	(gr_poly
		(pts
			(arc
				(start 313.903106 -310.149748)
				(mid 313.496706 -310.149748)
				(end 313.903106 -310.149748)
			)
		)
		(stroke
			(width 0)
			(type solid)
		)
		(fill yes)
		(layer "In6.Cu")
		(net "P5E_PEX2_STN4_RX_DP<70>")
	)
	(gr_poly
		(pts
			(arc
				(start 313.903106 -308.249828)
				(mid 313.496706 -308.249828)
				(end 313.903106 -308.249828)
			)
		)
		(stroke
			(width 0)
			(type solid)
		)
		(fill yes)
		(layer "In6.Cu")
		(net "P5E_PEX2_STN4_RX_DP<68>")
	)
	(gr_poly
		(pts
			(arc
				(start 313.903106 -306.349908)
				(mid 313.496706 -306.349908)
				(end 313.903106 -306.349908)
			)
		)
		(stroke
			(width 0)
			(type solid)
		)
		(fill yes)
		(layer "In6.Cu")
		(net "P5E_PEX2_STN4_RX_DP<66>")
	)
	(gr_poly
		(pts
			(arc
				(start 313.903106 -304.449734)
				(mid 313.496706 -304.449734)
				(end 313.903106 -304.449734)
			)
		)
		(stroke
			(width 0)
			(type solid)
		)
		(fill yes)
		(layer "In6.Cu")
		(net "P5E_PEX2_STN4_RX_DP<64>")
	)
	(gr_poly
		(pts
			(arc
				(start 313.903106 -279.749758)
				(mid 313.496706 -279.749758)
				(end 313.903106 -279.749758)
			)
		)
		(stroke
			(width 0)
			(type solid)
		)
		(fill yes)
		(layer "In6.Cu")
		(net "P5E_PEX2_STN0_TX_DP<7>")
	)
	(gr_poly
		(pts
			(arc
				(start 313.903106 -276.899878)
				(mid 313.496706 -276.899878)
				(end 313.903106 -276.899878)
			)
		)
		(stroke
			(width 0)
			(type solid)
		)
		(fill yes)
		(layer "In6.Cu")
		(net "P5E_PEX2_STN0_TX_DP<8>")
	)
	(gr_poly
		(pts
			(arc
				(start 314.853066 -316.799722)
				(mid 314.446666 -316.799722)
				(end 314.853066 -316.799722)
			)
		)
		(stroke
			(width 0)
			(type solid)
		)
		(fill yes)
		(layer "In6.Cu")
		(net "P5E_PEX2_STN4_RX_DN<71>")
	)
	(gr_poly
		(pts
			(arc
				(start 314.853066 -314.899802)
				(mid 314.446666 -314.899802)
				(end 314.853066 -314.899802)
			)
		)
		(stroke
			(width 0)
			(type solid)
		)
		(fill yes)
		(layer "In6.Cu")
		(net "P5E_PEX2_STN4_TX_DN<71>")
	)
	(gr_poly
		(pts
			(arc
				(start 314.853066 -312.049922)
				(mid 314.446666 -312.049922)
				(end 314.853066 -312.049922)
			)
		)
		(stroke
			(width 0)
			(type solid)
		)
		(fill yes)
		(layer "In6.Cu")
		(net "P5E_PEX2_STN4_TX_DN<70>")
	)
	(gr_poly
		(pts
			(arc
				(start 314.853066 -310.149748)
				(mid 314.446666 -310.149748)
				(end 314.853066 -310.149748)
			)
		)
		(stroke
			(width 0)
			(type solid)
		)
		(fill yes)
		(layer "In6.Cu")
		(net "P5E_PEX2_STN4_RX_DN<70>")
	)
	(gr_poly
		(pts
			(arc
				(start 314.853066 -308.249828)
				(mid 314.446666 -308.249828)
				(end 314.853066 -308.249828)
			)
		)
		(stroke
			(width 0)
			(type solid)
		)
		(fill yes)
		(layer "In6.Cu")
		(net "P5E_PEX2_STN4_RX_DN<68>")
	)
	(gr_poly
		(pts
			(arc
				(start 314.853066 -306.349908)
				(mid 314.446666 -306.349908)
				(end 314.853066 -306.349908)
			)
		)
		(stroke
			(width 0)
			(type solid)
		)
		(fill yes)
		(layer "In6.Cu")
		(net "P5E_PEX2_STN4_RX_DN<66>")
	)
	(gr_poly
		(pts
			(arc
				(start 314.853066 -304.449734)
				(mid 314.446666 -304.449734)
				(end 314.853066 -304.449734)
			)
		)
		(stroke
			(width 0)
			(type solid)
		)
		(fill yes)
		(layer "In6.Cu")
		(net "P5E_PEX2_STN4_RX_DN<64>")
	)
	(gr_poly
		(pts
			(arc
				(start 314.853066 -279.749758)
				(mid 314.446666 -279.749758)
				(end 314.853066 -279.749758)
			)
		)
		(stroke
			(width 0)
			(type solid)
		)
		(fill yes)
		(layer "In6.Cu")
		(net "P5E_PEX2_STN0_TX_DN<7>")
	)
	(gr_poly
		(pts
			(arc
				(start 314.853066 -276.899878)
				(mid 314.446666 -276.899878)
				(end 314.853066 -276.899878)
			)
		)
		(stroke
			(width 0)
			(type solid)
		)
		(fill yes)
		(layer "In6.Cu")
		(net "P5E_PEX2_STN0_TX_DN<8>")
	)
	(gr_poly
		(pts
			(arc
				(start 385.353052 -316.799722)
				(mid 384.946652 -316.799722)
				(end 385.353052 -316.799722)
			)
		)
		(stroke
			(width 0)
			(type solid)
		)
		(fill yes)
		(layer "In6.Cu")
		(net "P5E_PEX3_STN7_RX_DN<122>")
	)
	(gr_poly
		(pts
			(arc
				(start 385.353052 -314.899802)
				(mid 384.946652 -314.899802)
				(end 385.353052 -314.899802)
			)
		)
		(stroke
			(width 0)
			(type solid)
		)
		(fill yes)
		(layer "In6.Cu")
		(net "P5E_PEX3_STN7_TX_DN<122>")
	)
	(gr_poly
		(pts
			(arc
				(start 385.353052 -312.049922)
				(mid 384.946652 -312.049922)
				(end 385.353052 -312.049922)
			)
		)
		(stroke
			(width 0)
			(type solid)
		)
		(fill yes)
		(layer "In6.Cu")
		(net "P5E_PEX3_STN7_TX_DN<121>")
	)
	(gr_poly
		(pts
			(arc
				(start 385.353052 -310.149748)
				(mid 384.946652 -310.149748)
				(end 385.353052 -310.149748)
			)
		)
		(stroke
			(width 0)
			(type solid)
		)
		(fill yes)
		(layer "In6.Cu")
		(net "P5E_PEX3_STN7_RX_DN<121>")
	)
	(gr_poly
		(pts
			(arc
				(start 385.353052 -308.249828)
				(mid 384.946652 -308.249828)
				(end 385.353052 -308.249828)
			)
		)
		(stroke
			(width 0)
			(type solid)
		)
		(fill yes)
		(layer "In6.Cu")
		(net "P5E_PEX3_STN7_RX_DN<119>")
	)
	(gr_poly
		(pts
			(arc
				(start 385.353052 -306.349908)
				(mid 384.946652 -306.349908)
				(end 385.353052 -306.349908)
			)
		)
		(stroke
			(width 0)
			(type solid)
		)
		(fill yes)
		(layer "In6.Cu")
		(net "P5E_PEX3_STN7_RX_DN<117>")
	)
	(gr_poly
		(pts
			(arc
				(start 385.353052 -304.449734)
				(mid 384.946652 -304.449734)
				(end 385.353052 -304.449734)
			)
		)
		(stroke
			(width 0)
			(type solid)
		)
		(fill yes)
		(layer "In6.Cu")
		(net "P5E_PEX3_STN7_RX_DN<115>")
	)
	(gr_poly
		(pts
			(arc
				(start 385.353052 -302.549814)
				(mid 384.946652 -302.549814)
				(end 385.353052 -302.549814)
			)
		)
		(stroke
			(width 0)
			(type solid)
		)
		(fill yes)
		(layer "In6.Cu")
		(net "P5E_PEX3_STN7_RX_DN<113>")
	)
	(gr_poly
		(pts
			(arc
				(start 386.303012 -316.799722)
				(mid 385.896612 -316.799722)
				(end 386.303012 -316.799722)
			)
		)
		(stroke
			(width 0)
			(type solid)
		)
		(fill yes)
		(layer "In6.Cu")
		(net "P5E_PEX3_STN7_RX_DP<122>")
	)
	(gr_poly
		(pts
			(arc
				(start 386.303012 -314.899802)
				(mid 385.896612 -314.899802)
				(end 386.303012 -314.899802)
			)
		)
		(stroke
			(width 0)
			(type solid)
		)
		(fill yes)
		(layer "In6.Cu")
		(net "P5E_PEX3_STN7_TX_DP<122>")
	)
	(gr_poly
		(pts
			(arc
				(start 386.303012 -312.049922)
				(mid 385.896612 -312.049922)
				(end 386.303012 -312.049922)
			)
		)
		(stroke
			(width 0)
			(type solid)
		)
		(fill yes)
		(layer "In6.Cu")
		(net "P5E_PEX3_STN7_TX_DP<121>")
	)
	(gr_poly
		(pts
			(arc
				(start 386.303012 -310.149748)
				(mid 385.896612 -310.149748)
				(end 386.303012 -310.149748)
			)
		)
		(stroke
			(width 0)
			(type solid)
		)
		(fill yes)
		(layer "In6.Cu")
		(net "P5E_PEX3_STN7_RX_DP<121>")
	)
	(gr_poly
		(pts
			(arc
				(start 386.303012 -308.249828)
				(mid 385.896612 -308.249828)
				(end 386.303012 -308.249828)
			)
		)
		(stroke
			(width 0)
			(type solid)
		)
		(fill yes)
		(layer "In6.Cu")
		(net "P5E_PEX3_STN7_RX_DP<119>")
	)
	(gr_poly
		(pts
			(arc
				(start 386.303012 -306.349908)
				(mid 385.896612 -306.349908)
				(end 386.303012 -306.349908)
			)
		)
		(stroke
			(width 0)
			(type solid)
		)
		(fill yes)
		(layer "In6.Cu")
		(net "P5E_PEX3_STN7_RX_DP<117>")
	)
	(gr_poly
		(pts
			(arc
				(start 386.303012 -304.449734)
				(mid 385.896612 -304.449734)
				(end 386.303012 -304.449734)
			)
		)
		(stroke
			(width 0)
			(type solid)
		)
		(fill yes)
		(layer "In6.Cu")
		(net "P5E_PEX3_STN7_RX_DP<115>")
	)
	(gr_poly
		(pts
			(arc
				(start 386.303012 -302.549814)
				(mid 385.896612 -302.549814)
				(end 386.303012 -302.549814)
			)
		)
		(stroke
			(width 0)
			(type solid)
		)
		(fill yes)
		(layer "In6.Cu")
		(net "P5E_PEX3_STN7_RX_DP<113>")
	)
	(gr_poly
		(pts
			(arc
				(start 387.253226 -318.699896)
				(mid 386.846826 -318.699896)
				(end 387.253226 -318.699896)
			)
		)
		(stroke
			(width 0)
			(type solid)
		)
		(fill yes)
		(layer "In6.Cu")
		(net "P5E_PEX3_STN7_RX_DN<123>")
	)
	(gr_poly
		(pts
			(arc
				(start 387.253226 -317.749936)
				(mid 386.846826 -317.749936)
				(end 387.253226 -317.749936)
			)
		)
		(stroke
			(width 0)
			(type solid)
		)
		(fill yes)
		(layer "In6.Cu")
		(net "P5E_PEX3_STN7_RX_DP<123>")
	)
	(gr_poly
		(pts
			(arc
				(start 387.253226 -313.949842)
				(mid 386.846826 -313.949842)
				(end 387.253226 -313.949842)
			)
		)
		(stroke
			(width 0)
			(type solid)
		)
		(fill yes)
		(layer "In6.Cu")
		(net "P5E_PEX3_STN7_TX_DN<123>")
	)
	(gr_poly
		(pts
			(arc
				(start 387.253226 -312.999882)
				(mid 386.846826 -312.999882)
				(end 387.253226 -312.999882)
			)
		)
		(stroke
			(width 0)
			(type solid)
		)
		(fill yes)
		(layer "In6.Cu")
		(net "P5E_PEX3_STN7_TX_DP<123>")
	)
	(gr_poly
		(pts
			(arc
				(start 387.253226 -309.199788)
				(mid 386.846826 -309.199788)
				(end 387.253226 -309.199788)
			)
		)
		(stroke
			(width 0)
			(type solid)
		)
		(fill yes)
		(layer "In6.Cu")
		(net "P5E_PEX3_STN7_RX_DN<120>")
	)
	(gr_poly
		(pts
			(arc
				(start 387.253226 -307.299868)
				(mid 386.846826 -307.299868)
				(end 387.253226 -307.299868)
			)
		)
		(stroke
			(width 0)
			(type solid)
		)
		(fill yes)
		(layer "In6.Cu")
		(net "P5E_PEX3_STN7_RX_DN<118>")
	)
	(gr_poly
		(pts
			(arc
				(start 387.253226 -305.399948)
				(mid 386.846826 -305.399948)
				(end 387.253226 -305.399948)
			)
		)
		(stroke
			(width 0)
			(type solid)
		)
		(fill yes)
		(layer "In6.Cu")
		(net "P5E_PEX3_STN7_RX_DN<116>")
	)
	(gr_poly
		(pts
			(arc
				(start 387.253226 -303.499774)
				(mid 386.846826 -303.499774)
				(end 387.253226 -303.499774)
			)
		)
		(stroke
			(width 0)
			(type solid)
		)
		(fill yes)
		(layer "In6.Cu")
		(net "P5E_PEX3_STN7_RX_DN<114>")
	)
	(gr_poly
		(pts
			(arc
				(start 387.253226 -301.599854)
				(mid 386.846826 -301.599854)
				(end 387.253226 -301.599854)
			)
		)
		(stroke
			(width 0)
			(type solid)
		)
		(fill yes)
		(layer "In6.Cu")
		(net "P5E_PEX3_STN7_RX_DN<112>")
	)
	(gr_poly
		(pts
			(arc
				(start 388.203186 -316.799722)
				(mid 387.796786 -316.799722)
				(end 388.203186 -316.799722)
			)
		)
		(stroke
			(width 0)
			(type solid)
		)
		(fill yes)
		(layer "In6.Cu")
		(net "P5E_PEX3_STN7_RX_DN<124>")
	)
	(gr_poly
		(pts
			(arc
				(start 388.203186 -315.849762)
				(mid 387.796786 -315.849762)
				(end 388.203186 -315.849762)
			)
		)
		(stroke
			(width 0)
			(type solid)
		)
		(fill yes)
		(layer "In6.Cu")
		(net "P5E_PEX3_STN7_RX_DP<124>")
	)
	(gr_poly
		(pts
			(arc
				(start 388.203186 -312.049922)
				(mid 387.796786 -312.049922)
				(end 388.203186 -312.049922)
			)
		)
		(stroke
			(width 0)
			(type solid)
		)
		(fill yes)
		(layer "In6.Cu")
		(net "P5E_PEX3_STN7_TX_DN<124>")
	)
	(gr_poly
		(pts
			(arc
				(start 388.203186 -311.099962)
				(mid 387.796786 -311.099962)
				(end 388.203186 -311.099962)
			)
		)
		(stroke
			(width 0)
			(type solid)
		)
		(fill yes)
		(layer "In6.Cu")
		(net "P5E_PEX3_STN7_TX_DP<124>")
	)
	(gr_poly
		(pts
			(arc
				(start 388.203186 -309.199788)
				(mid 387.796786 -309.199788)
				(end 388.203186 -309.199788)
			)
		)
		(stroke
			(width 0)
			(type solid)
		)
		(fill yes)
		(layer "In6.Cu")
		(net "P5E_PEX3_STN7_RX_DP<120>")
	)
	(gr_poly
		(pts
			(arc
				(start 388.203186 -307.299868)
				(mid 387.796786 -307.299868)
				(end 388.203186 -307.299868)
			)
		)
		(stroke
			(width 0)
			(type solid)
		)
		(fill yes)
		(layer "In6.Cu")
		(net "P5E_PEX3_STN7_RX_DP<118>")
	)
	(gr_poly
		(pts
			(arc
				(start 388.203186 -305.399948)
				(mid 387.796786 -305.399948)
				(end 388.203186 -305.399948)
			)
		)
		(stroke
			(width 0)
			(type solid)
		)
		(fill yes)
		(layer "In6.Cu")
		(net "P5E_PEX3_STN7_RX_DP<116>")
	)
	(gr_poly
		(pts
			(arc
				(start 388.203186 -303.499774)
				(mid 387.796786 -303.499774)
				(end 388.203186 -303.499774)
			)
		)
		(stroke
			(width 0)
			(type solid)
		)
		(fill yes)
		(layer "In6.Cu")
		(net "P5E_PEX3_STN7_RX_DP<114>")
	)
	(gr_poly
		(pts
			(arc
				(start 388.203186 -301.599854)
				(mid 387.796786 -301.599854)
				(end 388.203186 -301.599854)
			)
		)
		(stroke
			(width 0)
			(type solid)
		)
		(fill yes)
		(layer "In6.Cu")
		(net "P5E_PEX3_STN7_RX_DP<112>")
	)
	(gr_poly
		(pts
			(arc
				(start 389.153146 -318.699896)
				(mid 388.746746 -318.699896)
				(end 389.153146 -318.699896)
			)
		)
		(stroke
			(width 0)
			(type solid)
		)
		(fill yes)
		(layer "In6.Cu")
		(net "P5E_PEX3_STN7_RX_DN<125>")
	)
	(gr_poly
		(pts
			(arc
				(start 389.153146 -317.749936)
				(mid 388.746746 -317.749936)
				(end 389.153146 -317.749936)
			)
		)
		(stroke
			(width 0)
			(type solid)
		)
		(fill yes)
		(layer "In6.Cu")
		(net "P5E_PEX3_STN7_RX_DP<125>")
	)
	(gr_poly
		(pts
			(arc
				(start 389.153146 -313.949842)
				(mid 388.746746 -313.949842)
				(end 389.153146 -313.949842)
			)
		)
		(stroke
			(width 0)
			(type solid)
		)
		(fill yes)
		(layer "In6.Cu")
		(net "P5E_PEX3_STN7_TX_DN<125>")
	)
	(gr_poly
		(pts
			(arc
				(start 389.153146 -312.999882)
				(mid 388.746746 -312.999882)
				(end 389.153146 -312.999882)
			)
		)
		(stroke
			(width 0)
			(type solid)
		)
		(fill yes)
		(layer "In6.Cu")
		(net "P5E_PEX3_STN7_TX_DP<125>")
	)
	(gr_poly
		(pts
			(arc
				(start 390.103106 -316.799722)
				(mid 389.696706 -316.799722)
				(end 390.103106 -316.799722)
			)
		)
		(stroke
			(width 0)
			(type solid)
		)
		(fill yes)
		(layer "In6.Cu")
		(net "P5E_PEX3_STN7_RX_DN<126>")
	)
	(gr_poly
		(pts
			(arc
				(start 390.103106 -315.849762)
				(mid 389.696706 -315.849762)
				(end 390.103106 -315.849762)
			)
		)
		(stroke
			(width 0)
			(type solid)
		)
		(fill yes)
		(layer "In6.Cu")
		(net "P5E_PEX3_STN7_RX_DP<126>")
	)
	(gr_poly
		(pts
			(arc
				(start 390.103106 -312.049922)
				(mid 389.696706 -312.049922)
				(end 390.103106 -312.049922)
			)
		)
		(stroke
			(width 0)
			(type solid)
		)
		(fill yes)
		(layer "In6.Cu")
		(net "P5E_PEX3_STN7_TX_DN<126>")
	)
	(gr_poly
		(pts
			(arc
				(start 390.103106 -311.099962)
				(mid 389.696706 -311.099962)
				(end 390.103106 -311.099962)
			)
		)
		(stroke
			(width 0)
			(type solid)
		)
		(fill yes)
		(layer "In6.Cu")
		(net "P5E_PEX3_STN7_TX_DP<126>")
	)
	(gr_poly
		(pts
			(arc
				(start 390.103106 -309.199788)
				(mid 389.696706 -309.199788)
				(end 390.103106 -309.199788)
			)
		)
		(stroke
			(width 0)
			(type solid)
		)
		(fill yes)
		(layer "In6.Cu")
		(net "P5E_PEX3_STN7_TX_DN<120>")
	)
	(gr_poly
		(pts
			(arc
				(start 390.103106 -307.299868)
				(mid 389.696706 -307.299868)
				(end 390.103106 -307.299868)
			)
		)
		(stroke
			(width 0)
			(type solid)
		)
		(fill yes)
		(layer "In6.Cu")
		(net "P5E_PEX3_STN7_TX_DN<118>")
	)
	(gr_poly
		(pts
			(arc
				(start 390.103106 -305.399948)
				(mid 389.696706 -305.399948)
				(end 390.103106 -305.399948)
			)
		)
		(stroke
			(width 0)
			(type solid)
		)
		(fill yes)
		(layer "In6.Cu")
		(net "P5E_PEX3_STN7_TX_DN<116>")
	)
	(gr_poly
		(pts
			(arc
				(start 390.103106 -303.499774)
				(mid 389.696706 -303.499774)
				(end 390.103106 -303.499774)
			)
		)
		(stroke
			(width 0)
			(type solid)
		)
		(fill yes)
		(layer "In6.Cu")
		(net "P5E_PEX3_STN7_TX_DN<114>")
	)
	(gr_poly
		(pts
			(arc
				(start 390.103106 -301.599854)
				(mid 389.696706 -301.599854)
				(end 390.103106 -301.599854)
			)
		)
		(stroke
			(width 0)
			(type solid)
		)
		(fill yes)
		(layer "In6.Cu")
		(net "P5E_PEX3_STN7_TX_DN<112>")
	)
	(gr_poly
		(pts
			(arc
				(start 391.053066 -318.699896)
				(mid 390.646666 -318.699896)
				(end 391.053066 -318.699896)
			)
		)
		(stroke
			(width 0)
			(type solid)
		)
		(fill yes)
		(layer "In6.Cu")
		(net "P5E_PEX3_STN7_RX_DN<127>")
	)
	(gr_poly
		(pts
			(arc
				(start 391.053066 -317.749936)
				(mid 390.646666 -317.749936)
				(end 391.053066 -317.749936)
			)
		)
		(stroke
			(width 0)
			(type solid)
		)
		(fill yes)
		(layer "In6.Cu")
		(net "P5E_PEX3_STN7_RX_DP<127>")
	)
	(gr_poly
		(pts
			(arc
				(start 391.053066 -313.949842)
				(mid 390.646666 -313.949842)
				(end 391.053066 -313.949842)
			)
		)
		(stroke
			(width 0)
			(type solid)
		)
		(fill yes)
		(layer "In6.Cu")
		(net "P5E_PEX3_STN7_TX_DN<127>")
	)
	(gr_poly
		(pts
			(arc
				(start 391.053066 -312.999882)
				(mid 390.646666 -312.999882)
				(end 391.053066 -312.999882)
			)
		)
		(stroke
			(width 0)
			(type solid)
		)
		(fill yes)
		(layer "In6.Cu")
		(net "P5E_PEX3_STN7_TX_DP<127>")
	)
	(gr_poly
		(pts
			(arc
				(start 391.053066 -309.199788)
				(mid 390.646666 -309.199788)
				(end 391.053066 -309.199788)
			)
		)
		(stroke
			(width 0)
			(type solid)
		)
		(fill yes)
		(layer "In6.Cu")
		(net "P5E_PEX3_STN7_TX_DP<120>")
	)
	(gr_poly
		(pts
			(arc
				(start 391.053066 -307.299868)
				(mid 390.646666 -307.299868)
				(end 391.053066 -307.299868)
			)
		)
		(stroke
			(width 0)
			(type solid)
		)
		(fill yes)
		(layer "In6.Cu")
		(net "P5E_PEX3_STN7_TX_DP<118>")
	)
	(gr_poly
		(pts
			(arc
				(start 391.053066 -305.399948)
				(mid 390.646666 -305.399948)
				(end 391.053066 -305.399948)
			)
		)
		(stroke
			(width 0)
			(type solid)
		)
		(fill yes)
		(layer "In6.Cu")
		(net "P5E_PEX3_STN7_TX_DP<116>")
	)
	(gr_poly
		(pts
			(arc
				(start 391.053066 -303.499774)
				(mid 390.646666 -303.499774)
				(end 391.053066 -303.499774)
			)
		)
		(stroke
			(width 0)
			(type solid)
		)
		(fill yes)
		(layer "In6.Cu")
		(net "P5E_PEX3_STN7_TX_DP<114>")
	)
	(gr_poly
		(pts
			(arc
				(start 391.053066 -301.599854)
				(mid 390.646666 -301.599854)
				(end 391.053066 -301.599854)
			)
		)
		(stroke
			(width 0)
			(type solid)
		)
		(fill yes)
		(layer "In6.Cu")
		(net "P5E_PEX3_STN7_TX_DP<112>")
	)
	(gr_poly
		(pts
			(arc
				(start 392.003026 -316.799722)
				(mid 391.596626 -316.799722)
				(end 392.003026 -316.799722)
			)
		)
		(stroke
			(width 0)
			(type solid)
		)
		(fill yes)
		(layer "In6.Cu")
		(net "P5E_PEX3_STN6_RX_DN<111>")
	)
	(gr_poly
		(pts
			(arc
				(start 392.003026 -315.849762)
				(mid 391.596626 -315.849762)
				(end 392.003026 -315.849762)
			)
		)
		(stroke
			(width 0)
			(type solid)
		)
		(fill yes)
		(layer "In6.Cu")
		(net "P5E_PEX3_STN6_RX_DP<111>")
	)
	(gr_poly
		(pts
			(arc
				(start 392.003026 -312.049922)
				(mid 391.596626 -312.049922)
				(end 392.003026 -312.049922)
			)
		)
		(stroke
			(width 0)
			(type solid)
		)
		(fill yes)
		(layer "In6.Cu")
		(net "P5E_PEX3_STN6_TX_DN<111>")
	)
	(gr_poly
		(pts
			(arc
				(start 392.003026 -311.099962)
				(mid 391.596626 -311.099962)
				(end 392.003026 -311.099962)
			)
		)
		(stroke
			(width 0)
			(type solid)
		)
		(fill yes)
		(layer "In6.Cu")
		(net "P5E_PEX3_STN6_TX_DP<111>")
	)
	(gr_poly
		(pts
			(arc
				(start 392.003026 -308.249828)
				(mid 391.596626 -308.249828)
				(end 392.003026 -308.249828)
			)
		)
		(stroke
			(width 0)
			(type solid)
		)
		(fill yes)
		(layer "In6.Cu")
		(net "P5E_PEX3_STN7_TX_DN<119>")
	)
	(gr_poly
		(pts
			(arc
				(start 392.003026 -306.349908)
				(mid 391.596626 -306.349908)
				(end 392.003026 -306.349908)
			)
		)
		(stroke
			(width 0)
			(type solid)
		)
		(fill yes)
		(layer "In6.Cu")
		(net "P5E_PEX3_STN7_TX_DN<117>")
	)
	(gr_poly
		(pts
			(arc
				(start 392.003026 -304.449734)
				(mid 391.596626 -304.449734)
				(end 392.003026 -304.449734)
			)
		)
		(stroke
			(width 0)
			(type solid)
		)
		(fill yes)
		(layer "In6.Cu")
		(net "P5E_PEX3_STN7_TX_DN<115>")
	)
	(gr_poly
		(pts
			(arc
				(start 392.003026 -302.549814)
				(mid 391.596626 -302.549814)
				(end 392.003026 -302.549814)
			)
		)
		(stroke
			(width 0)
			(type solid)
		)
		(fill yes)
		(layer "In6.Cu")
		(net "P5E_PEX3_STN7_TX_DN<113>")
	)
	(gr_poly
		(pts
			(arc
				(start 392.952986 -318.699896)
				(mid 392.546586 -318.699896)
				(end 392.952986 -318.699896)
			)
		)
		(stroke
			(width 0)
			(type solid)
		)
		(fill yes)
		(layer "In6.Cu")
		(net "P5E_PEX3_STN6_RX_DN<110>")
	)
	(gr_poly
		(pts
			(arc
				(start 392.952986 -317.749936)
				(mid 392.546586 -317.749936)
				(end 392.952986 -317.749936)
			)
		)
		(stroke
			(width 0)
			(type solid)
		)
		(fill yes)
		(layer "In6.Cu")
		(net "P5E_PEX3_STN6_RX_DP<110>")
	)
	(gr_poly
		(pts
			(arc
				(start 392.952986 -313.949842)
				(mid 392.546586 -313.949842)
				(end 392.952986 -313.949842)
			)
		)
		(stroke
			(width 0)
			(type solid)
		)
		(fill yes)
		(layer "In6.Cu")
		(net "P5E_PEX3_STN6_TX_DN<110>")
	)
	(gr_poly
		(pts
			(arc
				(start 392.952986 -312.999882)
				(mid 392.546586 -312.999882)
				(end 392.952986 -312.999882)
			)
		)
		(stroke
			(width 0)
			(type solid)
		)
		(fill yes)
		(layer "In6.Cu")
		(net "P5E_PEX3_STN6_TX_DP<110>")
	)
	(gr_poly
		(pts
			(arc
				(start 392.952986 -308.249828)
				(mid 392.546586 -308.249828)
				(end 392.952986 -308.249828)
			)
		)
		(stroke
			(width 0)
			(type solid)
		)
		(fill yes)
		(layer "In6.Cu")
		(net "P5E_PEX3_STN7_TX_DP<119>")
	)
	(gr_poly
		(pts
			(arc
				(start 392.952986 -306.349908)
				(mid 392.546586 -306.349908)
				(end 392.952986 -306.349908)
			)
		)
		(stroke
			(width 0)
			(type solid)
		)
		(fill yes)
		(layer "In6.Cu")
		(net "P5E_PEX3_STN7_TX_DP<117>")
	)
	(gr_poly
		(pts
			(arc
				(start 392.952986 -304.449734)
				(mid 392.546586 -304.449734)
				(end 392.952986 -304.449734)
			)
		)
		(stroke
			(width 0)
			(type solid)
		)
		(fill yes)
		(layer "In6.Cu")
		(net "P5E_PEX3_STN7_TX_DP<115>")
	)
	(gr_poly
		(pts
			(arc
				(start 392.952986 -302.549814)
				(mid 392.546586 -302.549814)
				(end 392.952986 -302.549814)
			)
		)
		(stroke
			(width 0)
			(type solid)
		)
		(fill yes)
		(layer "In6.Cu")
		(net "P5E_PEX3_STN7_TX_DP<113>")
	)
	(gr_poly
		(pts
			(arc
				(start 392.952986 -278.799798)
				(mid 392.546586 -278.799798)
				(end 392.952986 -278.799798)
			)
		)
		(stroke
			(width 0)
			(type solid)
		)
		(fill yes)
		(layer "In6.Cu")
		(net "P5E_PEX3_STN2_TX_DP<47>")
	)
	(gr_poly
		(pts
			(arc
				(start 392.952986 -277.849838)
				(mid 392.546586 -277.849838)
				(end 392.952986 -277.849838)
			)
		)
		(stroke
			(width 0)
			(type solid)
		)
		(fill yes)
		(layer "In6.Cu")
		(net "P5E_PEX3_STN2_TX_DN<47>")
	)
	(gr_poly
		(pts
			(arc
				(start 392.952986 -274.049744)
				(mid 392.546586 -274.049744)
				(end 392.952986 -274.049744)
			)
		)
		(stroke
			(width 0)
			(type solid)
		)
		(fill yes)
		(layer "In6.Cu")
		(net "P5E_PEX3_STN2_RX_DP<47>")
	)
	(gr_poly
		(pts
			(arc
				(start 392.952986 -273.099784)
				(mid 392.546586 -273.099784)
				(end 392.952986 -273.099784)
			)
		)
		(stroke
			(width 0)
			(type solid)
		)
		(fill yes)
		(layer "In6.Cu")
		(net "P5E_PEX3_STN2_RX_DN<47>")
	)
	(gr_poly
		(pts
			(arc
				(start 393.9032 -316.799722)
				(mid 393.4968 -316.799722)
				(end 393.9032 -316.799722)
			)
		)
		(stroke
			(width 0)
			(type solid)
		)
		(fill yes)
		(layer "In6.Cu")
		(net "P5E_PEX3_STN6_RX_DN<109>")
	)
	(gr_poly
		(pts
			(arc
				(start 393.9032 -315.849762)
				(mid 393.4968 -315.849762)
				(end 393.9032 -315.849762)
			)
		)
		(stroke
			(width 0)
			(type solid)
		)
		(fill yes)
		(layer "In6.Cu")
		(net "P5E_PEX3_STN6_RX_DP<109>")
	)
	(gr_poly
		(pts
			(arc
				(start 393.9032 -312.049922)
				(mid 393.4968 -312.049922)
				(end 393.9032 -312.049922)
			)
		)
		(stroke
			(width 0)
			(type solid)
		)
		(fill yes)
		(layer "In6.Cu")
		(net "P5E_PEX3_STN6_TX_DN<109>")
	)
	(gr_poly
		(pts
			(arc
				(start 393.9032 -311.099962)
				(mid 393.4968 -311.099962)
				(end 393.9032 -311.099962)
			)
		)
		(stroke
			(width 0)
			(type solid)
		)
		(fill yes)
		(layer "In6.Cu")
		(net "P5E_PEX3_STN6_TX_DP<109>")
	)
	(gr_poly
		(pts
			(arc
				(start 393.9032 -280.699464)
				(mid 393.4968 -280.699464)
				(end 393.9032 -280.699464)
			)
		)
		(stroke
			(width 0)
			(type solid)
		)
		(fill yes)
		(layer "In6.Cu")
		(net "P5E_PEX3_STN2_TX_DP<46>")
	)
	(gr_poly
		(pts
			(arc
				(start 393.9032 -279.749504)
				(mid 393.4968 -279.749504)
				(end 393.9032 -279.749504)
			)
		)
		(stroke
			(width 0)
			(type solid)
		)
		(fill yes)
		(layer "In6.Cu")
		(net "P5E_PEX3_STN2_TX_DN<46>")
	)
	(gr_poly
		(pts
			(arc
				(start 393.9032 -275.949918)
				(mid 393.4968 -275.949918)
				(end 393.9032 -275.949918)
			)
		)
		(stroke
			(width 0)
			(type solid)
		)
		(fill yes)
		(layer "In6.Cu")
		(net "P5E_PEX3_STN2_RX_DP<46>")
	)
	(gr_poly
		(pts
			(arc
				(start 393.9032 -274.999958)
				(mid 393.4968 -274.999958)
				(end 393.9032 -274.999958)
			)
		)
		(stroke
			(width 0)
			(type solid)
		)
		(fill yes)
		(layer "In6.Cu")
		(net "P5E_PEX3_STN2_RX_DN<46>")
	)
	(gr_poly
		(pts
			(arc
				(start 394.85316 -318.699896)
				(mid 394.44676 -318.699896)
				(end 394.85316 -318.699896)
			)
		)
		(stroke
			(width 0)
			(type solid)
		)
		(fill yes)
		(layer "In6.Cu")
		(net "P5E_PEX3_STN6_RX_DN<108>")
	)
	(gr_poly
		(pts
			(arc
				(start 394.85316 -317.749936)
				(mid 394.44676 -317.749936)
				(end 394.85316 -317.749936)
			)
		)
		(stroke
			(width 0)
			(type solid)
		)
		(fill yes)
		(layer "In6.Cu")
		(net "P5E_PEX3_STN6_RX_DP<108>")
	)
	(gr_poly
		(pts
			(arc
				(start 394.85316 -313.949842)
				(mid 394.44676 -313.949842)
				(end 394.85316 -313.949842)
			)
		)
		(stroke
			(width 0)
			(type solid)
		)
		(fill yes)
		(layer "In6.Cu")
		(net "P5E_PEX3_STN6_TX_DN<108>")
	)
	(gr_poly
		(pts
			(arc
				(start 394.85316 -312.999882)
				(mid 394.44676 -312.999882)
				(end 394.85316 -312.999882)
			)
		)
		(stroke
			(width 0)
			(type solid)
		)
		(fill yes)
		(layer "In6.Cu")
		(net "P5E_PEX3_STN6_TX_DP<108>")
	)
	(gr_poly
		(pts
			(arc
				(start 394.85316 -278.799798)
				(mid 394.44676 -278.799798)
				(end 394.85316 -278.799798)
			)
		)
		(stroke
			(width 0)
			(type solid)
		)
		(fill yes)
		(layer "In6.Cu")
		(net "P5E_PEX3_STN2_TX_DP<45>")
	)
	(gr_poly
		(pts
			(arc
				(start 394.85316 -277.849838)
				(mid 394.44676 -277.849838)
				(end 394.85316 -277.849838)
			)
		)
		(stroke
			(width 0)
			(type solid)
		)
		(fill yes)
		(layer "In6.Cu")
		(net "P5E_PEX3_STN2_TX_DN<45>")
	)
	(gr_poly
		(pts
			(arc
				(start 394.85316 -274.049744)
				(mid 394.44676 -274.049744)
				(end 394.85316 -274.049744)
			)
		)
		(stroke
			(width 0)
			(type solid)
		)
		(fill yes)
		(layer "In6.Cu")
		(net "P5E_PEX3_STN2_RX_DP<45>")
	)
	(gr_poly
		(pts
			(arc
				(start 394.85316 -273.099784)
				(mid 394.44676 -273.099784)
				(end 394.85316 -273.099784)
			)
		)
		(stroke
			(width 0)
			(type solid)
		)
		(fill yes)
		(layer "In6.Cu")
		(net "P5E_PEX3_STN2_RX_DN<45>")
	)
	(gr_poly
		(pts
			(arc
				(start 395.80312 -316.799722)
				(mid 395.39672 -316.799722)
				(end 395.80312 -316.799722)
			)
		)
		(stroke
			(width 0)
			(type solid)
		)
		(fill yes)
		(layer "In6.Cu")
		(net "P5E_PEX3_STN6_RX_DN<107>")
	)
	(gr_poly
		(pts
			(arc
				(start 395.80312 -315.849762)
				(mid 395.39672 -315.849762)
				(end 395.80312 -315.849762)
			)
		)
		(stroke
			(width 0)
			(type solid)
		)
		(fill yes)
		(layer "In6.Cu")
		(net "P5E_PEX3_STN6_RX_DP<107>")
	)
	(gr_poly
		(pts
			(arc
				(start 395.80312 -312.049922)
				(mid 395.39672 -312.049922)
				(end 395.80312 -312.049922)
			)
		)
		(stroke
			(width 0)
			(type solid)
		)
		(fill yes)
		(layer "In6.Cu")
		(net "P5E_PEX3_STN6_TX_DN<107>")
	)
	(gr_poly
		(pts
			(arc
				(start 395.80312 -311.099962)
				(mid 395.39672 -311.099962)
				(end 395.80312 -311.099962)
			)
		)
		(stroke
			(width 0)
			(type solid)
		)
		(fill yes)
		(layer "In6.Cu")
		(net "P5E_PEX3_STN6_TX_DP<107>")
	)
	(gr_poly
		(pts
			(arc
				(start 395.80312 -280.699464)
				(mid 395.39672 -280.699464)
				(end 395.80312 -280.699464)
			)
		)
		(stroke
			(width 0)
			(type solid)
		)
		(fill yes)
		(layer "In6.Cu")
		(net "P5E_PEX3_STN2_TX_DP<44>")
	)
	(gr_poly
		(pts
			(arc
				(start 395.80312 -279.749504)
				(mid 395.39672 -279.749504)
				(end 395.80312 -279.749504)
			)
		)
		(stroke
			(width 0)
			(type solid)
		)
		(fill yes)
		(layer "In6.Cu")
		(net "P5E_PEX3_STN2_TX_DN<44>")
	)
	(gr_poly
		(pts
			(arc
				(start 395.80312 -275.949918)
				(mid 395.39672 -275.949918)
				(end 395.80312 -275.949918)
			)
		)
		(stroke
			(width 0)
			(type solid)
		)
		(fill yes)
		(layer "In6.Cu")
		(net "P5E_PEX3_STN2_RX_DP<44>")
	)
	(gr_poly
		(pts
			(arc
				(start 395.80312 -274.999958)
				(mid 395.39672 -274.999958)
				(end 395.80312 -274.999958)
			)
		)
		(stroke
			(width 0)
			(type solid)
		)
		(fill yes)
		(layer "In6.Cu")
		(net "P5E_PEX3_STN2_RX_DN<44>")
	)
	(gr_poly
		(pts
			(arc
				(start 396.75308 -318.699896)
				(mid 396.34668 -318.699896)
				(end 396.75308 -318.699896)
			)
		)
		(stroke
			(width 0)
			(type solid)
		)
		(fill yes)
		(layer "In6.Cu")
		(net "P5E_PEX3_STN6_RX_DN<106>")
	)
	(gr_poly
		(pts
			(arc
				(start 396.75308 -317.749936)
				(mid 396.34668 -317.749936)
				(end 396.75308 -317.749936)
			)
		)
		(stroke
			(width 0)
			(type solid)
		)
		(fill yes)
		(layer "In6.Cu")
		(net "P5E_PEX3_STN6_RX_DP<106>")
	)
	(gr_poly
		(pts
			(arc
				(start 396.75308 -313.949842)
				(mid 396.34668 -313.949842)
				(end 396.75308 -313.949842)
			)
		)
		(stroke
			(width 0)
			(type solid)
		)
		(fill yes)
		(layer "In6.Cu")
		(net "P5E_PEX3_STN6_TX_DN<106>")
	)
	(gr_poly
		(pts
			(arc
				(start 396.75308 -312.999882)
				(mid 396.34668 -312.999882)
				(end 396.75308 -312.999882)
			)
		)
		(stroke
			(width 0)
			(type solid)
		)
		(fill yes)
		(layer "In6.Cu")
		(net "P5E_PEX3_STN6_TX_DP<106>")
	)
	(gr_poly
		(pts
			(arc
				(start 396.75308 -278.799798)
				(mid 396.34668 -278.799798)
				(end 396.75308 -278.799798)
			)
		)
		(stroke
			(width 0)
			(type solid)
		)
		(fill yes)
		(layer "In6.Cu")
		(net "P5E_PEX3_STN2_TX_DP<43>")
	)
	(gr_poly
		(pts
			(arc
				(start 396.75308 -277.849838)
				(mid 396.34668 -277.849838)
				(end 396.75308 -277.849838)
			)
		)
		(stroke
			(width 0)
			(type solid)
		)
		(fill yes)
		(layer "In6.Cu")
		(net "P5E_PEX3_STN2_TX_DN<43>")
	)
	(gr_poly
		(pts
			(arc
				(start 396.75308 -274.049744)
				(mid 396.34668 -274.049744)
				(end 396.75308 -274.049744)
			)
		)
		(stroke
			(width 0)
			(type solid)
		)
		(fill yes)
		(layer "In6.Cu")
		(net "P5E_PEX3_STN2_RX_DP<43>")
	)
	(gr_poly
		(pts
			(arc
				(start 396.75308 -273.099784)
				(mid 396.34668 -273.099784)
				(end 396.75308 -273.099784)
			)
		)
		(stroke
			(width 0)
			(type solid)
		)
		(fill yes)
		(layer "In6.Cu")
		(net "P5E_PEX3_STN2_RX_DN<43>")
	)
	(gr_poly
		(pts
			(arc
				(start 397.70304 -316.799722)
				(mid 397.29664 -316.799722)
				(end 397.70304 -316.799722)
			)
		)
		(stroke
			(width 0)
			(type solid)
		)
		(fill yes)
		(layer "In6.Cu")
		(net "P5E_PEX3_STN6_RX_DN<105>")
	)
	(gr_poly
		(pts
			(arc
				(start 397.70304 -315.849762)
				(mid 397.29664 -315.849762)
				(end 397.70304 -315.849762)
			)
		)
		(stroke
			(width 0)
			(type solid)
		)
		(fill yes)
		(layer "In6.Cu")
		(net "P5E_PEX3_STN6_RX_DP<105>")
	)
	(gr_poly
		(pts
			(arc
				(start 397.70304 -312.049922)
				(mid 397.29664 -312.049922)
				(end 397.70304 -312.049922)
			)
		)
		(stroke
			(width 0)
			(type solid)
		)
		(fill yes)
		(layer "In6.Cu")
		(net "P5E_PEX3_STN6_TX_DN<105>")
	)
	(gr_poly
		(pts
			(arc
				(start 397.70304 -311.099962)
				(mid 397.29664 -311.099962)
				(end 397.70304 -311.099962)
			)
		)
		(stroke
			(width 0)
			(type solid)
		)
		(fill yes)
		(layer "In6.Cu")
		(net "P5E_PEX3_STN6_TX_DP<105>")
	)
	(gr_poly
		(pts
			(arc
				(start 397.70304 -280.699464)
				(mid 397.29664 -280.699464)
				(end 397.70304 -280.699464)
			)
		)
		(stroke
			(width 0)
			(type solid)
		)
		(fill yes)
		(layer "In6.Cu")
		(net "P5E_PEX3_STN2_TX_DP<42>")
	)
	(gr_poly
		(pts
			(arc
				(start 397.70304 -279.749504)
				(mid 397.29664 -279.749504)
				(end 397.70304 -279.749504)
			)
		)
		(stroke
			(width 0)
			(type solid)
		)
		(fill yes)
		(layer "In6.Cu")
		(net "P5E_PEX3_STN2_TX_DN<42>")
	)
	(gr_poly
		(pts
			(arc
				(start 397.70304 -275.949918)
				(mid 397.29664 -275.949918)
				(end 397.70304 -275.949918)
			)
		)
		(stroke
			(width 0)
			(type solid)
		)
		(fill yes)
		(layer "In6.Cu")
		(net "P5E_PEX3_STN2_RX_DP<42>")
	)
	(gr_poly
		(pts
			(arc
				(start 397.70304 -274.999958)
				(mid 397.29664 -274.999958)
				(end 397.70304 -274.999958)
			)
		)
		(stroke
			(width 0)
			(type solid)
		)
		(fill yes)
		(layer "In6.Cu")
		(net "P5E_PEX3_STN2_RX_DN<42>")
	)
	(gr_poly
		(pts
			(arc
				(start 398.653 -318.699896)
				(mid 398.2466 -318.699896)
				(end 398.653 -318.699896)
			)
		)
		(stroke
			(width 0)
			(type solid)
		)
		(fill yes)
		(layer "In6.Cu")
		(net "P5E_PEX3_STN6_RX_DN<104>")
	)
	(gr_poly
		(pts
			(arc
				(start 398.653 -317.749936)
				(mid 398.2466 -317.749936)
				(end 398.653 -317.749936)
			)
		)
		(stroke
			(width 0)
			(type solid)
		)
		(fill yes)
		(layer "In6.Cu")
		(net "P5E_PEX3_STN6_RX_DP<104>")
	)
	(gr_poly
		(pts
			(arc
				(start 398.653 -313.949842)
				(mid 398.2466 -313.949842)
				(end 398.653 -313.949842)
			)
		)
		(stroke
			(width 0)
			(type solid)
		)
		(fill yes)
		(layer "In6.Cu")
		(net "P5E_PEX3_STN6_TX_DN<104>")
	)
	(gr_poly
		(pts
			(arc
				(start 398.653 -312.999882)
				(mid 398.2466 -312.999882)
				(end 398.653 -312.999882)
			)
		)
		(stroke
			(width 0)
			(type solid)
		)
		(fill yes)
		(layer "In6.Cu")
		(net "P5E_PEX3_STN6_TX_DP<104>")
	)
	(gr_poly
		(pts
			(arc
				(start 398.653 -278.799798)
				(mid 398.2466 -278.799798)
				(end 398.653 -278.799798)
			)
		)
		(stroke
			(width 0)
			(type solid)
		)
		(fill yes)
		(layer "In6.Cu")
		(net "P5E_PEX3_STN2_TX_DP<41>")
	)
	(gr_poly
		(pts
			(arc
				(start 398.653 -277.849838)
				(mid 398.2466 -277.849838)
				(end 398.653 -277.849838)
			)
		)
		(stroke
			(width 0)
			(type solid)
		)
		(fill yes)
		(layer "In6.Cu")
		(net "P5E_PEX3_STN2_TX_DN<41>")
	)
	(gr_poly
		(pts
			(arc
				(start 398.653 -274.049744)
				(mid 398.2466 -274.049744)
				(end 398.653 -274.049744)
			)
		)
		(stroke
			(width 0)
			(type solid)
		)
		(fill yes)
		(layer "In6.Cu")
		(net "P5E_PEX3_STN2_RX_DP<41>")
	)
	(gr_poly
		(pts
			(arc
				(start 398.653 -273.099784)
				(mid 398.2466 -273.099784)
				(end 398.653 -273.099784)
			)
		)
		(stroke
			(width 0)
			(type solid)
		)
		(fill yes)
		(layer "In6.Cu")
		(net "P5E_PEX3_STN2_RX_DN<41>")
	)
	(gr_poly
		(pts
			(arc
				(start 399.603214 -312.049922)
				(mid 399.196814 -312.049922)
				(end 399.603214 -312.049922)
			)
		)
		(stroke
			(width 0)
			(type solid)
		)
		(fill yes)
		(layer "In6.Cu")
		(net "P5E_PEX3_STN6_TX_DN<103>")
	)
	(gr_poly
		(pts
			(arc
				(start 399.603214 -311.099962)
				(mid 399.196814 -311.099962)
				(end 399.603214 -311.099962)
			)
		)
		(stroke
			(width 0)
			(type solid)
		)
		(fill yes)
		(layer "In6.Cu")
		(net "P5E_PEX3_STN6_TX_DP<103>")
	)
	(gr_poly
		(pts
			(arc
				(start 399.603214 -280.699464)
				(mid 399.196814 -280.699464)
				(end 399.603214 -280.699464)
			)
		)
		(stroke
			(width 0)
			(type solid)
		)
		(fill yes)
		(layer "In6.Cu")
		(net "P5E_PEX3_STN2_TX_DP<40>")
	)
	(gr_poly
		(pts
			(arc
				(start 399.603214 -279.749504)
				(mid 399.196814 -279.749504)
				(end 399.603214 -279.749504)
			)
		)
		(stroke
			(width 0)
			(type solid)
		)
		(fill yes)
		(layer "In6.Cu")
		(net "P5E_PEX3_STN2_TX_DN<40>")
	)
	(gr_poly
		(pts
			(arc
				(start 399.603214 -275.949918)
				(mid 399.196814 -275.949918)
				(end 399.603214 -275.949918)
			)
		)
		(stroke
			(width 0)
			(type solid)
		)
		(fill yes)
		(layer "In6.Cu")
		(net "P5E_PEX3_STN2_RX_DP<40>")
	)
	(gr_poly
		(pts
			(arc
				(start 399.603214 -274.999958)
				(mid 399.196814 -274.999958)
				(end 399.603214 -274.999958)
			)
		)
		(stroke
			(width 0)
			(type solid)
		)
		(fill yes)
		(layer "In6.Cu")
		(net "P5E_PEX3_STN2_RX_DN<40>")
	)
	(gr_poly
		(pts
			(arc
				(start 400.553174 -313.949842)
				(mid 400.146774 -313.949842)
				(end 400.553174 -313.949842)
			)
		)
		(stroke
			(width 0)
			(type solid)
		)
		(fill yes)
		(layer "In6.Cu")
		(net "P5E_PEX3_STN6_TX_DN<102>")
	)
	(gr_poly
		(pts
			(arc
				(start 400.553174 -312.999882)
				(mid 400.146774 -312.999882)
				(end 400.553174 -312.999882)
			)
		)
		(stroke
			(width 0)
			(type solid)
		)
		(fill yes)
		(layer "In6.Cu")
		(net "P5E_PEX3_STN6_TX_DP<102>")
	)
	(gr_poly
		(pts
			(arc
				(start 400.553174 -278.799798)
				(mid 400.146774 -278.799798)
				(end 400.553174 -278.799798)
			)
		)
		(stroke
			(width 0)
			(type solid)
		)
		(fill yes)
		(layer "In6.Cu")
		(net "P5E_PEX3_STN2_TX_DP<39>")
	)
	(gr_poly
		(pts
			(arc
				(start 400.553174 -277.849838)
				(mid 400.146774 -277.849838)
				(end 400.553174 -277.849838)
			)
		)
		(stroke
			(width 0)
			(type solid)
		)
		(fill yes)
		(layer "In6.Cu")
		(net "P5E_PEX3_STN2_TX_DN<39>")
	)
	(gr_poly
		(pts
			(arc
				(start 400.553174 -274.049744)
				(mid 400.146774 -274.049744)
				(end 400.553174 -274.049744)
			)
		)
		(stroke
			(width 0)
			(type solid)
		)
		(fill yes)
		(layer "In6.Cu")
		(net "P5E_PEX3_STN2_RX_DP<39>")
	)
	(gr_poly
		(pts
			(arc
				(start 400.553174 -273.099784)
				(mid 400.146774 -273.099784)
				(end 400.553174 -273.099784)
			)
		)
		(stroke
			(width 0)
			(type solid)
		)
		(fill yes)
		(layer "In6.Cu")
		(net "P5E_PEX3_STN2_RX_DN<39>")
	)
	(gr_poly
		(pts
			(arc
				(start 401.503134 -312.049922)
				(mid 401.096734 -312.049922)
				(end 401.503134 -312.049922)
			)
		)
		(stroke
			(width 0)
			(type solid)
		)
		(fill yes)
		(layer "In6.Cu")
		(net "P5E_PEX3_STN6_TX_DN<101>")
	)
	(gr_poly
		(pts
			(arc
				(start 401.503134 -311.099962)
				(mid 401.096734 -311.099962)
				(end 401.503134 -311.099962)
			)
		)
		(stroke
			(width 0)
			(type solid)
		)
		(fill yes)
		(layer "In6.Cu")
		(net "P5E_PEX3_STN6_TX_DP<101>")
	)
	(gr_poly
		(pts
			(arc
				(start 401.503134 -280.699464)
				(mid 401.096734 -280.699464)
				(end 401.503134 -280.699464)
			)
		)
		(stroke
			(width 0)
			(type solid)
		)
		(fill yes)
		(layer "In6.Cu")
		(net "P5E_PEX3_STN2_TX_DP<38>")
	)
	(gr_poly
		(pts
			(arc
				(start 401.503134 -279.749504)
				(mid 401.096734 -279.749504)
				(end 401.503134 -279.749504)
			)
		)
		(stroke
			(width 0)
			(type solid)
		)
		(fill yes)
		(layer "In6.Cu")
		(net "P5E_PEX3_STN2_TX_DN<38>")
	)
	(gr_poly
		(pts
			(arc
				(start 401.503134 -275.949918)
				(mid 401.096734 -275.949918)
				(end 401.503134 -275.949918)
			)
		)
		(stroke
			(width 0)
			(type solid)
		)
		(fill yes)
		(layer "In6.Cu")
		(net "P5E_PEX3_STN2_RX_DP<38>")
	)
	(gr_poly
		(pts
			(arc
				(start 401.503134 -274.999958)
				(mid 401.096734 -274.999958)
				(end 401.503134 -274.999958)
			)
		)
		(stroke
			(width 0)
			(type solid)
		)
		(fill yes)
		(layer "In6.Cu")
		(net "P5E_PEX3_STN2_RX_DN<38>")
	)
	(gr_poly
		(pts
			(arc
				(start 402.453094 -313.949842)
				(mid 402.046694 -313.949842)
				(end 402.453094 -313.949842)
			)
		)
		(stroke
			(width 0)
			(type solid)
		)
		(fill yes)
		(layer "In6.Cu")
		(net "P5E_PEX3_STN6_TX_DN<100>")
	)
	(gr_poly
		(pts
			(arc
				(start 402.453094 -312.999882)
				(mid 402.046694 -312.999882)
				(end 402.453094 -312.999882)
			)
		)
		(stroke
			(width 0)
			(type solid)
		)
		(fill yes)
		(layer "In6.Cu")
		(net "P5E_PEX3_STN6_TX_DP<100>")
	)
	(gr_poly
		(pts
			(arc
				(start 402.453094 -278.799798)
				(mid 402.046694 -278.799798)
				(end 402.453094 -278.799798)
			)
		)
		(stroke
			(width 0)
			(type solid)
		)
		(fill yes)
		(layer "In6.Cu")
		(net "P5E_PEX3_STN2_TX_DP<37>")
	)
	(gr_poly
		(pts
			(arc
				(start 402.453094 -277.849838)
				(mid 402.046694 -277.849838)
				(end 402.453094 -277.849838)
			)
		)
		(stroke
			(width 0)
			(type solid)
		)
		(fill yes)
		(layer "In6.Cu")
		(net "P5E_PEX3_STN2_TX_DN<37>")
	)
	(gr_poly
		(pts
			(arc
				(start 402.453094 -274.049744)
				(mid 402.046694 -274.049744)
				(end 402.453094 -274.049744)
			)
		)
		(stroke
			(width 0)
			(type solid)
		)
		(fill yes)
		(layer "In6.Cu")
		(net "P5E_PEX3_STN2_RX_DP<37>")
	)
	(gr_poly
		(pts
			(arc
				(start 402.453094 -273.099784)
				(mid 402.046694 -273.099784)
				(end 402.453094 -273.099784)
			)
		)
		(stroke
			(width 0)
			(type solid)
		)
		(fill yes)
		(layer "In6.Cu")
		(net "P5E_PEX3_STN2_RX_DN<37>")
	)
	(gr_poly
		(pts
			(arc
				(start 403.403054 -312.049922)
				(mid 402.996654 -312.049922)
				(end 403.403054 -312.049922)
			)
		)
		(stroke
			(width 0)
			(type solid)
		)
		(fill yes)
		(layer "In6.Cu")
		(net "P5E_PEX3_STN6_TX_DN<99>")
	)
	(gr_poly
		(pts
			(arc
				(start 403.403054 -311.099962)
				(mid 402.996654 -311.099962)
				(end 403.403054 -311.099962)
			)
		)
		(stroke
			(width 0)
			(type solid)
		)
		(fill yes)
		(layer "In6.Cu")
		(net "P5E_PEX3_STN6_TX_DP<99>")
	)
	(gr_poly
		(pts
			(arc
				(start 403.403054 -280.699464)
				(mid 402.996654 -280.699464)
				(end 403.403054 -280.699464)
			)
		)
		(stroke
			(width 0)
			(type solid)
		)
		(fill yes)
		(layer "In6.Cu")
		(net "P5E_PEX3_STN2_TX_DP<36>")
	)
	(gr_poly
		(pts
			(arc
				(start 403.403054 -279.749504)
				(mid 402.996654 -279.749504)
				(end 403.403054 -279.749504)
			)
		)
		(stroke
			(width 0)
			(type solid)
		)
		(fill yes)
		(layer "In6.Cu")
		(net "P5E_PEX3_STN2_TX_DN<36>")
	)
	(gr_poly
		(pts
			(arc
				(start 403.403054 -275.949918)
				(mid 402.996654 -275.949918)
				(end 403.403054 -275.949918)
			)
		)
		(stroke
			(width 0)
			(type solid)
		)
		(fill yes)
		(layer "In6.Cu")
		(net "P5E_PEX3_STN2_RX_DP<36>")
	)
	(gr_poly
		(pts
			(arc
				(start 403.403054 -274.999958)
				(mid 402.996654 -274.999958)
				(end 403.403054 -274.999958)
			)
		)
		(stroke
			(width 0)
			(type solid)
		)
		(fill yes)
		(layer "In6.Cu")
		(net "P5E_PEX3_STN2_RX_DN<36>")
	)
	(gr_poly
		(pts
			(arc
				(start 404.353014 -313.949842)
				(mid 403.946614 -313.949842)
				(end 404.353014 -313.949842)
			)
		)
		(stroke
			(width 0)
			(type solid)
		)
		(fill yes)
		(layer "In6.Cu")
		(net "P5E_PEX3_STN6_TX_DN<98>")
	)
	(gr_poly
		(pts
			(arc
				(start 404.353014 -312.999882)
				(mid 403.946614 -312.999882)
				(end 404.353014 -312.999882)
			)
		)
		(stroke
			(width 0)
			(type solid)
		)
		(fill yes)
		(layer "In6.Cu")
		(net "P5E_PEX3_STN6_TX_DP<98>")
	)
	(gr_poly
		(pts
			(arc
				(start 404.353014 -278.799798)
				(mid 403.946614 -278.799798)
				(end 404.353014 -278.799798)
			)
		)
		(stroke
			(width 0)
			(type solid)
		)
		(fill yes)
		(layer "In6.Cu")
		(net "P5E_PEX3_STN2_TX_DP<35>")
	)
	(gr_poly
		(pts
			(arc
				(start 404.353014 -277.849838)
				(mid 403.946614 -277.849838)
				(end 404.353014 -277.849838)
			)
		)
		(stroke
			(width 0)
			(type solid)
		)
		(fill yes)
		(layer "In6.Cu")
		(net "P5E_PEX3_STN2_TX_DN<35>")
	)
	(gr_poly
		(pts
			(arc
				(start 404.353014 -274.049744)
				(mid 403.946614 -274.049744)
				(end 404.353014 -274.049744)
			)
		)
		(stroke
			(width 0)
			(type solid)
		)
		(fill yes)
		(layer "In6.Cu")
		(net "P5E_PEX3_STN2_RX_DP<35>")
	)
	(gr_poly
		(pts
			(arc
				(start 404.353014 -273.099784)
				(mid 403.946614 -273.099784)
				(end 404.353014 -273.099784)
			)
		)
		(stroke
			(width 0)
			(type solid)
		)
		(fill yes)
		(layer "In6.Cu")
		(net "P5E_PEX3_STN2_RX_DN<35>")
	)
	(gr_poly
		(pts
			(arc
				(start 405.302974 -280.699464)
				(mid 404.896574 -280.699464)
				(end 405.302974 -280.699464)
			)
		)
		(stroke
			(width 0)
			(type solid)
		)
		(fill yes)
		(layer "In6.Cu")
		(net "P5E_PEX3_STN2_TX_DP<34>")
	)
	(gr_poly
		(pts
			(arc
				(start 405.302974 -279.749504)
				(mid 404.896574 -279.749504)
				(end 405.302974 -279.749504)
			)
		)
		(stroke
			(width 0)
			(type solid)
		)
		(fill yes)
		(layer "In6.Cu")
		(net "P5E_PEX3_STN2_TX_DN<34>")
	)
	(gr_poly
		(pts
			(arc
				(start 405.303228 -312.049922)
				(mid 404.896828 -312.049922)
				(end 405.303228 -312.049922)
			)
		)
		(stroke
			(width 0)
			(type solid)
		)
		(fill yes)
		(layer "In6.Cu")
		(net "P5E_PEX3_STN6_TX_DN<97>")
	)
	(gr_poly
		(pts
			(arc
				(start 405.303228 -311.099962)
				(mid 404.896828 -311.099962)
				(end 405.303228 -311.099962)
			)
		)
		(stroke
			(width 0)
			(type solid)
		)
		(fill yes)
		(layer "In6.Cu")
		(net "P5E_PEX3_STN6_TX_DP<97>")
	)
	(gr_poly
		(pts
			(arc
				(start 405.303228 -275.949918)
				(mid 404.896828 -275.949918)
				(end 405.303228 -275.949918)
			)
		)
		(stroke
			(width 0)
			(type solid)
		)
		(fill yes)
		(layer "In6.Cu")
		(net "P5E_PEX3_STN2_RX_DP<34>")
	)
	(gr_poly
		(pts
			(arc
				(start 405.303228 -274.999958)
				(mid 404.896828 -274.999958)
				(end 405.303228 -274.999958)
			)
		)
		(stroke
			(width 0)
			(type solid)
		)
		(fill yes)
		(layer "In6.Cu")
		(net "P5E_PEX3_STN2_RX_DN<34>")
	)
	(gr_poly
		(pts
			(arc
				(start 406.253188 -313.949842)
				(mid 405.846788 -313.949842)
				(end 406.253188 -313.949842)
			)
		)
		(stroke
			(width 0)
			(type solid)
		)
		(fill yes)
		(layer "In6.Cu")
		(net "P5E_PEX3_STN6_TX_DN<96>")
	)
	(gr_poly
		(pts
			(arc
				(start 406.253188 -312.999882)
				(mid 405.846788 -312.999882)
				(end 406.253188 -312.999882)
			)
		)
		(stroke
			(width 0)
			(type solid)
		)
		(fill yes)
		(layer "In6.Cu")
		(net "P5E_PEX3_STN6_TX_DP<96>")
	)
	(gr_poly
		(pts
			(arc
				(start 406.253188 -278.799798)
				(mid 405.846788 -278.799798)
				(end 406.253188 -278.799798)
			)
		)
		(stroke
			(width 0)
			(type solid)
		)
		(fill yes)
		(layer "In6.Cu")
		(net "P5E_PEX3_STN2_TX_DP<33>")
	)
	(gr_poly
		(pts
			(arc
				(start 406.253188 -277.849838)
				(mid 405.846788 -277.849838)
				(end 406.253188 -277.849838)
			)
		)
		(stroke
			(width 0)
			(type solid)
		)
		(fill yes)
		(layer "In6.Cu")
		(net "P5E_PEX3_STN2_TX_DN<33>")
	)
	(gr_poly
		(pts
			(arc
				(start 406.253188 -274.049744)
				(mid 405.846788 -274.049744)
				(end 406.253188 -274.049744)
			)
		)
		(stroke
			(width 0)
			(type solid)
		)
		(fill yes)
		(layer "In6.Cu")
		(net "P5E_PEX3_STN2_RX_DP<33>")
	)
	(gr_poly
		(pts
			(arc
				(start 406.253188 -273.099784)
				(mid 405.846788 -273.099784)
				(end 406.253188 -273.099784)
			)
		)
		(stroke
			(width 0)
			(type solid)
		)
		(fill yes)
		(layer "In6.Cu")
		(net "P5E_PEX3_STN2_RX_DN<33>")
	)
	(gr_poly
		(pts
			(arc
				(start 407.203148 -312.049922)
				(mid 406.796748 -312.049922)
				(end 407.203148 -312.049922)
			)
		)
		(stroke
			(width 0)
			(type solid)
		)
		(fill yes)
		(layer "In6.Cu")
		(net "P5E_PEX3_STN5_TX_DN<80>")
	)
	(gr_poly
		(pts
			(arc
				(start 407.203148 -311.099962)
				(mid 406.796748 -311.099962)
				(end 407.203148 -311.099962)
			)
		)
		(stroke
			(width 0)
			(type solid)
		)
		(fill yes)
		(layer "In6.Cu")
		(net "P5E_PEX3_STN5_TX_DP<80>")
	)
	(gr_poly
		(pts
			(arc
				(start 407.203148 -280.699464)
				(mid 406.796748 -280.699464)
				(end 407.203148 -280.699464)
			)
		)
		(stroke
			(width 0)
			(type solid)
		)
		(fill yes)
		(layer "In6.Cu")
		(net "P5E_PEX3_STN2_TX_DP<32>")
	)
	(gr_poly
		(pts
			(arc
				(start 407.203148 -279.749504)
				(mid 406.796748 -279.749504)
				(end 407.203148 -279.749504)
			)
		)
		(stroke
			(width 0)
			(type solid)
		)
		(fill yes)
		(layer "In6.Cu")
		(net "P5E_PEX3_STN2_TX_DN<32>")
	)
	(gr_poly
		(pts
			(arc
				(start 407.203148 -275.949918)
				(mid 406.796748 -275.949918)
				(end 407.203148 -275.949918)
			)
		)
		(stroke
			(width 0)
			(type solid)
		)
		(fill yes)
		(layer "In6.Cu")
		(net "P5E_PEX3_STN2_RX_DP<32>")
	)
	(gr_poly
		(pts
			(arc
				(start 407.203148 -274.999958)
				(mid 406.796748 -274.999958)
				(end 407.203148 -274.999958)
			)
		)
		(stroke
			(width 0)
			(type solid)
		)
		(fill yes)
		(layer "In6.Cu")
		(net "P5E_PEX3_STN2_RX_DN<32>")
	)
	(gr_poly
		(pts
			(arc
				(start 408.152854 -278.799798)
				(mid 407.746454 -278.799798)
				(end 408.152854 -278.799798)
			)
		)
		(stroke
			(width 0)
			(type solid)
		)
		(fill yes)
		(layer "In6.Cu")
		(net "P5E_PEX3_STN1_TX_DP<16>")
	)
	(gr_poly
		(pts
			(arc
				(start 408.152854 -277.849838)
				(mid 407.746454 -277.849838)
				(end 408.152854 -277.849838)
			)
		)
		(stroke
			(width 0)
			(type solid)
		)
		(fill yes)
		(layer "In6.Cu")
		(net "P5E_PEX3_STN1_TX_DN<16>")
	)
	(gr_poly
		(pts
			(arc
				(start 408.153108 -313.949842)
				(mid 407.746708 -313.949842)
				(end 408.153108 -313.949842)
			)
		)
		(stroke
			(width 0)
			(type solid)
		)
		(fill yes)
		(layer "In6.Cu")
		(net "P5E_PEX3_STN5_TX_DN<81>")
	)
	(gr_poly
		(pts
			(arc
				(start 408.153108 -312.999882)
				(mid 407.746708 -312.999882)
				(end 408.153108 -312.999882)
			)
		)
		(stroke
			(width 0)
			(type solid)
		)
		(fill yes)
		(layer "In6.Cu")
		(net "P5E_PEX3_STN5_TX_DP<81>")
	)
	(gr_poly
		(pts
			(arc
				(start 409.103068 -312.049922)
				(mid 408.696668 -312.049922)
				(end 409.103068 -312.049922)
			)
		)
		(stroke
			(width 0)
			(type solid)
		)
		(fill yes)
		(layer "In6.Cu")
		(net "P5E_PEX3_STN5_TX_DN<82>")
	)
	(gr_poly
		(pts
			(arc
				(start 409.103068 -311.099962)
				(mid 408.696668 -311.099962)
				(end 409.103068 -311.099962)
			)
		)
		(stroke
			(width 0)
			(type solid)
		)
		(fill yes)
		(layer "In6.Cu")
		(net "P5E_PEX3_STN5_TX_DP<82>")
	)
	(gr_poly
		(pts
			(arc
				(start 409.103068 -280.699464)
				(mid 408.696668 -280.699464)
				(end 409.103068 -280.699464)
			)
		)
		(stroke
			(width 0)
			(type solid)
		)
		(fill yes)
		(layer "In6.Cu")
		(net "P5E_PEX3_STN1_TX_DN<17>")
	)
	(gr_poly
		(pts
			(arc
				(start 409.103068 -279.749504)
				(mid 408.696668 -279.749504)
				(end 409.103068 -279.749504)
			)
		)
		(stroke
			(width 0)
			(type solid)
		)
		(fill yes)
		(layer "In6.Cu")
		(net "P5E_PEX3_STN1_TX_DP<17>")
	)
	(gr_poly
		(pts
			(arc
				(start 410.052774 -278.799798)
				(mid 409.646374 -278.799798)
				(end 410.052774 -278.799798)
			)
		)
		(stroke
			(width 0)
			(type solid)
		)
		(fill yes)
		(layer "In6.Cu")
		(net "P5E_PEX3_STN1_TX_DP<18>")
	)
	(gr_poly
		(pts
			(arc
				(start 410.052774 -277.849838)
				(mid 409.646374 -277.849838)
				(end 410.052774 -277.849838)
			)
		)
		(stroke
			(width 0)
			(type solid)
		)
		(fill yes)
		(layer "In6.Cu")
		(net "P5E_PEX3_STN1_TX_DN<18>")
	)
	(gr_poly
		(pts
			(arc
				(start 410.053028 -313.949842)
				(mid 409.646628 -313.949842)
				(end 410.053028 -313.949842)
			)
		)
		(stroke
			(width 0)
			(type solid)
		)
		(fill yes)
		(layer "In6.Cu")
		(net "P5E_PEX3_STN5_TX_DN<83>")
	)
	(gr_poly
		(pts
			(arc
				(start 410.053028 -312.999882)
				(mid 409.646628 -312.999882)
				(end 410.053028 -312.999882)
			)
		)
		(stroke
			(width 0)
			(type solid)
		)
		(fill yes)
		(layer "In6.Cu")
		(net "P5E_PEX3_STN5_TX_DP<83>")
	)
	(gr_poly
		(pts
			(arc
				(start 411.002988 -312.049922)
				(mid 410.596588 -312.049922)
				(end 411.002988 -312.049922)
			)
		)
		(stroke
			(width 0)
			(type solid)
		)
		(fill yes)
		(layer "In6.Cu")
		(net "P5E_PEX3_STN5_TX_DN<84>")
	)
	(gr_poly
		(pts
			(arc
				(start 411.002988 -311.099962)
				(mid 410.596588 -311.099962)
				(end 411.002988 -311.099962)
			)
		)
		(stroke
			(width 0)
			(type solid)
		)
		(fill yes)
		(layer "In6.Cu")
		(net "P5E_PEX3_STN5_TX_DP<84>")
	)
	(gr_poly
		(pts
			(arc
				(start 411.002988 -280.699464)
				(mid 410.596588 -280.699464)
				(end 411.002988 -280.699464)
			)
		)
		(stroke
			(width 0)
			(type solid)
		)
		(fill yes)
		(layer "In6.Cu")
		(net "P5E_PEX3_STN1_TX_DN<19>")
	)
	(gr_poly
		(pts
			(arc
				(start 411.002988 -279.749504)
				(mid 410.596588 -279.749504)
				(end 411.002988 -279.749504)
			)
		)
		(stroke
			(width 0)
			(type solid)
		)
		(fill yes)
		(layer "In6.Cu")
		(net "P5E_PEX3_STN1_TX_DP<19>")
	)
	(gr_poly
		(pts
			(arc
				(start 411.952948 -278.799798)
				(mid 411.546548 -278.799798)
				(end 411.952948 -278.799798)
			)
		)
		(stroke
			(width 0)
			(type solid)
		)
		(fill yes)
		(layer "In6.Cu")
		(net "P5E_PEX3_STN1_TX_DP<20>")
	)
	(gr_poly
		(pts
			(arc
				(start 411.952948 -277.849838)
				(mid 411.546548 -277.849838)
				(end 411.952948 -277.849838)
			)
		)
		(stroke
			(width 0)
			(type solid)
		)
		(fill yes)
		(layer "In6.Cu")
		(net "P5E_PEX3_STN1_TX_DN<20>")
	)
	(gr_poly
		(pts
			(arc
				(start 411.953202 -313.949842)
				(mid 411.546802 -313.949842)
				(end 411.953202 -313.949842)
			)
		)
		(stroke
			(width 0)
			(type solid)
		)
		(fill yes)
		(layer "In6.Cu")
		(net "P5E_PEX3_STN5_TX_DN<85>")
	)
	(gr_poly
		(pts
			(arc
				(start 411.953202 -312.999882)
				(mid 411.546802 -312.999882)
				(end 411.953202 -312.999882)
			)
		)
		(stroke
			(width 0)
			(type solid)
		)
		(fill yes)
		(layer "In6.Cu")
		(net "P5E_PEX3_STN5_TX_DP<85>")
	)
	(gr_poly
		(pts
			(arc
				(start 412.903162 -312.049922)
				(mid 412.496762 -312.049922)
				(end 412.903162 -312.049922)
			)
		)
		(stroke
			(width 0)
			(type solid)
		)
		(fill yes)
		(layer "In6.Cu")
		(net "P5E_PEX3_STN5_TX_DN<86>")
	)
	(gr_poly
		(pts
			(arc
				(start 412.903162 -311.099962)
				(mid 412.496762 -311.099962)
				(end 412.903162 -311.099962)
			)
		)
		(stroke
			(width 0)
			(type solid)
		)
		(fill yes)
		(layer "In6.Cu")
		(net "P5E_PEX3_STN5_TX_DP<86>")
	)
	(gr_poly
		(pts
			(arc
				(start 412.903162 -280.699464)
				(mid 412.496762 -280.699464)
				(end 412.903162 -280.699464)
			)
		)
		(stroke
			(width 0)
			(type solid)
		)
		(fill yes)
		(layer "In6.Cu")
		(net "P5E_PEX3_STN1_TX_DN<21>")
	)
	(gr_poly
		(pts
			(arc
				(start 412.903162 -279.749504)
				(mid 412.496762 -279.749504)
				(end 412.903162 -279.749504)
			)
		)
		(stroke
			(width 0)
			(type solid)
		)
		(fill yes)
		(layer "In6.Cu")
		(net "P5E_PEX3_STN1_TX_DP<21>")
	)
	(gr_poly
		(pts
			(arc
				(start 413.852868 -278.799798)
				(mid 413.446468 -278.799798)
				(end 413.852868 -278.799798)
			)
		)
		(stroke
			(width 0)
			(type solid)
		)
		(fill yes)
		(layer "In6.Cu")
		(net "P5E_PEX3_STN1_TX_DP<22>")
	)
	(gr_poly
		(pts
			(arc
				(start 413.852868 -277.849838)
				(mid 413.446468 -277.849838)
				(end 413.852868 -277.849838)
			)
		)
		(stroke
			(width 0)
			(type solid)
		)
		(fill yes)
		(layer "In6.Cu")
		(net "P5E_PEX3_STN1_TX_DN<22>")
	)
	(gr_poly
		(pts
			(arc
				(start 413.853122 -313.949842)
				(mid 413.446722 -313.949842)
				(end 413.853122 -313.949842)
			)
		)
		(stroke
			(width 0)
			(type solid)
		)
		(fill yes)
		(layer "In6.Cu")
		(net "P5E_PEX3_STN5_TX_DN<87>")
	)
	(gr_poly
		(pts
			(arc
				(start 413.853122 -312.999882)
				(mid 413.446722 -312.999882)
				(end 413.853122 -312.999882)
			)
		)
		(stroke
			(width 0)
			(type solid)
		)
		(fill yes)
		(layer "In6.Cu")
		(net "P5E_PEX3_STN5_TX_DP<87>")
	)
	(gr_poly
		(pts
			(arc
				(start 414.803082 -316.799722)
				(mid 414.396682 -316.799722)
				(end 414.803082 -316.799722)
			)
		)
		(stroke
			(width 0)
			(type solid)
		)
		(fill yes)
		(layer "In6.Cu")
		(net "P5E_PEX3_STN5_RX_DN<88>")
	)
	(gr_poly
		(pts
			(arc
				(start 414.803082 -315.849762)
				(mid 414.396682 -315.849762)
				(end 414.803082 -315.849762)
			)
		)
		(stroke
			(width 0)
			(type solid)
		)
		(fill yes)
		(layer "In6.Cu")
		(net "P5E_PEX3_STN5_RX_DP<88>")
	)
	(gr_poly
		(pts
			(arc
				(start 414.803082 -312.049922)
				(mid 414.396682 -312.049922)
				(end 414.803082 -312.049922)
			)
		)
		(stroke
			(width 0)
			(type solid)
		)
		(fill yes)
		(layer "In6.Cu")
		(net "P5E_PEX3_STN5_TX_DN<88>")
	)
	(gr_poly
		(pts
			(arc
				(start 414.803082 -311.099962)
				(mid 414.396682 -311.099962)
				(end 414.803082 -311.099962)
			)
		)
		(stroke
			(width 0)
			(type solid)
		)
		(fill yes)
		(layer "In6.Cu")
		(net "P5E_PEX3_STN5_TX_DP<88>")
	)
	(gr_poly
		(pts
			(arc
				(start 414.803082 -280.699464)
				(mid 414.396682 -280.699464)
				(end 414.803082 -280.699464)
			)
		)
		(stroke
			(width 0)
			(type solid)
		)
		(fill yes)
		(layer "In6.Cu")
		(net "P5E_PEX3_STN1_TX_DN<23>")
	)
	(gr_poly
		(pts
			(arc
				(start 414.803082 -279.749504)
				(mid 414.396682 -279.749504)
				(end 414.803082 -279.749504)
			)
		)
		(stroke
			(width 0)
			(type solid)
		)
		(fill yes)
		(layer "In6.Cu")
		(net "P5E_PEX3_STN1_TX_DP<23>")
	)
	(gr_poly
		(pts
			(arc
				(start 415.752788 -278.799798)
				(mid 415.346388 -278.799798)
				(end 415.752788 -278.799798)
			)
		)
		(stroke
			(width 0)
			(type solid)
		)
		(fill yes)
		(layer "In6.Cu")
		(net "P5E_PEX3_STN1_TX_DP<24>")
	)
	(gr_poly
		(pts
			(arc
				(start 415.752788 -277.849838)
				(mid 415.346388 -277.849838)
				(end 415.752788 -277.849838)
			)
		)
		(stroke
			(width 0)
			(type solid)
		)
		(fill yes)
		(layer "In6.Cu")
		(net "P5E_PEX3_STN1_TX_DN<24>")
	)
	(gr_poly
		(pts
			(arc
				(start 415.753042 -318.699896)
				(mid 415.346642 -318.699896)
				(end 415.753042 -318.699896)
			)
		)
		(stroke
			(width 0)
			(type solid)
		)
		(fill yes)
		(layer "In6.Cu")
		(net "P5E_PEX3_STN5_RX_DN<89>")
	)
	(gr_poly
		(pts
			(arc
				(start 415.753042 -317.749936)
				(mid 415.346642 -317.749936)
				(end 415.753042 -317.749936)
			)
		)
		(stroke
			(width 0)
			(type solid)
		)
		(fill yes)
		(layer "In6.Cu")
		(net "P5E_PEX3_STN5_RX_DP<89>")
	)
	(gr_poly
		(pts
			(arc
				(start 415.753042 -313.949842)
				(mid 415.346642 -313.949842)
				(end 415.753042 -313.949842)
			)
		)
		(stroke
			(width 0)
			(type solid)
		)
		(fill yes)
		(layer "In6.Cu")
		(net "P5E_PEX3_STN5_TX_DN<89>")
	)
	(gr_poly
		(pts
			(arc
				(start 415.753042 -312.999882)
				(mid 415.346642 -312.999882)
				(end 415.753042 -312.999882)
			)
		)
		(stroke
			(width 0)
			(type solid)
		)
		(fill yes)
		(layer "In6.Cu")
		(net "P5E_PEX3_STN5_TX_DP<89>")
	)
	(gr_poly
		(pts
			(arc
				(start 416.703002 -316.799722)
				(mid 416.296602 -316.799722)
				(end 416.703002 -316.799722)
			)
		)
		(stroke
			(width 0)
			(type solid)
		)
		(fill yes)
		(layer "In6.Cu")
		(net "P5E_PEX3_STN5_RX_DN<90>")
	)
	(gr_poly
		(pts
			(arc
				(start 416.703002 -315.849762)
				(mid 416.296602 -315.849762)
				(end 416.703002 -315.849762)
			)
		)
		(stroke
			(width 0)
			(type solid)
		)
		(fill yes)
		(layer "In6.Cu")
		(net "P5E_PEX3_STN5_RX_DP<90>")
	)
	(gr_poly
		(pts
			(arc
				(start 416.703002 -312.049922)
				(mid 416.296602 -312.049922)
				(end 416.703002 -312.049922)
			)
		)
		(stroke
			(width 0)
			(type solid)
		)
		(fill yes)
		(layer "In6.Cu")
		(net "P5E_PEX3_STN5_TX_DN<90>")
	)
	(gr_poly
		(pts
			(arc
				(start 416.703002 -311.099962)
				(mid 416.296602 -311.099962)
				(end 416.703002 -311.099962)
			)
		)
		(stroke
			(width 0)
			(type solid)
		)
		(fill yes)
		(layer "In6.Cu")
		(net "P5E_PEX3_STN5_TX_DP<90>")
	)
	(gr_poly
		(pts
			(arc
				(start 416.703002 -280.699464)
				(mid 416.296602 -280.699464)
				(end 416.703002 -280.699464)
			)
		)
		(stroke
			(width 0)
			(type solid)
		)
		(fill yes)
		(layer "In6.Cu")
		(net "P5E_PEX3_STN1_TX_DN<25>")
	)
	(gr_poly
		(pts
			(arc
				(start 416.703002 -279.749504)
				(mid 416.296602 -279.749504)
				(end 416.703002 -279.749504)
			)
		)
		(stroke
			(width 0)
			(type solid)
		)
		(fill yes)
		(layer "In6.Cu")
		(net "P5E_PEX3_STN1_TX_DP<25>")
	)
	(gr_poly
		(pts
			(arc
				(start 417.652962 -278.799798)
				(mid 417.246562 -278.799798)
				(end 417.652962 -278.799798)
			)
		)
		(stroke
			(width 0)
			(type solid)
		)
		(fill yes)
		(layer "In6.Cu")
		(net "P5E_PEX3_STN1_TX_DP<26>")
	)
	(gr_poly
		(pts
			(arc
				(start 417.652962 -277.849838)
				(mid 417.246562 -277.849838)
				(end 417.652962 -277.849838)
			)
		)
		(stroke
			(width 0)
			(type solid)
		)
		(fill yes)
		(layer "In6.Cu")
		(net "P5E_PEX3_STN1_TX_DN<26>")
	)
	(gr_poly
		(pts
			(arc
				(start 417.653216 -318.699896)
				(mid 417.246816 -318.699896)
				(end 417.653216 -318.699896)
			)
		)
		(stroke
			(width 0)
			(type solid)
		)
		(fill yes)
		(layer "In6.Cu")
		(net "P5E_PEX3_STN5_RX_DN<91>")
	)
	(gr_poly
		(pts
			(arc
				(start 417.653216 -317.749936)
				(mid 417.246816 -317.749936)
				(end 417.653216 -317.749936)
			)
		)
		(stroke
			(width 0)
			(type solid)
		)
		(fill yes)
		(layer "In6.Cu")
		(net "P5E_PEX3_STN5_RX_DP<91>")
	)
	(gr_poly
		(pts
			(arc
				(start 417.653216 -313.949842)
				(mid 417.246816 -313.949842)
				(end 417.653216 -313.949842)
			)
		)
		(stroke
			(width 0)
			(type solid)
		)
		(fill yes)
		(layer "In6.Cu")
		(net "P5E_PEX3_STN5_TX_DN<91>")
	)
	(gr_poly
		(pts
			(arc
				(start 417.653216 -312.999882)
				(mid 417.246816 -312.999882)
				(end 417.653216 -312.999882)
			)
		)
		(stroke
			(width 0)
			(type solid)
		)
		(fill yes)
		(layer "In6.Cu")
		(net "P5E_PEX3_STN5_TX_DP<91>")
	)
	(gr_poly
		(pts
			(arc
				(start 418.603176 -316.799722)
				(mid 418.196776 -316.799722)
				(end 418.603176 -316.799722)
			)
		)
		(stroke
			(width 0)
			(type solid)
		)
		(fill yes)
		(layer "In6.Cu")
		(net "P5E_PEX3_STN5_RX_DN<92>")
	)
	(gr_poly
		(pts
			(arc
				(start 418.603176 -315.849762)
				(mid 418.196776 -315.849762)
				(end 418.603176 -315.849762)
			)
		)
		(stroke
			(width 0)
			(type solid)
		)
		(fill yes)
		(layer "In6.Cu")
		(net "P5E_PEX3_STN5_RX_DP<92>")
	)
	(gr_poly
		(pts
			(arc
				(start 418.603176 -312.049922)
				(mid 418.196776 -312.049922)
				(end 418.603176 -312.049922)
			)
		)
		(stroke
			(width 0)
			(type solid)
		)
		(fill yes)
		(layer "In6.Cu")
		(net "P5E_PEX3_STN5_TX_DN<92>")
	)
	(gr_poly
		(pts
			(arc
				(start 418.603176 -311.099962)
				(mid 418.196776 -311.099962)
				(end 418.603176 -311.099962)
			)
		)
		(stroke
			(width 0)
			(type solid)
		)
		(fill yes)
		(layer "In6.Cu")
		(net "P5E_PEX3_STN5_TX_DP<92>")
	)
	(gr_poly
		(pts
			(arc
				(start 418.603176 -280.699464)
				(mid 418.196776 -280.699464)
				(end 418.603176 -280.699464)
			)
		)
		(stroke
			(width 0)
			(type solid)
		)
		(fill yes)
		(layer "In6.Cu")
		(net "P5E_PEX3_STN1_TX_DN<27>")
	)
	(gr_poly
		(pts
			(arc
				(start 418.603176 -279.749504)
				(mid 418.196776 -279.749504)
				(end 418.603176 -279.749504)
			)
		)
		(stroke
			(width 0)
			(type solid)
		)
		(fill yes)
		(layer "In6.Cu")
		(net "P5E_PEX3_STN1_TX_DP<27>")
	)
	(gr_poly
		(pts
			(arc
				(start 419.552882 -278.799798)
				(mid 419.146482 -278.799798)
				(end 419.552882 -278.799798)
			)
		)
		(stroke
			(width 0)
			(type solid)
		)
		(fill yes)
		(layer "In6.Cu")
		(net "P5E_PEX3_STN1_TX_DP<28>")
	)
	(gr_poly
		(pts
			(arc
				(start 419.552882 -277.849838)
				(mid 419.146482 -277.849838)
				(end 419.552882 -277.849838)
			)
		)
		(stroke
			(width 0)
			(type solid)
		)
		(fill yes)
		(layer "In6.Cu")
		(net "P5E_PEX3_STN1_TX_DN<28>")
	)
	(gr_poly
		(pts
			(arc
				(start 419.553136 -318.699896)
				(mid 419.146736 -318.699896)
				(end 419.553136 -318.699896)
			)
		)
		(stroke
			(width 0)
			(type solid)
		)
		(fill yes)
		(layer "In6.Cu")
		(net "P5E_PEX3_STN5_RX_DN<93>")
	)
	(gr_poly
		(pts
			(arc
				(start 419.553136 -317.749936)
				(mid 419.146736 -317.749936)
				(end 419.553136 -317.749936)
			)
		)
		(stroke
			(width 0)
			(type solid)
		)
		(fill yes)
		(layer "In6.Cu")
		(net "P5E_PEX3_STN5_RX_DP<93>")
	)
	(gr_poly
		(pts
			(arc
				(start 419.553136 -313.949842)
				(mid 419.146736 -313.949842)
				(end 419.553136 -313.949842)
			)
		)
		(stroke
			(width 0)
			(type solid)
		)
		(fill yes)
		(layer "In6.Cu")
		(net "P5E_PEX3_STN5_TX_DN<93>")
	)
	(gr_poly
		(pts
			(arc
				(start 419.553136 -312.999882)
				(mid 419.146736 -312.999882)
				(end 419.553136 -312.999882)
			)
		)
		(stroke
			(width 0)
			(type solid)
		)
		(fill yes)
		(layer "In6.Cu")
		(net "P5E_PEX3_STN5_TX_DP<93>")
	)
	(gr_poly
		(pts
			(arc
				(start 420.503096 -316.799722)
				(mid 420.096696 -316.799722)
				(end 420.503096 -316.799722)
			)
		)
		(stroke
			(width 0)
			(type solid)
		)
		(fill yes)
		(layer "In6.Cu")
		(net "P5E_PEX3_STN5_RX_DN<94>")
	)
	(gr_poly
		(pts
			(arc
				(start 420.503096 -315.849762)
				(mid 420.096696 -315.849762)
				(end 420.503096 -315.849762)
			)
		)
		(stroke
			(width 0)
			(type solid)
		)
		(fill yes)
		(layer "In6.Cu")
		(net "P5E_PEX3_STN5_RX_DP<94>")
	)
	(gr_poly
		(pts
			(arc
				(start 420.503096 -312.049922)
				(mid 420.096696 -312.049922)
				(end 420.503096 -312.049922)
			)
		)
		(stroke
			(width 0)
			(type solid)
		)
		(fill yes)
		(layer "In6.Cu")
		(net "P5E_PEX3_STN5_TX_DN<94>")
	)
	(gr_poly
		(pts
			(arc
				(start 420.503096 -311.099962)
				(mid 420.096696 -311.099962)
				(end 420.503096 -311.099962)
			)
		)
		(stroke
			(width 0)
			(type solid)
		)
		(fill yes)
		(layer "In6.Cu")
		(net "P5E_PEX3_STN5_TX_DP<94>")
	)
	(gr_poly
		(pts
			(arc
				(start 420.503096 -280.699464)
				(mid 420.096696 -280.699464)
				(end 420.503096 -280.699464)
			)
		)
		(stroke
			(width 0)
			(type solid)
		)
		(fill yes)
		(layer "In6.Cu")
		(net "P5E_PEX3_STN1_TX_DN<29>")
	)
	(gr_poly
		(pts
			(arc
				(start 420.503096 -279.749504)
				(mid 420.096696 -279.749504)
				(end 420.503096 -279.749504)
			)
		)
		(stroke
			(width 0)
			(type solid)
		)
		(fill yes)
		(layer "In6.Cu")
		(net "P5E_PEX3_STN1_TX_DP<29>")
	)
	(gr_poly
		(pts
			(arc
				(start 421.452802 -278.799798)
				(mid 421.046402 -278.799798)
				(end 421.452802 -278.799798)
			)
		)
		(stroke
			(width 0)
			(type solid)
		)
		(fill yes)
		(layer "In6.Cu")
		(net "P5E_PEX3_STN1_TX_DP<30>")
	)
	(gr_poly
		(pts
			(arc
				(start 421.452802 -277.849838)
				(mid 421.046402 -277.849838)
				(end 421.452802 -277.849838)
			)
		)
		(stroke
			(width 0)
			(type solid)
		)
		(fill yes)
		(layer "In6.Cu")
		(net "P5E_PEX3_STN1_TX_DN<30>")
	)
	(gr_poly
		(pts
			(arc
				(start 421.453056 -318.699896)
				(mid 421.046656 -318.699896)
				(end 421.453056 -318.699896)
			)
		)
		(stroke
			(width 0)
			(type solid)
		)
		(fill yes)
		(layer "In6.Cu")
		(net "P5E_PEX3_STN5_RX_DN<95>")
	)
	(gr_poly
		(pts
			(arc
				(start 421.453056 -317.749936)
				(mid 421.046656 -317.749936)
				(end 421.453056 -317.749936)
			)
		)
		(stroke
			(width 0)
			(type solid)
		)
		(fill yes)
		(layer "In6.Cu")
		(net "P5E_PEX3_STN5_RX_DP<95>")
	)
	(gr_poly
		(pts
			(arc
				(start 421.453056 -313.949842)
				(mid 421.046656 -313.949842)
				(end 421.453056 -313.949842)
			)
		)
		(stroke
			(width 0)
			(type solid)
		)
		(fill yes)
		(layer "In6.Cu")
		(net "P5E_PEX3_STN5_TX_DN<95>")
	)
	(gr_poly
		(pts
			(arc
				(start 421.453056 -312.999882)
				(mid 421.046656 -312.999882)
				(end 421.453056 -312.999882)
			)
		)
		(stroke
			(width 0)
			(type solid)
		)
		(fill yes)
		(layer "In6.Cu")
		(net "P5E_PEX3_STN5_TX_DP<95>")
	)
	(gr_poly
		(pts
			(arc
				(start 422.403016 -312.049922)
				(mid 421.996616 -312.049922)
				(end 422.403016 -312.049922)
			)
		)
		(stroke
			(width 0)
			(type solid)
		)
		(fill yes)
		(layer "In6.Cu")
		(net "P5E_PEX3_STN4_TX_DN<79>")
	)
	(gr_poly
		(pts
			(arc
				(start 422.403016 -311.099962)
				(mid 421.996616 -311.099962)
				(end 422.403016 -311.099962)
			)
		)
		(stroke
			(width 0)
			(type solid)
		)
		(fill yes)
		(layer "In6.Cu")
		(net "P5E_PEX3_STN4_TX_DP<79>")
	)
	(gr_poly
		(pts
			(arc
				(start 422.403016 -280.699464)
				(mid 421.996616 -280.699464)
				(end 422.403016 -280.699464)
			)
		)
		(stroke
			(width 0)
			(type solid)
		)
		(fill yes)
		(layer "In6.Cu")
		(net "P5E_PEX3_STN1_TX_DN<31>")
	)
	(gr_poly
		(pts
			(arc
				(start 422.403016 -279.749504)
				(mid 421.996616 -279.749504)
				(end 422.403016 -279.749504)
			)
		)
		(stroke
			(width 0)
			(type solid)
		)
		(fill yes)
		(layer "In6.Cu")
		(net "P5E_PEX3_STN1_TX_DP<31>")
	)
	(gr_poly
		(pts
			(arc
				(start 423.352976 -278.799798)
				(mid 422.946576 -278.799798)
				(end 423.352976 -278.799798)
			)
		)
		(stroke
			(width 0)
			(type solid)
		)
		(fill yes)
		(layer "In6.Cu")
		(net "P5E_PEX3_STN0_TX_DP<15>")
	)
	(gr_poly
		(pts
			(arc
				(start 423.352976 -277.849838)
				(mid 422.946576 -277.849838)
				(end 423.352976 -277.849838)
			)
		)
		(stroke
			(width 0)
			(type solid)
		)
		(fill yes)
		(layer "In6.Cu")
		(net "P5E_PEX3_STN0_TX_DN<15>")
	)
	(gr_poly
		(pts
			(arc
				(start 423.35323 -313.949842)
				(mid 422.94683 -313.949842)
				(end 423.35323 -313.949842)
			)
		)
		(stroke
			(width 0)
			(type solid)
		)
		(fill yes)
		(layer "In6.Cu")
		(net "P5E_PEX3_STN4_TX_DN<78>")
	)
	(gr_poly
		(pts
			(arc
				(start 423.35323 -312.999882)
				(mid 422.94683 -312.999882)
				(end 423.35323 -312.999882)
			)
		)
		(stroke
			(width 0)
			(type solid)
		)
		(fill yes)
		(layer "In6.Cu")
		(net "P5E_PEX3_STN4_TX_DP<78>")
	)
	(gr_poly
		(pts
			(arc
				(start 423.35323 -308.249828)
				(mid 422.94683 -308.249828)
				(end 423.35323 -308.249828)
			)
		)
		(stroke
			(width 0)
			(type solid)
		)
		(fill yes)
		(layer "In6.Cu")
		(net "P5E_PEX3_STN4_TX_DP<68>")
	)
	(gr_poly
		(pts
			(arc
				(start 423.35323 -306.349908)
				(mid 422.94683 -306.349908)
				(end 423.35323 -306.349908)
			)
		)
		(stroke
			(width 0)
			(type solid)
		)
		(fill yes)
		(layer "In6.Cu")
		(net "P5E_PEX3_STN4_TX_DP<66>")
	)
	(gr_poly
		(pts
			(arc
				(start 423.35323 -304.449734)
				(mid 422.94683 -304.449734)
				(end 423.35323 -304.449734)
			)
		)
		(stroke
			(width 0)
			(type solid)
		)
		(fill yes)
		(layer "In6.Cu")
		(net "P5E_PEX3_STN4_TX_DP<64>")
	)
	(gr_poly
		(pts
			(arc
				(start 423.35323 -287.349946)
				(mid 422.94683 -287.349946)
				(end 423.35323 -287.349946)
			)
		)
		(stroke
			(width 0)
			(type solid)
		)
		(fill yes)
		(layer "In6.Cu")
		(net "P5E_PEX3_STN0_TX_DP<1>")
	)
	(gr_poly
		(pts
			(arc
				(start 423.35323 -285.449772)
				(mid 422.94683 -285.449772)
				(end 423.35323 -285.449772)
			)
		)
		(stroke
			(width 0)
			(type solid)
		)
		(fill yes)
		(layer "In6.Cu")
		(net "P5E_PEX3_STN0_TX_DP<3>")
	)
	(gr_poly
		(pts
			(arc
				(start 423.35323 -283.549852)
				(mid 422.94683 -283.549852)
				(end 423.35323 -283.549852)
			)
		)
		(stroke
			(width 0)
			(type solid)
		)
		(fill yes)
		(layer "In6.Cu")
		(net "P5E_PEX3_STN0_TX_DP<5>")
	)
	(gr_poly
		(pts
			(arc
				(start 424.30319 -312.049922)
				(mid 423.89679 -312.049922)
				(end 424.30319 -312.049922)
			)
		)
		(stroke
			(width 0)
			(type solid)
		)
		(fill yes)
		(layer "In6.Cu")
		(net "P5E_PEX3_STN4_TX_DN<77>")
	)
	(gr_poly
		(pts
			(arc
				(start 424.30319 -311.099962)
				(mid 423.89679 -311.099962)
				(end 424.30319 -311.099962)
			)
		)
		(stroke
			(width 0)
			(type solid)
		)
		(fill yes)
		(layer "In6.Cu")
		(net "P5E_PEX3_STN4_TX_DP<77>")
	)
	(gr_poly
		(pts
			(arc
				(start 424.30319 -308.249828)
				(mid 423.89679 -308.249828)
				(end 424.30319 -308.249828)
			)
		)
		(stroke
			(width 0)
			(type solid)
		)
		(fill yes)
		(layer "In6.Cu")
		(net "P5E_PEX3_STN4_TX_DN<68>")
	)
	(gr_poly
		(pts
			(arc
				(start 424.30319 -306.349908)
				(mid 423.89679 -306.349908)
				(end 424.30319 -306.349908)
			)
		)
		(stroke
			(width 0)
			(type solid)
		)
		(fill yes)
		(layer "In6.Cu")
		(net "P5E_PEX3_STN4_TX_DN<66>")
	)
	(gr_poly
		(pts
			(arc
				(start 424.30319 -304.449734)
				(mid 423.89679 -304.449734)
				(end 424.30319 -304.449734)
			)
		)
		(stroke
			(width 0)
			(type solid)
		)
		(fill yes)
		(layer "In6.Cu")
		(net "P5E_PEX3_STN4_TX_DN<64>")
	)
	(gr_poly
		(pts
			(arc
				(start 424.30319 -287.349946)
				(mid 423.89679 -287.349946)
				(end 424.30319 -287.349946)
			)
		)
		(stroke
			(width 0)
			(type solid)
		)
		(fill yes)
		(layer "In6.Cu")
		(net "P5E_PEX3_STN0_TX_DN<1>")
	)
	(gr_poly
		(pts
			(arc
				(start 424.30319 -285.449772)
				(mid 423.89679 -285.449772)
				(end 424.30319 -285.449772)
			)
		)
		(stroke
			(width 0)
			(type solid)
		)
		(fill yes)
		(layer "In6.Cu")
		(net "P5E_PEX3_STN0_TX_DN<3>")
	)
	(gr_poly
		(pts
			(arc
				(start 424.30319 -283.549852)
				(mid 423.89679 -283.549852)
				(end 424.30319 -283.549852)
			)
		)
		(stroke
			(width 0)
			(type solid)
		)
		(fill yes)
		(layer "In6.Cu")
		(net "P5E_PEX3_STN0_TX_DN<5>")
	)
	(gr_poly
		(pts
			(arc
				(start 424.30319 -280.699464)
				(mid 423.89679 -280.699464)
				(end 424.30319 -280.699464)
			)
		)
		(stroke
			(width 0)
			(type solid)
		)
		(fill yes)
		(layer "In6.Cu")
		(net "P5E_PEX3_STN0_TX_DN<14>")
	)
	(gr_poly
		(pts
			(arc
				(start 424.30319 -279.749504)
				(mid 423.89679 -279.749504)
				(end 424.30319 -279.749504)
			)
		)
		(stroke
			(width 0)
			(type solid)
		)
		(fill yes)
		(layer "In6.Cu")
		(net "P5E_PEX3_STN0_TX_DP<14>")
	)
	(gr_poly
		(pts
			(arc
				(start 425.252896 -278.799798)
				(mid 424.846496 -278.799798)
				(end 425.252896 -278.799798)
			)
		)
		(stroke
			(width 0)
			(type solid)
		)
		(fill yes)
		(layer "In6.Cu")
		(net "P5E_PEX3_STN0_TX_DP<13>")
	)
	(gr_poly
		(pts
			(arc
				(start 425.252896 -277.849838)
				(mid 424.846496 -277.849838)
				(end 425.252896 -277.849838)
			)
		)
		(stroke
			(width 0)
			(type solid)
		)
		(fill yes)
		(layer "In6.Cu")
		(net "P5E_PEX3_STN0_TX_DN<13>")
	)
	(gr_poly
		(pts
			(arc
				(start 425.25315 -313.949842)
				(mid 424.84675 -313.949842)
				(end 425.25315 -313.949842)
			)
		)
		(stroke
			(width 0)
			(type solid)
		)
		(fill yes)
		(layer "In6.Cu")
		(net "P5E_PEX3_STN4_TX_DN<76>")
	)
	(gr_poly
		(pts
			(arc
				(start 425.25315 -312.999882)
				(mid 424.84675 -312.999882)
				(end 425.25315 -312.999882)
			)
		)
		(stroke
			(width 0)
			(type solid)
		)
		(fill yes)
		(layer "In6.Cu")
		(net "P5E_PEX3_STN4_TX_DP<76>")
	)
	(gr_poly
		(pts
			(arc
				(start 425.25315 -309.199788)
				(mid 424.84675 -309.199788)
				(end 425.25315 -309.199788)
			)
		)
		(stroke
			(width 0)
			(type solid)
		)
		(fill yes)
		(layer "In6.Cu")
		(net "P5E_PEX3_STN4_TX_DP<69>")
	)
	(gr_poly
		(pts
			(arc
				(start 425.25315 -307.299868)
				(mid 424.84675 -307.299868)
				(end 425.25315 -307.299868)
			)
		)
		(stroke
			(width 0)
			(type solid)
		)
		(fill yes)
		(layer "In6.Cu")
		(net "P5E_PEX3_STN4_TX_DP<67>")
	)
	(gr_poly
		(pts
			(arc
				(start 425.25315 -305.399948)
				(mid 424.84675 -305.399948)
				(end 425.25315 -305.399948)
			)
		)
		(stroke
			(width 0)
			(type solid)
		)
		(fill yes)
		(layer "In6.Cu")
		(net "P5E_PEX3_STN4_TX_DP<65>")
	)
	(gr_poly
		(pts
			(arc
				(start 425.25315 -288.299906)
				(mid 424.84675 -288.299906)
				(end 425.25315 -288.299906)
			)
		)
		(stroke
			(width 0)
			(type solid)
		)
		(fill yes)
		(layer "In6.Cu")
		(net "P5E_PEX3_STN0_TX_DP<0>")
	)
	(gr_poly
		(pts
			(arc
				(start 425.25315 -286.399986)
				(mid 424.84675 -286.399986)
				(end 425.25315 -286.399986)
			)
		)
		(stroke
			(width 0)
			(type solid)
		)
		(fill yes)
		(layer "In6.Cu")
		(net "P5E_PEX3_STN0_TX_DP<2>")
	)
	(gr_poly
		(pts
			(arc
				(start 425.25315 -284.499812)
				(mid 424.84675 -284.499812)
				(end 425.25315 -284.499812)
			)
		)
		(stroke
			(width 0)
			(type solid)
		)
		(fill yes)
		(layer "In6.Cu")
		(net "P5E_PEX3_STN0_TX_DP<4>")
	)
	(gr_poly
		(pts
			(arc
				(start 425.25315 -282.599892)
				(mid 424.84675 -282.599892)
				(end 425.25315 -282.599892)
			)
		)
		(stroke
			(width 0)
			(type solid)
		)
		(fill yes)
		(layer "In6.Cu")
		(net "P5E_PEX3_STN0_TX_DP<6>")
	)
	(gr_poly
		(pts
			(arc
				(start 426.20311 -312.049922)
				(mid 425.79671 -312.049922)
				(end 426.20311 -312.049922)
			)
		)
		(stroke
			(width 0)
			(type solid)
		)
		(fill yes)
		(layer "In6.Cu")
		(net "P5E_PEX3_STN4_TX_DN<75>")
	)
	(gr_poly
		(pts
			(arc
				(start 426.20311 -311.099962)
				(mid 425.79671 -311.099962)
				(end 426.20311 -311.099962)
			)
		)
		(stroke
			(width 0)
			(type solid)
		)
		(fill yes)
		(layer "In6.Cu")
		(net "P5E_PEX3_STN4_TX_DP<75>")
	)
	(gr_poly
		(pts
			(arc
				(start 426.20311 -309.199788)
				(mid 425.79671 -309.199788)
				(end 426.20311 -309.199788)
			)
		)
		(stroke
			(width 0)
			(type solid)
		)
		(fill yes)
		(layer "In6.Cu")
		(net "P5E_PEX3_STN4_TX_DN<69>")
	)
	(gr_poly
		(pts
			(arc
				(start 426.20311 -307.299868)
				(mid 425.79671 -307.299868)
				(end 426.20311 -307.299868)
			)
		)
		(stroke
			(width 0)
			(type solid)
		)
		(fill yes)
		(layer "In6.Cu")
		(net "P5E_PEX3_STN4_TX_DN<67>")
	)
	(gr_poly
		(pts
			(arc
				(start 426.20311 -305.399948)
				(mid 425.79671 -305.399948)
				(end 426.20311 -305.399948)
			)
		)
		(stroke
			(width 0)
			(type solid)
		)
		(fill yes)
		(layer "In6.Cu")
		(net "P5E_PEX3_STN4_TX_DN<65>")
	)
	(gr_poly
		(pts
			(arc
				(start 426.20311 -288.299906)
				(mid 425.79671 -288.299906)
				(end 426.20311 -288.299906)
			)
		)
		(stroke
			(width 0)
			(type solid)
		)
		(fill yes)
		(layer "In6.Cu")
		(net "P5E_PEX3_STN0_TX_DN<0>")
	)
	(gr_poly
		(pts
			(arc
				(start 426.20311 -286.399986)
				(mid 425.79671 -286.399986)
				(end 426.20311 -286.399986)
			)
		)
		(stroke
			(width 0)
			(type solid)
		)
		(fill yes)
		(layer "In6.Cu")
		(net "P5E_PEX3_STN0_TX_DN<2>")
	)
	(gr_poly
		(pts
			(arc
				(start 426.20311 -284.499812)
				(mid 425.79671 -284.499812)
				(end 426.20311 -284.499812)
			)
		)
		(stroke
			(width 0)
			(type solid)
		)
		(fill yes)
		(layer "In6.Cu")
		(net "P5E_PEX3_STN0_TX_DN<4>")
	)
	(gr_poly
		(pts
			(arc
				(start 426.20311 -282.599892)
				(mid 425.79671 -282.599892)
				(end 426.20311 -282.599892)
			)
		)
		(stroke
			(width 0)
			(type solid)
		)
		(fill yes)
		(layer "In6.Cu")
		(net "P5E_PEX3_STN0_TX_DN<6>")
	)
	(gr_poly
		(pts
			(arc
				(start 426.20311 -280.699464)
				(mid 425.79671 -280.699464)
				(end 426.20311 -280.699464)
			)
		)
		(stroke
			(width 0)
			(type solid)
		)
		(fill yes)
		(layer "In6.Cu")
		(net "P5E_PEX3_STN0_TX_DN<12>")
	)
	(gr_poly
		(pts
			(arc
				(start 426.20311 -279.749504)
				(mid 425.79671 -279.749504)
				(end 426.20311 -279.749504)
			)
		)
		(stroke
			(width 0)
			(type solid)
		)
		(fill yes)
		(layer "In6.Cu")
		(net "P5E_PEX3_STN0_TX_DP<12>")
	)
	(gr_poly
		(pts
			(arc
				(start 427.152816 -278.799798)
				(mid 426.746416 -278.799798)
				(end 427.152816 -278.799798)
			)
		)
		(stroke
			(width 0)
			(type solid)
		)
		(fill yes)
		(layer "In6.Cu")
		(net "P5E_PEX3_STN0_TX_DP<11>")
	)
	(gr_poly
		(pts
			(arc
				(start 427.152816 -277.849838)
				(mid 426.746416 -277.849838)
				(end 427.152816 -277.849838)
			)
		)
		(stroke
			(width 0)
			(type solid)
		)
		(fill yes)
		(layer "In6.Cu")
		(net "P5E_PEX3_STN0_TX_DN<11>")
	)
	(gr_poly
		(pts
			(arc
				(start 427.15307 -313.949842)
				(mid 426.74667 -313.949842)
				(end 427.15307 -313.949842)
			)
		)
		(stroke
			(width 0)
			(type solid)
		)
		(fill yes)
		(layer "In6.Cu")
		(net "P5E_PEX3_STN4_TX_DN<74>")
	)
	(gr_poly
		(pts
			(arc
				(start 427.15307 -312.999882)
				(mid 426.74667 -312.999882)
				(end 427.15307 -312.999882)
			)
		)
		(stroke
			(width 0)
			(type solid)
		)
		(fill yes)
		(layer "In6.Cu")
		(net "P5E_PEX3_STN4_TX_DP<74>")
	)
	(gr_poly
		(pts
			(arc
				(start 428.10303 -312.049922)
				(mid 427.69663 -312.049922)
				(end 428.10303 -312.049922)
			)
		)
		(stroke
			(width 0)
			(type solid)
		)
		(fill yes)
		(layer "In6.Cu")
		(net "P5E_PEX3_STN4_TX_DN<73>")
	)
	(gr_poly
		(pts
			(arc
				(start 428.10303 -311.099962)
				(mid 427.69663 -311.099962)
				(end 428.10303 -311.099962)
			)
		)
		(stroke
			(width 0)
			(type solid)
		)
		(fill yes)
		(layer "In6.Cu")
		(net "P5E_PEX3_STN4_TX_DP<73>")
	)
	(gr_poly
		(pts
			(arc
				(start 428.10303 -280.699718)
				(mid 427.69663 -280.699718)
				(end 428.10303 -280.699718)
			)
		)
		(stroke
			(width 0)
			(type solid)
		)
		(fill yes)
		(layer "In6.Cu")
		(net "P5E_PEX3_STN0_TX_DP<10>")
	)
	(gr_poly
		(pts
			(arc
				(start 428.10303 -279.749758)
				(mid 427.69663 -279.749758)
				(end 428.10303 -279.749758)
			)
		)
		(stroke
			(width 0)
			(type solid)
		)
		(fill yes)
		(layer "In6.Cu")
		(net "P5E_PEX3_STN0_TX_DN<10>")
	)
	(gr_poly
		(pts
			(arc
				(start 429.05299 -313.949842)
				(mid 428.64659 -313.949842)
				(end 429.05299 -313.949842)
			)
		)
		(stroke
			(width 0)
			(type solid)
		)
		(fill yes)
		(layer "In6.Cu")
		(net "P5E_PEX3_STN4_TX_DN<72>")
	)
	(gr_poly
		(pts
			(arc
				(start 429.05299 -312.999882)
				(mid 428.64659 -312.999882)
				(end 429.05299 -312.999882)
			)
		)
		(stroke
			(width 0)
			(type solid)
		)
		(fill yes)
		(layer "In6.Cu")
		(net "P5E_PEX3_STN4_TX_DP<72>")
	)
	(gr_poly
		(pts
			(arc
				(start 429.05299 -278.799798)
				(mid 428.64659 -278.799798)
				(end 429.05299 -278.799798)
			)
		)
		(stroke
			(width 0)
			(type solid)
		)
		(fill yes)
		(layer "In6.Cu")
		(net "P5E_PEX3_STN0_TX_DP<9>")
	)
	(gr_poly
		(pts
			(arc
				(start 429.05299 -277.849838)
				(mid 428.64659 -277.849838)
				(end 429.05299 -277.849838)
			)
		)
		(stroke
			(width 0)
			(type solid)
		)
		(fill yes)
		(layer "In6.Cu")
		(net "P5E_PEX3_STN0_TX_DN<9>")
	)
	(gr_poly
		(pts
			(arc
				(start 430.003204 -314.899802)
				(mid 429.596804 -314.899802)
				(end 430.003204 -314.899802)
			)
		)
		(stroke
			(width 0)
			(type solid)
		)
		(fill yes)
		(layer "In6.Cu")
		(net "P5E_PEX3_STN4_TX_DP<71>")
	)
	(gr_poly
		(pts
			(arc
				(start 430.003204 -312.049922)
				(mid 429.596804 -312.049922)
				(end 430.003204 -312.049922)
			)
		)
		(stroke
			(width 0)
			(type solid)
		)
		(fill yes)
		(layer "In6.Cu")
		(net "P5E_PEX3_STN4_TX_DP<70>")
	)
	(gr_poly
		(pts
			(arc
				(start 430.003204 -279.749758)
				(mid 429.596804 -279.749758)
				(end 430.003204 -279.749758)
			)
		)
		(stroke
			(width 0)
			(type solid)
		)
		(fill yes)
		(layer "In6.Cu")
		(net "P5E_PEX3_STN0_TX_DP<7>")
	)
	(gr_poly
		(pts
			(arc
				(start 430.003204 -276.899878)
				(mid 429.596804 -276.899878)
				(end 430.003204 -276.899878)
			)
		)
		(stroke
			(width 0)
			(type solid)
		)
		(fill yes)
		(layer "In6.Cu")
		(net "P5E_PEX3_STN0_TX_DP<8>")
	)
	(gr_poly
		(pts
			(arc
				(start 430.953164 -314.899802)
				(mid 430.546764 -314.899802)
				(end 430.953164 -314.899802)
			)
		)
		(stroke
			(width 0)
			(type solid)
		)
		(fill yes)
		(layer "In6.Cu")
		(net "P5E_PEX3_STN4_TX_DN<71>")
	)
	(gr_poly
		(pts
			(arc
				(start 430.953164 -312.049922)
				(mid 430.546764 -312.049922)
				(end 430.953164 -312.049922)
			)
		)
		(stroke
			(width 0)
			(type solid)
		)
		(fill yes)
		(layer "In6.Cu")
		(net "P5E_PEX3_STN4_TX_DN<70>")
	)
	(gr_poly
		(pts
			(arc
				(start 430.953164 -279.749758)
				(mid 430.546764 -279.749758)
				(end 430.953164 -279.749758)
			)
		)
		(stroke
			(width 0)
			(type solid)
		)
		(fill yes)
		(layer "In6.Cu")
		(net "P5E_PEX3_STN0_TX_DN<7>")
	)
	(gr_poly
		(pts
			(arc
				(start 430.953164 -276.899878)
				(mid 430.546764 -276.899878)
				(end 430.953164 -276.899878)
			)
		)
		(stroke
			(width 0)
			(type solid)
		)
		(fill yes)
		(layer "In6.Cu")
		(net "P5E_PEX3_STN0_TX_DN<8>")
	)
	(gr_poly
		(pts
			(arc
				(start 241.741198 -376.399806)
				(mid 241.763367 -376.39459)
				(end 241.781076 -376.380248)
			)
			(arc
				(start 241.781076 -376.380248)
				(mid 241.793461 -376.365378)
				(end 241.80673 -376.351292)
			)
			(xy 242.08994 -376.068082)
			(arc
				(start 242.09502 -376.063002)
				(mid 242.106647 -376.046325)
				(end 242.110768 -376.026426)
			)
			(arc
				(start 242.110768 -368.666268)
				(mid 242.106867 -368.646745)
				(end 242.095782 -368.6302)
			)
			(arc
				(start 241.977672 -368.51209)
				(mid 241.961138 -368.500979)
				(end 241.941604 -368.497104)
			)
			(arc
				(start 236.370368 -368.497104)
				(mid 236.350845 -368.501005)
				(end 236.3343 -368.51209)
			)
			(arc
				(start 236.123734 -368.722656)
				(mid 236.112623 -368.73919)
				(end 236.108748 -368.758724)
			)
			(arc
				(start 236.108748 -376.146314)
				(mid 236.112649 -376.165837)
				(end 236.123734 -376.182382)
			)
			(arc
				(start 236.326172 -376.38482)
				(mid 236.342706 -376.395931)
				(end 236.36224 -376.399806)
			)
		)
		(stroke
			(width 0)
			(type solid)
		)
		(fill yes)
		(layer "In6.Cu")
		(net "P12V_STBY_R1")
	)
	(gr_poly
		(pts
			(arc
				(start 235.60151 -413.087058)
				(mid 235.621033 -413.083157)
				(end 235.637578 -413.072072)
			)
			(arc
				(start 236.756956 -411.952694)
				(mid 236.768067 -411.93616)
				(end 236.771942 -411.916626)
			)
			(arc
				(start 236.771942 -402.84527)
				(mid 236.796095 -402.723754)
				(end 236.864906 -402.620734)
			)
			(arc
				(start 238.766604 -400.719036)
				(mid 238.869636 -400.650255)
				(end 238.99114 -400.626072)
			)
			(arc
				(start 242.910868 -400.626072)
				(mid 242.930391 -400.622171)
				(end 242.946936 -400.611086)
			)
			(arc
				(start 243.79682 -399.761202)
				(mid 243.807931 -399.744668)
				(end 243.811806 -399.725134)
			)
			(arc
				(start 243.811806 -392.09472)
				(mid 243.835959 -391.973204)
				(end 243.90477 -391.870184)
			)
			(arc
				(start 244.93093 -390.844024)
				(mid 245.033962 -390.775243)
				(end 245.155466 -390.75106)
			)
			(arc
				(start 259.056124 -390.75106)
				(mid 259.075647 -390.747159)
				(end 259.092192 -390.736074)
			)
			(arc
				(start 262.00481 -387.823456)
				(mid 262.015921 -387.806922)
				(end 262.019796 -387.787388)
			)
			(arc
				(start 262.019796 -379.197616)
				(mid 262.015895 -379.178093)
				(end 262.00481 -379.161548)
			)
			(arc
				(start 261.967472 -379.12421)
				(mid 261.950938 -379.113099)
				(end 261.931404 -379.109224)
			)
			(arc
				(start 240.584482 -379.109224)
				(mid 240.564959 -379.113125)
				(end 240.548414 -379.12421)
			)
			(arc
				(start 239.998504 -379.67412)
				(mid 239.895472 -379.742901)
				(end 239.773968 -379.767084)
			)
			(arc
				(start 237.129066 -379.767084)
				(mid 237.00755 -379.742931)
				(end 236.90453 -379.67412)
			)
			(arc
				(start 232.953814 -375.723404)
				(mid 232.885033 -375.620372)
				(end 232.86085 -375.498868)
			)
			(arc
				(start 232.86085 -372.11508)
				(mid 232.856949 -372.095557)
				(end 232.845864 -372.079012)
			)
			(arc
				(start 232.203752 -371.4369)
				(mid 232.134971 -371.333868)
				(end 232.110788 -371.212364)
			)
			(arc
				(start 232.110788 -371.075712)
				(mid 232.106887 -371.056189)
				(end 232.095802 -371.039644)
			)
			(arc
				(start 232.035858 -370.9797)
				(mid 231.967077 -370.876668)
				(end 231.942894 -370.755164)
			)
			(arc
				(start 231.942894 -367.397792)
				(mid 231.938993 -367.378269)
				(end 231.927908 -367.361724)
			)
			(arc
				(start 231.89057 -367.324386)
				(mid 231.874036 -367.313275)
				(end 231.854502 -367.3094)
			)
			(arc
				(start 228.741986 -367.3094)
				(mid 228.722463 -367.313301)
				(end 228.705918 -367.324386)
			)
			(arc
				(start 228.66858 -367.361724)
				(mid 228.657469 -367.378258)
				(end 228.653594 -367.397792)
			)
			(arc
				(start 228.653594 -370.74856)
				(mid 228.629441 -370.870076)
				(end 228.56063 -370.973096)
			)
			(arc
				(start 228.481128 -371.052598)
				(mid 228.470017 -371.069132)
				(end 228.466142 -371.088666)
			)
			(arc
				(start 228.466142 -371.354096)
				(mid 228.441989 -371.475612)
				(end 228.373178 -371.578632)
			)
			(arc
				(start 227.178362 -372.773448)
				(mid 227.167251 -372.789982)
				(end 227.163376 -372.809516)
			)
			(arc
				(start 227.163376 -374.166384)
				(mid 227.139223 -374.2879)
				(end 227.070412 -374.39092)
			)
			(arc
				(start 225.794062 -375.66727)
				(mid 225.69103 -375.736051)
				(end 225.569526 -375.760234)
			)
			(arc
				(start 223.648016 -375.760234)
				(mid 223.5265 -375.736081)
				(end 223.42348 -375.66727)
			)
			(arc
				(start 221.55531 -373.7991)
				(mid 221.486529 -373.696068)
				(end 221.462346 -373.574564)
			)
			(arc
				(start 221.462346 -371.091714)
				(mid 221.458445 -371.072191)
				(end 221.44736 -371.055646)
			)
			(arc
				(start 221.361508 -370.969794)
				(mid 221.292727 -370.866762)
				(end 221.268544 -370.745258)
			)
			(arc
				(start 221.268544 -367.391442)
				(mid 221.264643 -367.371919)
				(end 221.253558 -367.355374)
			)
			(arc
				(start 221.225872 -367.327688)
				(mid 221.209338 -367.316577)
				(end 221.189804 -367.312702)
			)
			(arc
				(start 218.110308 -367.312702)
				(mid 218.090785 -367.316603)
				(end 218.07424 -367.327688)
			)
			(arc
				(start 217.967306 -367.434622)
				(mid 217.956195 -367.451156)
				(end 217.95232 -367.47069)
			)
			(arc
				(start 217.95232 -370.719096)
				(mid 217.928167 -370.840612)
				(end 217.859356 -370.943632)
			)
			(arc
				(start 216.82964 -371.973348)
				(mid 216.726608 -372.042129)
				(end 216.605104 -372.066312)
			)
			(arc
				(start 210.424014 -372.066312)
				(mid 210.302498 -372.042159)
				(end 210.199478 -371.973348)
			)
			(arc
				(start 210.067906 -371.841776)
				(mid 209.999125 -371.738744)
				(end 209.974942 -371.61724)
			)
			(arc
				(start 209.974942 -371.309138)
				(mid 209.971041 -371.289615)
				(end 209.959956 -371.27307)
			)
			(arc
				(start 209.949034 -371.262148)
				(mid 209.9325 -371.251037)
				(end 209.912966 -371.247162)
			)
			(arc
				(start 209.559144 -371.247162)
				(mid 209.437628 -371.223009)
				(end 209.334608 -371.154198)
			)
			(arc
				(start 208.669382 -370.488972)
				(mid 208.652848 -370.477861)
				(end 208.633314 -370.473986)
			)
			(arc
				(start 208.394554 -370.473986)
				(mid 208.273038 -370.449833)
				(end 208.170018 -370.381022)
			)
			(arc
				(start 208.11744 -370.328444)
				(mid 208.048659 -370.225412)
				(end 208.024476 -370.103908)
			)
			(arc
				(start 208.024476 -367.401348)
				(mid 208.020575 -367.381825)
				(end 208.00949 -367.36528)
			)
			(arc
				(start 207.981804 -367.337594)
				(mid 207.96527 -367.326483)
				(end 207.945736 -367.322608)
			)
			(arc
				(start 204.823822 -367.322608)
				(mid 204.804299 -367.326509)
				(end 204.787754 -367.337594)
			)
			(arc
				(start 204.740002 -367.385346)
				(mid 204.728891 -367.40188)
				(end 204.725016 -367.421414)
			)
			(arc
				(start 204.725016 -370.796312)
				(mid 204.728917 -370.815835)
				(end 204.740002 -370.83238)
			)
			(arc
				(start 204.77353 -370.865908)
				(mid 204.842311 -370.96894)
				(end 204.866494 -371.090444)
			)
			(arc
				(start 204.866494 -374.47474)
				(mid 204.870058 -374.493432)
				(end 204.88021 -374.509538)
			)
			(arc
				(start 204.88021 -374.509538)
				(mid 204.94326 -374.609679)
				(end 204.9653 -374.725946)
			)
			(arc
				(start 204.9653 -387.02361)
				(mid 204.969201 -387.043133)
				(end 204.980286 -387.059678)
			)
			(arc
				(start 207.47482 -389.554212)
				(mid 207.543601 -389.657244)
				(end 207.567784 -389.778748)
			)
			(arc
				(start 207.567784 -411.696662)
				(mid 207.571685 -411.716185)
				(end 207.58277 -411.73273)
			)
			(arc
				(start 208.922112 -413.072072)
				(mid 208.938646 -413.083183)
				(end 208.95818 -413.087058)
			)
		)
		(stroke
			(width 0)
			(type solid)
		)
		(fill yes)
		(layer "In6.Cu")
		(net "P12V_STBY")
	)
	(gr_poly
		(pts
			(xy 465.600034 -461.99552) (xy 465.655841 -461.994997) (xy 465.767141 -461.986654) (xy 465.877508 -461.970017)
			(xy 465.986322 -461.945179) (xy 466.092976 -461.912278) (xy 466.196873 -461.8715) (xy 466.297432 -461.823072)
			(xy 466.394091 -461.767264) (xy 466.48631 -461.70439) (xy 466.573572 -461.6348) (xy 466.65539 -461.558883)
			(xy 466.731306 -461.477065) (xy 466.800896 -461.389802) (xy 466.86377 -461.297583) (xy 466.919577 -461.200923)
			(xy 466.968004 -461.100364) (xy 467.008782 -460.996466) (xy 467.041681 -460.889812) (xy 467.066519 -460.780998)
			(xy 467.083155 -460.670631) (xy 467.091497 -460.559331) (xy 467.09203 -460.503524) (xy 467.09203 -422.58996)
			(xy 467.091507 -422.534153) (xy 467.083163 -422.422853) (xy 467.066526 -422.312487) (xy 467.041687 -422.203672)
			(xy 467.008787 -422.097019) (xy 466.968009 -421.993121) (xy 466.91958 -421.892562) (xy 466.863773 -421.795903)
			(xy 466.800898 -421.703684) (xy 466.731308 -421.616422) (xy 466.655392 -421.534604) (xy 466.573573 -421.458688)
			(xy 466.486311 -421.389098) (xy 466.394092 -421.326224) (xy 466.297433 -421.270417) (xy 466.196873 -421.221989)
			(xy 466.092976 -421.181211) (xy 465.986322 -421.148311) (xy 465.877508 -421.123473) (xy 465.767141 -421.106836)
			(xy 465.655841 -421.098493) (xy 465.600034 -421.097964) (xy 447.939922 -421.097964) (xy 447.884114 -421.098485)
			(xy 447.77281 -421.106824) (xy 447.66244 -421.123458) (xy 447.553622 -421.148293) (xy 447.446964 -421.181191)
			(xy 447.343062 -421.221967) (xy 447.242499 -421.270394) (xy 447.145835 -421.3262) (xy 447.053613 -421.389074)
			(xy 446.966346 -421.458664) (xy 446.884524 -421.53458) (xy 446.808604 -421.616399) (xy 446.739011 -421.703663)
			(xy 446.676133 -421.795883) (xy 446.620323 -421.892544) (xy 446.571892 -421.993106) (xy 446.531111 -422.097005)
			(xy 446.498209 -422.203662) (xy 446.47337 -422.312479) (xy 446.456731 -422.422848) (xy 446.448387 -422.534152)
			(xy 446.447926 -422.58996) (xy 446.447926 -429.090074) (xy 446.447433 -429.160429) (xy 446.439545 -429.300916)
			(xy 446.423792 -429.440741) (xy 446.400224 -429.579462) (xy 446.368915 -429.716643) (xy 446.329963 -429.851854)
			(xy 446.283491 -429.984667) (xy 446.229646 -430.114666) (xy 446.168596 -430.241441) (xy 446.100533 -430.364593)
			(xy 446.025673 -430.483736) (xy 445.94425 -430.598494) (xy 445.856521 -430.708505) (xy 445.762761 -430.813425)
			(xy 445.663266 -430.912922) (xy 445.558348 -431.006684) (xy 445.448338 -431.094416) (xy 445.333582 -431.175842)
			(xy 445.214442 -431.250705) (xy 445.091291 -431.31877) (xy 444.964517 -431.379823) (xy 444.834519 -431.433671)
			(xy 444.701707 -431.480146) (xy 444.566498 -431.519101) (xy 444.429317 -431.550413) (xy 444.290596 -431.573985)
			(xy 444.150772 -431.589741) (xy 444.010285 -431.597632) (xy 443.93993 -431.59807) (xy 371.24005 -431.59807)
			(xy 371.169695 -431.597587) (xy 371.029207 -431.5897) (xy 370.889383 -431.573948) (xy 370.750661 -431.550381)
			(xy 370.613479 -431.519072) (xy 370.478269 -431.480121) (xy 370.345455 -431.433649) (xy 370.215456 -431.379804)
			(xy 370.088681 -431.318754) (xy 369.965528 -431.250691) (xy 369.846385 -431.175831) (xy 369.731628 -431.094407)
			(xy 369.621616 -431.006677) (xy 369.516697 -430.912917) (xy 369.4172 -430.813421) (xy 369.323438 -430.708502)
			(xy 369.235707 -430.598492) (xy 369.154283 -430.483735) (xy 369.079421 -430.364593) (xy 369.011357 -430.241441)
			(xy 368.950306 -430.114666) (xy 368.896459 -429.984667) (xy 368.849986 -429.851854) (xy 368.811034 -429.716644)
			(xy 368.779724 -429.579463) (xy 368.756155 -429.440741) (xy 368.740402 -429.300917) (xy 368.732514 -429.160429)
			(xy 368.732054 -429.090074) (xy 368.732054 -422.58996) (xy 368.731543 -422.534154) (xy 368.7232 -422.422854)
			(xy 368.706562 -422.31249) (xy 368.681723 -422.203677) (xy 368.648822 -422.097024) (xy 368.608042 -421.993129)
			(xy 368.559613 -421.892571) (xy 368.503804 -421.795914) (xy 368.440929 -421.703697) (xy 368.371337 -421.616438)
			(xy 368.29542 -421.534622) (xy 368.2136 -421.458709) (xy 368.126337 -421.389123) (xy 368.034117 -421.326252)
			(xy 367.937456 -421.270449) (xy 367.836896 -421.222025) (xy 367.732998 -421.181251) (xy 367.626344 -421.148356)
			(xy 367.51753 -421.123523) (xy 367.407164 -421.106891) (xy 367.295864 -421.098554) (xy 367.240058 -421.097964)
			(xy 359.940098 -421.097964) (xy 359.88429 -421.098486) (xy 359.772988 -421.106827) (xy 359.662619 -421.123462)
			(xy 359.553802 -421.148298) (xy 359.447146 -421.181197) (xy 359.343246 -421.221974) (xy 359.242684 -421.270401)
			(xy 359.146022 -421.326208) (xy 359.053801 -421.389082) (xy 358.966536 -421.458672) (xy 358.884716 -421.534589)
			(xy 358.808797 -421.616407) (xy 358.739205 -421.70367) (xy 358.676328 -421.79589) (xy 358.620519 -421.892551)
			(xy 358.572089 -421.993111) (xy 358.53131 -422.09701) (xy 358.498408 -422.203666) (xy 358.473569 -422.312482)
			(xy 358.456931 -422.42285) (xy 358.448587 -422.534152) (xy 358.448102 -422.58996) (xy 358.448102 -429.090074)
			(xy 358.447618 -429.160429) (xy 358.43973 -429.300916) (xy 358.423977 -429.440741) (xy 358.400409 -429.579462)
			(xy 358.369099 -429.716643) (xy 358.330147 -429.851853) (xy 358.283675 -429.984667) (xy 358.229829 -430.114665)
			(xy 358.168779 -430.24144) (xy 358.100716 -430.364593) (xy 358.025856 -430.483735) (xy 357.944432 -430.598492)
			(xy 357.856702 -430.708504) (xy 357.762942 -430.813423) (xy 357.663446 -430.91292) (xy 357.558528 -431.006682)
			(xy 357.448518 -431.094413) (xy 357.333762 -431.175838) (xy 357.21462 -431.2507) (xy 357.091469 -431.318764)
			(xy 356.964695 -431.379816) (xy 356.834697 -431.433664) (xy 356.701884 -431.480138) (xy 356.566674 -431.519091)
			(xy 356.429493 -431.550403) (xy 356.290772 -431.573973) (xy 356.150948 -431.589728) (xy 356.010461 -431.597618)
			(xy 355.940106 -431.59807) (xy 283.239972 -431.59807) (xy 283.169619 -431.597576) (xy 283.029135 -431.589685)
			(xy 282.889313 -431.573929) (xy 282.750596 -431.550359) (xy 282.613418 -431.519047) (xy 282.478212 -431.480093)
			(xy 282.345402 -431.43362) (xy 282.215407 -431.379772) (xy 282.088636 -431.318721) (xy 281.965488 -431.250657)
			(xy 281.84635 -431.175796) (xy 281.731596 -431.094372) (xy 281.621589 -431.006642) (xy 281.516674 -430.912882)
			(xy 281.417181 -430.813387) (xy 281.323423 -430.70847) (xy 281.235695 -430.598461) (xy 281.154274 -430.483705)
			(xy 281.079415 -430.364565) (xy 281.011354 -430.241416) (xy 280.950306 -430.114643) (xy 280.896461 -429.984647)
			(xy 280.84999 -429.851837) (xy 280.811039 -429.71663) (xy 280.779731 -429.579451) (xy 280.756163 -429.440733)
			(xy 280.740411 -429.300912) (xy 280.732523 -429.160427) (xy 280.731976 -429.090074) (xy 280.731976 -422.58996)
			(xy 280.731453 -422.534154) (xy 280.723109 -422.422855) (xy 280.706471 -422.31249) (xy 280.681633 -422.203678)
			(xy 280.648732 -422.097025) (xy 280.607953 -421.99313) (xy 280.559525 -421.892573) (xy 280.503717 -421.795915)
			(xy 280.440842 -421.703699) (xy 280.371251 -421.616439) (xy 280.295334 -421.534623) (xy 280.213516 -421.45871)
			(xy 280.126253 -421.389123) (xy 280.034034 -421.326251) (xy 279.937374 -421.270447) (xy 279.836815 -421.222023)
			(xy 279.732918 -421.181248) (xy 279.626264 -421.148352) (xy 279.517451 -421.123517) (xy 279.407085 -421.106884)
			(xy 279.295786 -421.098545) (xy 279.23998 -421.097964) (xy 276.880066 -421.097964) (xy 276.824259 -421.098487)
			(xy 276.712958 -421.10683) (xy 276.602591 -421.123467) (xy 276.493777 -421.148305) (xy 276.387122 -421.181205)
			(xy 276.283225 -421.221984) (xy 276.182665 -421.270412) (xy 276.086005 -421.326219) (xy 275.993786 -421.389094)
			(xy 275.906523 -421.458684) (xy 275.824704 -421.5346) (xy 275.748787 -421.616418) (xy 275.679197 -421.703681)
			(xy 275.616322 -421.7959) (xy 275.560514 -421.892559) (xy 275.512086 -421.993119) (xy 275.471307 -422.097017)
			(xy 275.438407 -422.203671) (xy 275.413568 -422.312485) (xy 275.396931 -422.422852) (xy 275.388587 -422.534153)
			(xy 275.38807 -422.58996) (xy 275.38807 -430.55794) (xy 275.387576 -430.628293) (xy 275.379684 -430.768777)
			(xy 275.363928 -430.908597) (xy 275.340357 -431.047314) (xy 275.309045 -431.184492) (xy 275.27009 -431.319698)
			(xy 275.223616 -431.452506) (xy 275.169769 -431.582501) (xy 275.108717 -431.709271) (xy 275.040653 -431.832419)
			(xy 274.965792 -431.951557) (xy 274.884368 -432.066309) (xy 274.796638 -432.176316) (xy 274.702878 -432.281231)
			(xy 274.603383 -432.380723) (xy 274.498466 -432.474481) (xy 274.388457 -432.562208) (xy 274.273702 -432.643629)
			(xy 274.154562 -432.718487) (xy 274.031412 -432.786547) (xy 273.90464 -432.847596) (xy 273.774645 -432.90144)
			(xy 273.641835 -432.94791) (xy 273.506628 -432.986861) (xy 273.36945 -433.018169) (xy 273.230732 -433.041737)
			(xy 273.090911 -433.05749) (xy 272.950427 -433.065377) (xy 272.880074 -433.065936) (xy 202.360022 -433.065936)
			(xy 202.289667 -433.065443) (xy 202.14918 -433.057555) (xy 202.009355 -433.041802) (xy 201.870634 -433.018234)
			(xy 201.733452 -432.986924) (xy 201.598242 -432.947972) (xy 201.465429 -432.9015) (xy 201.33543 -432.847655)
			(xy 201.208655 -432.786605) (xy 201.085502 -432.718542) (xy 200.96636 -432.643682) (xy 200.851602 -432.562259)
			(xy 200.74159 -432.47453) (xy 200.63667 -432.38077) (xy 200.537173 -432.281275) (xy 200.44341 -432.176357)
			(xy 200.355678 -432.066348) (xy 200.274252 -431.951592) (xy 200.199389 -431.832451) (xy 200.131324 -431.7093)
			(xy 200.070271 -431.582527) (xy 200.016422 -431.452529) (xy 199.969947 -431.319717) (xy 199.930991 -431.184508)
			(xy 199.899679 -431.047327) (xy 199.876107 -430.908606) (xy 199.86035 -430.768782) (xy 199.852458 -430.628295)
			(xy 199.852026 -430.55794) (xy 199.852026 -422.58996) (xy 199.851503 -422.534154) (xy 199.843159 -422.422853)
			(xy 199.826522 -422.312487) (xy 199.801683 -422.203673) (xy 199.768783 -422.097019) (xy 199.728004 -421.993122)
			(xy 199.679576 -421.892563) (xy 199.623769 -421.795904) (xy 199.560894 -421.703685) (xy 199.491304 -421.616423)
			(xy 199.415387 -421.534606) (xy 199.333569 -421.45869) (xy 199.246306 -421.3891) (xy 199.154088 -421.326226)
			(xy 199.057428 -421.270419) (xy 198.956869 -421.221992) (xy 198.852972 -421.181214) (xy 198.746318 -421.148314)
			(xy 198.637503 -421.123476) (xy 198.527137 -421.10684) (xy 198.415836 -421.098497) (xy 198.36003 -421.097964)
			(xy 188.36005 -421.097964) (xy 188.304244 -421.098488) (xy 188.192943 -421.106832) (xy 188.082578 -421.12347)
			(xy 187.973764 -421.148309) (xy 187.86711 -421.18121) (xy 187.763214 -421.221988) (xy 187.662655 -421.270417)
			(xy 187.565996 -421.326225) (xy 187.473778 -421.389099) (xy 187.386516 -421.458689) (xy 187.304699 -421.534606)
			(xy 187.228783 -421.616424) (xy 187.159193 -421.703686) (xy 187.096319 -421.795905) (xy 187.040512 -421.892564)
			(xy 186.992084 -421.993123) (xy 186.951306 -422.09702) (xy 186.918406 -422.203673) (xy 186.893568 -422.312487)
			(xy 186.876931 -422.422853) (xy 186.868587 -422.534154) (xy 186.868054 -422.58996) (xy 186.868054 -429.090074)
			(xy 186.86757 -429.160428) (xy 186.859682 -429.300915) (xy 186.843929 -429.440738) (xy 186.820361 -429.579458)
			(xy 186.789051 -429.716639) (xy 186.750099 -429.851848) (xy 186.703626 -429.98466) (xy 186.64978 -430.114658)
			(xy 186.58873 -430.241431) (xy 186.520667 -430.364582) (xy 186.445806 -430.483723) (xy 186.364382 -430.598479)
			(xy 186.276652 -430.708489) (xy 186.182891 -430.813407) (xy 186.083395 -430.912902) (xy 185.978477 -431.006662)
			(xy 185.868467 -431.094392) (xy 185.75371 -431.175815) (xy 185.634569 -431.250675) (xy 185.511417 -431.318737)
			(xy 185.384643 -431.379787) (xy 185.254645 -431.433632) (xy 185.121833 -431.480104) (xy 184.986623 -431.519055)
			(xy 184.849443 -431.550364) (xy 184.710722 -431.573931) (xy 184.570899 -431.589684) (xy 184.430412 -431.597571)
			(xy 184.360058 -431.59807) (xy 111.660178 -431.59807) (xy 111.589825 -431.597585) (xy 111.449339 -431.589694)
			(xy 111.309518 -431.573939) (xy 111.170799 -431.550369) (xy 111.033621 -431.519057) (xy 110.898414 -431.480103)
			(xy 110.765603 -431.43363) (xy 110.635608 -431.379782) (xy 110.508836 -431.318731) (xy 110.385687 -431.250667)
			(xy 110.266548 -431.175806) (xy 110.151794 -431.094382) (xy 110.041786 -431.006651) (xy 109.93687 -430.912891)
			(xy 109.837376 -430.813395) (xy 109.743618 -430.708478) (xy 109.65589 -430.598468) (xy 109.574468 -430.483712)
			(xy 109.499608 -430.364572) (xy 109.431547 -430.241421) (xy 109.370498 -430.114648) (xy 109.316653 -429.984652)
			(xy 109.270182 -429.851841) (xy 109.231231 -429.716633) (xy 109.199922 -429.579454) (xy 109.176354 -429.440735)
			(xy 109.160602 -429.300913) (xy 109.152714 -429.160427) (xy 109.152182 -429.090074) (xy 109.152182 -422.58996)
			(xy 109.151659 -422.534154) (xy 109.143315 -422.422855) (xy 109.126678 -422.31249) (xy 109.101839 -422.203677)
			(xy 109.068938 -422.097025) (xy 109.02816 -421.993129) (xy 108.979731 -421.892571) (xy 108.923923 -421.795914)
			(xy 108.861048 -421.703697) (xy 108.791457 -421.616437) (xy 108.715541 -421.534621) (xy 108.633722 -421.458707)
			(xy 108.546459 -421.38912) (xy 108.45424 -421.326248) (xy 108.357581 -421.270444) (xy 108.257021 -421.222019)
			(xy 108.153124 -421.181244) (xy 108.046471 -421.148347) (xy 107.937657 -421.123512) (xy 107.827292 -421.106879)
			(xy 107.715992 -421.098539) (xy 107.660186 -421.097964) (xy 100.359972 -421.097964) (xy 100.304165 -421.098487)
			(xy 100.192864 -421.106829) (xy 100.082497 -421.123466) (xy 99.973681 -421.148304) (xy 99.867027 -421.181204)
			(xy 99.763129 -421.221982) (xy 99.662568 -421.27041) (xy 99.565908 -421.326217) (xy 99.473689 -421.389091)
			(xy 99.386425 -421.458681) (xy 99.304606 -421.534598) (xy 99.228689 -421.616416) (xy 99.159099 -421.703679)
			(xy 99.096223 -421.795898) (xy 99.040415 -421.892558) (xy 98.991987 -421.993118) (xy 98.951208 -422.097015)
			(xy 98.918307 -422.20367) (xy 98.893468 -422.312485) (xy 98.876831 -422.422852) (xy 98.868487 -422.534153)
			(xy 98.867976 -422.58996) (xy 98.867976 -429.090074) (xy 98.867492 -429.160428) (xy 98.859604 -429.300915)
			(xy 98.843851 -429.440739) (xy 98.820283 -429.57946) (xy 98.788973 -429.716641) (xy 98.750021 -429.85185)
			(xy 98.703549 -429.984663) (xy 98.649703 -430.114661) (xy 98.588652 -430.241435) (xy 98.520589 -430.364587)
			(xy 98.445729 -430.483729) (xy 98.364305 -430.598485) (xy 98.276575 -430.708496) (xy 98.182814 -430.813414)
			(xy 98.083319 -430.91291) (xy 97.9784 -431.006671) (xy 97.86839 -431.094401) (xy 97.753634 -431.175825)
			(xy 97.634492 -431.250686) (xy 97.511341 -431.31875) (xy 97.384567 -431.3798) (xy 97.254569 -431.433647)
			(xy 97.121756 -431.480119) (xy 96.986547 -431.519072) (xy 96.849366 -431.550382) (xy 96.710645 -431.57395)
			(xy 96.570821 -431.589704) (xy 96.430334 -431.597592) (xy 96.35998 -431.59807) (xy 23.6601 -431.59807)
			(xy 23.589746 -431.597586) (xy 23.44926 -431.589696) (xy 23.309437 -431.573942) (xy 23.170718 -431.550372)
			(xy 23.033539 -431.519062) (xy 22.89833 -431.480109) (xy 22.765519 -431.433636) (xy 22.635522 -431.379789)
			(xy 22.50875 -431.318738) (xy 22.385599 -431.250675) (xy 22.266459 -431.175813) (xy 22.151704 -431.094389)
			(xy 22.041695 -431.006659) (xy 21.936778 -430.912899) (xy 21.837283 -430.813403) (xy 21.743524 -430.708485)
			(xy 21.655795 -430.598475) (xy 21.574372 -430.483719) (xy 21.499512 -430.364578) (xy 21.43145 -430.241427)
			(xy 21.370401 -430.114654) (xy 21.316555 -429.984657) (xy 21.270083 -429.851845) (xy 21.231132 -429.716636)
			(xy 21.199823 -429.579456) (xy 21.176255 -429.440737) (xy 21.160502 -429.300914) (xy 21.152614 -429.160428)
			(xy 21.152104 -429.090074) (xy 21.152104 -422.58996) (xy 21.151595 -422.534153) (xy 21.143254 -422.42285)
			(xy 21.126618 -422.312481) (xy 21.101782 -422.203665) (xy 21.068883 -422.097009) (xy 21.028105 -421.993109)
			(xy 20.979677 -421.892548) (xy 20.92387 -421.795886) (xy 20.860995 -421.703666) (xy 20.791404 -421.616402)
			(xy 20.715486 -421.534582) (xy 20.633667 -421.458665) (xy 20.546403 -421.389074) (xy 20.454182 -421.326199)
			(xy 20.357521 -421.270392) (xy 20.256959 -421.221964) (xy 20.153059 -421.181187) (xy 20.046403 -421.148288)
			(xy 19.937587 -421.123451) (xy 19.827218 -421.106816) (xy 19.715915 -421.098475) (xy 19.660108 -421.097964)
			(xy 1.999996 -421.097964) (xy 1.944189 -421.098486) (xy 1.832887 -421.106827) (xy 1.72252 -421.123463)
			(xy 1.613705 -421.148299) (xy 1.50705 -421.181198) (xy 1.403151 -421.221976) (xy 1.302591 -421.270403)
			(xy 1.20593 -421.32621) (xy 1.113711 -421.389085) (xy 1.026448 -421.458675) (xy 0.944629 -421.534592)
			(xy 0.868712 -421.616411) (xy 0.799122 -421.703674) (xy 0.736248 -421.795894) (xy 0.680441 -421.892554)
			(xy 0.632014 -421.993115) (xy 0.591237 -422.097013) (xy 0.558338 -422.203669) (xy 0.533502 -422.312484)
			(xy 0.516867 -422.422851) (xy 0.508526 -422.534153) (xy 0.508 -422.58996) (xy 0.508 -457.5681) (xy 2.904225 -457.5681)
			(xy 2.904225 -457.43896) (xy 2.912175 -457.310065) (xy 2.928045 -457.181905) (xy 2.951774 -457.054964)
			(xy 2.983273 -456.929725) (xy 3.022422 -456.806662) (xy 3.069073 -456.686243) (xy 3.123048 -456.568924)
			(xy 3.184143 -456.45515) (xy 3.252126 -456.345353) (xy 3.32674 -456.23995) (xy 3.407701 -456.13934)
			(xy 3.494701 -456.043905) (xy 3.587412 -455.954006) (xy 3.685482 -455.869985) (xy 3.788537 -455.792161)
			(xy 3.896188 -455.720829) (xy 4.008027 -455.656259) (xy 4.123628 -455.598697) (xy 4.242553 -455.54836)
			(xy 4.364352 -455.50544) (xy 4.488562 -455.470099) (xy 4.614711 -455.442472) (xy 4.742323 -455.422663)
			(xy 4.870912 -455.410747) (xy 4.99999 -455.406771) (xy 5.129068 -455.410747) (xy 5.257657 -455.422663)
			(xy 5.385269 -455.442472) (xy 5.511418 -455.470099) (xy 5.635628 -455.50544) (xy 5.757427 -455.54836)
			(xy 5.876352 -455.598697) (xy 5.991953 -455.656259) (xy 6.103792 -455.720829) (xy 6.211443 -455.792161)
			(xy 6.314498 -455.869985) (xy 6.412568 -455.954006) (xy 6.505279 -456.043905) (xy 6.592279 -456.13934)
			(xy 6.67324 -456.23995) (xy 6.747854 -456.345353) (xy 6.815837 -456.45515) (xy 6.876932 -456.568924)
			(xy 6.930907 -456.686243) (xy 6.977558 -456.806662) (xy 7.016707 -456.929725) (xy 7.048206 -457.054964)
			(xy 7.071935 -457.181905) (xy 7.087805 -457.310065) (xy 7.095755 -457.43896) (xy 7.096252 -457.50353)
			(xy 7.095755 -457.5681) (xy 460.504275 -457.5681) (xy 460.504275 -457.43896) (xy 460.512225 -457.310065)
			(xy 460.528095 -457.181905) (xy 460.551824 -457.054964) (xy 460.583323 -456.929725) (xy 460.622472 -456.806662)
			(xy 460.669123 -456.686243) (xy 460.723098 -456.568924) (xy 460.784193 -456.45515) (xy 460.852176 -456.345353)
			(xy 460.92679 -456.23995) (xy 461.007751 -456.13934) (xy 461.094751 -456.043905) (xy 461.187462 -455.954006)
			(xy 461.285532 -455.869985) (xy 461.388587 -455.792161) (xy 461.496238 -455.720829) (xy 461.608077 -455.656259)
			(xy 461.723678 -455.598697) (xy 461.842603 -455.54836) (xy 461.964402 -455.50544) (xy 462.088612 -455.470099)
			(xy 462.214761 -455.442472) (xy 462.342373 -455.422663) (xy 462.470962 -455.410747) (xy 462.60004 -455.406771)
			(xy 462.729118 -455.410747) (xy 462.857707 -455.422663) (xy 462.985319 -455.442472) (xy 463.111468 -455.470099)
			(xy 463.235678 -455.50544) (xy 463.357477 -455.54836) (xy 463.476402 -455.598697) (xy 463.592003 -455.656259)
			(xy 463.703842 -455.720829) (xy 463.811493 -455.792161) (xy 463.914548 -455.869985) (xy 464.012618 -455.954006)
			(xy 464.105329 -456.043905) (xy 464.192329 -456.13934) (xy 464.27329 -456.23995) (xy 464.347904 -456.345353)
			(xy 464.415887 -456.45515) (xy 464.476982 -456.568924) (xy 464.530957 -456.686243) (xy 464.577608 -456.806662)
			(xy 464.616757 -456.929725) (xy 464.648256 -457.054964) (xy 464.671985 -457.181905) (xy 464.687855 -457.310065)
			(xy 464.695805 -457.43896) (xy 464.696302 -457.50353) (xy 464.695805 -457.5681) (xy 464.687855 -457.696995)
			(xy 464.671985 -457.825155) (xy 464.648256 -457.952096) (xy 464.616757 -458.077335) (xy 464.577608 -458.200398)
			(xy 464.530957 -458.320817) (xy 464.476982 -458.438136) (xy 464.415887 -458.55191) (xy 464.347904 -458.661707)
			(xy 464.27329 -458.76711) (xy 464.192329 -458.86772) (xy 464.105329 -458.963155) (xy 464.012618 -459.053054)
			(xy 463.914548 -459.137075) (xy 463.811493 -459.214899) (xy 463.703842 -459.286231) (xy 463.592003 -459.350801)
			(xy 463.476402 -459.408363) (xy 463.357477 -459.4587) (xy 463.235678 -459.50162) (xy 463.111468 -459.536961)
			(xy 462.985319 -459.564588) (xy 462.857707 -459.584397) (xy 462.729118 -459.596313) (xy 462.60004 -459.60029)
			(xy 462.470962 -459.596313) (xy 462.342373 -459.584397) (xy 462.214761 -459.564588) (xy 462.088612 -459.536961)
			(xy 461.964402 -459.50162) (xy 461.842603 -459.4587) (xy 461.723678 -459.408363) (xy 461.608077 -459.350801)
			(xy 461.496238 -459.286231) (xy 461.388587 -459.214899) (xy 461.285532 -459.137075) (xy 461.187462 -459.053054)
			(xy 461.094751 -458.963155) (xy 461.007751 -458.86772) (xy 460.92679 -458.76711) (xy 460.852176 -458.661707)
			(xy 460.784193 -458.55191) (xy 460.723098 -458.438136) (xy 460.669123 -458.320817) (xy 460.622472 -458.200398)
			(xy 460.583323 -458.077335) (xy 460.551824 -457.952096) (xy 460.528095 -457.825155) (xy 460.512225 -457.696995)
			(xy 460.504275 -457.5681) (xy 7.095755 -457.5681) (xy 7.087805 -457.696995) (xy 7.071935 -457.825155)
			(xy 7.048206 -457.952096) (xy 7.016707 -458.077335) (xy 6.977558 -458.200398) (xy 6.930907 -458.320817)
			(xy 6.876932 -458.438136) (xy 6.815837 -458.55191) (xy 6.747854 -458.661707) (xy 6.67324 -458.76711)
			(xy 6.592279 -458.86772) (xy 6.505279 -458.963155) (xy 6.412568 -459.053054) (xy 6.314498 -459.137075)
			(xy 6.211443 -459.214899) (xy 6.103792 -459.286231) (xy 5.991953 -459.350801) (xy 5.876352 -459.408363)
			(xy 5.757427 -459.4587) (xy 5.635628 -459.50162) (xy 5.511418 -459.536961) (xy 5.385269 -459.564588)
			(xy 5.257657 -459.584397) (xy 5.129068 -459.596313) (xy 4.99999 -459.60029) (xy 4.870912 -459.596313)
			(xy 4.742323 -459.584397) (xy 4.614711 -459.564588) (xy 4.488562 -459.536961) (xy 4.364352 -459.50162)
			(xy 4.242553 -459.4587) (xy 4.123628 -459.408363) (xy 4.008027 -459.350801) (xy 3.896188 -459.286231)
			(xy 3.788537 -459.214899) (xy 3.685482 -459.137075) (xy 3.587412 -459.053054) (xy 3.494701 -458.963155)
			(xy 3.407701 -458.86772) (xy 3.32674 -458.76711) (xy 3.252126 -458.661707) (xy 3.184143 -458.55191)
			(xy 3.123048 -458.438136) (xy 3.069073 -458.320817) (xy 3.022422 -458.200398) (xy 2.983273 -458.077335)
			(xy 2.951774 -457.952096) (xy 2.928045 -457.825155) (xy 2.912175 -457.696995) (xy 2.904225 -457.5681)
			(xy 0.508 -457.5681) (xy 0.508 -460.503524) (xy 0.508522 -460.559331) (xy 0.516863 -460.670633) (xy 0.533498 -460.781)
			(xy 0.558335 -460.889816) (xy 0.591234 -460.996471) (xy 0.632011 -461.10037) (xy 0.680438 -461.20093)
			(xy 0.736246 -461.297591) (xy 0.79912 -461.389811) (xy 0.86871 -461.477074) (xy 0.944627 -461.558893)
			(xy 1.026446 -461.63481) (xy 1.113709 -461.7044) (xy 1.205929 -461.767274) (xy 1.30259 -461.823082)
			(xy 1.40315 -461.871509) (xy 1.507049 -461.912286) (xy 1.613704 -461.945185) (xy 1.72252 -461.970022)
			(xy 1.832887 -461.986657) (xy 1.944189 -461.994998) (xy 1.999996 -461.99552)
		)
		(stroke
			(width 0)
			(type solid)
		)
		(fill yes)
		(layer "In6.Cu")
		(net "COUPON_GND1")
	)
	(gr_poly
		(pts
			(xy 13.96492 -10.342118) (xy 14.020727 -10.341596) (xy 14.132028 -10.333253) (xy 14.242395 -10.316617)
			(xy 14.35121 -10.29178) (xy 14.457865 -10.25888) (xy 14.561763 -10.218102) (xy 14.662323 -10.169674)
			(xy 14.758983 -10.113867) (xy 14.851203 -10.050993) (xy 14.938466 -9.981402) (xy 15.020284 -9.905486)
			(xy 15.096201 -9.823667) (xy 15.165791 -9.736404) (xy 15.228666 -9.644185) (xy 15.284473 -9.547525)
			(xy 15.332901 -9.446965) (xy 15.373679 -9.343067) (xy 15.406579 -9.236412) (xy 15.431417 -9.127597)
			(xy 15.448053 -9.01723) (xy 15.456395 -8.905929) (xy 15.456916 -8.850122) (xy 15.456916 0) (xy 15.4574 0.070354)
			(xy 15.46529 0.21084) (xy 15.481044 0.350663) (xy 15.504614 0.489383) (xy 15.535924 0.626563) (xy 15.574877 0.761771)
			(xy 15.62135 0.894583) (xy 15.675197 1.02458) (xy 15.736248 1.151353) (xy 15.804311 1.274504) (xy 15.879172 1.393644)
			(xy 15.960596 1.5084) (xy 16.048326 1.618409) (xy 16.142086 1.723327) (xy 16.241582 1.822822) (xy 16.3465 1.916582)
			(xy 16.45651 2.004311) (xy 16.571266 2.085734) (xy 16.690407 2.160595) (xy 16.813558 2.228658) (xy 16.940331 2.289708)
			(xy 17.070328 2.343554) (xy 17.20314 2.390026) (xy 17.338349 2.428979) (xy 17.475529 2.460289) (xy 17.614249 2.483858)
			(xy 17.754072 2.499611) (xy 17.894558 2.5075) (xy 17.964912 2.507996) (xy 33.96488 2.507996) (xy 34.035234 2.507512)
			(xy 34.175722 2.499624) (xy 34.315546 2.48387) (xy 34.454267 2.460302) (xy 34.591448 2.428992) (xy 34.726657 2.39004)
			(xy 34.85947 2.343568) (xy 34.989468 2.289721) (xy 35.116243 2.228671) (xy 35.239395 2.160608) (xy 35.358537 2.085747)
			(xy 35.473294 2.004324) (xy 35.583304 1.916594) (xy 35.688223 1.822833) (xy 35.78772 1.723338) (xy 35.881481 1.61842)
			(xy 35.969212 1.50841) (xy 36.050636 1.393653) (xy 36.125498 1.274512) (xy 36.193562 1.151361) (xy 36.254613 1.024587)
			(xy 36.30846 0.894589) (xy 36.354934 0.761776) (xy 36.393887 0.626567) (xy 36.425198 0.489386) (xy 36.448768 0.350666)
			(xy 36.464522 0.210842) (xy 36.472412 0.070354) (xy 36.472876 0) (xy 36.472876 -8.850122) (xy 36.473399 -8.905929)
			(xy 36.481741 -9.01723) (xy 36.498377 -9.127597) (xy 36.523215 -9.236413) (xy 36.556114 -9.343067)
			(xy 36.596892 -9.446965) (xy 36.64532 -9.547526) (xy 36.701127 -9.644186) (xy 36.764002 -9.736405)
			(xy 36.833592 -9.823668) (xy 36.909508 -9.905487) (xy 36.991327 -9.981404) (xy 37.07859 -10.050995)
			(xy 37.170809 -10.113869) (xy 37.267469 -10.169677) (xy 37.368029 -10.218105) (xy 37.471927 -10.258884)
			(xy 37.578582 -10.291784) (xy 37.687397 -10.316622) (xy 37.797764 -10.333258) (xy 37.909065 -10.341601)
			(xy 37.964872 -10.342118) (xy 39.965122 -10.342118) (xy 40.020929 -10.341595) (xy 40.13223 -10.333253)
			(xy 40.242597 -10.316617) (xy 40.351412 -10.291779) (xy 40.458067 -10.258879) (xy 40.561964 -10.218102)
			(xy 40.662525 -10.169674) (xy 40.759184 -10.113866) (xy 40.851404 -10.050992) (xy 40.938667 -9.981402)
			(xy 41.020485 -9.905485) (xy 41.096402 -9.823667) (xy 41.165992 -9.736404) (xy 41.228866 -9.644184)
			(xy 41.284674 -9.547525) (xy 41.333102 -9.446964) (xy 41.373879 -9.343067) (xy 41.406779 -9.236412)
			(xy 41.431617 -9.127597) (xy 41.448253 -9.01723) (xy 41.456595 -8.905929) (xy 41.457118 -8.850122)
			(xy 41.457118 0) (xy 41.457602 0.070354) (xy 41.465492 0.21084) (xy 41.481246 0.350663) (xy 41.504816 0.489383)
			(xy 41.536126 0.626563) (xy 41.575079 0.761771) (xy 41.621552 0.894583) (xy 41.675399 1.02458) (xy 41.73645 1.151353)
			(xy 41.804513 1.274503) (xy 41.879374 1.393644) (xy 41.960798 1.508399) (xy 42.048528 1.618409) (xy 42.142288 1.723326)
			(xy 42.241784 1.822821) (xy 42.346702 1.916581) (xy 42.456712 2.00431) (xy 42.571468 2.085733) (xy 42.690609 2.160594)
			(xy 42.81376 2.228657) (xy 42.940533 2.289707) (xy 43.07053 2.343553) (xy 43.203342 2.390025) (xy 43.338551 2.428977)
			(xy 43.475731 2.460287) (xy 43.614451 2.483856) (xy 43.754274 2.499609) (xy 43.89476 2.507498) (xy 43.965114 2.507996)
			(xy 59.965082 2.507996) (xy 60.035436 2.507512) (xy 60.175924 2.499624) (xy 60.315748 2.48387) (xy 60.454468 2.460301)
			(xy 60.591649 2.428992) (xy 60.726859 2.390039) (xy 60.859672 2.343567) (xy 60.98967 2.289721) (xy 61.116444 2.22867)
			(xy 61.239596 2.160607) (xy 61.358738 2.085747) (xy 61.473495 2.004323) (xy 61.583505 1.916593) (xy 61.688424 1.822833)
			(xy 61.78792 1.723337) (xy 61.881681 1.618419) (xy 61.969412 1.508409) (xy 62.050837 1.393653) (xy 62.125698 1.274512)
			(xy 62.193762 1.15136) (xy 62.254813 1.024586) (xy 62.308661 0.894588) (xy 62.355134 0.761776) (xy 62.394087 0.626567)
			(xy 62.425398 0.489386) (xy 62.448968 0.350665) (xy 62.464722 0.210842) (xy 62.472612 0.070354) (xy 62.473078 0)
			(xy 62.473078 -8.850122) (xy 62.473601 -8.905929) (xy 62.481943 -9.01723) (xy 62.498579 -9.127597)
			(xy 62.523417 -9.236412) (xy 62.556316 -9.343067) (xy 62.597094 -9.446965) (xy 62.645522 -9.547525)
			(xy 62.701329 -9.644185) (xy 62.764204 -9.736405) (xy 62.833794 -9.823668) (xy 62.909711 -9.905487)
			(xy 62.991529 -9.981403) (xy 63.078792 -10.050994) (xy 63.171011 -10.113868) (xy 63.267671 -10.169676)
			(xy 63.368231 -10.218104) (xy 63.472129 -10.258882) (xy 63.578784 -10.291782) (xy 63.687599 -10.31662)
			(xy 63.797966 -10.333257) (xy 63.909267 -10.341599) (xy 63.965074 -10.342118) (xy 65.96507 -10.342118)
			(xy 66.020879 -10.34161) (xy 66.132184 -10.333271) (xy 66.242554 -10.316637) (xy 66.351373 -10.291802)
			(xy 66.458032 -10.258905) (xy 66.561934 -10.218128) (xy 66.662499 -10.169702) (xy 66.759163 -10.113895)
			(xy 66.851386 -10.05102) (xy 66.938653 -9.98143) (xy 67.020476 -9.905512) (xy 67.096396 -9.823693)
			(xy 67.165989 -9.736428) (xy 67.228867 -9.644207) (xy 67.284677 -9.547545) (xy 67.333108 -9.446982)
			(xy 67.373888 -9.343081) (xy 67.406789 -9.236424) (xy 67.431628 -9.127605) (xy 67.448265 -9.017235)
			(xy 67.456608 -8.905931) (xy 67.457066 -8.850122) (xy 67.457066 0) (xy 67.457559 0.070354) (xy 67.465449 0.210841)
			(xy 67.481203 0.350665) (xy 67.504772 0.489385) (xy 67.536082 0.626565) (xy 67.575035 0.761774) (xy 67.621508 0.894587)
			(xy 67.675354 1.024584) (xy 67.736404 1.151358) (xy 67.804467 1.27451) (xy 67.879328 1.393651) (xy 67.960751 1.508408)
			(xy 68.04848 1.618419) (xy 68.14224 1.723337) (xy 68.241735 1.822834) (xy 68.346652 1.916595) (xy 68.456662 2.004326)
			(xy 68.571417 2.085751) (xy 68.690557 2.160614) (xy 68.813708 2.228678) (xy 68.940481 2.289731) (xy 69.070478 2.343579)
			(xy 69.203289 2.390053) (xy 69.338498 2.429008) (xy 69.475678 2.46032) (xy 69.614398 2.483892) (xy 69.754221 2.499648)
			(xy 69.894708 2.50754) (xy 69.965062 2.507996) (xy 85.96503 2.507996) (xy 86.035383 2.507502) (xy 86.175868 2.499611)
			(xy 86.31569 2.483855) (xy 86.454408 2.460284) (xy 86.591586 2.428973) (xy 86.726793 2.390019) (xy 86.859603 2.343545)
			(xy 86.989598 2.289698) (xy 87.11637 2.228647) (xy 87.239519 2.160584) (xy 87.358658 2.085722) (xy 87.473412 2.004299)
			(xy 87.58342 1.916569) (xy 87.688336 1.822809) (xy 87.78783 1.723314) (xy 87.881588 1.618397) (xy 87.969317 1.508388)
			(xy 88.050739 1.393633) (xy 88.125599 1.274493) (xy 88.193661 1.151343) (xy 88.254711 1.024571) (xy 88.308556 0.894575)
			(xy 88.355028 0.761764) (xy 88.39398 0.626557) (xy 88.42529 0.489378) (xy 88.448859 0.35066) (xy 88.464613 0.210838)
			(xy 88.472503 0.070353) (xy 88.473026 0) (xy 88.473026 -8.850122) (xy 88.473549 -8.905928) (xy 88.481891 -9.017228)
			(xy 88.498528 -9.127594) (xy 88.523365 -9.236408) (xy 88.556265 -9.343061) (xy 88.597043 -9.446957)
			(xy 88.645472 -9.547516) (xy 88.701279 -9.644174) (xy 88.764154 -9.736392) (xy 88.833745 -9.823653)
			(xy 88.909662 -9.90547) (xy 88.99148 -9.981384) (xy 89.078743 -10.050972) (xy 89.170963 -10.113844)
			(xy 89.267623 -10.169649) (xy 89.368183 -10.218074) (xy 89.472081 -10.258849) (xy 89.578735 -10.291746)
			(xy 89.687549 -10.316581) (xy 89.797915 -10.333214) (xy 89.909216 -10.341553) (xy 89.965022 -10.342118)
			(xy 91.965018 -10.342118) (xy 92.020825 -10.341596) (xy 92.132127 -10.333254) (xy 92.242494 -10.316617)
			(xy 92.351309 -10.29178) (xy 92.457964 -10.258881) (xy 92.561862 -10.218103) (xy 92.662422 -10.169675)
			(xy 92.759082 -10.113868) (xy 92.851302 -10.050993) (xy 92.938565 -9.981403) (xy 93.020384 -9.905487)
			(xy 93.096301 -9.823668) (xy 93.165891 -9.736405) (xy 93.228766 -9.644186) (xy 93.284573 -9.547526)
			(xy 93.333001 -9.446965) (xy 93.373779 -9.343067) (xy 93.406679 -9.236413) (xy 93.431517 -9.127597)
			(xy 93.448153 -9.01723) (xy 93.456495 -8.905929) (xy 93.457014 -8.850122) (xy 93.457014 0) (xy 93.457498 0.070354)
			(xy 93.465388 0.21084) (xy 93.481142 0.350663) (xy 93.504712 0.489383) (xy 93.536022 0.626563) (xy 93.574975 0.761771)
			(xy 93.621448 0.894583) (xy 93.675295 1.02458) (xy 93.736346 1.151353) (xy 93.804409 1.274504) (xy 93.87927 1.393645)
			(xy 93.960694 1.5084) (xy 94.048424 1.61841) (xy 94.142184 1.723327) (xy 94.24168 1.822823) (xy 94.346598 1.916583)
			(xy 94.456608 2.004312) (xy 94.571364 2.085735) (xy 94.690505 2.160596) (xy 94.813655 2.228659) (xy 94.940429 2.289709)
			(xy 95.070426 2.343555) (xy 95.203238 2.390028) (xy 95.338447 2.42898) (xy 95.475627 2.46029) (xy 95.614347 2.483859)
			(xy 95.75417 2.499613) (xy 95.894656 2.507502) (xy 95.96501 2.507996) (xy 124.06503 2.507996) (xy 124.135383 2.507502)
			(xy 124.275868 2.499611) (xy 124.41569 2.483855) (xy 124.554408 2.460284) (xy 124.691586 2.428973)
			(xy 124.826793 2.390019) (xy 124.959603 2.343545) (xy 125.089598 2.289698) (xy 125.21637 2.228647)
			(xy 125.339519 2.160584) (xy 125.458658 2.085722) (xy 125.573412 2.004299) (xy 125.68342 1.916569)
			(xy 125.788336 1.822809) (xy 125.88783 1.723314) (xy 125.981588 1.618397) (xy 126.069317 1.508388)
			(xy 126.150739 1.393633) (xy 126.225599 1.274493) (xy 126.293661 1.151343) (xy 126.354711 1.024571)
			(xy 126.408556 0.894575) (xy 126.455028 0.761764) (xy 126.49398 0.626557) (xy 126.52529 0.489378)
			(xy 126.548859 0.35066) (xy 126.564613 0.210838) (xy 126.572503 0.070353) (xy 126.573026 0) (xy 126.573026 -8.850122)
			(xy 126.573549 -8.905928) (xy 126.581891 -9.017228) (xy 126.598528 -9.127594) (xy 126.623365 -9.236408)
			(xy 126.656265 -9.343061) (xy 126.697043 -9.446957) (xy 126.745472 -9.547516) (xy 126.801279 -9.644174)
			(xy 126.864154 -9.736392) (xy 126.933745 -9.823653) (xy 127.009662 -9.90547) (xy 127.09148 -9.981384)
			(xy 127.178743 -10.050972) (xy 127.270963 -10.113844) (xy 127.367623 -10.169649) (xy 127.468183 -10.218074)
			(xy 127.572081 -10.258849) (xy 127.678735 -10.291746) (xy 127.787549 -10.316581) (xy 127.897915 -10.333214)
			(xy 128.009216 -10.341553) (xy 128.065022 -10.342118) (xy 130.065018 -10.342118) (xy 130.120825 -10.341596)
			(xy 130.232127 -10.333254) (xy 130.342494 -10.316617) (xy 130.451309 -10.29178) (xy 130.557964 -10.258881)
			(xy 130.661862 -10.218103) (xy 130.762422 -10.169675) (xy 130.859082 -10.113868) (xy 130.951302 -10.050993)
			(xy 131.038565 -9.981403) (xy 131.120384 -9.905487) (xy 131.196301 -9.823668) (xy 131.265891 -9.736405)
			(xy 131.328766 -9.644186) (xy 131.384573 -9.547526) (xy 131.433001 -9.446965) (xy 131.473779 -9.343067)
			(xy 131.506679 -9.236413) (xy 131.531517 -9.127597) (xy 131.548153 -9.01723) (xy 131.556495 -8.905929)
			(xy 131.557014 -8.850122) (xy 131.557014 0) (xy 131.557498 0.070354) (xy 131.565388 0.21084) (xy 131.581142 0.350663)
			(xy 131.604712 0.489383) (xy 131.636022 0.626563) (xy 131.674975 0.761771) (xy 131.721448 0.894583)
			(xy 131.775295 1.02458) (xy 131.836346 1.151353) (xy 131.904409 1.274504) (xy 131.97927 1.393645)
			(xy 132.060694 1.5084) (xy 132.148424 1.61841) (xy 132.242184 1.723327) (xy 132.34168 1.822823) (xy 132.446598 1.916583)
			(xy 132.556608 2.004312) (xy 132.671364 2.085735) (xy 132.790505 2.160596) (xy 132.913655 2.228659)
			(xy 133.040429 2.289709) (xy 133.170426 2.343555) (xy 133.303238 2.390028) (xy 133.438447 2.42898)
			(xy 133.575627 2.46029) (xy 133.714347 2.483859) (xy 133.85417 2.499613) (xy 133.994656 2.507502)
			(xy 134.06501 2.507996) (xy 150.064978 2.507996) (xy 150.135332 2.507512) (xy 150.27582 2.499624)
			(xy 150.415644 2.483871) (xy 150.554365 2.460302) (xy 150.691546 2.428993) (xy 150.826756 2.39004)
			(xy 150.959569 2.343568) (xy 151.089567 2.289722) (xy 151.216342 2.228672) (xy 151.339494 2.160609)
			(xy 151.458636 2.085748) (xy 151.573393 2.004324) (xy 151.683404 1.916594) (xy 151.788322 1.822834)
			(xy 151.887819 1.723338) (xy 151.98158 1.61842) (xy 152.069311 1.50841) (xy 152.150736 1.393654)
			(xy 152.225598 1.274513) (xy 152.293661 1.151361) (xy 152.354713 1.024587) (xy 152.40856 0.894589)
			(xy 152.455034 0.761777) (xy 152.493987 0.626567) (xy 152.525298 0.489386) (xy 152.548868 0.350666)
			(xy 152.564622 0.210842) (xy 152.572512 0.070354) (xy 152.572974 0) (xy 152.572974 -8.850122) (xy 152.573497 -8.905929)
			(xy 152.581839 -9.017231) (xy 152.598475 -9.127598) (xy 152.623313 -9.236413) (xy 152.656212 -9.343068)
			(xy 152.69699 -9.446966) (xy 152.745418 -9.547526) (xy 152.801225 -9.644186) (xy 152.8641 -9.736406)
			(xy 152.93369 -9.823669) (xy 153.009606 -9.905488) (xy 153.091425 -9.981405) (xy 153.178688 -10.050995)
			(xy 153.270907 -10.11387) (xy 153.367567 -10.169678) (xy 153.468127 -10.218107) (xy 153.572025 -10.258885)
			(xy 153.67868 -10.291785) (xy 153.787495 -10.316623) (xy 153.897862 -10.33326) (xy 154.009163 -10.341603)
			(xy 154.06497 -10.342118) (xy 156.064966 -10.342118) (xy 156.120775 -10.34161) (xy 156.23208 -10.333271)
			(xy 156.342451 -10.316638) (xy 156.45127 -10.291803) (xy 156.557929 -10.258906) (xy 156.661832 -10.21813)
			(xy 156.762396 -10.169703) (xy 156.859061 -10.113896) (xy 156.951284 -10.051022) (xy 157.038552 -9.981431)
			(xy 157.120374 -9.905514) (xy 157.196295 -9.823694) (xy 157.265888 -9.736429) (xy 157.328766 -9.644208)
			(xy 157.384577 -9.547546) (xy 157.433007 -9.446983) (xy 157.473787 -9.343082) (xy 157.506689 -9.236424)
			(xy 157.531528 -9.127606) (xy 157.548165 -9.017236) (xy 157.556508 -8.905931) (xy 157.556962 -8.850122)
			(xy 157.556962 0) (xy 157.557455 0.070354) (xy 157.565345 0.210841) (xy 157.581099 0.350665) (xy 157.604668 0.489385)
			(xy 157.635978 0.626566) (xy 157.674931 0.761775) (xy 157.721404 0.894587) (xy 157.77525 1.024585)
			(xy 157.8363 1.151359) (xy 157.904363 1.274511) (xy 157.979224 1.393652) (xy 158.060647 1.508409)
			(xy 158.148376 1.61842) (xy 158.242136 1.723339) (xy 158.341631 1.822835) (xy 158.446548 1.916597)
			(xy 158.556557 2.004328) (xy 158.671313 2.085753) (xy 158.790453 2.160616) (xy 158.913604 2.22868)
			(xy 159.040377 2.289733) (xy 159.170374 2.343581) (xy 159.303185 2.390056) (xy 159.438394 2.429011)
			(xy 159.575574 2.460324) (xy 159.714294 2.483895) (xy 159.854117 2.499652) (xy 159.994604 2.507544)
			(xy 160.064958 2.507996) (xy 176.064926 2.507996) (xy 176.135279 2.507502) (xy 176.275764 2.499611)
			(xy 176.415586 2.483856) (xy 176.554304 2.460285) (xy 176.691483 2.428974) (xy 176.82669 2.39002)
			(xy 176.9595 2.343547) (xy 177.089496 2.289699) (xy 177.216267 2.228648) (xy 177.339416 2.160585)
			(xy 177.458556 2.085724) (xy 177.57331 2.0043) (xy 177.683318 1.91657) (xy 177.788234 1.822811) (xy 177.887728 1.723315)
			(xy 177.981487 1.618398) (xy 178.069216 1.508389) (xy 178.150638 1.393634) (xy 178.225498 1.274494)
			(xy 178.29356 1.151344) (xy 178.35461 1.024572) (xy 178.408456 0.894576) (xy 178.454928 0.761765)
			(xy 178.49388 0.626558) (xy 178.52519 0.489379) (xy 178.548759 0.35066) (xy 178.564513 0.210838)
			(xy 178.572403 0.070353) (xy 178.572922 0) (xy 178.572922 -8.850122) (xy 178.573445 -8.905928) (xy 178.581787 -9.017229)
			(xy 178.598424 -9.127594) (xy 178.623261 -9.236408) (xy 178.656161 -9.343061) (xy 178.696939 -9.446958)
			(xy 178.745367 -9.547517) (xy 178.801175 -9.644175) (xy 178.86405 -9.736393) (xy 178.93364 -9.823654)
			(xy 179.009557 -9.905471) (xy 179.091376 -9.981386) (xy 179.178639 -10.050974) (xy 179.270859 -10.113846)
			(xy 179.367519 -10.169651) (xy 179.468079 -10.218077) (xy 179.571976 -10.258852) (xy 179.678631 -10.291749)
			(xy 179.787445 -10.316584) (xy 179.897811 -10.333218) (xy 180.009112 -10.341557) (xy 180.064918 -10.342118)
			(xy 182.064914 -10.342118) (xy 182.120721 -10.341596) (xy 182.232023 -10.333254) (xy 182.34239 -10.316618)
			(xy 182.451206 -10.291781) (xy 182.557861 -10.258882) (xy 182.661759 -10.218104) (xy 182.76232 -10.169676)
			(xy 182.85898 -10.113869) (xy 182.9512 -10.050995) (xy 183.038463 -9.981405) (xy 183.120282 -9.905488)
			(xy 183.196199 -9.823669) (xy 183.26579 -9.736406) (xy 183.328665 -9.644187) (xy 183.384473 -9.547527)
			(xy 183.432901 -9.446966) (xy 183.473679 -9.343068) (xy 183.506579 -9.236413) (xy 183.531416 -9.127598)
			(xy 183.548053 -9.017231) (xy 183.556395 -8.905929) (xy 183.55691 -8.850122) (xy 183.55691 0) (xy 183.557394 0.070354)
			(xy 183.565284 0.21084) (xy 183.581038 0.350664) (xy 183.604608 0.489383) (xy 183.635918 0.626563)
			(xy 183.674871 0.761772) (xy 183.721344 0.894584) (xy 183.775191 1.024581) (xy 183.836242 1.151354)
			(xy 183.904305 1.274505) (xy 183.979166 1.393646) (xy 184.06059 1.508401) (xy 184.14832 1.618411)
			(xy 184.24208 1.723329) (xy 184.341576 1.822824) (xy 184.446493 1.916584) (xy 184.556503 2.004314)
			(xy 184.671259 2.085737) (xy 184.7904 2.160598) (xy 184.913551 2.228661) (xy 185.040325 2.289712)
			(xy 185.170322 2.343558) (xy 185.303134 2.390031) (xy 185.438342 2.428983) (xy 185.575523 2.460294)
			(xy 185.714242 2.483863) (xy 185.854066 2.499617) (xy 185.994552 2.507506) (xy 186.064906 2.507996)
			(xy 202.064874 2.507996) (xy 202.135228 2.507512) (xy 202.275716 2.499624) (xy 202.41554 2.483871)
			(xy 202.554261 2.460303) (xy 202.691443 2.428993) (xy 202.826653 2.390041) (xy 202.959466 2.343569)
			(xy 203.089464 2.289723) (xy 203.216239 2.228673) (xy 203.339391 2.16061) (xy 203.458534 2.085749)
			(xy 203.573291 2.004326) (xy 203.683302 1.916596) (xy 203.788221 1.822836) (xy 203.887718 1.72334)
			(xy 203.981479 1.618422) (xy 204.06921 1.508412) (xy 204.150635 1.393655) (xy 204.225497 1.274514)
			(xy 204.293561 1.151362) (xy 204.354613 1.024588) (xy 204.40846 0.89459) (xy 204.454933 0.761778)
			(xy 204.493887 0.626568) (xy 204.525198 0.489387) (xy 204.548768 0.350666) (xy 204.564522 0.210842)
			(xy 204.572412 0.070354) (xy 204.57287 0) (xy 204.57287 -8.850122) (xy 204.573393 -8.905929) (xy 204.581735 -9.017231)
			(xy 204.598371 -9.127598) (xy 204.623209 -9.236413) (xy 204.656108 -9.343068) (xy 204.696886 -9.446966)
			(xy 204.745314 -9.547527) (xy 204.801121 -9.644187) (xy 204.863996 -9.736407) (xy 204.933586 -9.82367)
			(xy 205.009502 -9.905489) (xy 205.091321 -9.981407) (xy 205.178583 -10.050997) (xy 205.270803 -10.113872)
			(xy 205.367463 -10.16968) (xy 205.468023 -10.218109) (xy 205.571921 -10.258888) (xy 205.678575 -10.291788)
			(xy 205.78739 -10.316626) (xy 205.897757 -10.333264) (xy 206.009059 -10.341607) (xy 206.064866 -10.342118)
			(xy 208.065116 -10.342118) (xy 208.120923 -10.341596) (xy 208.232225 -10.333254) (xy 208.342592 -10.316618)
			(xy 208.451407 -10.29178) (xy 208.558062 -10.258881) (xy 208.66196 -10.218103) (xy 208.762521 -10.169676)
			(xy 208.859181 -10.113868) (xy 208.951401 -10.050994) (xy 209.038664 -9.981404) (xy 209.120483 -9.905487)
			(xy 209.1964 -9.823669) (xy 209.26599 -9.736406) (xy 209.328865 -9.644186) (xy 209.384673 -9.547526)
			(xy 209.433101 -9.446966) (xy 209.473879 -9.343068) (xy 209.506779 -9.236413) (xy 209.531617 -9.127598)
			(xy 209.548253 -9.017231) (xy 209.556595 -8.905929) (xy 209.557112 -8.850122) (xy 209.557112 0) (xy 209.557596 0.070354)
			(xy 209.565486 0.21084) (xy 209.58124 0.350663) (xy 209.60481 0.489383) (xy 209.63612 0.626563) (xy 209.675073 0.761772)
			(xy 209.721546 0.894583) (xy 209.775393 1.02458) (xy 209.836444 1.151354) (xy 209.904507 1.274505)
			(xy 209.979368 1.393645) (xy 210.060792 1.508401) (xy 210.148522 1.618411) (xy 210.242282 1.723328)
			(xy 210.341778 1.822823) (xy 210.446696 1.916583) (xy 210.556706 2.004313) (xy 210.671462 2.085736)
			(xy 210.790602 2.160597) (xy 210.913753 2.22866) (xy 211.040527 2.289711) (xy 211.170524 2.343557)
			(xy 211.303336 2.390029) (xy 211.438545 2.428982) (xy 211.575725 2.460292) (xy 211.714444 2.483861)
			(xy 211.854268 2.499615) (xy 211.994754 2.507504) (xy 212.065108 2.507996) (xy 240.164874 2.507996)
			(xy 240.235228 2.507512) (xy 240.375716 2.499624) (xy 240.51554 2.483871) (xy 240.654261 2.460303)
			(xy 240.791443 2.428993) (xy 240.926653 2.390041) (xy 241.059466 2.343569) (xy 241.189464 2.289723)
			(xy 241.316239 2.228673) (xy 241.439391 2.16061) (xy 241.558534 2.085749) (xy 241.673291 2.004326)
			(xy 241.783302 1.916596) (xy 241.888221 1.822836) (xy 241.987718 1.72334) (xy 242.081479 1.618422)
			(xy 242.16921 1.508412) (xy 242.250635 1.393655) (xy 242.325497 1.274514) (xy 242.393561 1.151362)
			(xy 242.454613 1.024588) (xy 242.50846 0.89459) (xy 242.554933 0.761778) (xy 242.593887 0.626568)
			(xy 242.625198 0.489387) (xy 242.648768 0.350666) (xy 242.664522 0.210842) (xy 242.672412 0.070354)
			(xy 242.67287 0) (xy 242.67287 -8.850122) (xy 242.673393 -8.905929) (xy 242.681735 -9.017231) (xy 242.698371 -9.127598)
			(xy 242.723209 -9.236413) (xy 242.756108 -9.343068) (xy 242.796886 -9.446966) (xy 242.845314 -9.547527)
			(xy 242.901121 -9.644187) (xy 242.963996 -9.736407) (xy 243.033586 -9.82367) (xy 243.109502 -9.905489)
			(xy 243.191321 -9.981407) (xy 243.278583 -10.050997) (xy 243.370803 -10.113872) (xy 243.467463 -10.16968)
			(xy 243.568023 -10.218109) (xy 243.671921 -10.258888) (xy 243.778575 -10.291788) (xy 243.88739 -10.316626)
			(xy 243.997757 -10.333264) (xy 244.109059 -10.341607) (xy 244.164866 -10.342118) (xy 246.165116 -10.342118)
			(xy 246.220923 -10.341596) (xy 246.332225 -10.333254) (xy 246.442592 -10.316618) (xy 246.551407 -10.29178)
			(xy 246.658062 -10.258881) (xy 246.76196 -10.218103) (xy 246.862521 -10.169676) (xy 246.959181 -10.113868)
			(xy 247.051401 -10.050994) (xy 247.138664 -9.981404) (xy 247.220483 -9.905487) (xy 247.2964 -9.823669)
			(xy 247.36599 -9.736406) (xy 247.428865 -9.644186) (xy 247.484673 -9.547526) (xy 247.533101 -9.446966)
			(xy 247.573879 -9.343068) (xy 247.606779 -9.236413) (xy 247.631617 -9.127598) (xy 247.648253 -9.017231)
			(xy 247.656595 -8.905929) (xy 247.657112 -8.850122) (xy 247.657112 0) (xy 247.657596 0.070354) (xy 247.665486 0.21084)
			(xy 247.68124 0.350663) (xy 247.70481 0.489383) (xy 247.73612 0.626563) (xy 247.775073 0.761772)
			(xy 247.821546 0.894583) (xy 247.875393 1.02458) (xy 247.936444 1.151354) (xy 248.004507 1.274505)
			(xy 248.079368 1.393645) (xy 248.160792 1.508401) (xy 248.248522 1.618411) (xy 248.342282 1.723328)
			(xy 248.441778 1.822823) (xy 248.546696 1.916583) (xy 248.656706 2.004313) (xy 248.771462 2.085736)
			(xy 248.890602 2.160597) (xy 249.013753 2.22866) (xy 249.140527 2.289711) (xy 249.270524 2.343557)
			(xy 249.403336 2.390029) (xy 249.538545 2.428982) (xy 249.675725 2.460292) (xy 249.814444 2.483861)
			(xy 249.954268 2.499615) (xy 250.094754 2.507504) (xy 250.165108 2.507996) (xy 266.165076 2.507996)
			(xy 266.23543 2.507512) (xy 266.375918 2.499624) (xy 266.515742 2.483871) (xy 266.654463 2.460303)
			(xy 266.791644 2.428993) (xy 266.926854 2.390041) (xy 267.059667 2.343569) (xy 267.189666 2.289723)
			(xy 267.31644 2.228672) (xy 267.439593 2.160609) (xy 267.558735 2.085749) (xy 267.673492 2.004325)
			(xy 267.783503 1.916595) (xy 267.888422 1.822835) (xy 267.987918 1.723339) (xy 268.08168 1.618421)
			(xy 268.169411 1.508411) (xy 268.250835 1.393655) (xy 268.325697 1.274513) (xy 268.393761 1.151362)
			(xy 268.454813 1.024588) (xy 268.50866 0.89459) (xy 268.555134 0.761777) (xy 268.594087 0.626568)
			(xy 268.625398 0.489387) (xy 268.648968 0.350666) (xy 268.664722 0.210842) (xy 268.672612 0.070354)
			(xy 268.673072 0) (xy 268.673072 -8.850122) (xy 268.673595 -8.905929) (xy 268.681937 -9.017231) (xy 268.698573 -9.127598)
			(xy 268.723411 -9.236413) (xy 268.75631 -9.343068) (xy 268.797088 -9.446966) (xy 268.845516 -9.547526)
			(xy 268.901323 -9.644187) (xy 268.964198 -9.736406) (xy 269.033788 -9.82367) (xy 269.109704 -9.905489)
			(xy 269.191523 -9.981406) (xy 269.278786 -10.050996) (xy 269.371005 -10.113871) (xy 269.467665 -10.169679)
			(xy 269.568225 -10.218108) (xy 269.672123 -10.258886) (xy 269.778777 -10.291787) (xy 269.887592 -10.316625)
			(xy 269.997959 -10.333262) (xy 270.109261 -10.341605) (xy 270.165068 -10.342118) (xy 272.165064 -10.342118)
			(xy 272.220873 -10.34161) (xy 272.332178 -10.333272) (xy 272.442549 -10.316638) (xy 272.551368 -10.291804)
			(xy 272.658028 -10.258906) (xy 272.76193 -10.21813) (xy 272.862495 -10.169703) (xy 272.95916 -10.113897)
			(xy 273.051383 -10.051022) (xy 273.138651 -9.981432) (xy 273.220473 -9.905515) (xy 273.296394 -9.823695)
			(xy 273.365988 -9.73643) (xy 273.428866 -9.644209) (xy 273.484676 -9.547546) (xy 273.533107 -9.446983)
			(xy 273.573887 -9.343082) (xy 273.606789 -9.236425) (xy 273.631628 -9.127606) (xy 273.648265 -9.017236)
			(xy 273.656608 -8.905931) (xy 273.65706 -8.850122) (xy 273.65706 0) (xy 273.657553 0.070354) (xy 273.665443 0.210841)
			(xy 273.681197 0.350665) (xy 273.704766 0.489385) (xy 273.736076 0.626566) (xy 273.775029 0.761775)
			(xy 273.821502 0.894588) (xy 273.875348 1.024585) (xy 273.936398 1.15136) (xy 274.004461 1.274511)
			(xy 274.079321 1.393653) (xy 274.160745 1.50841) (xy 274.248474 1.618421) (xy 274.342234 1.723339)
			(xy 274.441729 1.822836) (xy 274.546646 1.916598) (xy 274.656655 2.004329) (xy 274.771411 2.085754)
			(xy 274.890551 2.160617) (xy 275.013701 2.228682) (xy 275.140474 2.289734) (xy 275.270471 2.343583)
			(xy 275.403283 2.390058) (xy 275.538492 2.429013) (xy 275.675672 2.460325) (xy 275.814392 2.483897)
			(xy 275.954215 2.499654) (xy 276.094702 2.507545) (xy 276.165056 2.507996) (xy 292.165024 2.507996)
			(xy 292.235377 2.507502) (xy 292.375862 2.499611) (xy 292.515684 2.483856) (xy 292.654403 2.460285)
			(xy 292.791581 2.428974) (xy 292.926788 2.390021) (xy 293.059599 2.343547) (xy 293.189594 2.2897)
			(xy 293.316366 2.228649) (xy 293.439515 2.160586) (xy 293.558655 2.085724) (xy 293.673409 2.004301)
			(xy 293.783417 1.916571) (xy 293.888334 1.822811) (xy 293.987828 1.723316) (xy 294.081587 1.618399)
			(xy 294.169315 1.50839) (xy 294.250738 1.393635) (xy 294.325598 1.274495) (xy 294.39366 1.151345)
			(xy 294.45471 1.024572) (xy 294.508556 0.894576) (xy 294.555028 0.761765) (xy 294.59398 0.626558)
			(xy 294.62529 0.489379) (xy 294.648859 0.35066) (xy 294.664613 0.210839) (xy 294.672503 0.070353)
			(xy 294.67302 0) (xy 294.67302 -8.850122) (xy 294.673543 -8.905928) (xy 294.681885 -9.017229) (xy 294.698522 -9.127594)
			(xy 294.723359 -9.236408) (xy 294.756259 -9.343062) (xy 294.797037 -9.446958) (xy 294.845465 -9.547517)
			(xy 294.901273 -9.644176) (xy 294.964148 -9.736394) (xy 295.033738 -9.823655) (xy 295.109655 -9.905472)
			(xy 295.191474 -9.981387) (xy 295.278737 -10.050975) (xy 295.370956 -10.113847) (xy 295.467616 -10.169652)
			(xy 295.568176 -10.218078) (xy 295.672074 -10.258853) (xy 295.778728 -10.291751) (xy 295.887543 -10.316586)
			(xy 295.997909 -10.333219) (xy 296.10921 -10.341559) (xy 296.165016 -10.342118) (xy 298.165012 -10.342118)
			(xy 298.220819 -10.341596) (xy 298.332121 -10.333254) (xy 298.442488 -10.316618) (xy 298.551304 -10.291781)
			(xy 298.657959 -10.258882) (xy 298.761858 -10.218105) (xy 298.862418 -10.169677) (xy 298.959079 -10.11387)
			(xy 299.051299 -10.050995) (xy 299.138562 -9.981405) (xy 299.220382 -9.905489) (xy 299.296299 -9.82367)
			(xy 299.365889 -9.736407) (xy 299.428764 -9.644188) (xy 299.484572 -9.547527) (xy 299.533001 -9.446967)
			(xy 299.573779 -9.343069) (xy 299.606679 -9.236414) (xy 299.631516 -9.127598) (xy 299.648153 -9.017231)
			(xy 299.656495 -8.905929) (xy 299.657008 -8.850122) (xy 299.657008 0) (xy 299.657492 0.070354) (xy 299.665382 0.21084)
			(xy 299.681136 0.350664) (xy 299.704706 0.489383) (xy 299.736016 0.626564) (xy 299.774969 0.761772)
			(xy 299.821442 0.894584) (xy 299.875289 1.024581) (xy 299.93634 1.151355) (xy 300.004403 1.274505)
			(xy 300.079264 1.393646) (xy 300.160688 1.508402) (xy 300.248418 1.618412) (xy 300.342178 1.723329)
			(xy 300.441673 1.822825) (xy 300.546591 1.916585) (xy 300.656601 2.004315) (xy 300.771357 2.085738)
			(xy 300.890498 2.160599) (xy 301.013649 2.228662) (xy 301.140423 2.289713) (xy 301.27042 2.343559)
			(xy 301.403232 2.390032) (xy 301.53844 2.428985) (xy 301.67562 2.460295) (xy 301.81434 2.483864)
			(xy 301.954163 2.499618) (xy 302.09465 2.507508) (xy 302.165004 2.507996) (xy 318.164972 2.507996)
			(xy 318.235326 2.507512) (xy 318.375814 2.499624) (xy 318.515639 2.483871) (xy 318.65436 2.460303)
			(xy 318.791541 2.428994) (xy 318.926751 2.390042) (xy 319.059564 2.34357) (xy 319.189563 2.289724)
			(xy 319.316338 2.228673) (xy 319.43949 2.160611) (xy 319.558633 2.08575) (xy 319.67339 2.004327)
			(xy 319.783401 1.916597) (xy 319.88832 1.822836) (xy 319.987817 1.723341) (xy 320.081579 1.618423)
			(xy 320.16931 1.508412) (xy 320.250734 1.393656) (xy 320.325597 1.274514) (xy 320.393661 1.151363)
			(xy 320.454712 1.024589) (xy 320.50856 0.894591) (xy 320.555033 0.761778) (xy 320.593987 0.626568)
			(xy 320.625298 0.489387) (xy 320.648868 0.350666) (xy 320.664622 0.210842) (xy 320.672512 0.070354)
			(xy 320.672968 0) (xy 320.672968 -8.850122) (xy 320.673491 -8.905929) (xy 320.681833 -9.017231) (xy 320.698469 -9.127598)
			(xy 320.723307 -9.236413) (xy 320.756206 -9.343068) (xy 320.796984 -9.446967) (xy 320.845412 -9.547527)
			(xy 320.901219 -9.644188) (xy 320.964093 -9.736408) (xy 321.033684 -9.823671) (xy 321.1096 -9.90549)
			(xy 321.191418 -9.981407) (xy 321.278681 -10.050998) (xy 321.3709 -10.113873) (xy 321.46756 -10.169682)
			(xy 321.56812 -10.21811) (xy 321.672018 -10.258889) (xy 321.778673 -10.29179) (xy 321.887488 -10.316628)
			(xy 321.997855 -10.333266) (xy 322.109157 -10.341609) (xy 322.164964 -10.342118) (xy 324.16496 -10.342118)
			(xy 324.220769 -10.34161) (xy 324.332074 -10.333272) (xy 324.442446 -10.316639) (xy 324.551265 -10.291805)
			(xy 324.657925 -10.258907) (xy 324.761827 -10.218131) (xy 324.862393 -10.169705) (xy 324.959057 -10.113898)
			(xy 325.051281 -10.051024) (xy 325.138549 -9.981433) (xy 325.220372 -9.905516) (xy 325.296293 -9.823696)
			(xy 325.365887 -9.736431) (xy 325.428765 -9.64421) (xy 325.484576 -9.547547) (xy 325.533007 -9.446984)
			(xy 325.573787 -9.343083) (xy 325.606689 -9.236425) (xy 325.631528 -9.127607) (xy 325.648165 -9.017236)
			(xy 325.656508 -8.905931) (xy 325.656956 -8.850122) (xy 325.656956 0) (xy 325.657449 0.070354) (xy 325.665339 0.210841)
			(xy 325.681093 0.350665) (xy 325.704662 0.489386) (xy 325.735972 0.626566) (xy 325.774925 0.761776)
			(xy 325.821398 0.894588) (xy 325.875244 1.024586) (xy 325.936294 1.15136) (xy 326.004357 1.274512)
			(xy 326.079217 1.393654) (xy 326.16064 1.508411) (xy 326.24837 1.618422) (xy 326.342129 1.723341)
			(xy 326.441624 1.822838) (xy 326.546542 1.916599) (xy 326.656551 2.004331) (xy 326.771306 2.085756)
			(xy 326.890447 2.160619) (xy 327.013597 2.228684) (xy 327.14037 2.289737) (xy 327.270367 2.343585)
			(xy 327.403179 2.39006) (xy 327.538387 2.429016) (xy 327.675567 2.460328) (xy 327.814287 2.4839)
			(xy 327.954111 2.499657) (xy 328.094598 2.507549) (xy 328.164952 2.507996) (xy 356.264972 2.507996)
			(xy 356.335326 2.507512) (xy 356.475814 2.499624) (xy 356.615639 2.483871) (xy 356.75436 2.460303)
			(xy 356.891541 2.428994) (xy 357.026751 2.390042) (xy 357.159564 2.34357) (xy 357.289563 2.289724)
			(xy 357.416338 2.228673) (xy 357.53949 2.160611) (xy 357.658633 2.08575) (xy 357.77339 2.004327)
			(xy 357.883401 1.916597) (xy 357.98832 1.822836) (xy 358.087817 1.723341) (xy 358.181579 1.618423)
			(xy 358.26931 1.508412) (xy 358.350734 1.393656) (xy 358.425597 1.274514) (xy 358.493661 1.151363)
			(xy 358.554712 1.024589) (xy 358.60856 0.894591) (xy 358.655033 0.761778) (xy 358.693987 0.626568)
			(xy 358.725298 0.489387) (xy 358.748868 0.350666) (xy 358.764622 0.210842) (xy 358.772512 0.070354)
			(xy 358.772968 0) (xy 358.772968 -8.850122) (xy 358.773491 -8.905929) (xy 358.781833 -9.017231) (xy 358.798469 -9.127598)
			(xy 358.823307 -9.236413) (xy 358.856206 -9.343068) (xy 358.896984 -9.446967) (xy 358.945412 -9.547527)
			(xy 359.001219 -9.644188) (xy 359.064093 -9.736408) (xy 359.133684 -9.823671) (xy 359.2096 -9.90549)
			(xy 359.291418 -9.981407) (xy 359.378681 -10.050998) (xy 359.4709 -10.113873) (xy 359.56756 -10.169682)
			(xy 359.66812 -10.21811) (xy 359.772018 -10.258889) (xy 359.878673 -10.29179) (xy 359.987488 -10.316628)
			(xy 360.097855 -10.333266) (xy 360.209157 -10.341609) (xy 360.264964 -10.342118) (xy 362.26496 -10.342118)
			(xy 362.320769 -10.34161) (xy 362.432074 -10.333272) (xy 362.542446 -10.316639) (xy 362.651265 -10.291805)
			(xy 362.757925 -10.258907) (xy 362.861827 -10.218131) (xy 362.962393 -10.169705) (xy 363.059057 -10.113898)
			(xy 363.151281 -10.051024) (xy 363.238549 -9.981433) (xy 363.320372 -9.905516) (xy 363.396293 -9.823696)
			(xy 363.465887 -9.736431) (xy 363.528765 -9.64421) (xy 363.584576 -9.547547) (xy 363.633007 -9.446984)
			(xy 363.673787 -9.343083) (xy 363.706689 -9.236425) (xy 363.731528 -9.127607) (xy 363.748165 -9.017236)
			(xy 363.756508 -8.905931) (xy 363.756956 -8.850122) (xy 363.756956 0) (xy 363.757449 0.070354) (xy 363.765339 0.210841)
			(xy 363.781093 0.350665) (xy 363.804662 0.489386) (xy 363.835972 0.626566) (xy 363.874925 0.761776)
			(xy 363.921398 0.894588) (xy 363.975244 1.024586) (xy 364.036294 1.15136) (xy 364.104357 1.274512)
			(xy 364.179217 1.393654) (xy 364.26064 1.508411) (xy 364.34837 1.618422) (xy 364.442129 1.723341)
			(xy 364.541624 1.822838) (xy 364.646542 1.916599) (xy 364.756551 2.004331) (xy 364.871306 2.085756)
			(xy 364.990447 2.160619) (xy 365.113597 2.228684) (xy 365.24037 2.289737) (xy 365.370367 2.343585)
			(xy 365.503179 2.39006) (xy 365.638387 2.429016) (xy 365.775567 2.460328) (xy 365.914287 2.4839)
			(xy 366.054111 2.499657) (xy 366.194598 2.507549) (xy 366.264952 2.507996) (xy 382.26492 2.507996)
			(xy 382.335273 2.507502) (xy 382.475759 2.499612) (xy 382.615581 2.483856) (xy 382.754299 2.460286)
			(xy 382.891478 2.428975) (xy 383.026685 2.390022) (xy 383.159496 2.343548) (xy 383.289491 2.289701)
			(xy 383.416264 2.22865) (xy 383.539413 2.160587) (xy 383.658552 2.085726) (xy 383.773307 2.004302)
			(xy 383.883316 1.916573) (xy 383.988232 1.822813) (xy 384.087726 1.723318) (xy 384.181485 1.6184)
			(xy 384.269214 1.508391) (xy 384.350637 1.393636) (xy 384.425497 1.274496) (xy 384.493559 1.151346)
			(xy 384.554609 1.024573) (xy 384.608455 0.894577) (xy 384.654928 0.761766) (xy 384.69388 0.626559)
			(xy 384.72519 0.48938) (xy 384.748759 0.350661) (xy 384.764513 0.210839) (xy 384.772403 0.070353)
			(xy 384.772916 0) (xy 384.772916 -8.850122) (xy 384.773439 -8.905928) (xy 384.781781 -9.017229) (xy 384.798418 -9.127595)
			(xy 384.823255 -9.236409) (xy 384.856155 -9.343062) (xy 384.896933 -9.446959) (xy 384.945361 -9.547518)
			(xy 385.001169 -9.644177) (xy 385.064044 -9.736395) (xy 385.133634 -9.823656) (xy 385.209551 -9.905473)
			(xy 385.29137 -9.981388) (xy 385.378633 -10.050977) (xy 385.470852 -10.113849) (xy 385.567512 -10.169655)
			(xy 385.668072 -10.218081) (xy 385.77197 -10.258856) (xy 385.878624 -10.291754) (xy 385.987439 -10.316589)
			(xy 386.097805 -10.333223) (xy 386.209106 -10.341563) (xy 386.264912 -10.342118) (xy 388.264908 -10.342118)
			(xy 388.320715 -10.341596) (xy 388.432017 -10.333255) (xy 388.542385 -10.316619) (xy 388.651201 -10.291782)
			(xy 388.757856 -10.258883) (xy 388.861755 -10.218106) (xy 388.962316 -10.169678) (xy 389.058977 -10.113871)
			(xy 389.151197 -10.050997) (xy 389.238461 -9.981407) (xy 389.32028 -9.90549) (xy 389.396198 -9.823671)
			(xy 389.465789 -9.736408) (xy 389.528664 -9.644189) (xy 389.584472 -9.547528) (xy 389.6329 -9.446968)
			(xy 389.673678 -9.343069) (xy 389.706579 -9.236414) (xy 389.731416 -9.127599) (xy 389.748053 -9.017231)
			(xy 389.756395 -8.905929) (xy 389.756904 -8.850122) (xy 389.756904 0) (xy 389.757397 0.070354) (xy 389.765287 0.21084)
			(xy 389.781041 0.350663) (xy 389.80461 0.489382) (xy 389.835921 0.626562) (xy 389.874874 0.76177)
			(xy 389.921346 0.894581) (xy 389.975193 1.024578) (xy 390.036243 1.151351) (xy 390.104306 1.274502)
			(xy 390.179167 1.393642) (xy 390.260591 1.508398) (xy 390.34832 1.618407) (xy 390.44208 1.723325)
			(xy 390.541575 1.82282) (xy 390.646493 1.91658) (xy 390.756502 2.004309) (xy 390.871258 2.085733)
			(xy 390.990398 2.160594) (xy 391.113549 2.228657) (xy 391.240322 2.289707) (xy 391.370319 2.343554)
			(xy 391.50313 2.390026) (xy 391.638338 2.428979) (xy 391.775518 2.46029) (xy 391.914237 2.483859)
			(xy 392.05406 2.499613) (xy 392.194546 2.507503) (xy 392.2649 2.507996) (xy 408.265122 2.507996)
			(xy 408.335475 2.507502) (xy 408.475961 2.499611) (xy 408.615782 2.483856) (xy 408.754501 2.460286)
			(xy 408.89168 2.428975) (xy 409.026887 2.390021) (xy 409.159697 2.343548) (xy 409.289693 2.289701)
			(xy 409.416465 2.22865) (xy 409.539614 2.160586) (xy 409.658754 2.085725) (xy 409.773508 2.004302)
			(xy 409.883516 1.916572) (xy 409.988433 1.822812) (xy 410.087927 1.723317) (xy 410.181686 1.6184)
			(xy 410.269415 1.50839) (xy 410.350837 1.393635) (xy 410.425697 1.274495) (xy 410.49376 1.151345)
			(xy 410.55481 1.024573) (xy 410.608655 0.894577) (xy 410.655128 0.761766) (xy 410.69408 0.626558)
			(xy 410.72539 0.489379) (xy 410.748959 0.350661) (xy 410.764713 0.210839) (xy 410.772603 0.070353)
			(xy 410.773118 0) (xy 410.773118 -8.850122) (xy 410.773641 -8.905928) (xy 410.781983 -9.017229) (xy 410.79862 -9.127595)
			(xy 410.823457 -9.236408) (xy 410.856357 -9.343062) (xy 410.897135 -9.446959) (xy 410.945563 -9.547518)
			(xy 411.001371 -9.644176) (xy 411.064246 -9.736394) (xy 411.133836 -9.823656) (xy 411.209753 -9.905472)
			(xy 411.291572 -9.981387) (xy 411.378835 -10.050976) (xy 411.471054 -10.113848) (xy 411.567714 -10.169653)
			(xy 411.668274 -10.218079) (xy 411.772172 -10.258855) (xy 411.878826 -10.291752) (xy 411.987641 -10.316587)
			(xy 412.098007 -10.333221) (xy 412.209308 -10.341561) (xy 412.265114 -10.342118) (xy 414.26511 -10.342118)
			(xy 414.320917 -10.341596) (xy 414.432219 -10.333254) (xy 414.542587 -10.316619) (xy 414.651402 -10.291782)
			(xy 414.758058 -10.258883) (xy 414.861956 -10.218105) (xy 414.962517 -10.169678) (xy 415.059178 -10.11387)
			(xy 415.151398 -10.050996) (xy 415.238662 -9.981406) (xy 415.320481 -9.905489) (xy 415.396398 -9.823671)
			(xy 415.465989 -9.736408) (xy 415.528864 -9.644188) (xy 415.584672 -9.547528) (xy 415.6331 -9.446967)
			(xy 415.673879 -9.343069) (xy 415.706779 -9.236414) (xy 415.731616 -9.127598) (xy 415.748253 -9.017231)
			(xy 415.756595 -8.905929) (xy 415.757106 -8.850122) (xy 415.757106 0) (xy 415.75759 0.070354) (xy 415.76548 0.210841)
			(xy 415.781234 0.350664) (xy 415.804804 0.489384) (xy 415.836114 0.626564) (xy 415.875067 0.761772)
			(xy 415.92154 0.894584) (xy 415.975387 1.024581) (xy 416.036438 1.151355) (xy 416.104501 1.274506)
			(xy 416.179362 1.393647) (xy 416.260785 1.508402) (xy 416.348515 1.618412) (xy 416.442276 1.72333)
			(xy 416.541771 1.822826) (xy 416.646689 1.916586) (xy 416.756699 2.004316) (xy 416.871455 2.085739)
			(xy 416.990596 2.1606) (xy 417.113747 2.228663) (xy 417.24052 2.289714) (xy 417.370518 2.343561)
			(xy 417.503329 2.390034) (xy 417.638538 2.428986) (xy 417.775718 2.460297) (xy 417.914438 2.483866)
			(xy 418.054261 2.49962) (xy 418.194748 2.50751) (xy 418.265102 2.507996) (xy 434.26507 2.507996)
			(xy 434.335425 2.507513) (xy 434.475912 2.499625) (xy 434.615737 2.483872) (xy 434.754458 2.460304)
			(xy 434.89164 2.428994) (xy 435.02685 2.390042) (xy 435.159663 2.34357) (xy 435.289662 2.289724)
			(xy 435.416437 2.228674) (xy 435.539589 2.160612) (xy 435.658732 2.085751) (xy 435.773489 2.004327)
			(xy 435.8835 1.916597) (xy 435.988419 1.822837) (xy 436.087916 1.723341) (xy 436.181678 1.618423)
			(xy 436.269409 1.508413) (xy 436.350834 1.393656) (xy 436.425696 1.274515) (xy 436.49376 1.151363)
			(xy 436.554812 1.024589) (xy 436.60866 0.894591) (xy 436.655133 0.761778) (xy 436.694087 0.626569)
			(xy 436.725398 0.489387) (xy 436.748967 0.350667) (xy 436.764722 0.210842) (xy 436.772612 0.070355)
			(xy 436.773066 0) (xy 436.773066 -8.850122) (xy 436.773589 -8.905929) (xy 436.781931 -9.017231) (xy 436.798567 -9.127598)
			(xy 436.823405 -9.236414) (xy 436.856304 -9.343069) (xy 436.897082 -9.446967) (xy 436.94551 -9.547528)
			(xy 437.001317 -9.644188) (xy 437.064191 -9.736408) (xy 437.133781 -9.823672) (xy 437.209698 -9.905491)
			(xy 437.291516 -9.981408) (xy 437.378779 -10.050999) (xy 437.470998 -10.113874) (xy 437.567658 -10.169683)
			(xy 437.668218 -10.218112) (xy 437.772116 -10.25889) (xy 437.878771 -10.291791) (xy 437.987586 -10.31663)
			(xy 438.097953 -10.333267) (xy 438.209255 -10.341611) (xy 438.265062 -10.342118) (xy 440.265058 -10.342118)
			(xy 440.320867 -10.34161) (xy 440.432173 -10.333272) (xy 440.542544 -10.316639) (xy 440.651364 -10.291805)
			(xy 440.758023 -10.258908) (xy 440.861926 -10.218132) (xy 440.962491 -10.169705) (xy 441.059156 -10.113899)
			(xy 441.151381 -10.051025) (xy 441.238648 -9.981434) (xy 441.320471 -9.905517) (xy 441.396392 -9.823697)
			(xy 441.465987 -9.736432) (xy 441.528865 -9.64421) (xy 441.584675 -9.547548) (xy 441.633106 -9.446985)
			(xy 441.673887 -9.343084) (xy 441.706788 -9.236425) (xy 441.731628 -9.127607) (xy 441.748265 -9.017236)
			(xy 441.756608 -8.905931) (xy 441.757054 -8.850122) (xy 441.757054 0) (xy 441.757538 0.070353) (xy 441.765428 0.210839)
			(xy 441.781182 0.350661) (xy 441.804752 0.48938) (xy 441.836062 0.626559) (xy 441.875016 0.761767)
			(xy 441.921489 0.894578) (xy 441.975336 1.024574) (xy 442.036387 1.151346) (xy 442.10445 1.274495)
			(xy 442.179312 1.393635) (xy 442.260736 1.508389) (xy 442.348466 1.618398) (xy 442.442227 1.723314)
			(xy 442.541722 1.822808) (xy 442.64664 1.916566) (xy 442.756651 2.004294) (xy 442.871407 2.085716)
			(xy 442.990548 2.160575) (xy 443.113699 2.228636) (xy 443.240472 2.289685) (xy 443.370469 2.343529)
			(xy 443.503281 2.39) (xy 443.638489 2.42895) (xy 443.775669 2.460258) (xy 443.914388 2.483825) (xy 444.054211 2.499576)
			(xy 444.194697 2.507463) (xy 444.26505 2.507996) (xy 465.600034 2.507996) (xy 465.65584 2.508519)
			(xy 465.767141 2.516862) (xy 465.877506 2.533499) (xy 465.98632 2.558338) (xy 466.092974 2.591238)
			(xy 466.19687 2.632016) (xy 466.297429 2.680445) (xy 466.394088 2.736252) (xy 466.486306 2.799127)
			(xy 466.573567 2.868717) (xy 466.655384 2.944634) (xy 466.7313 3.026452) (xy 466.800888 3.113715)
			(xy 466.863762 3.205934) (xy 466.919568 3.302594) (xy 466.967994 3.403154) (xy 467.008771 3.507051)
			(xy 467.041669 3.613705) (xy 467.066505 3.722519) (xy 467.083141 3.832885) (xy 467.091482 3.944186)
			(xy 467.09203 3.999992) (xy 467.09203 24.157686) (xy 467.091509 24.213494) (xy 467.083169 24.324797)
			(xy 467.066535 24.435167) (xy 467.041699 24.543984) (xy 467.008801 24.650641) (xy 466.968025 24.754542)
			(xy 466.919598 24.855105) (xy 466.863791 24.951768) (xy 466.800917 25.04399) (xy 466.731327 25.131255)
			(xy 466.655411 25.213077) (xy 466.573592 25.288996) (xy 466.486328 25.358589) (xy 466.394108 25.421466)
			(xy 466.297447 25.477275) (xy 466.196886 25.525705) (xy 466.092987 25.566485) (xy 465.986331 25.599387)
			(xy 465.877514 25.624226) (xy 465.767145 25.640863) (xy 465.655842 25.649207) (xy 465.600034 25.649682)
			(xy 160.11398 25.649682) (xy 160.058174 25.64916) (xy 159.946873 25.640817) (xy 159.836507 25.624181)
			(xy 159.727693 25.599343) (xy 159.62104 25.566443) (xy 159.517143 25.525665) (xy 159.416584 25.477237)
			(xy 159.319925 25.42143) (xy 159.227707 25.358555) (xy 159.140445 25.288965) (xy 159.058628 25.213048)
			(xy 158.982713 25.131229) (xy 158.913125 25.043966) (xy 158.850252 24.951746) (xy 158.794447 24.855086)
			(xy 158.746021 24.754526) (xy 158.705245 24.650628) (xy 158.672348 24.543974) (xy 158.647513 24.435159)
			(xy 158.630879 24.324793) (xy 158.622539 24.213492) (xy 158.621984 24.157686) (xy 158.621984 21.802649)
			(xy 269.304757 21.802649) (xy 269.304757 21.888399) (xy 269.312669 21.973782) (xy 269.328425 22.058072)
			(xy 269.351892 22.140548) (xy 269.382868 22.220507) (xy 269.42109 22.297267) (xy 269.466231 22.370173)
			(xy 269.517907 22.438602) (xy 269.575676 22.501972) (xy 269.639046 22.559741) (xy 269.707475 22.611417)
			(xy 269.780381 22.656558) (xy 269.857141 22.69478) (xy 269.9371 22.725756) (xy 270.019576 22.749223)
			(xy 270.103866 22.764979) (xy 270.189249 22.772891) (xy 270.274999 22.772891) (xy 270.360382 22.764979)
			(xy 270.444672 22.749223) (xy 270.527148 22.725756) (xy 270.607107 22.69478) (xy 270.683867 22.656558)
			(xy 270.756773 22.611417) (xy 270.825202 22.559741) (xy 270.888572 22.501972) (xy 270.946341 22.438602)
			(xy 270.998017 22.370173) (xy 271.043158 22.297267) (xy 271.08138 22.220507) (xy 271.112356 22.140548)
			(xy 271.135823 22.058072) (xy 271.151579 21.973782) (xy 271.159491 21.888399) (xy 271.159986 21.845524)
			(xy 271.159491 21.802649) (xy 275.654757 21.802649) (xy 275.654757 21.888399) (xy 275.662669 21.973782)
			(xy 275.678425 22.058072) (xy 275.701892 22.140548) (xy 275.732868 22.220507) (xy 275.77109 22.297267)
			(xy 275.816231 22.370173) (xy 275.867907 22.438602) (xy 275.925676 22.501972) (xy 275.989046 22.559741)
			(xy 276.057475 22.611417) (xy 276.130381 22.656558) (xy 276.207141 22.69478) (xy 276.2871 22.725756)
			(xy 276.369576 22.749223) (xy 276.453866 22.764979) (xy 276.539249 22.772891) (xy 276.624999 22.772891)
			(xy 276.710382 22.764979) (xy 276.794672 22.749223) (xy 276.877148 22.725756) (xy 276.957107 22.69478)
			(xy 277.033867 22.656558) (xy 277.106773 22.611417) (xy 277.175202 22.559741) (xy 277.238572 22.501972)
			(xy 277.296341 22.438602) (xy 277.348017 22.370173) (xy 277.393158 22.297267) (xy 277.43138 22.220507)
			(xy 277.462356 22.140548) (xy 277.485823 22.058072) (xy 277.501579 21.973782) (xy 277.509491 21.888399)
			(xy 277.509986 21.845524) (xy 277.509491 21.802649) (xy 277.508832 21.795537) (xy 308.364877 21.795537)
			(xy 308.364877 21.881287) (xy 308.372789 21.96667) (xy 308.388545 22.05096) (xy 308.412012 22.133436)
			(xy 308.442988 22.213395) (xy 308.48121 22.290155) (xy 308.526351 22.363061) (xy 308.578027 22.43149)
			(xy 308.635796 22.49486) (xy 308.699166 22.552629) (xy 308.767595 22.604305) (xy 308.840501 22.649446)
			(xy 308.917261 22.687668) (xy 308.99722 22.718644) (xy 309.079696 22.742111) (xy 309.163986 22.757867)
			(xy 309.249369 22.765779) (xy 309.335119 22.765779) (xy 309.420502 22.757867) (xy 309.504792 22.742111)
			(xy 309.587268 22.718644) (xy 309.667227 22.687668) (xy 309.743987 22.649446) (xy 309.816893 22.604305)
			(xy 309.885322 22.552629) (xy 309.948692 22.49486) (xy 310.006461 22.43149) (xy 310.058137 22.363061)
			(xy 310.103278 22.290155) (xy 310.1415 22.213395) (xy 310.172476 22.133436) (xy 310.195943 22.05096)
			(xy 310.211699 21.96667) (xy 310.219611 21.881287) (xy 310.220106 21.838412) (xy 310.219611 21.795537)
			(xy 314.714877 21.795537) (xy 314.714877 21.881287) (xy 314.722789 21.96667) (xy 314.738545 22.05096)
			(xy 314.762012 22.133436) (xy 314.792988 22.213395) (xy 314.83121 22.290155) (xy 314.876351 22.363061)
			(xy 314.928027 22.43149) (xy 314.985796 22.49486) (xy 315.049166 22.552629) (xy 315.117595 22.604305)
			(xy 315.190501 22.649446) (xy 315.267261 22.687668) (xy 315.34722 22.718644) (xy 315.429696 22.742111)
			(xy 315.513986 22.757867) (xy 315.599369 22.765779) (xy 315.685119 22.765779) (xy 315.770502 22.757867)
			(xy 315.854792 22.742111) (xy 315.937268 22.718644) (xy 316.017227 22.687668) (xy 316.093987 22.649446)
			(xy 316.166893 22.604305) (xy 316.235322 22.552629) (xy 316.298692 22.49486) (xy 316.356461 22.43149)
			(xy 316.408137 22.363061) (xy 316.453278 22.290155) (xy 316.4915 22.213395) (xy 316.522476 22.133436)
			(xy 316.545943 22.05096) (xy 316.561699 21.96667) (xy 316.569611 21.881287) (xy 316.570106 21.838412)
			(xy 316.569693 21.802649) (xy 334.455757 21.802649) (xy 334.455757 21.888399) (xy 334.463669 21.973782)
			(xy 334.479425 22.058072) (xy 334.502892 22.140548) (xy 334.533868 22.220507) (xy 334.57209 22.297267)
			(xy 334.617231 22.370173) (xy 334.668907 22.438602) (xy 334.726676 22.501972) (xy 334.790046 22.559741)
			(xy 334.858475 22.611417) (xy 334.931381 22.656558) (xy 335.008141 22.69478) (xy 335.0881 22.725756)
			(xy 335.170576 22.749223) (xy 335.254866 22.764979) (xy 335.340249 22.772891) (xy 335.425999 22.772891)
			(xy 335.511382 22.764979) (xy 335.595672 22.749223) (xy 335.678148 22.725756) (xy 335.758107 22.69478)
			(xy 335.834867 22.656558) (xy 335.907773 22.611417) (xy 335.976202 22.559741) (xy 336.039572 22.501972)
			(xy 336.097341 22.438602) (xy 336.149017 22.370173) (xy 336.194158 22.297267) (xy 336.23238 22.220507)
			(xy 336.263356 22.140548) (xy 336.286823 22.058072) (xy 336.302579 21.973782) (xy 336.310491 21.888399)
			(xy 336.310986 21.845524) (xy 336.310491 21.802649) (xy 340.805757 21.802649) (xy 340.805757 21.888399)
			(xy 340.813669 21.973782) (xy 340.829425 22.058072) (xy 340.852892 22.140548) (xy 340.883868 22.220507)
			(xy 340.92209 22.297267) (xy 340.967231 22.370173) (xy 341.018907 22.438602) (xy 341.076676 22.501972)
			(xy 341.140046 22.559741) (xy 341.208475 22.611417) (xy 341.281381 22.656558) (xy 341.358141 22.69478)
			(xy 341.4381 22.725756) (xy 341.520576 22.749223) (xy 341.604866 22.764979) (xy 341.690249 22.772891)
			(xy 341.775999 22.772891) (xy 341.861382 22.764979) (xy 341.945672 22.749223) (xy 342.028148 22.725756)
			(xy 342.108107 22.69478) (xy 342.184867 22.656558) (xy 342.257773 22.611417) (xy 342.326202 22.559741)
			(xy 342.389572 22.501972) (xy 342.447341 22.438602) (xy 342.499017 22.370173) (xy 342.544158 22.297267)
			(xy 342.58238 22.220507) (xy 342.613356 22.140548) (xy 342.636823 22.058072) (xy 342.652579 21.973782)
			(xy 342.660491 21.888399) (xy 342.660986 21.845524) (xy 342.660491 21.802649) (xy 342.659832 21.795537)
			(xy 373.515877 21.795537) (xy 373.515877 21.881287) (xy 373.523789 21.96667) (xy 373.539545 22.05096)
			(xy 373.563012 22.133436) (xy 373.593988 22.213395) (xy 373.63221 22.290155) (xy 373.677351 22.363061)
			(xy 373.729027 22.43149) (xy 373.786796 22.49486) (xy 373.850166 22.552629) (xy 373.918595 22.604305)
			(xy 373.991501 22.649446) (xy 374.068261 22.687668) (xy 374.14822 22.718644) (xy 374.230696 22.742111)
			(xy 374.314986 22.757867) (xy 374.400369 22.765779) (xy 374.486119 22.765779) (xy 374.571502 22.757867)
			(xy 374.655792 22.742111) (xy 374.738268 22.718644) (xy 374.818227 22.687668) (xy 374.894987 22.649446)
			(xy 374.967893 22.604305) (xy 375.036322 22.552629) (xy 375.099692 22.49486) (xy 375.157461 22.43149)
			(xy 375.209137 22.363061) (xy 375.254278 22.290155) (xy 375.2925 22.213395) (xy 375.323476 22.133436)
			(xy 375.346943 22.05096) (xy 375.362699 21.96667) (xy 375.370611 21.881287) (xy 375.371106 21.838412)
			(xy 375.370611 21.795537) (xy 379.865877 21.795537) (xy 379.865877 21.881287) (xy 379.873789 21.96667)
			(xy 379.889545 22.05096) (xy 379.913012 22.133436) (xy 379.943988 22.213395) (xy 379.98221 22.290155)
			(xy 380.027351 22.363061) (xy 380.079027 22.43149) (xy 380.136796 22.49486) (xy 380.200166 22.552629)
			(xy 380.268595 22.604305) (xy 380.341501 22.649446) (xy 380.418261 22.687668) (xy 380.49822 22.718644)
			(xy 380.580696 22.742111) (xy 380.664986 22.757867) (xy 380.750369 22.765779) (xy 380.836119 22.765779)
			(xy 380.921502 22.757867) (xy 381.005792 22.742111) (xy 381.088268 22.718644) (xy 381.168227 22.687668)
			(xy 381.244987 22.649446) (xy 381.317893 22.604305) (xy 381.386322 22.552629) (xy 381.449692 22.49486)
			(xy 381.507461 22.43149) (xy 381.559137 22.363061) (xy 381.604278 22.290155) (xy 381.6425 22.213395)
			(xy 381.673476 22.133436) (xy 381.696943 22.05096) (xy 381.712699 21.96667) (xy 381.720611 21.881287)
			(xy 381.721106 21.838412) (xy 381.720693 21.802649) (xy 399.098757 21.802649) (xy 399.098757 21.888399)
			(xy 399.106669 21.973782) (xy 399.122425 22.058072) (xy 399.145892 22.140548) (xy 399.176868 22.220507)
			(xy 399.21509 22.297267) (xy 399.260231 22.370173) (xy 399.311907 22.438602) (xy 399.369676 22.501972)
			(xy 399.433046 22.559741) (xy 399.501475 22.611417) (xy 399.574381 22.656558) (xy 399.651141 22.69478)
			(xy 399.7311 22.725756) (xy 399.813576 22.749223) (xy 399.897866 22.764979) (xy 399.983249 22.772891)
			(xy 400.068999 22.772891) (xy 400.154382 22.764979) (xy 400.238672 22.749223) (xy 400.321148 22.725756)
			(xy 400.401107 22.69478) (xy 400.477867 22.656558) (xy 400.550773 22.611417) (xy 400.619202 22.559741)
			(xy 400.682572 22.501972) (xy 400.740341 22.438602) (xy 400.792017 22.370173) (xy 400.837158 22.297267)
			(xy 400.87538 22.220507) (xy 400.906356 22.140548) (xy 400.929823 22.058072) (xy 400.945579 21.973782)
			(xy 400.953491 21.888399) (xy 400.953986 21.845524) (xy 400.953491 21.802649) (xy 405.448757 21.802649)
			(xy 405.448757 21.888399) (xy 405.456669 21.973782) (xy 405.472425 22.058072) (xy 405.495892 22.140548)
			(xy 405.526868 22.220507) (xy 405.56509 22.297267) (xy 405.610231 22.370173) (xy 405.661907 22.438602)
			(xy 405.719676 22.501972) (xy 405.783046 22.559741) (xy 405.851475 22.611417) (xy 405.924381 22.656558)
			(xy 406.001141 22.69478) (xy 406.0811 22.725756) (xy 406.163576 22.749223) (xy 406.247866 22.764979)
			(xy 406.333249 22.772891) (xy 406.418999 22.772891) (xy 406.504382 22.764979) (xy 406.588672 22.749223)
			(xy 406.671148 22.725756) (xy 406.751107 22.69478) (xy 406.827867 22.656558) (xy 406.900773 22.611417)
			(xy 406.969202 22.559741) (xy 407.032572 22.501972) (xy 407.090341 22.438602) (xy 407.142017 22.370173)
			(xy 407.187158 22.297267) (xy 407.22538 22.220507) (xy 407.256356 22.140548) (xy 407.279823 22.058072)
			(xy 407.295579 21.973782) (xy 407.303491 21.888399) (xy 407.303986 21.845524) (xy 407.303491 21.802649)
			(xy 407.302832 21.795537) (xy 438.158877 21.795537) (xy 438.158877 21.881287) (xy 438.166789 21.96667)
			(xy 438.182545 22.05096) (xy 438.206012 22.133436) (xy 438.236988 22.213395) (xy 438.27521 22.290155)
			(xy 438.320351 22.363061) (xy 438.372027 22.43149) (xy 438.429796 22.49486) (xy 438.493166 22.552629)
			(xy 438.561595 22.604305) (xy 438.634501 22.649446) (xy 438.711261 22.687668) (xy 438.79122 22.718644)
			(xy 438.873696 22.742111) (xy 438.957986 22.757867) (xy 439.043369 22.765779) (xy 439.129119 22.765779)
			(xy 439.214502 22.757867) (xy 439.298792 22.742111) (xy 439.381268 22.718644) (xy 439.461227 22.687668)
			(xy 439.537987 22.649446) (xy 439.610893 22.604305) (xy 439.679322 22.552629) (xy 439.742692 22.49486)
			(xy 439.800461 22.43149) (xy 439.852137 22.363061) (xy 439.897278 22.290155) (xy 439.9355 22.213395)
			(xy 439.966476 22.133436) (xy 439.989943 22.05096) (xy 440.005699 21.96667) (xy 440.013611 21.881287)
			(xy 440.014106 21.838412) (xy 440.013611 21.795537) (xy 444.508877 21.795537) (xy 444.508877 21.881287)
			(xy 444.516789 21.96667) (xy 444.532545 22.05096) (xy 444.556012 22.133436) (xy 444.586988 22.213395)
			(xy 444.62521 22.290155) (xy 444.670351 22.363061) (xy 444.722027 22.43149) (xy 444.779796 22.49486)
			(xy 444.843166 22.552629) (xy 444.911595 22.604305) (xy 444.984501 22.649446) (xy 445.061261 22.687668)
			(xy 445.14122 22.718644) (xy 445.223696 22.742111) (xy 445.307986 22.757867) (xy 445.393369 22.765779)
			(xy 445.479119 22.765779) (xy 445.564502 22.757867) (xy 445.648792 22.742111) (xy 445.731268 22.718644)
			(xy 445.811227 22.687668) (xy 445.887987 22.649446) (xy 445.960893 22.604305) (xy 446.029322 22.552629)
			(xy 446.092692 22.49486) (xy 446.150461 22.43149) (xy 446.202137 22.363061) (xy 446.247278 22.290155)
			(xy 446.2855 22.213395) (xy 446.316476 22.133436) (xy 446.339943 22.05096) (xy 446.355699 21.96667)
			(xy 446.363611 21.881287) (xy 446.364106 21.838412) (xy 446.363611 21.795537) (xy 446.355699 21.710154)
			(xy 446.339943 21.625864) (xy 446.316476 21.543388) (xy 446.2855 21.463429) (xy 446.247278 21.386669)
			(xy 446.202137 21.313763) (xy 446.150461 21.245334) (xy 446.092692 21.181964) (xy 446.029322 21.124195)
			(xy 445.988175 21.093122) (xy 460.504275 21.093122) (xy 460.504275 21.222262) (xy 460.512225 21.351157)
			(xy 460.528095 21.479317) (xy 460.551824 21.606258) (xy 460.583323 21.731497) (xy 460.622472 21.85456)
			(xy 460.669123 21.974979) (xy 460.723098 22.092298) (xy 460.784193 22.206072) (xy 460.852176 22.315869)
			(xy 460.92679 22.421272) (xy 461.007751 22.521882) (xy 461.094751 22.617317) (xy 461.187462 22.707216)
			(xy 461.285532 22.791237) (xy 461.388587 22.869061) (xy 461.496238 22.940393) (xy 461.608077 23.004963)
			(xy 461.723678 23.062525) (xy 461.842603 23.112862) (xy 461.964402 23.155782) (xy 462.088612 23.191123)
			(xy 462.214761 23.21875) (xy 462.342373 23.238559) (xy 462.470962 23.250475) (xy 462.60004 23.254452)
			(xy 462.729118 23.250475) (xy 462.857707 23.238559) (xy 462.985319 23.21875) (xy 463.111468 23.191123)
			(xy 463.235678 23.155782) (xy 463.357477 23.112862) (xy 463.476402 23.062525) (xy 463.592003 23.004963)
			(xy 463.703842 22.940393) (xy 463.811493 22.869061) (xy 463.914548 22.791237) (xy 464.012618 22.707216)
			(xy 464.105329 22.617317) (xy 464.192329 22.521882) (xy 464.27329 22.421272) (xy 464.347904 22.315869)
			(xy 464.415887 22.206072) (xy 464.476982 22.092298) (xy 464.530957 21.974979) (xy 464.577608 21.85456)
			(xy 464.616757 21.731497) (xy 464.648256 21.606258) (xy 464.671985 21.479317) (xy 464.687855 21.351157)
			(xy 464.695805 21.222262) (xy 464.696302 21.157692) (xy 464.695805 21.093122) (xy 464.687855 20.964227)
			(xy 464.671985 20.836067) (xy 464.648256 20.709126) (xy 464.616757 20.583887) (xy 464.577608 20.460824)
			(xy 464.530957 20.340405) (xy 464.476982 20.223086) (xy 464.415887 20.109312) (xy 464.347904 19.999515)
			(xy 464.27329 19.894112) (xy 464.192329 19.793502) (xy 464.105329 19.698067) (xy 464.012618 19.608168)
			(xy 463.914548 19.524147) (xy 463.811493 19.446323) (xy 463.703842 19.374991) (xy 463.592003 19.310421)
			(xy 463.476402 19.252859) (xy 463.357477 19.202522) (xy 463.235678 19.159602) (xy 463.111468 19.124261)
			(xy 462.985319 19.096634) (xy 462.857707 19.076825) (xy 462.729118 19.064909) (xy 462.60004 19.060933)
			(xy 462.470962 19.064909) (xy 462.342373 19.076825) (xy 462.214761 19.096634) (xy 462.088612 19.124261)
			(xy 461.964402 19.159602) (xy 461.842603 19.202522) (xy 461.723678 19.252859) (xy 461.608077 19.310421)
			(xy 461.496238 19.374991) (xy 461.388587 19.446323) (xy 461.285532 19.524147) (xy 461.187462 19.608168)
			(xy 461.094751 19.698067) (xy 461.007751 19.793502) (xy 460.92679 19.894112) (xy 460.852176 19.999515)
			(xy 460.784193 20.109312) (xy 460.723098 20.223086) (xy 460.669123 20.340405) (xy 460.622472 20.460824)
			(xy 460.583323 20.583887) (xy 460.551824 20.709126) (xy 460.528095 20.836067) (xy 460.512225 20.964227)
			(xy 460.504275 21.093122) (xy 445.988175 21.093122) (xy 445.960893 21.072519) (xy 445.887987 21.027378)
			(xy 445.811227 20.989156) (xy 445.731268 20.95818) (xy 445.648792 20.934713) (xy 445.564502 20.918957)
			(xy 445.479119 20.911045) (xy 445.393369 20.911045) (xy 445.307986 20.918957) (xy 445.223696 20.934713)
			(xy 445.14122 20.95818) (xy 445.061261 20.989156) (xy 444.984501 21.027378) (xy 444.911595 21.072519)
			(xy 444.843166 21.124195) (xy 444.779796 21.181964) (xy 444.722027 21.245334) (xy 444.670351 21.313763)
			(xy 444.62521 21.386669) (xy 444.586988 21.463429) (xy 444.556012 21.543388) (xy 444.532545 21.625864)
			(xy 444.516789 21.710154) (xy 444.508877 21.795537) (xy 440.013611 21.795537) (xy 440.005699 21.710154)
			(xy 439.989943 21.625864) (xy 439.966476 21.543388) (xy 439.9355 21.463429) (xy 439.897278 21.386669)
			(xy 439.852137 21.313763) (xy 439.800461 21.245334) (xy 439.742692 21.181964) (xy 439.679322 21.124195)
			(xy 439.610893 21.072519) (xy 439.537987 21.027378) (xy 439.461227 20.989156) (xy 439.381268 20.95818)
			(xy 439.298792 20.934713) (xy 439.214502 20.918957) (xy 439.129119 20.911045) (xy 439.043369 20.911045)
			(xy 438.957986 20.918957) (xy 438.873696 20.934713) (xy 438.79122 20.95818) (xy 438.711261 20.989156)
			(xy 438.634501 21.027378) (xy 438.561595 21.072519) (xy 438.493166 21.124195) (xy 438.429796 21.181964)
			(xy 438.372027 21.245334) (xy 438.320351 21.313763) (xy 438.27521 21.386669) (xy 438.236988 21.463429)
			(xy 438.206012 21.543388) (xy 438.182545 21.625864) (xy 438.166789 21.710154) (xy 438.158877 21.795537)
			(xy 407.302832 21.795537) (xy 407.295579 21.717266) (xy 407.279823 21.632976) (xy 407.256356 21.5505)
			(xy 407.22538 21.470541) (xy 407.187158 21.393781) (xy 407.142017 21.320875) (xy 407.090341 21.252446)
			(xy 407.032572 21.189076) (xy 406.969202 21.131307) (xy 406.900773 21.079631) (xy 406.827867 21.03449)
			(xy 406.751107 20.996268) (xy 406.671148 20.965292) (xy 406.588672 20.941825) (xy 406.504382 20.926069)
			(xy 406.418999 20.918157) (xy 406.333249 20.918157) (xy 406.247866 20.926069) (xy 406.163576 20.941825)
			(xy 406.0811 20.965292) (xy 406.001141 20.996268) (xy 405.924381 21.03449) (xy 405.851475 21.079631)
			(xy 405.783046 21.131307) (xy 405.719676 21.189076) (xy 405.661907 21.252446) (xy 405.610231 21.320875)
			(xy 405.56509 21.393781) (xy 405.526868 21.470541) (xy 405.495892 21.5505) (xy 405.472425 21.632976)
			(xy 405.456669 21.717266) (xy 405.448757 21.802649) (xy 400.953491 21.802649) (xy 400.945579 21.717266)
			(xy 400.929823 21.632976) (xy 400.906356 21.5505) (xy 400.87538 21.470541) (xy 400.837158 21.393781)
			(xy 400.792017 21.320875) (xy 400.740341 21.252446) (xy 400.682572 21.189076) (xy 400.619202 21.131307)
			(xy 400.550773 21.079631) (xy 400.477867 21.03449) (xy 400.401107 20.996268) (xy 400.321148 20.965292)
			(xy 400.238672 20.941825) (xy 400.154382 20.926069) (xy 400.068999 20.918157) (xy 399.983249 20.918157)
			(xy 399.897866 20.926069) (xy 399.813576 20.941825) (xy 399.7311 20.965292) (xy 399.651141 20.996268)
			(xy 399.574381 21.03449) (xy 399.501475 21.079631) (xy 399.433046 21.131307) (xy 399.369676 21.189076)
			(xy 399.311907 21.252446) (xy 399.260231 21.320875) (xy 399.21509 21.393781) (xy 399.176868 21.470541)
			(xy 399.145892 21.5505) (xy 399.122425 21.632976) (xy 399.106669 21.717266) (xy 399.098757 21.802649)
			(xy 381.720693 21.802649) (xy 381.720611 21.795537) (xy 381.712699 21.710154) (xy 381.696943 21.625864)
			(xy 381.673476 21.543388) (xy 381.6425 21.463429) (xy 381.604278 21.386669) (xy 381.559137 21.313763)
			(xy 381.507461 21.245334) (xy 381.449692 21.181964) (xy 381.386322 21.124195) (xy 381.317893 21.072519)
			(xy 381.244987 21.027378) (xy 381.168227 20.989156) (xy 381.088268 20.95818) (xy 381.005792 20.934713)
			(xy 380.921502 20.918957) (xy 380.836119 20.911045) (xy 380.750369 20.911045) (xy 380.664986 20.918957)
			(xy 380.580696 20.934713) (xy 380.49822 20.95818) (xy 380.418261 20.989156) (xy 380.341501 21.027378)
			(xy 380.268595 21.072519) (xy 380.200166 21.124195) (xy 380.136796 21.181964) (xy 380.079027 21.245334)
			(xy 380.027351 21.313763) (xy 379.98221 21.386669) (xy 379.943988 21.463429) (xy 379.913012 21.543388)
			(xy 379.889545 21.625864) (xy 379.873789 21.710154) (xy 379.865877 21.795537) (xy 375.370611 21.795537)
			(xy 375.362699 21.710154) (xy 375.346943 21.625864) (xy 375.323476 21.543388) (xy 375.2925 21.463429)
			(xy 375.254278 21.386669) (xy 375.209137 21.313763) (xy 375.157461 21.245334) (xy 375.099692 21.181964)
			(xy 375.036322 21.124195) (xy 374.967893 21.072519) (xy 374.894987 21.027378) (xy 374.818227 20.989156)
			(xy 374.738268 20.95818) (xy 374.655792 20.934713) (xy 374.571502 20.918957) (xy 374.486119 20.911045)
			(xy 374.400369 20.911045) (xy 374.314986 20.918957) (xy 374.230696 20.934713) (xy 374.14822 20.95818)
			(xy 374.068261 20.989156) (xy 373.991501 21.027378) (xy 373.918595 21.072519) (xy 373.850166 21.124195)
			(xy 373.786796 21.181964) (xy 373.729027 21.245334) (xy 373.677351 21.313763) (xy 373.63221 21.386669)
			(xy 373.593988 21.463429) (xy 373.563012 21.543388) (xy 373.539545 21.625864) (xy 373.523789 21.710154)
			(xy 373.515877 21.795537) (xy 342.659832 21.795537) (xy 342.652579 21.717266) (xy 342.636823 21.632976)
			(xy 342.613356 21.5505) (xy 342.58238 21.470541) (xy 342.544158 21.393781) (xy 342.499017 21.320875)
			(xy 342.447341 21.252446) (xy 342.389572 21.189076) (xy 342.326202 21.131307) (xy 342.257773 21.079631)
			(xy 342.184867 21.03449) (xy 342.108107 20.996268) (xy 342.028148 20.965292) (xy 341.945672 20.941825)
			(xy 341.861382 20.926069) (xy 341.775999 20.918157) (xy 341.690249 20.918157) (xy 341.604866 20.926069)
			(xy 341.520576 20.941825) (xy 341.4381 20.965292) (xy 341.358141 20.996268) (xy 341.281381 21.03449)
			(xy 341.208475 21.079631) (xy 341.140046 21.131307) (xy 341.076676 21.189076) (xy 341.018907 21.252446)
			(xy 340.967231 21.320875) (xy 340.92209 21.393781) (xy 340.883868 21.470541) (xy 340.852892 21.5505)
			(xy 340.829425 21.632976) (xy 340.813669 21.717266) (xy 340.805757 21.802649) (xy 336.310491 21.802649)
			(xy 336.302579 21.717266) (xy 336.286823 21.632976) (xy 336.263356 21.5505) (xy 336.23238 21.470541)
			(xy 336.194158 21.393781) (xy 336.149017 21.320875) (xy 336.097341 21.252446) (xy 336.039572 21.189076)
			(xy 335.976202 21.131307) (xy 335.907773 21.079631) (xy 335.834867 21.03449) (xy 335.758107 20.996268)
			(xy 335.678148 20.965292) (xy 335.595672 20.941825) (xy 335.511382 20.926069) (xy 335.425999 20.918157)
			(xy 335.340249 20.918157) (xy 335.254866 20.926069) (xy 335.170576 20.941825) (xy 335.0881 20.965292)
			(xy 335.008141 20.996268) (xy 334.931381 21.03449) (xy 334.858475 21.079631) (xy 334.790046 21.131307)
			(xy 334.726676 21.189076) (xy 334.668907 21.252446) (xy 334.617231 21.320875) (xy 334.57209 21.393781)
			(xy 334.533868 21.470541) (xy 334.502892 21.5505) (xy 334.479425 21.632976) (xy 334.463669 21.717266)
			(xy 334.455757 21.802649) (xy 316.569693 21.802649) (xy 316.569611 21.795537) (xy 316.561699 21.710154)
			(xy 316.545943 21.625864) (xy 316.522476 21.543388) (xy 316.4915 21.463429) (xy 316.453278 21.386669)
			(xy 316.408137 21.313763) (xy 316.356461 21.245334) (xy 316.298692 21.181964) (xy 316.235322 21.124195)
			(xy 316.166893 21.072519) (xy 316.093987 21.027378) (xy 316.017227 20.989156) (xy 315.937268 20.95818)
			(xy 315.854792 20.934713) (xy 315.770502 20.918957) (xy 315.685119 20.911045) (xy 315.599369 20.911045)
			(xy 315.513986 20.918957) (xy 315.429696 20.934713) (xy 315.34722 20.95818) (xy 315.267261 20.989156)
			(xy 315.190501 21.027378) (xy 315.117595 21.072519) (xy 315.049166 21.124195) (xy 314.985796 21.181964)
			(xy 314.928027 21.245334) (xy 314.876351 21.313763) (xy 314.83121 21.386669) (xy 314.792988 21.463429)
			(xy 314.762012 21.543388) (xy 314.738545 21.625864) (xy 314.722789 21.710154) (xy 314.714877 21.795537)
			(xy 310.219611 21.795537) (xy 310.211699 21.710154) (xy 310.195943 21.625864) (xy 310.172476 21.543388)
			(xy 310.1415 21.463429) (xy 310.103278 21.386669) (xy 310.058137 21.313763) (xy 310.006461 21.245334)
			(xy 309.948692 21.181964) (xy 309.885322 21.124195) (xy 309.816893 21.072519) (xy 309.743987 21.027378)
			(xy 309.667227 20.989156) (xy 309.587268 20.95818) (xy 309.504792 20.934713) (xy 309.420502 20.918957)
			(xy 309.335119 20.911045) (xy 309.249369 20.911045) (xy 309.163986 20.918957) (xy 309.079696 20.934713)
			(xy 308.99722 20.95818) (xy 308.917261 20.989156) (xy 308.840501 21.027378) (xy 308.767595 21.072519)
			(xy 308.699166 21.124195) (xy 308.635796 21.181964) (xy 308.578027 21.245334) (xy 308.526351 21.313763)
			(xy 308.48121 21.386669) (xy 308.442988 21.463429) (xy 308.412012 21.543388) (xy 308.388545 21.625864)
			(xy 308.372789 21.710154) (xy 308.364877 21.795537) (xy 277.508832 21.795537) (xy 277.501579 21.717266)
			(xy 277.485823 21.632976) (xy 277.462356 21.5505) (xy 277.43138 21.470541) (xy 277.393158 21.393781)
			(xy 277.348017 21.320875) (xy 277.296341 21.252446) (xy 277.238572 21.189076) (xy 277.175202 21.131307)
			(xy 277.106773 21.079631) (xy 277.033867 21.03449) (xy 276.957107 20.996268) (xy 276.877148 20.965292)
			(xy 276.794672 20.941825) (xy 276.710382 20.926069) (xy 276.624999 20.918157) (xy 276.539249 20.918157)
			(xy 276.453866 20.926069) (xy 276.369576 20.941825) (xy 276.2871 20.965292) (xy 276.207141 20.996268)
			(xy 276.130381 21.03449) (xy 276.057475 21.079631) (xy 275.989046 21.131307) (xy 275.925676 21.189076)
			(xy 275.867907 21.252446) (xy 275.816231 21.320875) (xy 275.77109 21.393781) (xy 275.732868 21.470541)
			(xy 275.701892 21.5505) (xy 275.678425 21.632976) (xy 275.662669 21.717266) (xy 275.654757 21.802649)
			(xy 271.159491 21.802649) (xy 271.151579 21.717266) (xy 271.135823 21.632976) (xy 271.112356 21.5505)
			(xy 271.08138 21.470541) (xy 271.043158 21.393781) (xy 270.998017 21.320875) (xy 270.946341 21.252446)
			(xy 270.888572 21.189076) (xy 270.825202 21.131307) (xy 270.756773 21.079631) (xy 270.683867 21.03449)
			(xy 270.607107 20.996268) (xy 270.527148 20.965292) (xy 270.444672 20.941825) (xy 270.360382 20.926069)
			(xy 270.274999 20.918157) (xy 270.189249 20.918157) (xy 270.103866 20.926069) (xy 270.019576 20.941825)
			(xy 269.9371 20.965292) (xy 269.857141 20.996268) (xy 269.780381 21.03449) (xy 269.707475 21.079631)
			(xy 269.639046 21.131307) (xy 269.575676 21.189076) (xy 269.517907 21.252446) (xy 269.466231 21.320875)
			(xy 269.42109 21.393781) (xy 269.382868 21.470541) (xy 269.351892 21.5505) (xy 269.328425 21.632976)
			(xy 269.312669 21.717266) (xy 269.304757 21.802649) (xy 158.621984 21.802649) (xy 158.621984 19.262649)
			(xy 209.995757 19.262649) (xy 209.995757 19.348399) (xy 210.003669 19.433782) (xy 210.019425 19.518072)
			(xy 210.042892 19.600548) (xy 210.073868 19.680507) (xy 210.11209 19.757267) (xy 210.157231 19.830173)
			(xy 210.208907 19.898602) (xy 210.266676 19.961972) (xy 210.330046 20.019741) (xy 210.398475 20.071417)
			(xy 210.471381 20.116558) (xy 210.548141 20.15478) (xy 210.6281 20.185756) (xy 210.710576 20.209223)
			(xy 210.794866 20.224979) (xy 210.880249 20.232891) (xy 210.965999 20.232891) (xy 211.051382 20.224979)
			(xy 211.135672 20.209223) (xy 211.218148 20.185756) (xy 211.298107 20.15478) (xy 211.374867 20.116558)
			(xy 211.447773 20.071417) (xy 211.516202 20.019741) (xy 211.579572 19.961972) (xy 211.637341 19.898602)
			(xy 211.689017 19.830173) (xy 211.734158 19.757267) (xy 211.77238 19.680507) (xy 211.803356 19.600548)
			(xy 211.826823 19.518072) (xy 211.842579 19.433782) (xy 211.850491 19.348399) (xy 211.850986 19.305524)
			(xy 211.850491 19.262649) (xy 216.345757 19.262649) (xy 216.345757 19.348399) (xy 216.353669 19.433782)
			(xy 216.369425 19.518072) (xy 216.392892 19.600548) (xy 216.423868 19.680507) (xy 216.46209 19.757267)
			(xy 216.507231 19.830173) (xy 216.558907 19.898602) (xy 216.616676 19.961972) (xy 216.680046 20.019741)
			(xy 216.748475 20.071417) (xy 216.821381 20.116558) (xy 216.898141 20.15478) (xy 216.9781 20.185756)
			(xy 217.060576 20.209223) (xy 217.144866 20.224979) (xy 217.230249 20.232891) (xy 217.315999 20.232891)
			(xy 217.401382 20.224979) (xy 217.485672 20.209223) (xy 217.568148 20.185756) (xy 217.648107 20.15478)
			(xy 217.724867 20.116558) (xy 217.797773 20.071417) (xy 217.866202 20.019741) (xy 217.929572 19.961972)
			(xy 217.987341 19.898602) (xy 218.039017 19.830173) (xy 218.084158 19.757267) (xy 218.12238 19.680507)
			(xy 218.153356 19.600548) (xy 218.176823 19.518072) (xy 218.192579 19.433782) (xy 218.200491 19.348399)
			(xy 218.200986 19.305524) (xy 218.200491 19.262649) (xy 218.199832 19.255537) (xy 244.026677 19.255537)
			(xy 244.026677 19.341287) (xy 244.034589 19.42667) (xy 244.050345 19.51096) (xy 244.073812 19.593436)
			(xy 244.104788 19.673395) (xy 244.14301 19.750155) (xy 244.188151 19.823061) (xy 244.239827 19.89149)
			(xy 244.297596 19.95486) (xy 244.360966 20.012629) (xy 244.429395 20.064305) (xy 244.502301 20.109446)
			(xy 244.579061 20.147668) (xy 244.65902 20.178644) (xy 244.741496 20.202111) (xy 244.825786 20.217867)
			(xy 244.911169 20.225779) (xy 244.996919 20.225779) (xy 245.082302 20.217867) (xy 245.166592 20.202111)
			(xy 245.249068 20.178644) (xy 245.329027 20.147668) (xy 245.405787 20.109446) (xy 245.478693 20.064305)
			(xy 245.547122 20.012629) (xy 245.610492 19.95486) (xy 245.668261 19.89149) (xy 245.719937 19.823061)
			(xy 245.765078 19.750155) (xy 245.8033 19.673395) (xy 245.834276 19.593436) (xy 245.857743 19.51096)
			(xy 245.873499 19.42667) (xy 245.881411 19.341287) (xy 245.881906 19.298412) (xy 245.881411 19.255537)
			(xy 250.376677 19.255537) (xy 250.376677 19.341287) (xy 250.384589 19.42667) (xy 250.400345 19.51096)
			(xy 250.423812 19.593436) (xy 250.454788 19.673395) (xy 250.49301 19.750155) (xy 250.538151 19.823061)
			(xy 250.589827 19.89149) (xy 250.647596 19.95486) (xy 250.710966 20.012629) (xy 250.779395 20.064305)
			(xy 250.852301 20.109446) (xy 250.929061 20.147668) (xy 251.00902 20.178644) (xy 251.091496 20.202111)
			(xy 251.175786 20.217867) (xy 251.261169 20.225779) (xy 251.346919 20.225779) (xy 251.432302 20.217867)
			(xy 251.516592 20.202111) (xy 251.599068 20.178644) (xy 251.679027 20.147668) (xy 251.755787 20.109446)
			(xy 251.828693 20.064305) (xy 251.897122 20.012629) (xy 251.960492 19.95486) (xy 252.018261 19.89149)
			(xy 252.069937 19.823061) (xy 252.115078 19.750155) (xy 252.1533 19.673395) (xy 252.184276 19.593436)
			(xy 252.207743 19.51096) (xy 252.223499 19.42667) (xy 252.231411 19.341287) (xy 252.231906 19.298412)
			(xy 252.231493 19.262649) (xy 269.304757 19.262649) (xy 269.304757 19.348399) (xy 269.312669 19.433782)
			(xy 269.328425 19.518072) (xy 269.351892 19.600548) (xy 269.382868 19.680507) (xy 269.42109 19.757267)
			(xy 269.466231 19.830173) (xy 269.517907 19.898602) (xy 269.575676 19.961972) (xy 269.639046 20.019741)
			(xy 269.707475 20.071417) (xy 269.780381 20.116558) (xy 269.857141 20.15478) (xy 269.9371 20.185756)
			(xy 270.019576 20.209223) (xy 270.103866 20.224979) (xy 270.189249 20.232891) (xy 270.274999 20.232891)
			(xy 270.360382 20.224979) (xy 270.444672 20.209223) (xy 270.527148 20.185756) (xy 270.607107 20.15478)
			(xy 270.62931 20.143724) (xy 274.239736 20.143724) (xy 274.239736 21.007324) (xy 274.240222 21.034593)
			(xy 274.247984 21.088577) (xy 274.263349 21.140907) (xy 274.286006 21.190517) (xy 274.315492 21.236398)
			(xy 274.351207 21.277615) (xy 274.392424 21.31333) (xy 274.438305 21.342816) (xy 274.487915 21.365473)
			(xy 274.540245 21.380838) (xy 274.594229 21.3886) (xy 274.648767 21.3886) (xy 274.702751 21.380838)
			(xy 274.755081 21.365473) (xy 274.804691 21.342816) (xy 274.850572 21.31333) (xy 274.891789 21.277615)
			(xy 274.927504 21.236398) (xy 274.95699 21.190517) (xy 274.979647 21.140907) (xy 274.995012 21.088577)
			(xy 275.002774 21.034593) (xy 275.00326 21.007324) (xy 275.00326 20.143724) (xy 275.002774 20.116455)
			(xy 274.995012 20.062471) (xy 274.979647 20.010141) (xy 274.95699 19.960531) (xy 274.927504 19.91465)
			(xy 274.891789 19.873433) (xy 274.850572 19.837718) (xy 274.804691 19.808232) (xy 274.755081 19.785575)
			(xy 274.702751 19.77021) (xy 274.648767 19.762448) (xy 274.594229 19.762448) (xy 274.540245 19.77021)
			(xy 274.487915 19.785575) (xy 274.438305 19.808232) (xy 274.392424 19.837718) (xy 274.351207 19.873433)
			(xy 274.315492 19.91465) (xy 274.286006 19.960531) (xy 274.263349 20.010141) (xy 274.247984 20.062471)
			(xy 274.240222 20.116455) (xy 274.239736 20.143724) (xy 270.62931 20.143724) (xy 270.683867 20.116558)
			(xy 270.756773 20.071417) (xy 270.825202 20.019741) (xy 270.888572 19.961972) (xy 270.946341 19.898602)
			(xy 270.998017 19.830173) (xy 271.043158 19.757267) (xy 271.08138 19.680507) (xy 271.112356 19.600548)
			(xy 271.135823 19.518072) (xy 271.151579 19.433782) (xy 271.159491 19.348399) (xy 271.159986 19.305524)
			(xy 271.159491 19.262649) (xy 275.654757 19.262649) (xy 275.654757 19.348399) (xy 275.662669 19.433782)
			(xy 275.678425 19.518072) (xy 275.701892 19.600548) (xy 275.732868 19.680507) (xy 275.77109 19.757267)
			(xy 275.816231 19.830173) (xy 275.867907 19.898602) (xy 275.925676 19.961972) (xy 275.989046 20.019741)
			(xy 276.057475 20.071417) (xy 276.130381 20.116558) (xy 276.207141 20.15478) (xy 276.2871 20.185756)
			(xy 276.369576 20.209223) (xy 276.453866 20.224979) (xy 276.539249 20.232891) (xy 276.624999 20.232891)
			(xy 276.710382 20.224979) (xy 276.794672 20.209223) (xy 276.877148 20.185756) (xy 276.957107 20.15478)
			(xy 277.033867 20.116558) (xy 277.106773 20.071417) (xy 277.175202 20.019741) (xy 277.238572 19.961972)
			(xy 277.296341 19.898602) (xy 277.348017 19.830173) (xy 277.393158 19.757267) (xy 277.43138 19.680507)
			(xy 277.462356 19.600548) (xy 277.485823 19.518072) (xy 277.501579 19.433782) (xy 277.509491 19.348399)
			(xy 277.509986 19.305524) (xy 277.509491 19.262649) (xy 277.508832 19.255537) (xy 308.364877 19.255537)
			(xy 308.364877 19.341287) (xy 308.372789 19.42667) (xy 308.388545 19.51096) (xy 308.412012 19.593436)
			(xy 308.442988 19.673395) (xy 308.48121 19.750155) (xy 308.526351 19.823061) (xy 308.578027 19.89149)
			(xy 308.635796 19.95486) (xy 308.699166 20.012629) (xy 308.767595 20.064305) (xy 308.840501 20.109446)
			(xy 308.917261 20.147668) (xy 308.99722 20.178644) (xy 309.079696 20.202111) (xy 309.163986 20.217867)
			(xy 309.249369 20.225779) (xy 309.335119 20.225779) (xy 309.420502 20.217867) (xy 309.504792 20.202111)
			(xy 309.587268 20.178644) (xy 309.667227 20.147668) (xy 309.68943 20.136612) (xy 310.871108 20.136612)
			(xy 310.871108 21.000212) (xy 310.871594 21.027481) (xy 310.879356 21.081465) (xy 310.894721 21.133795)
			(xy 310.917378 21.183405) (xy 310.946864 21.229286) (xy 310.982579 21.270503) (xy 311.023796 21.306218)
			(xy 311.069677 21.335704) (xy 311.119287 21.358361) (xy 311.171617 21.373726) (xy 311.225601 21.381488)
			(xy 311.280139 21.381488) (xy 311.334123 21.373726) (xy 311.386453 21.358361) (xy 311.436063 21.335704)
			(xy 311.481944 21.306218) (xy 311.523161 21.270503) (xy 311.558876 21.229286) (xy 311.588362 21.183405)
			(xy 311.611019 21.133795) (xy 311.626384 21.081465) (xy 311.634146 21.027481) (xy 311.634632 21.000212)
			(xy 311.634632 20.136612) (xy 311.634146 20.109343) (xy 311.626384 20.055359) (xy 311.611019 20.003029)
			(xy 311.588362 19.953419) (xy 311.558876 19.907538) (xy 311.523161 19.866321) (xy 311.481944 19.830606)
			(xy 311.436063 19.80112) (xy 311.386453 19.778463) (xy 311.334123 19.763098) (xy 311.280139 19.755336)
			(xy 311.225601 19.755336) (xy 311.171617 19.763098) (xy 311.119287 19.778463) (xy 311.069677 19.80112)
			(xy 311.023796 19.830606) (xy 310.982579 19.866321) (xy 310.946864 19.907538) (xy 310.917378 19.953419)
			(xy 310.894721 20.003029) (xy 310.879356 20.055359) (xy 310.871594 20.109343) (xy 310.871108 20.136612)
			(xy 309.68943 20.136612) (xy 309.743987 20.109446) (xy 309.816893 20.064305) (xy 309.885322 20.012629)
			(xy 309.948692 19.95486) (xy 310.006461 19.89149) (xy 310.058137 19.823061) (xy 310.103278 19.750155)
			(xy 310.1415 19.673395) (xy 310.172476 19.593436) (xy 310.195943 19.51096) (xy 310.211699 19.42667)
			(xy 310.219611 19.341287) (xy 310.220106 19.298412) (xy 310.219611 19.255537) (xy 314.714877 19.255537)
			(xy 314.714877 19.341287) (xy 314.722789 19.42667) (xy 314.738545 19.51096) (xy 314.762012 19.593436)
			(xy 314.792988 19.673395) (xy 314.83121 19.750155) (xy 314.876351 19.823061) (xy 314.928027 19.89149)
			(xy 314.985796 19.95486) (xy 315.049166 20.012629) (xy 315.117595 20.064305) (xy 315.190501 20.109446)
			(xy 315.267261 20.147668) (xy 315.34722 20.178644) (xy 315.429696 20.202111) (xy 315.513986 20.217867)
			(xy 315.599369 20.225779) (xy 315.685119 20.225779) (xy 315.770502 20.217867) (xy 315.854792 20.202111)
			(xy 315.937268 20.178644) (xy 316.017227 20.147668) (xy 316.093987 20.109446) (xy 316.166893 20.064305)
			(xy 316.235322 20.012629) (xy 316.298692 19.95486) (xy 316.356461 19.89149) (xy 316.408137 19.823061)
			(xy 316.453278 19.750155) (xy 316.4915 19.673395) (xy 316.522476 19.593436) (xy 316.545943 19.51096)
			(xy 316.561699 19.42667) (xy 316.569611 19.341287) (xy 316.570106 19.298412) (xy 316.569693 19.262649)
			(xy 334.455757 19.262649) (xy 334.455757 19.348399) (xy 334.463669 19.433782) (xy 334.479425 19.518072)
			(xy 334.502892 19.600548) (xy 334.533868 19.680507) (xy 334.57209 19.757267) (xy 334.617231 19.830173)
			(xy 334.668907 19.898602) (xy 334.726676 19.961972) (xy 334.790046 20.019741) (xy 334.858475 20.071417)
			(xy 334.931381 20.116558) (xy 335.008141 20.15478) (xy 335.0881 20.185756) (xy 335.170576 20.209223)
			(xy 335.254866 20.224979) (xy 335.340249 20.232891) (xy 335.425999 20.232891) (xy 335.511382 20.224979)
			(xy 335.595672 20.209223) (xy 335.678148 20.185756) (xy 335.758107 20.15478) (xy 335.78031 20.143724)
			(xy 339.390736 20.143724) (xy 339.390736 21.007324) (xy 339.391222 21.034593) (xy 339.398984 21.088577)
			(xy 339.414349 21.140907) (xy 339.437006 21.190517) (xy 339.466492 21.236398) (xy 339.502207 21.277615)
			(xy 339.543424 21.31333) (xy 339.589305 21.342816) (xy 339.638915 21.365473) (xy 339.691245 21.380838)
			(xy 339.745229 21.3886) (xy 339.799767 21.3886) (xy 339.853751 21.380838) (xy 339.906081 21.365473)
			(xy 339.955691 21.342816) (xy 340.001572 21.31333) (xy 340.042789 21.277615) (xy 340.078504 21.236398)
			(xy 340.10799 21.190517) (xy 340.130647 21.140907) (xy 340.146012 21.088577) (xy 340.153774 21.034593)
			(xy 340.15426 21.007324) (xy 340.15426 20.143724) (xy 340.153774 20.116455) (xy 340.146012 20.062471)
			(xy 340.130647 20.010141) (xy 340.10799 19.960531) (xy 340.078504 19.91465) (xy 340.042789 19.873433)
			(xy 340.001572 19.837718) (xy 339.955691 19.808232) (xy 339.906081 19.785575) (xy 339.853751 19.77021)
			(xy 339.799767 19.762448) (xy 339.745229 19.762448) (xy 339.691245 19.77021) (xy 339.638915 19.785575)
			(xy 339.589305 19.808232) (xy 339.543424 19.837718) (xy 339.502207 19.873433) (xy 339.466492 19.91465)
			(xy 339.437006 19.960531) (xy 339.414349 20.010141) (xy 339.398984 20.062471) (xy 339.391222 20.116455)
			(xy 339.390736 20.143724) (xy 335.78031 20.143724) (xy 335.834867 20.116558) (xy 335.907773 20.071417)
			(xy 335.976202 20.019741) (xy 336.039572 19.961972) (xy 336.097341 19.898602) (xy 336.149017 19.830173)
			(xy 336.194158 19.757267) (xy 336.23238 19.680507) (xy 336.263356 19.600548) (xy 336.286823 19.518072)
			(xy 336.302579 19.433782) (xy 336.310491 19.348399) (xy 336.310986 19.305524) (xy 336.310491 19.262649)
			(xy 340.805757 19.262649) (xy 340.805757 19.348399) (xy 340.813669 19.433782) (xy 340.829425 19.518072)
			(xy 340.852892 19.600548) (xy 340.883868 19.680507) (xy 340.92209 19.757267) (xy 340.967231 19.830173)
			(xy 341.018907 19.898602) (xy 341.076676 19.961972) (xy 341.140046 20.019741) (xy 341.208475 20.071417)
			(xy 341.281381 20.116558) (xy 341.358141 20.15478) (xy 341.4381 20.185756) (xy 341.520576 20.209223)
			(xy 341.604866 20.224979) (xy 341.690249 20.232891) (xy 341.775999 20.232891) (xy 341.861382 20.224979)
			(xy 341.945672 20.209223) (xy 342.028148 20.185756) (xy 342.108107 20.15478) (xy 342.184867 20.116558)
			(xy 342.257773 20.071417) (xy 342.326202 20.019741) (xy 342.389572 19.961972) (xy 342.447341 19.898602)
			(xy 342.499017 19.830173) (xy 342.544158 19.757267) (xy 342.58238 19.680507) (xy 342.613356 19.600548)
			(xy 342.636823 19.518072) (xy 342.652579 19.433782) (xy 342.660491 19.348399) (xy 342.660986 19.305524)
			(xy 342.660491 19.262649) (xy 342.659832 19.255537) (xy 373.515877 19.255537) (xy 373.515877 19.341287)
			(xy 373.523789 19.42667) (xy 373.539545 19.51096) (xy 373.563012 19.593436) (xy 373.593988 19.673395)
			(xy 373.63221 19.750155) (xy 373.677351 19.823061) (xy 373.729027 19.89149) (xy 373.786796 19.95486)
			(xy 373.850166 20.012629) (xy 373.918595 20.064305) (xy 373.991501 20.109446) (xy 374.068261 20.147668)
			(xy 374.14822 20.178644) (xy 374.230696 20.202111) (xy 374.314986 20.217867) (xy 374.400369 20.225779)
			(xy 374.486119 20.225779) (xy 374.571502 20.217867) (xy 374.655792 20.202111) (xy 374.738268 20.178644)
			(xy 374.818227 20.147668) (xy 374.84043 20.136612) (xy 376.022108 20.136612) (xy 376.022108 21.000212)
			(xy 376.022594 21.027481) (xy 376.030356 21.081465) (xy 376.045721 21.133795) (xy 376.068378 21.183405)
			(xy 376.097864 21.229286) (xy 376.133579 21.270503) (xy 376.174796 21.306218) (xy 376.220677 21.335704)
			(xy 376.270287 21.358361) (xy 376.322617 21.373726) (xy 376.376601 21.381488) (xy 376.431139 21.381488)
			(xy 376.485123 21.373726) (xy 376.537453 21.358361) (xy 376.587063 21.335704) (xy 376.632944 21.306218)
			(xy 376.674161 21.270503) (xy 376.709876 21.229286) (xy 376.739362 21.183405) (xy 376.762019 21.133795)
			(xy 376.777384 21.081465) (xy 376.785146 21.027481) (xy 376.785632 21.000212) (xy 376.785632 20.136612)
			(xy 376.785146 20.109343) (xy 376.777384 20.055359) (xy 376.762019 20.003029) (xy 376.739362 19.953419)
			(xy 376.709876 19.907538) (xy 376.674161 19.866321) (xy 376.632944 19.830606) (xy 376.587063 19.80112)
			(xy 376.537453 19.778463) (xy 376.485123 19.763098) (xy 376.431139 19.755336) (xy 376.376601 19.755336)
			(xy 376.322617 19.763098) (xy 376.270287 19.778463) (xy 376.220677 19.80112) (xy 376.174796 19.830606)
			(xy 376.133579 19.866321) (xy 376.097864 19.907538) (xy 376.068378 19.953419) (xy 376.045721 20.003029)
			(xy 376.030356 20.055359) (xy 376.022594 20.109343) (xy 376.022108 20.136612) (xy 374.84043 20.136612)
			(xy 374.894987 20.109446) (xy 374.967893 20.064305) (xy 375.036322 20.012629) (xy 375.099692 19.95486)
			(xy 375.157461 19.89149) (xy 375.209137 19.823061) (xy 375.254278 19.750155) (xy 375.2925 19.673395)
			(xy 375.323476 19.593436) (xy 375.346943 19.51096) (xy 375.362699 19.42667) (xy 375.370611 19.341287)
			(xy 375.371106 19.298412) (xy 375.370611 19.255537) (xy 379.865877 19.255537) (xy 379.865877 19.341287)
			(xy 379.873789 19.42667) (xy 379.889545 19.51096) (xy 379.913012 19.593436) (xy 379.943988 19.673395)
			(xy 379.98221 19.750155) (xy 380.027351 19.823061) (xy 380.079027 19.89149) (xy 380.136796 19.95486)
			(xy 380.200166 20.012629) (xy 380.268595 20.064305) (xy 380.341501 20.109446) (xy 380.418261 20.147668)
			(xy 380.49822 20.178644) (xy 380.580696 20.202111) (xy 380.664986 20.217867) (xy 380.750369 20.225779)
			(xy 380.836119 20.225779) (xy 380.921502 20.217867) (xy 381.005792 20.202111) (xy 381.088268 20.178644)
			(xy 381.168227 20.147668) (xy 381.244987 20.109446) (xy 381.317893 20.064305) (xy 381.386322 20.012629)
			(xy 381.449692 19.95486) (xy 381.507461 19.89149) (xy 381.559137 19.823061) (xy 381.604278 19.750155)
			(xy 381.6425 19.673395) (xy 381.673476 19.593436) (xy 381.696943 19.51096) (xy 381.712699 19.42667)
			(xy 381.720611 19.341287) (xy 381.721106 19.298412) (xy 381.720693 19.262649) (xy 399.098757 19.262649)
			(xy 399.098757 19.348399) (xy 399.106669 19.433782) (xy 399.122425 19.518072) (xy 399.145892 19.600548)
			(xy 399.176868 19.680507) (xy 399.21509 19.757267) (xy 399.260231 19.830173) (xy 399.311907 19.898602)
			(xy 399.369676 19.961972) (xy 399.433046 20.019741) (xy 399.501475 20.071417) (xy 399.574381 20.116558)
			(xy 399.651141 20.15478) (xy 399.7311 20.185756) (xy 399.813576 20.209223) (xy 399.897866 20.224979)
			(xy 399.983249 20.232891) (xy 400.068999 20.232891) (xy 400.154382 20.224979) (xy 400.238672 20.209223)
			(xy 400.321148 20.185756) (xy 400.401107 20.15478) (xy 400.42331 20.143724) (xy 404.033736 20.143724)
			(xy 404.033736 21.007324) (xy 404.034222 21.034593) (xy 404.041984 21.088577) (xy 404.057349 21.140907)
			(xy 404.080006 21.190517) (xy 404.109492 21.236398) (xy 404.145207 21.277615) (xy 404.186424 21.31333)
			(xy 404.232305 21.342816) (xy 404.281915 21.365473) (xy 404.334245 21.380838) (xy 404.388229 21.3886)
			(xy 404.442767 21.3886) (xy 404.496751 21.380838) (xy 404.549081 21.365473) (xy 404.598691 21.342816)
			(xy 404.644572 21.31333) (xy 404.685789 21.277615) (xy 404.721504 21.236398) (xy 404.75099 21.190517)
			(xy 404.773647 21.140907) (xy 404.789012 21.088577) (xy 404.796774 21.034593) (xy 404.79726 21.007324)
			(xy 404.79726 20.143724) (xy 404.796774 20.116455) (xy 404.789012 20.062471) (xy 404.773647 20.010141)
			(xy 404.75099 19.960531) (xy 404.721504 19.91465) (xy 404.685789 19.873433) (xy 404.644572 19.837718)
			(xy 404.598691 19.808232) (xy 404.549081 19.785575) (xy 404.496751 19.77021) (xy 404.442767 19.762448)
			(xy 404.388229 19.762448) (xy 404.334245 19.77021) (xy 404.281915 19.785575) (xy 404.232305 19.808232)
			(xy 404.186424 19.837718) (xy 404.145207 19.873433) (xy 404.109492 19.91465) (xy 404.080006 19.960531)
			(xy 404.057349 20.010141) (xy 404.041984 20.062471) (xy 404.034222 20.116455) (xy 404.033736 20.143724)
			(xy 400.42331 20.143724) (xy 400.477867 20.116558) (xy 400.550773 20.071417) (xy 400.619202 20.019741)
			(xy 400.682572 19.961972) (xy 400.740341 19.898602) (xy 400.792017 19.830173) (xy 400.837158 19.757267)
			(xy 400.87538 19.680507) (xy 400.906356 19.600548) (xy 400.929823 19.518072) (xy 400.945579 19.433782)
			(xy 400.953491 19.348399) (xy 400.953986 19.305524) (xy 400.953491 19.262649) (xy 405.448757 19.262649)
			(xy 405.448757 19.348399) (xy 405.456669 19.433782) (xy 405.472425 19.518072) (xy 405.495892 19.600548)
			(xy 405.526868 19.680507) (xy 405.56509 19.757267) (xy 405.610231 19.830173) (xy 405.661907 19.898602)
			(xy 405.719676 19.961972) (xy 405.783046 20.019741) (xy 405.851475 20.071417) (xy 405.924381 20.116558)
			(xy 406.001141 20.15478) (xy 406.0811 20.185756) (xy 406.163576 20.209223) (xy 406.247866 20.224979)
			(xy 406.333249 20.232891) (xy 406.418999 20.232891) (xy 406.504382 20.224979) (xy 406.588672 20.209223)
			(xy 406.671148 20.185756) (xy 406.751107 20.15478) (xy 406.827867 20.116558) (xy 406.900773 20.071417)
			(xy 406.969202 20.019741) (xy 407.032572 19.961972) (xy 407.090341 19.898602) (xy 407.142017 19.830173)
			(xy 407.187158 19.757267) (xy 407.22538 19.680507) (xy 407.256356 19.600548) (xy 407.279823 19.518072)
			(xy 407.295579 19.433782) (xy 407.303491 19.348399) (xy 407.303986 19.305524) (xy 407.303491 19.262649)
			(xy 407.302832 19.255537) (xy 438.158877 19.255537) (xy 438.158877 19.341287) (xy 438.166789 19.42667)
			(xy 438.182545 19.51096) (xy 438.206012 19.593436) (xy 438.236988 19.673395) (xy 438.27521 19.750155)
			(xy 438.320351 19.823061) (xy 438.372027 19.89149) (xy 438.429796 19.95486) (xy 438.493166 20.012629)
			(xy 438.561595 20.064305) (xy 438.634501 20.109446) (xy 438.711261 20.147668) (xy 438.79122 20.178644)
			(xy 438.873696 20.202111) (xy 438.957986 20.217867) (xy 439.043369 20.225779) (xy 439.129119 20.225779)
			(xy 439.214502 20.217867) (xy 439.298792 20.202111) (xy 439.381268 20.178644) (xy 439.461227 20.147668)
			(xy 439.48343 20.136612) (xy 440.665108 20.136612) (xy 440.665108 21.000212) (xy 440.665594 21.027481)
			(xy 440.673356 21.081465) (xy 440.688721 21.133795) (xy 440.711378 21.183405) (xy 440.740864 21.229286)
			(xy 440.776579 21.270503) (xy 440.817796 21.306218) (xy 440.863677 21.335704) (xy 440.913287 21.358361)
			(xy 440.965617 21.373726) (xy 441.019601 21.381488) (xy 441.074139 21.381488) (xy 441.128123 21.373726)
			(xy 441.180453 21.358361) (xy 441.230063 21.335704) (xy 441.275944 21.306218) (xy 441.317161 21.270503)
			(xy 441.352876 21.229286) (xy 441.382362 21.183405) (xy 441.405019 21.133795) (xy 441.420384 21.081465)
			(xy 441.428146 21.027481) (xy 441.428632 21.000212) (xy 441.428632 20.136612) (xy 441.428146 20.109343)
			(xy 441.420384 20.055359) (xy 441.405019 20.003029) (xy 441.382362 19.953419) (xy 441.352876 19.907538)
			(xy 441.317161 19.866321) (xy 441.275944 19.830606) (xy 441.230063 19.80112) (xy 441.180453 19.778463)
			(xy 441.128123 19.763098) (xy 441.074139 19.755336) (xy 441.019601 19.755336) (xy 440.965617 19.763098)
			(xy 440.913287 19.778463) (xy 440.863677 19.80112) (xy 440.817796 19.830606) (xy 440.776579 19.866321)
			(xy 440.740864 19.907538) (xy 440.711378 19.953419) (xy 440.688721 20.003029) (xy 440.673356 20.055359)
			(xy 440.665594 20.109343) (xy 440.665108 20.136612) (xy 439.48343 20.136612) (xy 439.537987 20.109446)
			(xy 439.610893 20.064305) (xy 439.679322 20.012629) (xy 439.742692 19.95486) (xy 439.800461 19.89149)
			(xy 439.852137 19.823061) (xy 439.897278 19.750155) (xy 439.9355 19.673395) (xy 439.966476 19.593436)
			(xy 439.989943 19.51096) (xy 440.005699 19.42667) (xy 440.013611 19.341287) (xy 440.014106 19.298412)
			(xy 440.013611 19.255537) (xy 444.508877 19.255537) (xy 444.508877 19.341287) (xy 444.516789 19.42667)
			(xy 444.532545 19.51096) (xy 444.556012 19.593436) (xy 444.586988 19.673395) (xy 444.62521 19.750155)
			(xy 444.670351 19.823061) (xy 444.722027 19.89149) (xy 444.779796 19.95486) (xy 444.843166 20.012629)
			(xy 444.911595 20.064305) (xy 444.984501 20.109446) (xy 445.061261 20.147668) (xy 445.14122 20.178644)
			(xy 445.223696 20.202111) (xy 445.307986 20.217867) (xy 445.393369 20.225779) (xy 445.479119 20.225779)
			(xy 445.564502 20.217867) (xy 445.648792 20.202111) (xy 445.731268 20.178644) (xy 445.811227 20.147668)
			(xy 445.887987 20.109446) (xy 445.960893 20.064305) (xy 446.029322 20.012629) (xy 446.092692 19.95486)
			(xy 446.150461 19.89149) (xy 446.202137 19.823061) (xy 446.247278 19.750155) (xy 446.2855 19.673395)
			(xy 446.316476 19.593436) (xy 446.339943 19.51096) (xy 446.355699 19.42667) (xy 446.363611 19.341287)
			(xy 446.364106 19.298412) (xy 446.363611 19.255537) (xy 446.355699 19.170154) (xy 446.339943 19.085864)
			(xy 446.316476 19.003388) (xy 446.2855 18.923429) (xy 446.247278 18.846669) (xy 446.202137 18.773763)
			(xy 446.150461 18.705334) (xy 446.092692 18.641964) (xy 446.029322 18.584195) (xy 445.960893 18.532519)
			(xy 445.887987 18.487378) (xy 445.811227 18.449156) (xy 445.731268 18.41818) (xy 445.648792 18.394713)
			(xy 445.564502 18.378957) (xy 445.479119 18.371045) (xy 445.393369 18.371045) (xy 445.307986 18.378957)
			(xy 445.223696 18.394713) (xy 445.14122 18.41818) (xy 445.061261 18.449156) (xy 444.984501 18.487378)
			(xy 444.911595 18.532519) (xy 444.843166 18.584195) (xy 444.779796 18.641964) (xy 444.722027 18.705334)
			(xy 444.670351 18.773763) (xy 444.62521 18.846669) (xy 444.586988 18.923429) (xy 444.556012 19.003388)
			(xy 444.532545 19.085864) (xy 444.516789 19.170154) (xy 444.508877 19.255537) (xy 440.013611 19.255537)
			(xy 440.005699 19.170154) (xy 439.989943 19.085864) (xy 439.966476 19.003388) (xy 439.9355 18.923429)
			(xy 439.897278 18.846669) (xy 439.852137 18.773763) (xy 439.800461 18.705334) (xy 439.742692 18.641964)
			(xy 439.679322 18.584195) (xy 439.610893 18.532519) (xy 439.537987 18.487378) (xy 439.461227 18.449156)
			(xy 439.381268 18.41818) (xy 439.298792 18.394713) (xy 439.214502 18.378957) (xy 439.129119 18.371045)
			(xy 439.043369 18.371045) (xy 438.957986 18.378957) (xy 438.873696 18.394713) (xy 438.79122 18.41818)
			(xy 438.711261 18.449156) (xy 438.634501 18.487378) (xy 438.561595 18.532519) (xy 438.493166 18.584195)
			(xy 438.429796 18.641964) (xy 438.372027 18.705334) (xy 438.320351 18.773763) (xy 438.27521 18.846669)
			(xy 438.236988 18.923429) (xy 438.206012 19.003388) (xy 438.182545 19.085864) (xy 438.166789 19.170154)
			(xy 438.158877 19.255537) (xy 407.302832 19.255537) (xy 407.295579 19.177266) (xy 407.279823 19.092976)
			(xy 407.256356 19.0105) (xy 407.22538 18.930541) (xy 407.187158 18.853781) (xy 407.142017 18.780875)
			(xy 407.090341 18.712446) (xy 407.032572 18.649076) (xy 406.969202 18.591307) (xy 406.900773 18.539631)
			(xy 406.827867 18.49449) (xy 406.751107 18.456268) (xy 406.671148 18.425292) (xy 406.588672 18.401825)
			(xy 406.504382 18.386069) (xy 406.418999 18.378157) (xy 406.333249 18.378157) (xy 406.247866 18.386069)
			(xy 406.163576 18.401825) (xy 406.0811 18.425292) (xy 406.001141 18.456268) (xy 405.924381 18.49449)
			(xy 405.851475 18.539631) (xy 405.783046 18.591307) (xy 405.719676 18.649076) (xy 405.661907 18.712446)
			(xy 405.610231 18.780875) (xy 405.56509 18.853781) (xy 405.526868 18.930541) (xy 405.495892 19.0105)
			(xy 405.472425 19.092976) (xy 405.456669 19.177266) (xy 405.448757 19.262649) (xy 400.953491 19.262649)
			(xy 400.945579 19.177266) (xy 400.929823 19.092976) (xy 400.906356 19.0105) (xy 400.87538 18.930541)
			(xy 400.837158 18.853781) (xy 400.792017 18.780875) (xy 400.740341 18.712446) (xy 400.682572 18.649076)
			(xy 400.619202 18.591307) (xy 400.550773 18.539631) (xy 400.477867 18.49449) (xy 400.401107 18.456268)
			(xy 400.321148 18.425292) (xy 400.238672 18.401825) (xy 400.154382 18.386069) (xy 400.068999 18.378157)
			(xy 399.983249 18.378157) (xy 399.897866 18.386069) (xy 399.813576 18.401825) (xy 399.7311 18.425292)
			(xy 399.651141 18.456268) (xy 399.574381 18.49449) (xy 399.501475 18.539631) (xy 399.433046 18.591307)
			(xy 399.369676 18.649076) (xy 399.311907 18.712446) (xy 399.260231 18.780875) (xy 399.21509 18.853781)
			(xy 399.176868 18.930541) (xy 399.145892 19.0105) (xy 399.122425 19.092976) (xy 399.106669 19.177266)
			(xy 399.098757 19.262649) (xy 381.720693 19.262649) (xy 381.720611 19.255537) (xy 381.712699 19.170154)
			(xy 381.696943 19.085864) (xy 381.673476 19.003388) (xy 381.6425 18.923429) (xy 381.604278 18.846669)
			(xy 381.559137 18.773763) (xy 381.507461 18.705334) (xy 381.449692 18.641964) (xy 381.386322 18.584195)
			(xy 381.317893 18.532519) (xy 381.244987 18.487378) (xy 381.168227 18.449156) (xy 381.088268 18.41818)
			(xy 381.005792 18.394713) (xy 380.921502 18.378957) (xy 380.836119 18.371045) (xy 380.750369 18.371045)
			(xy 380.664986 18.378957) (xy 380.580696 18.394713) (xy 380.49822 18.41818) (xy 380.418261 18.449156)
			(xy 380.341501 18.487378) (xy 380.268595 18.532519) (xy 380.200166 18.584195) (xy 380.136796 18.641964)
			(xy 380.079027 18.705334) (xy 380.027351 18.773763) (xy 379.98221 18.846669) (xy 379.943988 18.923429)
			(xy 379.913012 19.003388) (xy 379.889545 19.085864) (xy 379.873789 19.170154) (xy 379.865877 19.255537)
			(xy 375.370611 19.255537) (xy 375.362699 19.170154) (xy 375.346943 19.085864) (xy 375.323476 19.003388)
			(xy 375.2925 18.923429) (xy 375.254278 18.846669) (xy 375.209137 18.773763) (xy 375.157461 18.705334)
			(xy 375.099692 18.641964) (xy 375.036322 18.584195) (xy 374.967893 18.532519) (xy 374.894987 18.487378)
			(xy 374.818227 18.449156) (xy 374.738268 18.41818) (xy 374.655792 18.394713) (xy 374.571502 18.378957)
			(xy 374.486119 18.371045) (xy 374.400369 18.371045) (xy 374.314986 18.378957) (xy 374.230696 18.394713)
			(xy 374.14822 18.41818) (xy 374.068261 18.449156) (xy 373.991501 18.487378) (xy 373.918595 18.532519)
			(xy 373.850166 18.584195) (xy 373.786796 18.641964) (xy 373.729027 18.705334) (xy 373.677351 18.773763)
			(xy 373.63221 18.846669) (xy 373.593988 18.923429) (xy 373.563012 19.003388) (xy 373.539545 19.085864)
			(xy 373.523789 19.170154) (xy 373.515877 19.255537) (xy 342.659832 19.255537) (xy 342.652579 19.177266)
			(xy 342.636823 19.092976) (xy 342.613356 19.0105) (xy 342.58238 18.930541) (xy 342.544158 18.853781)
			(xy 342.499017 18.780875) (xy 342.447341 18.712446) (xy 342.389572 18.649076) (xy 342.326202 18.591307)
			(xy 342.257773 18.539631) (xy 342.184867 18.49449) (xy 342.108107 18.456268) (xy 342.028148 18.425292)
			(xy 341.945672 18.401825) (xy 341.861382 18.386069) (xy 341.775999 18.378157) (xy 341.690249 18.378157)
			(xy 341.604866 18.386069) (xy 341.520576 18.401825) (xy 341.4381 18.425292) (xy 341.358141 18.456268)
			(xy 341.281381 18.49449) (xy 341.208475 18.539631) (xy 341.140046 18.591307) (xy 341.076676 18.649076)
			(xy 341.018907 18.712446) (xy 340.967231 18.780875) (xy 340.92209 18.853781) (xy 340.883868 18.930541)
			(xy 340.852892 19.0105) (xy 340.829425 19.092976) (xy 340.813669 19.177266) (xy 340.805757 19.262649)
			(xy 336.310491 19.262649) (xy 336.302579 19.177266) (xy 336.286823 19.092976) (xy 336.263356 19.0105)
			(xy 336.23238 18.930541) (xy 336.194158 18.853781) (xy 336.149017 18.780875) (xy 336.097341 18.712446)
			(xy 336.039572 18.649076) (xy 335.976202 18.591307) (xy 335.907773 18.539631) (xy 335.834867 18.49449)
			(xy 335.758107 18.456268) (xy 335.678148 18.425292) (xy 335.595672 18.401825) (xy 335.511382 18.386069)
			(xy 335.425999 18.378157) (xy 335.340249 18.378157) (xy 335.254866 18.386069) (xy 335.170576 18.401825)
			(xy 335.0881 18.425292) (xy 335.008141 18.456268) (xy 334.931381 18.49449) (xy 334.858475 18.539631)
			(xy 334.790046 18.591307) (xy 334.726676 18.649076) (xy 334.668907 18.712446) (xy 334.617231 18.780875)
			(xy 334.57209 18.853781) (xy 334.533868 18.930541) (xy 334.502892 19.0105) (xy 334.479425 19.092976)
			(xy 334.463669 19.177266) (xy 334.455757 19.262649) (xy 316.569693 19.262649) (xy 316.569611 19.255537)
			(xy 316.561699 19.170154) (xy 316.545943 19.085864) (xy 316.522476 19.003388) (xy 316.4915 18.923429)
			(xy 316.453278 18.846669) (xy 316.408137 18.773763) (xy 316.356461 18.705334) (xy 316.298692 18.641964)
			(xy 316.235322 18.584195) (xy 316.166893 18.532519) (xy 316.093987 18.487378) (xy 316.017227 18.449156)
			(xy 315.937268 18.41818) (xy 315.854792 18.394713) (xy 315.770502 18.378957) (xy 315.685119 18.371045)
			(xy 315.599369 18.371045) (xy 315.513986 18.378957) (xy 315.429696 18.394713) (xy 315.34722 18.41818)
			(xy 315.267261 18.449156) (xy 315.190501 18.487378) (xy 315.117595 18.532519) (xy 315.049166 18.584195)
			(xy 314.985796 18.641964) (xy 314.928027 18.705334) (xy 314.876351 18.773763) (xy 314.83121 18.846669)
			(xy 314.792988 18.923429) (xy 314.762012 19.003388) (xy 314.738545 19.085864) (xy 314.722789 19.170154)
			(xy 314.714877 19.255537) (xy 310.219611 19.255537) (xy 310.211699 19.170154) (xy 310.195943 19.085864)
			(xy 310.172476 19.003388) (xy 310.1415 18.923429) (xy 310.103278 18.846669) (xy 310.058137 18.773763)
			(xy 310.006461 18.705334) (xy 309.948692 18.641964) (xy 309.885322 18.584195) (xy 309.816893 18.532519)
			(xy 309.743987 18.487378) (xy 309.667227 18.449156) (xy 309.587268 18.41818) (xy 309.504792 18.394713)
			(xy 309.420502 18.378957) (xy 309.335119 18.371045) (xy 309.249369 18.371045) (xy 309.163986 18.378957)
			(xy 309.079696 18.394713) (xy 308.99722 18.41818) (xy 308.917261 18.449156) (xy 308.840501 18.487378)
			(xy 308.767595 18.532519) (xy 308.699166 18.584195) (xy 308.635796 18.641964) (xy 308.578027 18.705334)
			(xy 308.526351 18.773763) (xy 308.48121 18.846669) (xy 308.442988 18.923429) (xy 308.412012 19.003388)
			(xy 308.388545 19.085864) (xy 308.372789 19.170154) (xy 308.364877 19.255537) (xy 277.508832 19.255537)
			(xy 277.501579 19.177266) (xy 277.485823 19.092976) (xy 277.462356 19.0105) (xy 277.43138 18.930541)
			(xy 277.393158 18.853781) (xy 277.348017 18.780875) (xy 277.296341 18.712446) (xy 277.238572 18.649076)
			(xy 277.175202 18.591307) (xy 277.106773 18.539631) (xy 277.033867 18.49449) (xy 276.957107 18.456268)
			(xy 276.877148 18.425292) (xy 276.794672 18.401825) (xy 276.710382 18.386069) (xy 276.624999 18.378157)
			(xy 276.539249 18.378157) (xy 276.453866 18.386069) (xy 276.369576 18.401825) (xy 276.2871 18.425292)
			(xy 276.207141 18.456268) (xy 276.130381 18.49449) (xy 276.057475 18.539631) (xy 275.989046 18.591307)
			(xy 275.925676 18.649076) (xy 275.867907 18.712446) (xy 275.816231 18.780875) (xy 275.77109 18.853781)
			(xy 275.732868 18.930541) (xy 275.701892 19.0105) (xy 275.678425 19.092976) (xy 275.662669 19.177266)
			(xy 275.654757 19.262649) (xy 271.159491 19.262649) (xy 271.151579 19.177266) (xy 271.135823 19.092976)
			(xy 271.112356 19.0105) (xy 271.08138 18.930541) (xy 271.043158 18.853781) (xy 270.998017 18.780875)
			(xy 270.946341 18.712446) (xy 270.888572 18.649076) (xy 270.825202 18.591307) (xy 270.756773 18.539631)
			(xy 270.683867 18.49449) (xy 270.607107 18.456268) (xy 270.527148 18.425292) (xy 270.444672 18.401825)
			(xy 270.360382 18.386069) (xy 270.274999 18.378157) (xy 270.189249 18.378157) (xy 270.103866 18.386069)
			(xy 270.019576 18.401825) (xy 269.9371 18.425292) (xy 269.857141 18.456268) (xy 269.780381 18.49449)
			(xy 269.707475 18.539631) (xy 269.639046 18.591307) (xy 269.575676 18.649076) (xy 269.517907 18.712446)
			(xy 269.466231 18.780875) (xy 269.42109 18.853781) (xy 269.382868 18.930541) (xy 269.351892 19.0105)
			(xy 269.328425 19.092976) (xy 269.312669 19.177266) (xy 269.304757 19.262649) (xy 252.231493 19.262649)
			(xy 252.231411 19.255537) (xy 252.223499 19.170154) (xy 252.207743 19.085864) (xy 252.184276 19.003388)
			(xy 252.1533 18.923429) (xy 252.115078 18.846669) (xy 252.069937 18.773763) (xy 252.018261 18.705334)
			(xy 251.960492 18.641964) (xy 251.897122 18.584195) (xy 251.828693 18.532519) (xy 251.755787 18.487378)
			(xy 251.679027 18.449156) (xy 251.599068 18.41818) (xy 251.516592 18.394713) (xy 251.432302 18.378957)
			(xy 251.346919 18.371045) (xy 251.261169 18.371045) (xy 251.175786 18.378957) (xy 251.091496 18.394713)
			(xy 251.00902 18.41818) (xy 250.929061 18.449156) (xy 250.852301 18.487378) (xy 250.779395 18.532519)
			(xy 250.710966 18.584195) (xy 250.647596 18.641964) (xy 250.589827 18.705334) (xy 250.538151 18.773763)
			(xy 250.49301 18.846669) (xy 250.454788 18.923429) (xy 250.423812 19.003388) (xy 250.400345 19.085864)
			(xy 250.384589 19.170154) (xy 250.376677 19.255537) (xy 245.881411 19.255537) (xy 245.873499 19.170154)
			(xy 245.857743 19.085864) (xy 245.834276 19.003388) (xy 245.8033 18.923429) (xy 245.765078 18.846669)
			(xy 245.719937 18.773763) (xy 245.668261 18.705334) (xy 245.610492 18.641964) (xy 245.547122 18.584195)
			(xy 245.478693 18.532519) (xy 245.405787 18.487378) (xy 245.329027 18.449156) (xy 245.249068 18.41818)
			(xy 245.166592 18.394713) (xy 245.082302 18.378957) (xy 244.996919 18.371045) (xy 244.911169 18.371045)
			(xy 244.825786 18.378957) (xy 244.741496 18.394713) (xy 244.65902 18.41818) (xy 244.579061 18.449156)
			(xy 244.502301 18.487378) (xy 244.429395 18.532519) (xy 244.360966 18.584195) (xy 244.297596 18.641964)
			(xy 244.239827 18.705334) (xy 244.188151 18.773763) (xy 244.14301 18.846669) (xy 244.104788 18.923429)
			(xy 244.073812 19.003388) (xy 244.050345 19.085864) (xy 244.034589 19.170154) (xy 244.026677 19.255537)
			(xy 218.199832 19.255537) (xy 218.192579 19.177266) (xy 218.176823 19.092976) (xy 218.153356 19.0105)
			(xy 218.12238 18.930541) (xy 218.084158 18.853781) (xy 218.039017 18.780875) (xy 217.987341 18.712446)
			(xy 217.929572 18.649076) (xy 217.866202 18.591307) (xy 217.797773 18.539631) (xy 217.724867 18.49449)
			(xy 217.648107 18.456268) (xy 217.568148 18.425292) (xy 217.485672 18.401825) (xy 217.401382 18.386069)
			(xy 217.315999 18.378157) (xy 217.230249 18.378157) (xy 217.144866 18.386069) (xy 217.060576 18.401825)
			(xy 216.9781 18.425292) (xy 216.898141 18.456268) (xy 216.821381 18.49449) (xy 216.748475 18.539631)
			(xy 216.680046 18.591307) (xy 216.616676 18.649076) (xy 216.558907 18.712446) (xy 216.507231 18.780875)
			(xy 216.46209 18.853781) (xy 216.423868 18.930541) (xy 216.392892 19.0105) (xy 216.369425 19.092976)
			(xy 216.353669 19.177266) (xy 216.345757 19.262649) (xy 211.850491 19.262649) (xy 211.842579 19.177266)
			(xy 211.826823 19.092976) (xy 211.803356 19.0105) (xy 211.77238 18.930541) (xy 211.734158 18.853781)
			(xy 211.689017 18.780875) (xy 211.637341 18.712446) (xy 211.579572 18.649076) (xy 211.516202 18.591307)
			(xy 211.447773 18.539631) (xy 211.374867 18.49449) (xy 211.298107 18.456268) (xy 211.218148 18.425292)
			(xy 211.135672 18.401825) (xy 211.051382 18.386069) (xy 210.965999 18.378157) (xy 210.880249 18.378157)
			(xy 210.794866 18.386069) (xy 210.710576 18.401825) (xy 210.6281 18.425292) (xy 210.548141 18.456268)
			(xy 210.471381 18.49449) (xy 210.398475 18.539631) (xy 210.330046 18.591307) (xy 210.266676 18.649076)
			(xy 210.208907 18.712446) (xy 210.157231 18.780875) (xy 210.11209 18.853781) (xy 210.073868 18.930541)
			(xy 210.042892 19.0105) (xy 210.019425 19.092976) (xy 210.003669 19.177266) (xy 209.995757 19.262649)
			(xy 158.621984 19.262649) (xy 158.621984 16.722649) (xy 209.995757 16.722649) (xy 209.995757 16.808399)
			(xy 210.003669 16.893782) (xy 210.019425 16.978072) (xy 210.042892 17.060548) (xy 210.073868 17.140507)
			(xy 210.11209 17.217267) (xy 210.157231 17.290173) (xy 210.208907 17.358602) (xy 210.266676 17.421972)
			(xy 210.330046 17.479741) (xy 210.398475 17.531417) (xy 210.471381 17.576558) (xy 210.548141 17.61478)
			(xy 210.6281 17.645756) (xy 210.710576 17.669223) (xy 210.794866 17.684979) (xy 210.880249 17.692891)
			(xy 210.965999 17.692891) (xy 211.051382 17.684979) (xy 211.135672 17.669223) (xy 211.218148 17.645756)
			(xy 211.298107 17.61478) (xy 211.374867 17.576558) (xy 211.447773 17.531417) (xy 211.516202 17.479741)
			(xy 211.579572 17.421972) (xy 211.637341 17.358602) (xy 211.689017 17.290173) (xy 211.734158 17.217267)
			(xy 211.77238 17.140507) (xy 211.803356 17.060548) (xy 211.826823 16.978072) (xy 211.842579 16.893782)
			(xy 211.850491 16.808399) (xy 211.850986 16.765524) (xy 211.850491 16.722649) (xy 216.345757 16.722649)
			(xy 216.345757 16.808399) (xy 216.353669 16.893782) (xy 216.369425 16.978072) (xy 216.392892 17.060548)
			(xy 216.423868 17.140507) (xy 216.46209 17.217267) (xy 216.507231 17.290173) (xy 216.558907 17.358602)
			(xy 216.616676 17.421972) (xy 216.680046 17.479741) (xy 216.748475 17.531417) (xy 216.821381 17.576558)
			(xy 216.898141 17.61478) (xy 216.9781 17.645756) (xy 217.060576 17.669223) (xy 217.144866 17.684979)
			(xy 217.230249 17.692891) (xy 217.315999 17.692891) (xy 217.401382 17.684979) (xy 217.485672 17.669223)
			(xy 217.568148 17.645756) (xy 217.648107 17.61478) (xy 217.724867 17.576558) (xy 217.797773 17.531417)
			(xy 217.866202 17.479741) (xy 217.929572 17.421972) (xy 217.987341 17.358602) (xy 218.039017 17.290173)
			(xy 218.084158 17.217267) (xy 218.12238 17.140507) (xy 218.153356 17.060548) (xy 218.176823 16.978072)
			(xy 218.192579 16.893782) (xy 218.200491 16.808399) (xy 218.200986 16.765524) (xy 218.200491 16.722649)
			(xy 218.199832 16.715537) (xy 244.026677 16.715537) (xy 244.026677 16.801287) (xy 244.034589 16.88667)
			(xy 244.050345 16.97096) (xy 244.073812 17.053436) (xy 244.104788 17.133395) (xy 244.14301 17.210155)
			(xy 244.188151 17.283061) (xy 244.239827 17.35149) (xy 244.297596 17.41486) (xy 244.360966 17.472629)
			(xy 244.429395 17.524305) (xy 244.502301 17.569446) (xy 244.579061 17.607668) (xy 244.65902 17.638644)
			(xy 244.741496 17.662111) (xy 244.825786 17.677867) (xy 244.911169 17.685779) (xy 244.996919 17.685779)
			(xy 245.082302 17.677867) (xy 245.166592 17.662111) (xy 245.249068 17.638644) (xy 245.329027 17.607668)
			(xy 245.405787 17.569446) (xy 245.478693 17.524305) (xy 245.547122 17.472629) (xy 245.610492 17.41486)
			(xy 245.668261 17.35149) (xy 245.719937 17.283061) (xy 245.765078 17.210155) (xy 245.8033 17.133395)
			(xy 245.834276 17.053436) (xy 245.857743 16.97096) (xy 245.873499 16.88667) (xy 245.881411 16.801287)
			(xy 245.881906 16.758412) (xy 245.881411 16.715537) (xy 250.376677 16.715537) (xy 250.376677 16.801287)
			(xy 250.384589 16.88667) (xy 250.400345 16.97096) (xy 250.423812 17.053436) (xy 250.454788 17.133395)
			(xy 250.49301 17.210155) (xy 250.538151 17.283061) (xy 250.589827 17.35149) (xy 250.647596 17.41486)
			(xy 250.710966 17.472629) (xy 250.779395 17.524305) (xy 250.852301 17.569446) (xy 250.929061 17.607668)
			(xy 251.00902 17.638644) (xy 251.091496 17.662111) (xy 251.175786 17.677867) (xy 251.261169 17.685779)
			(xy 251.346919 17.685779) (xy 251.432302 17.677867) (xy 251.516592 17.662111) (xy 251.599068 17.638644)
			(xy 251.679027 17.607668) (xy 251.755787 17.569446) (xy 251.828693 17.524305) (xy 251.897122 17.472629)
			(xy 251.960492 17.41486) (xy 252.018261 17.35149) (xy 252.069937 17.283061) (xy 252.115078 17.210155)
			(xy 252.1533 17.133395) (xy 252.184276 17.053436) (xy 252.207743 16.97096) (xy 252.223499 16.88667)
			(xy 252.231411 16.801287) (xy 252.231906 16.758412) (xy 252.231493 16.722649) (xy 269.304757 16.722649)
			(xy 269.304757 16.808399) (xy 269.312669 16.893782) (xy 269.328425 16.978072) (xy 269.351892 17.060548)
			(xy 269.382868 17.140507) (xy 269.42109 17.217267) (xy 269.466231 17.290173) (xy 269.517907 17.358602)
			(xy 269.575676 17.421972) (xy 269.639046 17.479741) (xy 269.707475 17.531417) (xy 269.780381 17.576558)
			(xy 269.857141 17.61478) (xy 269.9371 17.645756) (xy 270.019576 17.669223) (xy 270.103866 17.684979)
			(xy 270.189249 17.692891) (xy 270.274999 17.692891) (xy 270.360382 17.684979) (xy 270.444672 17.669223)
			(xy 270.527148 17.645756) (xy 270.607107 17.61478) (xy 270.62931 17.603724) (xy 274.239736 17.603724)
			(xy 274.239736 18.467324) (xy 274.240222 18.494593) (xy 274.247984 18.548577) (xy 274.263349 18.600907)
			(xy 274.286006 18.650517) (xy 274.315492 18.696398) (xy 274.351207 18.737615) (xy 274.392424 18.77333)
			(xy 274.438305 18.802816) (xy 274.487915 18.825473) (xy 274.540245 18.840838) (xy 274.594229 18.8486)
			(xy 274.648767 18.8486) (xy 274.702751 18.840838) (xy 274.755081 18.825473) (xy 274.804691 18.802816)
			(xy 274.850572 18.77333) (xy 274.891789 18.737615) (xy 274.927504 18.696398) (xy 274.95699 18.650517)
			(xy 274.979647 18.600907) (xy 274.995012 18.548577) (xy 275.002774 18.494593) (xy 275.00326 18.467324)
			(xy 275.00326 17.603724) (xy 275.002774 17.576455) (xy 274.995012 17.522471) (xy 274.979647 17.470141)
			(xy 274.95699 17.420531) (xy 274.927504 17.37465) (xy 274.891789 17.333433) (xy 274.850572 17.297718)
			(xy 274.804691 17.268232) (xy 274.755081 17.245575) (xy 274.702751 17.23021) (xy 274.648767 17.222448)
			(xy 274.594229 17.222448) (xy 274.540245 17.23021) (xy 274.487915 17.245575) (xy 274.438305 17.268232)
			(xy 274.392424 17.297718) (xy 274.351207 17.333433) (xy 274.315492 17.37465) (xy 274.286006 17.420531)
			(xy 274.263349 17.470141) (xy 274.247984 17.522471) (xy 274.240222 17.576455) (xy 274.239736 17.603724)
			(xy 270.62931 17.603724) (xy 270.683867 17.576558) (xy 270.756773 17.531417) (xy 270.825202 17.479741)
			(xy 270.888572 17.421972) (xy 270.946341 17.358602) (xy 270.998017 17.290173) (xy 271.043158 17.217267)
			(xy 271.08138 17.140507) (xy 271.112356 17.060548) (xy 271.135823 16.978072) (xy 271.151579 16.893782)
			(xy 271.159491 16.808399) (xy 271.159986 16.765524) (xy 271.159491 16.722649) (xy 275.654757 16.722649)
			(xy 275.654757 16.808399) (xy 275.662669 16.893782) (xy 275.678425 16.978072) (xy 275.701892 17.060548)
			(xy 275.732868 17.140507) (xy 275.77109 17.217267) (xy 275.816231 17.290173) (xy 275.867907 17.358602)
			(xy 275.925676 17.421972) (xy 275.989046 17.479741) (xy 276.057475 17.531417) (xy 276.130381 17.576558)
			(xy 276.207141 17.61478) (xy 276.2871 17.645756) (xy 276.369576 17.669223) (xy 276.453866 17.684979)
			(xy 276.539249 17.692891) (xy 276.624999 17.692891) (xy 276.710382 17.684979) (xy 276.794672 17.669223)
			(xy 276.877148 17.645756) (xy 276.957107 17.61478) (xy 277.033867 17.576558) (xy 277.106773 17.531417)
			(xy 277.175202 17.479741) (xy 277.238572 17.421972) (xy 277.296341 17.358602) (xy 277.348017 17.290173)
			(xy 277.393158 17.217267) (xy 277.43138 17.140507) (xy 277.462356 17.060548) (xy 277.485823 16.978072)
			(xy 277.501579 16.893782) (xy 277.509491 16.808399) (xy 277.509986 16.765524) (xy 277.509491 16.722649)
			(xy 277.508832 16.715537) (xy 308.364877 16.715537) (xy 308.364877 16.801287) (xy 308.372789 16.88667)
			(xy 308.388545 16.97096) (xy 308.412012 17.053436) (xy 308.442988 17.133395) (xy 308.48121 17.210155)
			(xy 308.526351 17.283061) (xy 308.578027 17.35149) (xy 308.635796 17.41486) (xy 308.699166 17.472629)
			(xy 308.767595 17.524305) (xy 308.840501 17.569446) (xy 308.917261 17.607668) (xy 308.99722 17.638644)
			(xy 309.079696 17.662111) (xy 309.163986 17.677867) (xy 309.249369 17.685779) (xy 309.335119 17.685779)
			(xy 309.420502 17.677867) (xy 309.504792 17.662111) (xy 309.587268 17.638644) (xy 309.667227 17.607668)
			(xy 309.68943 17.596612) (xy 310.871108 17.596612) (xy 310.871108 18.460212) (xy 310.871594 18.487481)
			(xy 310.879356 18.541465) (xy 310.894721 18.593795) (xy 310.917378 18.643405) (xy 310.946864 18.689286)
			(xy 310.982579 18.730503) (xy 311.023796 18.766218) (xy 311.069677 18.795704) (xy 311.119287 18.818361)
			(xy 311.171617 18.833726) (xy 311.225601 18.841488) (xy 311.280139 18.841488) (xy 311.334123 18.833726)
			(xy 311.386453 18.818361) (xy 311.436063 18.795704) (xy 311.481944 18.766218) (xy 311.523161 18.730503)
			(xy 311.558876 18.689286) (xy 311.588362 18.643405) (xy 311.611019 18.593795) (xy 311.626384 18.541465)
			(xy 311.634146 18.487481) (xy 311.634632 18.460212) (xy 311.634632 17.596612) (xy 311.634146 17.569343)
			(xy 311.626384 17.515359) (xy 311.611019 17.463029) (xy 311.588362 17.413419) (xy 311.558876 17.367538)
			(xy 311.523161 17.326321) (xy 311.481944 17.290606) (xy 311.436063 17.26112) (xy 311.386453 17.238463)
			(xy 311.334123 17.223098) (xy 311.280139 17.215336) (xy 311.225601 17.215336) (xy 311.171617 17.223098)
			(xy 311.119287 17.238463) (xy 311.069677 17.26112) (xy 311.023796 17.290606) (xy 310.982579 17.326321)
			(xy 310.946864 17.367538) (xy 310.917378 17.413419) (xy 310.894721 17.463029) (xy 310.879356 17.515359)
			(xy 310.871594 17.569343) (xy 310.871108 17.596612) (xy 309.68943 17.596612) (xy 309.743987 17.569446)
			(xy 309.816893 17.524305) (xy 309.885322 17.472629) (xy 309.948692 17.41486) (xy 310.006461 17.35149)
			(xy 310.058137 17.283061) (xy 310.103278 17.210155) (xy 310.1415 17.133395) (xy 310.172476 17.053436)
			(xy 310.195943 16.97096) (xy 310.211699 16.88667) (xy 310.219611 16.801287) (xy 310.220106 16.758412)
			(xy 310.219611 16.715537) (xy 314.714877 16.715537) (xy 314.714877 16.801287) (xy 314.722789 16.88667)
			(xy 314.738545 16.97096) (xy 314.762012 17.053436) (xy 314.792988 17.133395) (xy 314.83121 17.210155)
			(xy 314.876351 17.283061) (xy 314.928027 17.35149) (xy 314.985796 17.41486) (xy 315.049166 17.472629)
			(xy 315.117595 17.524305) (xy 315.190501 17.569446) (xy 315.267261 17.607668) (xy 315.34722 17.638644)
			(xy 315.429696 17.662111) (xy 315.513986 17.677867) (xy 315.599369 17.685779) (xy 315.685119 17.685779)
			(xy 315.770502 17.677867) (xy 315.854792 17.662111) (xy 315.937268 17.638644) (xy 316.017227 17.607668)
			(xy 316.093987 17.569446) (xy 316.166893 17.524305) (xy 316.235322 17.472629) (xy 316.298692 17.41486)
			(xy 316.356461 17.35149) (xy 316.408137 17.283061) (xy 316.453278 17.210155) (xy 316.4915 17.133395)
			(xy 316.522476 17.053436) (xy 316.545943 16.97096) (xy 316.561699 16.88667) (xy 316.569611 16.801287)
			(xy 316.570106 16.758412) (xy 316.569693 16.722649) (xy 334.455757 16.722649) (xy 334.455757 16.808399)
			(xy 334.463669 16.893782) (xy 334.479425 16.978072) (xy 334.502892 17.060548) (xy 334.533868 17.140507)
			(xy 334.57209 17.217267) (xy 334.617231 17.290173) (xy 334.668907 17.358602) (xy 334.726676 17.421972)
			(xy 334.790046 17.479741) (xy 334.858475 17.531417) (xy 334.931381 17.576558) (xy 335.008141 17.61478)
			(xy 335.0881 17.645756) (xy 335.170576 17.669223) (xy 335.254866 17.684979) (xy 335.340249 17.692891)
			(xy 335.425999 17.692891) (xy 335.511382 17.684979) (xy 335.595672 17.669223) (xy 335.678148 17.645756)
			(xy 335.758107 17.61478) (xy 335.78031 17.603724) (xy 339.390736 17.603724) (xy 339.390736 18.467324)
			(xy 339.391222 18.494593) (xy 339.398984 18.548577) (xy 339.414349 18.600907) (xy 339.437006 18.650517)
			(xy 339.466492 18.696398) (xy 339.502207 18.737615) (xy 339.543424 18.77333) (xy 339.589305 18.802816)
			(xy 339.638915 18.825473) (xy 339.691245 18.840838) (xy 339.745229 18.8486) (xy 339.799767 18.8486)
			(xy 339.853751 18.840838) (xy 339.906081 18.825473) (xy 339.955691 18.802816) (xy 340.001572 18.77333)
			(xy 340.042789 18.737615) (xy 340.078504 18.696398) (xy 340.10799 18.650517) (xy 340.130647 18.600907)
			(xy 340.146012 18.548577) (xy 340.153774 18.494593) (xy 340.15426 18.467324) (xy 340.15426 17.603724)
			(xy 340.153774 17.576455) (xy 340.146012 17.522471) (xy 340.130647 17.470141) (xy 340.10799 17.420531)
			(xy 340.078504 17.37465) (xy 340.042789 17.333433) (xy 340.001572 17.297718) (xy 339.955691 17.268232)
			(xy 339.906081 17.245575) (xy 339.853751 17.23021) (xy 339.799767 17.222448) (xy 339.745229 17.222448)
			(xy 339.691245 17.23021) (xy 339.638915 17.245575) (xy 339.589305 17.268232) (xy 339.543424 17.297718)
			(xy 339.502207 17.333433) (xy 339.466492 17.37465) (xy 339.437006 17.420531) (xy 339.414349 17.470141)
			(xy 339.398984 17.522471) (xy 339.391222 17.576455) (xy 339.390736 17.603724) (xy 335.78031 17.603724)
			(xy 335.834867 17.576558) (xy 335.907773 17.531417) (xy 335.976202 17.479741) (xy 336.039572 17.421972)
			(xy 336.097341 17.358602) (xy 336.149017 17.290173) (xy 336.194158 17.217267) (xy 336.23238 17.140507)
			(xy 336.263356 17.060548) (xy 336.286823 16.978072) (xy 336.302579 16.893782) (xy 336.310491 16.808399)
			(xy 336.310986 16.765524) (xy 336.310491 16.722649) (xy 340.805757 16.722649) (xy 340.805757 16.808399)
			(xy 340.813669 16.893782) (xy 340.829425 16.978072) (xy 340.852892 17.060548) (xy 340.883868 17.140507)
			(xy 340.92209 17.217267) (xy 340.967231 17.290173) (xy 341.018907 17.358602) (xy 341.076676 17.421972)
			(xy 341.140046 17.479741) (xy 341.208475 17.531417) (xy 341.281381 17.576558) (xy 341.358141 17.61478)
			(xy 341.4381 17.645756) (xy 341.520576 17.669223) (xy 341.604866 17.684979) (xy 341.690249 17.692891)
			(xy 341.775999 17.692891) (xy 341.861382 17.684979) (xy 341.945672 17.669223) (xy 342.028148 17.645756)
			(xy 342.108107 17.61478) (xy 342.184867 17.576558) (xy 342.257773 17.531417) (xy 342.326202 17.479741)
			(xy 342.389572 17.421972) (xy 342.447341 17.358602) (xy 342.499017 17.290173) (xy 342.544158 17.217267)
			(xy 342.58238 17.140507) (xy 342.613356 17.060548) (xy 342.636823 16.978072) (xy 342.652579 16.893782)
			(xy 342.660491 16.808399) (xy 342.660986 16.765524) (xy 342.660491 16.722649) (xy 342.659832 16.715537)
			(xy 373.515877 16.715537) (xy 373.515877 16.801287) (xy 373.523789 16.88667) (xy 373.539545 16.97096)
			(xy 373.563012 17.053436) (xy 373.593988 17.133395) (xy 373.63221 17.210155) (xy 373.677351 17.283061)
			(xy 373.729027 17.35149) (xy 373.786796 17.41486) (xy 373.850166 17.472629) (xy 373.918595 17.524305)
			(xy 373.991501 17.569446) (xy 374.068261 17.607668) (xy 374.14822 17.638644) (xy 374.230696 17.662111)
			(xy 374.314986 17.677867) (xy 374.400369 17.685779) (xy 374.486119 17.685779) (xy 374.571502 17.677867)
			(xy 374.655792 17.662111) (xy 374.738268 17.638644) (xy 374.818227 17.607668) (xy 374.84043 17.596612)
			(xy 376.022108 17.596612) (xy 376.022108 18.460212) (xy 376.022594 18.487481) (xy 376.030356 18.541465)
			(xy 376.045721 18.593795) (xy 376.068378 18.643405) (xy 376.097864 18.689286) (xy 376.133579 18.730503)
			(xy 376.174796 18.766218) (xy 376.220677 18.795704) (xy 376.270287 18.818361) (xy 376.322617 18.833726)
			(xy 376.376601 18.841488) (xy 376.431139 18.841488) (xy 376.485123 18.833726) (xy 376.537453 18.818361)
			(xy 376.587063 18.795704) (xy 376.632944 18.766218) (xy 376.674161 18.730503) (xy 376.709876 18.689286)
			(xy 376.739362 18.643405) (xy 376.762019 18.593795) (xy 376.777384 18.541465) (xy 376.785146 18.487481)
			(xy 376.785632 18.460212) (xy 376.785632 17.596612) (xy 376.785146 17.569343) (xy 376.777384 17.515359)
			(xy 376.762019 17.463029) (xy 376.739362 17.413419) (xy 376.709876 17.367538) (xy 376.674161 17.326321)
			(xy 376.632944 17.290606) (xy 376.587063 17.26112) (xy 376.537453 17.238463) (xy 376.485123 17.223098)
			(xy 376.431139 17.215336) (xy 376.376601 17.215336) (xy 376.322617 17.223098) (xy 376.270287 17.238463)
			(xy 376.220677 17.26112) (xy 376.174796 17.290606) (xy 376.133579 17.326321) (xy 376.097864 17.367538)
			(xy 376.068378 17.413419) (xy 376.045721 17.463029) (xy 376.030356 17.515359) (xy 376.022594 17.569343)
			(xy 376.022108 17.596612) (xy 374.84043 17.596612) (xy 374.894987 17.569446) (xy 374.967893 17.524305)
			(xy 375.036322 17.472629) (xy 375.099692 17.41486) (xy 375.157461 17.35149) (xy 375.209137 17.283061)
			(xy 375.254278 17.210155) (xy 375.2925 17.133395) (xy 375.323476 17.053436) (xy 375.346943 16.97096)
			(xy 375.362699 16.88667) (xy 375.370611 16.801287) (xy 375.371106 16.758412) (xy 375.370611 16.715537)
			(xy 379.865877 16.715537) (xy 379.865877 16.801287) (xy 379.873789 16.88667) (xy 379.889545 16.97096)
			(xy 379.913012 17.053436) (xy 379.943988 17.133395) (xy 379.98221 17.210155) (xy 380.027351 17.283061)
			(xy 380.079027 17.35149) (xy 380.136796 17.41486) (xy 380.200166 17.472629) (xy 380.268595 17.524305)
			(xy 380.341501 17.569446) (xy 380.418261 17.607668) (xy 380.49822 17.638644) (xy 380.580696 17.662111)
			(xy 380.664986 17.677867) (xy 380.750369 17.685779) (xy 380.836119 17.685779) (xy 380.921502 17.677867)
			(xy 381.005792 17.662111) (xy 381.088268 17.638644) (xy 381.168227 17.607668) (xy 381.244987 17.569446)
			(xy 381.317893 17.524305) (xy 381.386322 17.472629) (xy 381.449692 17.41486) (xy 381.507461 17.35149)
			(xy 381.559137 17.283061) (xy 381.604278 17.210155) (xy 381.6425 17.133395) (xy 381.673476 17.053436)
			(xy 381.696943 16.97096) (xy 381.712699 16.88667) (xy 381.720611 16.801287) (xy 381.721106 16.758412)
			(xy 381.720693 16.722649) (xy 399.098757 16.722649) (xy 399.098757 16.808399) (xy 399.106669 16.893782)
			(xy 399.122425 16.978072) (xy 399.145892 17.060548) (xy 399.176868 17.140507) (xy 399.21509 17.217267)
			(xy 399.260231 17.290173) (xy 399.311907 17.358602) (xy 399.369676 17.421972) (xy 399.433046 17.479741)
			(xy 399.501475 17.531417) (xy 399.574381 17.576558) (xy 399.651141 17.61478) (xy 399.7311 17.645756)
			(xy 399.813576 17.669223) (xy 399.897866 17.684979) (xy 399.983249 17.692891) (xy 400.068999 17.692891)
			(xy 400.154382 17.684979) (xy 400.238672 17.669223) (xy 400.321148 17.645756) (xy 400.401107 17.61478)
			(xy 400.42331 17.603724) (xy 404.033736 17.603724) (xy 404.033736 18.467324) (xy 404.034222 18.494593)
			(xy 404.041984 18.548577) (xy 404.057349 18.600907) (xy 404.080006 18.650517) (xy 404.109492 18.696398)
			(xy 404.145207 18.737615) (xy 404.186424 18.77333) (xy 404.232305 18.802816) (xy 404.281915 18.825473)
			(xy 404.334245 18.840838) (xy 404.388229 18.8486) (xy 404.442767 18.8486) (xy 404.496751 18.840838)
			(xy 404.549081 18.825473) (xy 404.598691 18.802816) (xy 404.644572 18.77333) (xy 404.685789 18.737615)
			(xy 404.721504 18.696398) (xy 404.75099 18.650517) (xy 404.773647 18.600907) (xy 404.789012 18.548577)
			(xy 404.796774 18.494593) (xy 404.79726 18.467324) (xy 404.79726 17.603724) (xy 404.796774 17.576455)
			(xy 404.789012 17.522471) (xy 404.773647 17.470141) (xy 404.75099 17.420531) (xy 404.721504 17.37465)
			(xy 404.685789 17.333433) (xy 404.644572 17.297718) (xy 404.598691 17.268232) (xy 404.549081 17.245575)
			(xy 404.496751 17.23021) (xy 404.442767 17.222448) (xy 404.388229 17.222448) (xy 404.334245 17.23021)
			(xy 404.281915 17.245575) (xy 404.232305 17.268232) (xy 404.186424 17.297718) (xy 404.145207 17.333433)
			(xy 404.109492 17.37465) (xy 404.080006 17.420531) (xy 404.057349 17.470141) (xy 404.041984 17.522471)
			(xy 404.034222 17.576455) (xy 404.033736 17.603724) (xy 400.42331 17.603724) (xy 400.477867 17.576558)
			(xy 400.550773 17.531417) (xy 400.619202 17.479741) (xy 400.682572 17.421972) (xy 400.740341 17.358602)
			(xy 400.792017 17.290173) (xy 400.837158 17.217267) (xy 400.87538 17.140507) (xy 400.906356 17.060548)
			(xy 400.929823 16.978072) (xy 400.945579 16.893782) (xy 400.953491 16.808399) (xy 400.953986 16.765524)
			(xy 400.953491 16.722649) (xy 405.448757 16.722649) (xy 405.448757 16.808399) (xy 405.456669 16.893782)
			(xy 405.472425 16.978072) (xy 405.495892 17.060548) (xy 405.526868 17.140507) (xy 405.56509 17.217267)
			(xy 405.610231 17.290173) (xy 405.661907 17.358602) (xy 405.719676 17.421972) (xy 405.783046 17.479741)
			(xy 405.851475 17.531417) (xy 405.924381 17.576558) (xy 406.001141 17.61478) (xy 406.0811 17.645756)
			(xy 406.163576 17.669223) (xy 406.247866 17.684979) (xy 406.333249 17.692891) (xy 406.418999 17.692891)
			(xy 406.504382 17.684979) (xy 406.588672 17.669223) (xy 406.671148 17.645756) (xy 406.751107 17.61478)
			(xy 406.827867 17.576558) (xy 406.900773 17.531417) (xy 406.969202 17.479741) (xy 407.032572 17.421972)
			(xy 407.090341 17.358602) (xy 407.142017 17.290173) (xy 407.187158 17.217267) (xy 407.22538 17.140507)
			(xy 407.256356 17.060548) (xy 407.279823 16.978072) (xy 407.295579 16.893782) (xy 407.303491 16.808399)
			(xy 407.303986 16.765524) (xy 407.303491 16.722649) (xy 407.302832 16.715537) (xy 438.158877 16.715537)
			(xy 438.158877 16.801287) (xy 438.166789 16.88667) (xy 438.182545 16.97096) (xy 438.206012 17.053436)
			(xy 438.236988 17.133395) (xy 438.27521 17.210155) (xy 438.320351 17.283061) (xy 438.372027 17.35149)
			(xy 438.429796 17.41486) (xy 438.493166 17.472629) (xy 438.561595 17.524305) (xy 438.634501 17.569446)
			(xy 438.711261 17.607668) (xy 438.79122 17.638644) (xy 438.873696 17.662111) (xy 438.957986 17.677867)
			(xy 439.043369 17.685779) (xy 439.129119 17.685779) (xy 439.214502 17.677867) (xy 439.298792 17.662111)
			(xy 439.381268 17.638644) (xy 439.461227 17.607668) (xy 439.48343 17.596612) (xy 440.665108 17.596612)
			(xy 440.665108 18.460212) (xy 440.665594 18.487481) (xy 440.673356 18.541465) (xy 440.688721 18.593795)
			(xy 440.711378 18.643405) (xy 440.740864 18.689286) (xy 440.776579 18.730503) (xy 440.817796 18.766218)
			(xy 440.863677 18.795704) (xy 440.913287 18.818361) (xy 440.965617 18.833726) (xy 441.019601 18.841488)
			(xy 441.074139 18.841488) (xy 441.128123 18.833726) (xy 441.180453 18.818361) (xy 441.230063 18.795704)
			(xy 441.275944 18.766218) (xy 441.317161 18.730503) (xy 441.352876 18.689286) (xy 441.382362 18.643405)
			(xy 441.405019 18.593795) (xy 441.420384 18.541465) (xy 441.428146 18.487481) (xy 441.428632 18.460212)
			(xy 441.428632 17.596612) (xy 441.428146 17.569343) (xy 441.420384 17.515359) (xy 441.405019 17.463029)
			(xy 441.382362 17.413419) (xy 441.352876 17.367538) (xy 441.317161 17.326321) (xy 441.275944 17.290606)
			(xy 441.230063 17.26112) (xy 441.180453 17.238463) (xy 441.128123 17.223098) (xy 441.074139 17.215336)
			(xy 441.019601 17.215336) (xy 440.965617 17.223098) (xy 440.913287 17.238463) (xy 440.863677 17.26112)
			(xy 440.817796 17.290606) (xy 440.776579 17.326321) (xy 440.740864 17.367538) (xy 440.711378 17.413419)
			(xy 440.688721 17.463029) (xy 440.673356 17.515359) (xy 440.665594 17.569343) (xy 440.665108 17.596612)
			(xy 439.48343 17.596612) (xy 439.537987 17.569446) (xy 439.610893 17.524305) (xy 439.679322 17.472629)
			(xy 439.742692 17.41486) (xy 439.800461 17.35149) (xy 439.852137 17.283061) (xy 439.897278 17.210155)
			(xy 439.9355 17.133395) (xy 439.966476 17.053436) (xy 439.989943 16.97096) (xy 440.005699 16.88667)
			(xy 440.013611 16.801287) (xy 440.014106 16.758412) (xy 440.013611 16.715537) (xy 444.508877 16.715537)
			(xy 444.508877 16.801287) (xy 444.516789 16.88667) (xy 444.532545 16.97096) (xy 444.556012 17.053436)
			(xy 444.586988 17.133395) (xy 444.62521 17.210155) (xy 444.670351 17.283061) (xy 444.722027 17.35149)
			(xy 444.779796 17.41486) (xy 444.843166 17.472629) (xy 444.911595 17.524305) (xy 444.984501 17.569446)
			(xy 445.061261 17.607668) (xy 445.14122 17.638644) (xy 445.223696 17.662111) (xy 445.307986 17.677867)
			(xy 445.393369 17.685779) (xy 445.479119 17.685779) (xy 445.564502 17.677867) (xy 445.648792 17.662111)
			(xy 445.731268 17.638644) (xy 445.811227 17.607668) (xy 445.887987 17.569446) (xy 445.960893 17.524305)
			(xy 446.029322 17.472629) (xy 446.092692 17.41486) (xy 446.150461 17.35149) (xy 446.202137 17.283061)
			(xy 446.247278 17.210155) (xy 446.2855 17.133395) (xy 446.316476 17.053436) (xy 446.339943 16.97096)
			(xy 446.355699 16.88667) (xy 446.363611 16.801287) (xy 446.364106 16.758412) (xy 446.363611 16.715537)
			(xy 446.355699 16.630154) (xy 446.339943 16.545864) (xy 446.316476 16.463388) (xy 446.2855 16.383429)
			(xy 446.247278 16.306669) (xy 446.202137 16.233763) (xy 446.150461 16.165334) (xy 446.092692 16.101964)
			(xy 446.029322 16.044195) (xy 445.960893 15.992519) (xy 445.887987 15.947378) (xy 445.811227 15.909156)
			(xy 445.731268 15.87818) (xy 445.648792 15.854713) (xy 445.564502 15.838957) (xy 445.479119 15.831045)
			(xy 445.393369 15.831045) (xy 445.307986 15.838957) (xy 445.223696 15.854713) (xy 445.14122 15.87818)
			(xy 445.061261 15.909156) (xy 444.984501 15.947378) (xy 444.911595 15.992519) (xy 444.843166 16.044195)
			(xy 444.779796 16.101964) (xy 444.722027 16.165334) (xy 444.670351 16.233763) (xy 444.62521 16.306669)
			(xy 444.586988 16.383429) (xy 444.556012 16.463388) (xy 444.532545 16.545864) (xy 444.516789 16.630154)
			(xy 444.508877 16.715537) (xy 440.013611 16.715537) (xy 440.005699 16.630154) (xy 439.989943 16.545864)
			(xy 439.966476 16.463388) (xy 439.9355 16.383429) (xy 439.897278 16.306669) (xy 439.852137 16.233763)
			(xy 439.800461 16.165334) (xy 439.742692 16.101964) (xy 439.679322 16.044195) (xy 439.610893 15.992519)
			(xy 439.537987 15.947378) (xy 439.461227 15.909156) (xy 439.381268 15.87818) (xy 439.298792 15.854713)
			(xy 439.214502 15.838957) (xy 439.129119 15.831045) (xy 439.043369 15.831045) (xy 438.957986 15.838957)
			(xy 438.873696 15.854713) (xy 438.79122 15.87818) (xy 438.711261 15.909156) (xy 438.634501 15.947378)
			(xy 438.561595 15.992519) (xy 438.493166 16.044195) (xy 438.429796 16.101964) (xy 438.372027 16.165334)
			(xy 438.320351 16.233763) (xy 438.27521 16.306669) (xy 438.236988 16.383429) (xy 438.206012 16.463388)
			(xy 438.182545 16.545864) (xy 438.166789 16.630154) (xy 438.158877 16.715537) (xy 407.302832 16.715537)
			(xy 407.295579 16.637266) (xy 407.279823 16.552976) (xy 407.256356 16.4705) (xy 407.22538 16.390541)
			(xy 407.187158 16.313781) (xy 407.142017 16.240875) (xy 407.090341 16.172446) (xy 407.032572 16.109076)
			(xy 406.969202 16.051307) (xy 406.900773 15.999631) (xy 406.827867 15.95449) (xy 406.751107 15.916268)
			(xy 406.671148 15.885292) (xy 406.588672 15.861825) (xy 406.504382 15.846069) (xy 406.418999 15.838157)
			(xy 406.333249 15.838157) (xy 406.247866 15.846069) (xy 406.163576 15.861825) (xy 406.0811 15.885292)
			(xy 406.001141 15.916268) (xy 405.924381 15.95449) (xy 405.851475 15.999631) (xy 405.783046 16.051307)
			(xy 405.719676 16.109076) (xy 405.661907 16.172446) (xy 405.610231 16.240875) (xy 405.56509 16.313781)
			(xy 405.526868 16.390541) (xy 405.495892 16.4705) (xy 405.472425 16.552976) (xy 405.456669 16.637266)
			(xy 405.448757 16.722649) (xy 400.953491 16.722649) (xy 400.945579 16.637266) (xy 400.929823 16.552976)
			(xy 400.906356 16.4705) (xy 400.87538 16.390541) (xy 400.837158 16.313781) (xy 400.792017 16.240875)
			(xy 400.740341 16.172446) (xy 400.682572 16.109076) (xy 400.619202 16.051307) (xy 400.550773 15.999631)
			(xy 400.477867 15.95449) (xy 400.401107 15.916268) (xy 400.321148 15.885292) (xy 400.238672 15.861825)
			(xy 400.154382 15.846069) (xy 400.068999 15.838157) (xy 399.983249 15.838157) (xy 399.897866 15.846069)
			(xy 399.813576 15.861825) (xy 399.7311 15.885292) (xy 399.651141 15.916268) (xy 399.574381 15.95449)
			(xy 399.501475 15.999631) (xy 399.433046 16.051307) (xy 399.369676 16.109076) (xy 399.311907 16.172446)
			(xy 399.260231 16.240875) (xy 399.21509 16.313781) (xy 399.176868 16.390541) (xy 399.145892 16.4705)
			(xy 399.122425 16.552976) (xy 399.106669 16.637266) (xy 399.098757 16.722649) (xy 381.720693 16.722649)
			(xy 381.720611 16.715537) (xy 381.712699 16.630154) (xy 381.696943 16.545864) (xy 381.673476 16.463388)
			(xy 381.6425 16.383429) (xy 381.604278 16.306669) (xy 381.559137 16.233763) (xy 381.507461 16.165334)
			(xy 381.449692 16.101964) (xy 381.386322 16.044195) (xy 381.317893 15.992519) (xy 381.244987 15.947378)
			(xy 381.168227 15.909156) (xy 381.088268 15.87818) (xy 381.005792 15.854713) (xy 380.921502 15.838957)
			(xy 380.836119 15.831045) (xy 380.750369 15.831045) (xy 380.664986 15.838957) (xy 380.580696 15.854713)
			(xy 380.49822 15.87818) (xy 380.418261 15.909156) (xy 380.341501 15.947378) (xy 380.268595 15.992519)
			(xy 380.200166 16.044195) (xy 380.136796 16.101964) (xy 380.079027 16.165334) (xy 380.027351 16.233763)
			(xy 379.98221 16.306669) (xy 379.943988 16.383429) (xy 379.913012 16.463388) (xy 379.889545 16.545864)
			(xy 379.873789 16.630154) (xy 379.865877 16.715537) (xy 375.370611 16.715537) (xy 375.362699 16.630154)
			(xy 375.346943 16.545864) (xy 375.323476 16.463388) (xy 375.2925 16.383429) (xy 375.254278 16.306669)
			(xy 375.209137 16.233763) (xy 375.157461 16.165334) (xy 375.099692 16.101964) (xy 375.036322 16.044195)
			(xy 374.967893 15.992519) (xy 374.894987 15.947378) (xy 374.818227 15.909156) (xy 374.738268 15.87818)
			(xy 374.655792 15.854713) (xy 374.571502 15.838957) (xy 374.486119 15.831045) (xy 374.400369 15.831045)
			(xy 374.314986 15.838957) (xy 374.230696 15.854713) (xy 374.14822 15.87818) (xy 374.068261 15.909156)
			(xy 373.991501 15.947378) (xy 373.918595 15.992519) (xy 373.850166 16.044195) (xy 373.786796 16.101964)
			(xy 373.729027 16.165334) (xy 373.677351 16.233763) (xy 373.63221 16.306669) (xy 373.593988 16.383429)
			(xy 373.563012 16.463388) (xy 373.539545 16.545864) (xy 373.523789 16.630154) (xy 373.515877 16.715537)
			(xy 342.659832 16.715537) (xy 342.652579 16.637266) (xy 342.636823 16.552976) (xy 342.613356 16.4705)
			(xy 342.58238 16.390541) (xy 342.544158 16.313781) (xy 342.499017 16.240875) (xy 342.447341 16.172446)
			(xy 342.389572 16.109076) (xy 342.326202 16.051307) (xy 342.257773 15.999631) (xy 342.184867 15.95449)
			(xy 342.108107 15.916268) (xy 342.028148 15.885292) (xy 341.945672 15.861825) (xy 341.861382 15.846069)
			(xy 341.775999 15.838157) (xy 341.690249 15.838157) (xy 341.604866 15.846069) (xy 341.520576 15.861825)
			(xy 341.4381 15.885292) (xy 341.358141 15.916268) (xy 341.281381 15.95449) (xy 341.208475 15.999631)
			(xy 341.140046 16.051307) (xy 341.076676 16.109076) (xy 341.018907 16.172446) (xy 340.967231 16.240875)
			(xy 340.92209 16.313781) (xy 340.883868 16.390541) (xy 340.852892 16.4705) (xy 340.829425 16.552976)
			(xy 340.813669 16.637266) (xy 340.805757 16.722649) (xy 336.310491 16.722649) (xy 336.302579 16.637266)
			(xy 336.286823 16.552976) (xy 336.263356 16.4705) (xy 336.23238 16.390541) (xy 336.194158 16.313781)
			(xy 336.149017 16.240875) (xy 336.097341 16.172446) (xy 336.039572 16.109076) (xy 335.976202 16.051307)
			(xy 335.907773 15.999631) (xy 335.834867 15.95449) (xy 335.758107 15.916268) (xy 335.678148 15.885292)
			(xy 335.595672 15.861825) (xy 335.511382 15.846069) (xy 335.425999 15.838157) (xy 335.340249 15.838157)
			(xy 335.254866 15.846069) (xy 335.170576 15.861825) (xy 335.0881 15.885292) (xy 335.008141 15.916268)
			(xy 334.931381 15.95449) (xy 334.858475 15.999631) (xy 334.790046 16.051307) (xy 334.726676 16.109076)
			(xy 334.668907 16.172446) (xy 334.617231 16.240875) (xy 334.57209 16.313781) (xy 334.533868 16.390541)
			(xy 334.502892 16.4705) (xy 334.479425 16.552976) (xy 334.463669 16.637266) (xy 334.455757 16.722649)
			(xy 316.569693 16.722649) (xy 316.569611 16.715537) (xy 316.561699 16.630154) (xy 316.545943 16.545864)
			(xy 316.522476 16.463388) (xy 316.4915 16.383429) (xy 316.453278 16.306669) (xy 316.408137 16.233763)
			(xy 316.356461 16.165334) (xy 316.298692 16.101964) (xy 316.235322 16.044195) (xy 316.166893 15.992519)
			(xy 316.093987 15.947378) (xy 316.017227 15.909156) (xy 315.937268 15.87818) (xy 315.854792 15.854713)
			(xy 315.770502 15.838957) (xy 315.685119 15.831045) (xy 315.599369 15.831045) (xy 315.513986 15.838957)
			(xy 315.429696 15.854713) (xy 315.34722 15.87818) (xy 315.267261 15.909156) (xy 315.190501 15.947378)
			(xy 315.117595 15.992519) (xy 315.049166 16.044195) (xy 314.985796 16.101964) (xy 314.928027 16.165334)
			(xy 314.876351 16.233763) (xy 314.83121 16.306669) (xy 314.792988 16.383429) (xy 314.762012 16.463388)
			(xy 314.738545 16.545864) (xy 314.722789 16.630154) (xy 314.714877 16.715537) (xy 310.219611 16.715537)
			(xy 310.211699 16.630154) (xy 310.195943 16.545864) (xy 310.172476 16.463388) (xy 310.1415 16.383429)
			(xy 310.103278 16.306669) (xy 310.058137 16.233763) (xy 310.006461 16.165334) (xy 309.948692 16.101964)
			(xy 309.885322 16.044195) (xy 309.816893 15.992519) (xy 309.743987 15.947378) (xy 309.667227 15.909156)
			(xy 309.587268 15.87818) (xy 309.504792 15.854713) (xy 309.420502 15.838957) (xy 309.335119 15.831045)
			(xy 309.249369 15.831045) (xy 309.163986 15.838957) (xy 309.079696 15.854713) (xy 308.99722 15.87818)
			(xy 308.917261 15.909156) (xy 308.840501 15.947378) (xy 308.767595 15.992519) (xy 308.699166 16.044195)
			(xy 308.635796 16.101964) (xy 308.578027 16.165334) (xy 308.526351 16.233763) (xy 308.48121 16.306669)
			(xy 308.442988 16.383429) (xy 308.412012 16.463388) (xy 308.388545 16.545864) (xy 308.372789 16.630154)
			(xy 308.364877 16.715537) (xy 277.508832 16.715537) (xy 277.501579 16.637266) (xy 277.485823 16.552976)
			(xy 277.462356 16.4705) (xy 277.43138 16.390541) (xy 277.393158 16.313781) (xy 277.348017 16.240875)
			(xy 277.296341 16.172446) (xy 277.238572 16.109076) (xy 277.175202 16.051307) (xy 277.106773 15.999631)
			(xy 277.033867 15.95449) (xy 276.957107 15.916268) (xy 276.877148 15.885292) (xy 276.794672 15.861825)
			(xy 276.710382 15.846069) (xy 276.624999 15.838157) (xy 276.539249 15.838157) (xy 276.453866 15.846069)
			(xy 276.369576 15.861825) (xy 276.2871 15.885292) (xy 276.207141 15.916268) (xy 276.130381 15.95449)
			(xy 276.057475 15.999631) (xy 275.989046 16.051307) (xy 275.925676 16.109076) (xy 275.867907 16.172446)
			(xy 275.816231 16.240875) (xy 275.77109 16.313781) (xy 275.732868 16.390541) (xy 275.701892 16.4705)
			(xy 275.678425 16.552976) (xy 275.662669 16.637266) (xy 275.654757 16.722649) (xy 271.159491 16.722649)
			(xy 271.151579 16.637266) (xy 271.135823 16.552976) (xy 271.112356 16.4705) (xy 271.08138 16.390541)
			(xy 271.043158 16.313781) (xy 270.998017 16.240875) (xy 270.946341 16.172446) (xy 270.888572 16.109076)
			(xy 270.825202 16.051307) (xy 270.756773 15.999631) (xy 270.683867 15.95449) (xy 270.607107 15.916268)
			(xy 270.527148 15.885292) (xy 270.444672 15.861825) (xy 270.360382 15.846069) (xy 270.274999 15.838157)
			(xy 270.189249 15.838157) (xy 270.103866 15.846069) (xy 270.019576 15.861825) (xy 269.9371 15.885292)
			(xy 269.857141 15.916268) (xy 269.780381 15.95449) (xy 269.707475 15.999631) (xy 269.639046 16.051307)
			(xy 269.575676 16.109076) (xy 269.517907 16.172446) (xy 269.466231 16.240875) (xy 269.42109 16.313781)
			(xy 269.382868 16.390541) (xy 269.351892 16.4705) (xy 269.328425 16.552976) (xy 269.312669 16.637266)
			(xy 269.304757 16.722649) (xy 252.231493 16.722649) (xy 252.231411 16.715537) (xy 252.223499 16.630154)
			(xy 252.207743 16.545864) (xy 252.184276 16.463388) (xy 252.1533 16.383429) (xy 252.115078 16.306669)
			(xy 252.069937 16.233763) (xy 252.018261 16.165334) (xy 251.960492 16.101964) (xy 251.897122 16.044195)
			(xy 251.828693 15.992519) (xy 251.755787 15.947378) (xy 251.679027 15.909156) (xy 251.599068 15.87818)
			(xy 251.516592 15.854713) (xy 251.432302 15.838957) (xy 251.346919 15.831045) (xy 251.261169 15.831045)
			(xy 251.175786 15.838957) (xy 251.091496 15.854713) (xy 251.00902 15.87818) (xy 250.929061 15.909156)
			(xy 250.852301 15.947378) (xy 250.779395 15.992519) (xy 250.710966 16.044195) (xy 250.647596 16.101964)
			(xy 250.589827 16.165334) (xy 250.538151 16.233763) (xy 250.49301 16.306669) (xy 250.454788 16.383429)
			(xy 250.423812 16.463388) (xy 250.400345 16.545864) (xy 250.384589 16.630154) (xy 250.376677 16.715537)
			(xy 245.881411 16.715537) (xy 245.873499 16.630154) (xy 245.857743 16.545864) (xy 245.834276 16.463388)
			(xy 245.8033 16.383429) (xy 245.765078 16.306669) (xy 245.719937 16.233763) (xy 245.668261 16.165334)
			(xy 245.610492 16.101964) (xy 245.547122 16.044195) (xy 245.478693 15.992519) (xy 245.405787 15.947378)
			(xy 245.329027 15.909156) (xy 245.249068 15.87818) (xy 245.166592 15.854713) (xy 245.082302 15.838957)
			(xy 244.996919 15.831045) (xy 244.911169 15.831045) (xy 244.825786 15.838957) (xy 244.741496 15.854713)
			(xy 244.65902 15.87818) (xy 244.579061 15.909156) (xy 244.502301 15.947378) (xy 244.429395 15.992519)
			(xy 244.360966 16.044195) (xy 244.297596 16.101964) (xy 244.239827 16.165334) (xy 244.188151 16.233763)
			(xy 244.14301 16.306669) (xy 244.104788 16.383429) (xy 244.073812 16.463388) (xy 244.050345 16.545864)
			(xy 244.034589 16.630154) (xy 244.026677 16.715537) (xy 218.199832 16.715537) (xy 218.192579 16.637266)
			(xy 218.176823 16.552976) (xy 218.153356 16.4705) (xy 218.12238 16.390541) (xy 218.084158 16.313781)
			(xy 218.039017 16.240875) (xy 217.987341 16.172446) (xy 217.929572 16.109076) (xy 217.866202 16.051307)
			(xy 217.797773 15.999631) (xy 217.724867 15.95449) (xy 217.648107 15.916268) (xy 217.568148 15.885292)
			(xy 217.485672 15.861825) (xy 217.401382 15.846069) (xy 217.315999 15.838157) (xy 217.230249 15.838157)
			(xy 217.144866 15.846069) (xy 217.060576 15.861825) (xy 216.9781 15.885292) (xy 216.898141 15.916268)
			(xy 216.821381 15.95449) (xy 216.748475 15.999631) (xy 216.680046 16.051307) (xy 216.616676 16.109076)
			(xy 216.558907 16.172446) (xy 216.507231 16.240875) (xy 216.46209 16.313781) (xy 216.423868 16.390541)
			(xy 216.392892 16.4705) (xy 216.369425 16.552976) (xy 216.353669 16.637266) (xy 216.345757 16.722649)
			(xy 211.850491 16.722649) (xy 211.842579 16.637266) (xy 211.826823 16.552976) (xy 211.803356 16.4705)
			(xy 211.77238 16.390541) (xy 211.734158 16.313781) (xy 211.689017 16.240875) (xy 211.637341 16.172446)
			(xy 211.579572 16.109076) (xy 211.516202 16.051307) (xy 211.447773 15.999631) (xy 211.374867 15.95449)
			(xy 211.298107 15.916268) (xy 211.218148 15.885292) (xy 211.135672 15.861825) (xy 211.051382 15.846069)
			(xy 210.965999 15.838157) (xy 210.880249 15.838157) (xy 210.794866 15.846069) (xy 210.710576 15.861825)
			(xy 210.6281 15.885292) (xy 210.548141 15.916268) (xy 210.471381 15.95449) (xy 210.398475 15.999631)
			(xy 210.330046 16.051307) (xy 210.266676 16.109076) (xy 210.208907 16.172446) (xy 210.157231 16.240875)
			(xy 210.11209 16.313781) (xy 210.073868 16.390541) (xy 210.042892 16.4705) (xy 210.019425 16.552976)
			(xy 210.003669 16.637266) (xy 209.995757 16.722649) (xy 158.621984 16.722649) (xy 158.621984 11.850929)
			(xy 251.524757 11.850929) (xy 251.524757 11.936679) (xy 251.532669 12.022062) (xy 251.548425 12.106352)
			(xy 251.571892 12.188828) (xy 251.602868 12.268787) (xy 251.64109 12.345547) (xy 251.686231 12.418453)
			(xy 251.737907 12.486882) (xy 251.795676 12.550252) (xy 251.859046 12.608021) (xy 251.927475 12.659697)
			(xy 252.000381 12.704838) (xy 252.077141 12.74306) (xy 252.1571 12.774036) (xy 252.239576 12.797503)
			(xy 252.323866 12.813259) (xy 252.409249 12.821171) (xy 252.494999 12.821171) (xy 252.580382 12.813259)
			(xy 252.664672 12.797503) (xy 252.747148 12.774036) (xy 252.827107 12.74306) (xy 252.903867 12.704838)
			(xy 252.976773 12.659697) (xy 253.045202 12.608021) (xy 253.108572 12.550252) (xy 253.166341 12.486882)
			(xy 253.218017 12.418453) (xy 253.263158 12.345547) (xy 253.30138 12.268787) (xy 253.332356 12.188828)
			(xy 253.355823 12.106352) (xy 253.371579 12.022062) (xy 253.379491 11.936679) (xy 253.379986 11.893804)
			(xy 253.379491 11.850929) (xy 257.874757 11.850929) (xy 257.874757 11.936679) (xy 257.882669 12.022062)
			(xy 257.898425 12.106352) (xy 257.921892 12.188828) (xy 257.952868 12.268787) (xy 257.99109 12.345547)
			(xy 258.036231 12.418453) (xy 258.087907 12.486882) (xy 258.145676 12.550252) (xy 258.209046 12.608021)
			(xy 258.277475 12.659697) (xy 258.350381 12.704838) (xy 258.427141 12.74306) (xy 258.5071 12.774036)
			(xy 258.589576 12.797503) (xy 258.673866 12.813259) (xy 258.759249 12.821171) (xy 258.844999 12.821171)
			(xy 258.930382 12.813259) (xy 259.014672 12.797503) (xy 259.097148 12.774036) (xy 259.177107 12.74306)
			(xy 259.253867 12.704838) (xy 259.326773 12.659697) (xy 259.395202 12.608021) (xy 259.458572 12.550252)
			(xy 259.516341 12.486882) (xy 259.568017 12.418453) (xy 259.613158 12.345547) (xy 259.65138 12.268787)
			(xy 259.682356 12.188828) (xy 259.705823 12.106352) (xy 259.721579 12.022062) (xy 259.729491 11.936679)
			(xy 259.729986 11.893804) (xy 259.72979 11.876837) (xy 309.725301 11.876837) (xy 309.725301 11.962587)
			(xy 309.733213 12.04797) (xy 309.748969 12.13226) (xy 309.772436 12.214736) (xy 309.803412 12.294695)
			(xy 309.841634 12.371455) (xy 309.886775 12.444361) (xy 309.938451 12.51279) (xy 309.99622 12.57616)
			(xy 310.05959 12.633929) (xy 310.128019 12.685605) (xy 310.200925 12.730746) (xy 310.277685 12.768968)
			(xy 310.357644 12.799944) (xy 310.44012 12.823411) (xy 310.52441 12.839167) (xy 310.609793 12.847079)
			(xy 310.695543 12.847079) (xy 310.780926 12.839167) (xy 310.865216 12.823411) (xy 310.947692 12.799944)
			(xy 311.027651 12.768968) (xy 311.104411 12.730746) (xy 311.177317 12.685605) (xy 311.245746 12.633929)
			(xy 311.309116 12.57616) (xy 311.366885 12.51279) (xy 311.418561 12.444361) (xy 311.463702 12.371455)
			(xy 311.501924 12.294695) (xy 311.5329 12.214736) (xy 311.556367 12.13226) (xy 311.572123 12.04797)
			(xy 311.580035 11.962587) (xy 311.58053 11.919712) (xy 311.580035 11.876837) (xy 316.075301 11.876837)
			(xy 316.075301 11.962587) (xy 316.083213 12.04797) (xy 316.098969 12.13226) (xy 316.122436 12.214736)
			(xy 316.153412 12.294695) (xy 316.191634 12.371455) (xy 316.236775 12.444361) (xy 316.288451 12.51279)
			(xy 316.34622 12.57616) (xy 316.40959 12.633929) (xy 316.478019 12.685605) (xy 316.550925 12.730746)
			(xy 316.627685 12.768968) (xy 316.707644 12.799944) (xy 316.79012 12.823411) (xy 316.87441 12.839167)
			(xy 316.959793 12.847079) (xy 317.045543 12.847079) (xy 317.130926 12.839167) (xy 317.215216 12.823411)
			(xy 317.297692 12.799944) (xy 317.377651 12.768968) (xy 317.454411 12.730746) (xy 317.527317 12.685605)
			(xy 317.595746 12.633929) (xy 317.659116 12.57616) (xy 317.716885 12.51279) (xy 317.768561 12.444361)
			(xy 317.813702 12.371455) (xy 317.851924 12.294695) (xy 317.8829 12.214736) (xy 317.906367 12.13226)
			(xy 317.922123 12.04797) (xy 317.930035 11.962587) (xy 317.93053 11.919712) (xy 317.930117 11.883949)
			(xy 324.295757 11.883949) (xy 324.295757 11.969699) (xy 324.303669 12.055082) (xy 324.319425 12.139372)
			(xy 324.342892 12.221848) (xy 324.373868 12.301807) (xy 324.41209 12.378567) (xy 324.457231 12.451473)
			(xy 324.508907 12.519902) (xy 324.566676 12.583272) (xy 324.630046 12.641041) (xy 324.698475 12.692717)
			(xy 324.771381 12.737858) (xy 324.848141 12.77608) (xy 324.9281 12.807056) (xy 325.010576 12.830523)
			(xy 325.094866 12.846279) (xy 325.180249 12.854191) (xy 325.265999 12.854191) (xy 325.351382 12.846279)
			(xy 325.435672 12.830523) (xy 325.518148 12.807056) (xy 325.598107 12.77608) (xy 325.674867 12.737858)
			(xy 325.747773 12.692717) (xy 325.816202 12.641041) (xy 325.879572 12.583272) (xy 325.937341 12.519902)
			(xy 325.989017 12.451473) (xy 326.034158 12.378567) (xy 326.07238 12.301807) (xy 326.103356 12.221848)
			(xy 326.126823 12.139372) (xy 326.142579 12.055082) (xy 326.150491 11.969699) (xy 326.150986 11.926824)
			(xy 326.150491 11.883949) (xy 330.645757 11.883949) (xy 330.645757 11.969699) (xy 330.653669 12.055082)
			(xy 330.669425 12.139372) (xy 330.692892 12.221848) (xy 330.723868 12.301807) (xy 330.76209 12.378567)
			(xy 330.807231 12.451473) (xy 330.858907 12.519902) (xy 330.916676 12.583272) (xy 330.980046 12.641041)
			(xy 331.048475 12.692717) (xy 331.121381 12.737858) (xy 331.198141 12.77608) (xy 331.2781 12.807056)
			(xy 331.360576 12.830523) (xy 331.444866 12.846279) (xy 331.530249 12.854191) (xy 331.615999 12.854191)
			(xy 331.701382 12.846279) (xy 331.785672 12.830523) (xy 331.868148 12.807056) (xy 331.948107 12.77608)
			(xy 332.024867 12.737858) (xy 332.097773 12.692717) (xy 332.166202 12.641041) (xy 332.229572 12.583272)
			(xy 332.287341 12.519902) (xy 332.339017 12.451473) (xy 332.384158 12.378567) (xy 332.42238 12.301807)
			(xy 332.453356 12.221848) (xy 332.476823 12.139372) (xy 332.492579 12.055082) (xy 332.500491 11.969699)
			(xy 332.500986 11.926824) (xy 332.50079 11.909857) (xy 382.496301 11.909857) (xy 382.496301 11.995607)
			(xy 382.504213 12.08099) (xy 382.519969 12.16528) (xy 382.543436 12.247756) (xy 382.574412 12.327715)
			(xy 382.612634 12.404475) (xy 382.657775 12.477381) (xy 382.709451 12.54581) (xy 382.76722 12.60918)
			(xy 382.83059 12.666949) (xy 382.899019 12.718625) (xy 382.971925 12.763766) (xy 383.048685 12.801988)
			(xy 383.128644 12.832964) (xy 383.21112 12.856431) (xy 383.29541 12.872187) (xy 383.380793 12.880099)
			(xy 383.466543 12.880099) (xy 383.551926 12.872187) (xy 383.636216 12.856431) (xy 383.718692 12.832964)
			(xy 383.798651 12.801988) (xy 383.875411 12.763766) (xy 383.948317 12.718625) (xy 384.016746 12.666949)
			(xy 384.080116 12.60918) (xy 384.137885 12.54581) (xy 384.189561 12.477381) (xy 384.234702 12.404475)
			(xy 384.272924 12.327715) (xy 384.3039 12.247756) (xy 384.327367 12.16528) (xy 384.343123 12.08099)
			(xy 384.351035 11.995607) (xy 384.35153 11.952732) (xy 384.351035 11.909857) (xy 388.846301 11.909857)
			(xy 388.846301 11.995607) (xy 388.854213 12.08099) (xy 388.869969 12.16528) (xy 388.893436 12.247756)
			(xy 388.924412 12.327715) (xy 388.962634 12.404475) (xy 389.007775 12.477381) (xy 389.059451 12.54581)
			(xy 389.11722 12.60918) (xy 389.18059 12.666949) (xy 389.249019 12.718625) (xy 389.321925 12.763766)
			(xy 389.398685 12.801988) (xy 389.478644 12.832964) (xy 389.56112 12.856431) (xy 389.64541 12.872187)
			(xy 389.730793 12.880099) (xy 389.816543 12.880099) (xy 389.901926 12.872187) (xy 389.986216 12.856431)
			(xy 390.068692 12.832964) (xy 390.148651 12.801988) (xy 390.225411 12.763766) (xy 390.298317 12.718625)
			(xy 390.366746 12.666949) (xy 390.430116 12.60918) (xy 390.487885 12.54581) (xy 390.539561 12.477381)
			(xy 390.584702 12.404475) (xy 390.622924 12.327715) (xy 390.6539 12.247756) (xy 390.677367 12.16528)
			(xy 390.693123 12.08099) (xy 390.701035 11.995607) (xy 390.70153 11.952732) (xy 390.701117 11.916969)
			(xy 396.558757 11.916969) (xy 396.558757 12.002719) (xy 396.566669 12.088102) (xy 396.582425 12.172392)
			(xy 396.605892 12.254868) (xy 396.636868 12.334827) (xy 396.67509 12.411587) (xy 396.720231 12.484493)
			(xy 396.771907 12.552922) (xy 396.829676 12.616292) (xy 396.893046 12.674061) (xy 396.961475 12.725737)
			(xy 397.034381 12.770878) (xy 397.111141 12.8091) (xy 397.1911 12.840076) (xy 397.273576 12.863543)
			(xy 397.357866 12.879299) (xy 397.443249 12.887211) (xy 397.528999 12.887211) (xy 397.614382 12.879299)
			(xy 397.698672 12.863543) (xy 397.781148 12.840076) (xy 397.861107 12.8091) (xy 397.937867 12.770878)
			(xy 398.010773 12.725737) (xy 398.079202 12.674061) (xy 398.142572 12.616292) (xy 398.200341 12.552922)
			(xy 398.252017 12.484493) (xy 398.297158 12.411587) (xy 398.33538 12.334827) (xy 398.366356 12.254868)
			(xy 398.389823 12.172392) (xy 398.405579 12.088102) (xy 398.413491 12.002719) (xy 398.413986 11.959844)
			(xy 398.413491 11.916969) (xy 402.908757 11.916969) (xy 402.908757 12.002719) (xy 402.916669 12.088102)
			(xy 402.932425 12.172392) (xy 402.955892 12.254868) (xy 402.986868 12.334827) (xy 403.02509 12.411587)
			(xy 403.070231 12.484493) (xy 403.121907 12.552922) (xy 403.179676 12.616292) (xy 403.243046 12.674061)
			(xy 403.311475 12.725737) (xy 403.384381 12.770878) (xy 403.461141 12.8091) (xy 403.5411 12.840076)
			(xy 403.623576 12.863543) (xy 403.707866 12.879299) (xy 403.793249 12.887211) (xy 403.878999 12.887211)
			(xy 403.964382 12.879299) (xy 404.048672 12.863543) (xy 404.131148 12.840076) (xy 404.211107 12.8091)
			(xy 404.287867 12.770878) (xy 404.360773 12.725737) (xy 404.429202 12.674061) (xy 404.492572 12.616292)
			(xy 404.550341 12.552922) (xy 404.602017 12.484493) (xy 404.647158 12.411587) (xy 404.68538 12.334827)
			(xy 404.716356 12.254868) (xy 404.739823 12.172392) (xy 404.755579 12.088102) (xy 404.763491 12.002719)
			(xy 404.763986 11.959844) (xy 404.76379 11.942877) (xy 454.759301 11.942877) (xy 454.759301 12.028627)
			(xy 454.767213 12.11401) (xy 454.782969 12.1983) (xy 454.806436 12.280776) (xy 454.837412 12.360735)
			(xy 454.875634 12.437495) (xy 454.920775 12.510401) (xy 454.972451 12.57883) (xy 455.03022 12.6422)
			(xy 455.09359 12.699969) (xy 455.162019 12.751645) (xy 455.234925 12.796786) (xy 455.311685 12.835008)
			(xy 455.391644 12.865984) (xy 455.47412 12.889451) (xy 455.55841 12.905207) (xy 455.643793 12.913119)
			(xy 455.729543 12.913119) (xy 455.814926 12.905207) (xy 455.899216 12.889451) (xy 455.981692 12.865984)
			(xy 456.061651 12.835008) (xy 456.138411 12.796786) (xy 456.211317 12.751645) (xy 456.279746 12.699969)
			(xy 456.343116 12.6422) (xy 456.400885 12.57883) (xy 456.452561 12.510401) (xy 456.497702 12.437495)
			(xy 456.535924 12.360735) (xy 456.5669 12.280776) (xy 456.590367 12.1983) (xy 456.606123 12.11401)
			(xy 456.614035 12.028627) (xy 456.61453 11.985752) (xy 456.614035 11.942877) (xy 461.109301 11.942877)
			(xy 461.109301 12.028627) (xy 461.117213 12.11401) (xy 461.132969 12.1983) (xy 461.156436 12.280776)
			(xy 461.187412 12.360735) (xy 461.225634 12.437495) (xy 461.270775 12.510401) (xy 461.322451 12.57883)
			(xy 461.38022 12.6422) (xy 461.44359 12.699969) (xy 461.512019 12.751645) (xy 461.584925 12.796786)
			(xy 461.661685 12.835008) (xy 461.741644 12.865984) (xy 461.82412 12.889451) (xy 461.90841 12.905207)
			(xy 461.993793 12.913119) (xy 462.079543 12.913119) (xy 462.164926 12.905207) (xy 462.249216 12.889451)
			(xy 462.331692 12.865984) (xy 462.411651 12.835008) (xy 462.488411 12.796786) (xy 462.561317 12.751645)
			(xy 462.629746 12.699969) (xy 462.693116 12.6422) (xy 462.750885 12.57883) (xy 462.802561 12.510401)
			(xy 462.847702 12.437495) (xy 462.885924 12.360735) (xy 462.9169 12.280776) (xy 462.940367 12.1983)
			(xy 462.956123 12.11401) (xy 462.964035 12.028627) (xy 462.96453 11.985752) (xy 462.964035 11.942877)
			(xy 462.956123 11.857494) (xy 462.940367 11.773204) (xy 462.9169 11.690728) (xy 462.885924 11.610769)
			(xy 462.847702 11.534009) (xy 462.802561 11.461103) (xy 462.750885 11.392674) (xy 462.693116 11.329304)
			(xy 462.629746 11.271535) (xy 462.561317 11.219859) (xy 462.488411 11.174718) (xy 462.411651 11.136496)
			(xy 462.331692 11.10552) (xy 462.249216 11.082053) (xy 462.164926 11.066297) (xy 462.079543 11.058385)
			(xy 461.993793 11.058385) (xy 461.90841 11.066297) (xy 461.82412 11.082053) (xy 461.741644 11.10552)
			(xy 461.661685 11.136496) (xy 461.584925 11.174718) (xy 461.512019 11.219859) (xy 461.44359 11.271535)
			(xy 461.38022 11.329304) (xy 461.322451 11.392674) (xy 461.270775 11.461103) (xy 461.225634 11.534009)
			(xy 461.187412 11.610769) (xy 461.156436 11.690728) (xy 461.132969 11.773204) (xy 461.117213 11.857494)
			(xy 461.109301 11.942877) (xy 456.614035 11.942877) (xy 456.606123 11.857494) (xy 456.590367 11.773204)
			(xy 456.5669 11.690728) (xy 456.535924 11.610769) (xy 456.497702 11.534009) (xy 456.452561 11.461103)
			(xy 456.400885 11.392674) (xy 456.343116 11.329304) (xy 456.279746 11.271535) (xy 456.211317 11.219859)
			(xy 456.138411 11.174718) (xy 456.061651 11.136496) (xy 455.981692 11.10552) (xy 455.899216 11.082053)
			(xy 455.814926 11.066297) (xy 455.729543 11.058385) (xy 455.643793 11.058385) (xy 455.55841 11.066297)
			(xy 455.47412 11.082053) (xy 455.391644 11.10552) (xy 455.311685 11.136496) (xy 455.234925 11.174718)
			(xy 455.162019 11.219859) (xy 455.09359 11.271535) (xy 455.03022 11.329304) (xy 454.972451 11.392674)
			(xy 454.920775 11.461103) (xy 454.875634 11.534009) (xy 454.837412 11.610769) (xy 454.806436 11.690728)
			(xy 454.782969 11.773204) (xy 454.767213 11.857494) (xy 454.759301 11.942877) (xy 404.76379 11.942877)
			(xy 404.763491 11.916969) (xy 404.755579 11.831586) (xy 404.739823 11.747296) (xy 404.716356 11.66482)
			(xy 404.68538 11.584861) (xy 404.647158 11.508101) (xy 404.602017 11.435195) (xy 404.550341 11.366766)
			(xy 404.492572 11.303396) (xy 404.429202 11.245627) (xy 404.360773 11.193951) (xy 404.287867 11.14881)
			(xy 404.211107 11.110588) (xy 404.131148 11.079612) (xy 404.048672 11.056145) (xy 403.964382 11.040389)
			(xy 403.878999 11.032477) (xy 403.793249 11.032477) (xy 403.707866 11.040389) (xy 403.623576 11.056145)
			(xy 403.5411 11.079612) (xy 403.461141 11.110588) (xy 403.384381 11.14881) (xy 403.311475 11.193951)
			(xy 403.243046 11.245627) (xy 403.179676 11.303396) (xy 403.121907 11.366766) (xy 403.070231 11.435195)
			(xy 403.02509 11.508101) (xy 402.986868 11.584861) (xy 402.955892 11.66482) (xy 402.932425 11.747296)
			(xy 402.916669 11.831586) (xy 402.908757 11.916969) (xy 398.413491 11.916969) (xy 398.405579 11.831586)
			(xy 398.389823 11.747296) (xy 398.366356 11.66482) (xy 398.33538 11.584861) (xy 398.297158 11.508101)
			(xy 398.252017 11.435195) (xy 398.200341 11.366766) (xy 398.142572 11.303396) (xy 398.079202 11.245627)
			(xy 398.010773 11.193951) (xy 397.937867 11.14881) (xy 397.861107 11.110588) (xy 397.781148 11.079612)
			(xy 397.698672 11.056145) (xy 397.614382 11.040389) (xy 397.528999 11.032477) (xy 397.443249 11.032477)
			(xy 397.357866 11.040389) (xy 397.273576 11.056145) (xy 397.1911 11.079612) (xy 397.111141 11.110588)
			(xy 397.034381 11.14881) (xy 396.961475 11.193951) (xy 396.893046 11.245627) (xy 396.829676 11.303396)
			(xy 396.771907 11.366766) (xy 396.720231 11.435195) (xy 396.67509 11.508101) (xy 396.636868 11.584861)
			(xy 396.605892 11.66482) (xy 396.582425 11.747296) (xy 396.566669 11.831586) (xy 396.558757 11.916969)
			(xy 390.701117 11.916969) (xy 390.701035 11.909857) (xy 390.693123 11.824474) (xy 390.677367 11.740184)
			(xy 390.6539 11.657708) (xy 390.622924 11.577749) (xy 390.584702 11.500989) (xy 390.539561 11.428083)
			(xy 390.487885 11.359654) (xy 390.430116 11.296284) (xy 390.366746 11.238515) (xy 390.298317 11.186839)
			(xy 390.225411 11.141698) (xy 390.148651 11.103476) (xy 390.068692 11.0725) (xy 389.986216 11.049033)
			(xy 389.901926 11.033277) (xy 389.816543 11.025365) (xy 389.730793 11.025365) (xy 389.64541 11.033277)
			(xy 389.56112 11.049033) (xy 389.478644 11.0725) (xy 389.398685 11.103476) (xy 389.321925 11.141698)
			(xy 389.249019 11.186839) (xy 389.18059 11.238515) (xy 389.11722 11.296284) (xy 389.059451 11.359654)
			(xy 389.007775 11.428083) (xy 388.962634 11.500989) (xy 388.924412 11.577749) (xy 388.893436 11.657708)
			(xy 388.869969 11.740184) (xy 388.854213 11.824474) (xy 388.846301 11.909857) (xy 384.351035 11.909857)
			(xy 384.343123 11.824474) (xy 384.327367 11.740184) (xy 384.3039 11.657708) (xy 384.272924 11.577749)
			(xy 384.234702 11.500989) (xy 384.189561 11.428083) (xy 384.137885 11.359654) (xy 384.080116 11.296284)
			(xy 384.016746 11.238515) (xy 383.948317 11.186839) (xy 383.875411 11.141698) (xy 383.798651 11.103476)
			(xy 383.718692 11.0725) (xy 383.636216 11.049033) (xy 383.551926 11.033277) (xy 383.466543 11.025365)
			(xy 383.380793 11.025365) (xy 383.29541 11.033277) (xy 383.21112 11.049033) (xy 383.128644 11.0725)
			(xy 383.048685 11.103476) (xy 382.971925 11.141698) (xy 382.899019 11.186839) (xy 382.83059 11.238515)
			(xy 382.76722 11.296284) (xy 382.709451 11.359654) (xy 382.657775 11.428083) (xy 382.612634 11.500989)
			(xy 382.574412 11.577749) (xy 382.543436 11.657708) (xy 382.519969 11.740184) (xy 382.504213 11.824474)
			(xy 382.496301 11.909857) (xy 332.50079 11.909857) (xy 332.500491 11.883949) (xy 332.492579 11.798566)
			(xy 332.476823 11.714276) (xy 332.453356 11.6318) (xy 332.42238 11.551841) (xy 332.384158 11.475081)
			(xy 332.339017 11.402175) (xy 332.287341 11.333746) (xy 332.229572 11.270376) (xy 332.166202 11.212607)
			(xy 332.097773 11.160931) (xy 332.024867 11.11579) (xy 331.948107 11.077568) (xy 331.868148 11.046592)
			(xy 331.785672 11.023125) (xy 331.701382 11.007369) (xy 331.615999 10.999457) (xy 331.530249 10.999457)
			(xy 331.444866 11.007369) (xy 331.360576 11.023125) (xy 331.2781 11.046592) (xy 331.198141 11.077568)
			(xy 331.121381 11.11579) (xy 331.048475 11.160931) (xy 330.980046 11.212607) (xy 330.916676 11.270376)
			(xy 330.858907 11.333746) (xy 330.807231 11.402175) (xy 330.76209 11.475081) (xy 330.723868 11.551841)
			(xy 330.692892 11.6318) (xy 330.669425 11.714276) (xy 330.653669 11.798566) (xy 330.645757 11.883949)
			(xy 326.150491 11.883949) (xy 326.142579 11.798566) (xy 326.126823 11.714276) (xy 326.103356 11.6318)
			(xy 326.07238 11.551841) (xy 326.034158 11.475081) (xy 325.989017 11.402175) (xy 325.937341 11.333746)
			(xy 325.879572 11.270376) (xy 325.816202 11.212607) (xy 325.747773 11.160931) (xy 325.674867 11.11579)
			(xy 325.598107 11.077568) (xy 325.518148 11.046592) (xy 325.435672 11.023125) (xy 325.351382 11.007369)
			(xy 325.265999 10.999457) (xy 325.180249 10.999457) (xy 325.094866 11.007369) (xy 325.010576 11.023125)
			(xy 324.9281 11.046592) (xy 324.848141 11.077568) (xy 324.771381 11.11579) (xy 324.698475 11.160931)
			(xy 324.630046 11.212607) (xy 324.566676 11.270376) (xy 324.508907 11.333746) (xy 324.457231 11.402175)
			(xy 324.41209 11.475081) (xy 324.373868 11.551841) (xy 324.342892 11.6318) (xy 324.319425 11.714276)
			(xy 324.303669 11.798566) (xy 324.295757 11.883949) (xy 317.930117 11.883949) (xy 317.930035 11.876837)
			(xy 317.922123 11.791454) (xy 317.906367 11.707164) (xy 317.8829 11.624688) (xy 317.851924 11.544729)
			(xy 317.813702 11.467969) (xy 317.768561 11.395063) (xy 317.716885 11.326634) (xy 317.659116 11.263264)
			(xy 317.595746 11.205495) (xy 317.527317 11.153819) (xy 317.454411 11.108678) (xy 317.377651 11.070456)
			(xy 317.297692 11.03948) (xy 317.215216 11.016013) (xy 317.130926 11.000257) (xy 317.045543 10.992345)
			(xy 316.959793 10.992345) (xy 316.87441 11.000257) (xy 316.79012 11.016013) (xy 316.707644 11.03948)
			(xy 316.627685 11.070456) (xy 316.550925 11.108678) (xy 316.478019 11.153819) (xy 316.40959 11.205495)
			(xy 316.34622 11.263264) (xy 316.288451 11.326634) (xy 316.236775 11.395063) (xy 316.191634 11.467969)
			(xy 316.153412 11.544729) (xy 316.122436 11.624688) (xy 316.098969 11.707164) (xy 316.083213 11.791454)
			(xy 316.075301 11.876837) (xy 311.580035 11.876837) (xy 311.572123 11.791454) (xy 311.556367 11.707164)
			(xy 311.5329 11.624688) (xy 311.501924 11.544729) (xy 311.463702 11.467969) (xy 311.418561 11.395063)
			(xy 311.366885 11.326634) (xy 311.309116 11.263264) (xy 311.245746 11.205495) (xy 311.177317 11.153819)
			(xy 311.104411 11.108678) (xy 311.027651 11.070456) (xy 310.947692 11.03948) (xy 310.865216 11.016013)
			(xy 310.780926 11.000257) (xy 310.695543 10.992345) (xy 310.609793 10.992345) (xy 310.52441 11.000257)
			(xy 310.44012 11.016013) (xy 310.357644 11.03948) (xy 310.277685 11.070456) (xy 310.200925 11.108678)
			(xy 310.128019 11.153819) (xy 310.05959 11.205495) (xy 309.99622 11.263264) (xy 309.938451 11.326634)
			(xy 309.886775 11.395063) (xy 309.841634 11.467969) (xy 309.803412 11.544729) (xy 309.772436 11.624688)
			(xy 309.748969 11.707164) (xy 309.733213 11.791454) (xy 309.725301 11.876837) (xy 259.72979 11.876837)
			(xy 259.729491 11.850929) (xy 259.721579 11.765546) (xy 259.705823 11.681256) (xy 259.682356 11.59878)
			(xy 259.65138 11.518821) (xy 259.613158 11.442061) (xy 259.568017 11.369155) (xy 259.516341 11.300726)
			(xy 259.458572 11.237356) (xy 259.395202 11.179587) (xy 259.326773 11.127911) (xy 259.253867 11.08277)
			(xy 259.177107 11.044548) (xy 259.097148 11.013572) (xy 259.014672 10.990105) (xy 258.930382 10.974349)
			(xy 258.844999 10.966437) (xy 258.759249 10.966437) (xy 258.673866 10.974349) (xy 258.589576 10.990105)
			(xy 258.5071 11.013572) (xy 258.427141 11.044548) (xy 258.350381 11.08277) (xy 258.277475 11.127911)
			(xy 258.209046 11.179587) (xy 258.145676 11.237356) (xy 258.087907 11.300726) (xy 258.036231 11.369155)
			(xy 257.99109 11.442061) (xy 257.952868 11.518821) (xy 257.921892 11.59878) (xy 257.898425 11.681256)
			(xy 257.882669 11.765546) (xy 257.874757 11.850929) (xy 253.379491 11.850929) (xy 253.371579 11.765546)
			(xy 253.355823 11.681256) (xy 253.332356 11.59878) (xy 253.30138 11.518821) (xy 253.263158 11.442061)
			(xy 253.218017 11.369155) (xy 253.166341 11.300726) (xy 253.108572 11.237356) (xy 253.045202 11.179587)
			(xy 252.976773 11.127911) (xy 252.903867 11.08277) (xy 252.827107 11.044548) (xy 252.747148 11.013572)
			(xy 252.664672 10.990105) (xy 252.580382 10.974349) (xy 252.494999 10.966437) (xy 252.409249 10.966437)
			(xy 252.323866 10.974349) (xy 252.239576 10.990105) (xy 252.1571 11.013572) (xy 252.077141 11.044548)
			(xy 252.000381 11.08277) (xy 251.927475 11.127911) (xy 251.859046 11.179587) (xy 251.795676 11.237356)
			(xy 251.737907 11.300726) (xy 251.686231 11.369155) (xy 251.64109 11.442061) (xy 251.602868 11.518821)
			(xy 251.571892 11.59878) (xy 251.548425 11.681256) (xy 251.532669 11.765546) (xy 251.524757 11.850929)
			(xy 158.621984 11.850929) (xy 158.621984 9.310929) (xy 179.515757 9.310929) (xy 179.515757 9.396679)
			(xy 179.523669 9.482062) (xy 179.539425 9.566352) (xy 179.562892 9.648828) (xy 179.593868 9.728787)
			(xy 179.63209 9.805547) (xy 179.677231 9.878453) (xy 179.728907 9.946882) (xy 179.786676 10.010252)
			(xy 179.850046 10.068021) (xy 179.918475 10.119697) (xy 179.991381 10.164838) (xy 180.068141 10.20306)
			(xy 180.1481 10.234036) (xy 180.230576 10.257503) (xy 180.314866 10.273259) (xy 180.400249 10.281171)
			(xy 180.485999 10.281171) (xy 180.571382 10.273259) (xy 180.655672 10.257503) (xy 180.738148 10.234036)
			(xy 180.818107 10.20306) (xy 180.894867 10.164838) (xy 180.967773 10.119697) (xy 181.036202 10.068021)
			(xy 181.099572 10.010252) (xy 181.157341 9.946882) (xy 181.209017 9.878453) (xy 181.254158 9.805547)
			(xy 181.29238 9.728787) (xy 181.323356 9.648828) (xy 181.346823 9.566352) (xy 181.362579 9.482062)
			(xy 181.370491 9.396679) (xy 181.370986 9.353804) (xy 181.370491 9.310929) (xy 185.865757 9.310929)
			(xy 185.865757 9.396679) (xy 185.873669 9.482062) (xy 185.889425 9.566352) (xy 185.912892 9.648828)
			(xy 185.943868 9.728787) (xy 185.98209 9.805547) (xy 186.027231 9.878453) (xy 186.078907 9.946882)
			(xy 186.136676 10.010252) (xy 186.200046 10.068021) (xy 186.268475 10.119697) (xy 186.341381 10.164838)
			(xy 186.418141 10.20306) (xy 186.4981 10.234036) (xy 186.580576 10.257503) (xy 186.664866 10.273259)
			(xy 186.750249 10.281171) (xy 186.835999 10.281171) (xy 186.921382 10.273259) (xy 187.005672 10.257503)
			(xy 187.088148 10.234036) (xy 187.168107 10.20306) (xy 187.244867 10.164838) (xy 187.317773 10.119697)
			(xy 187.386202 10.068021) (xy 187.449572 10.010252) (xy 187.507341 9.946882) (xy 187.559017 9.878453)
			(xy 187.604158 9.805547) (xy 187.64238 9.728787) (xy 187.673356 9.648828) (xy 187.696823 9.566352)
			(xy 187.712579 9.482062) (xy 187.720491 9.396679) (xy 187.720986 9.353804) (xy 187.720491 9.310929)
			(xy 187.719832 9.303817) (xy 237.716301 9.303817) (xy 237.716301 9.389567) (xy 237.724213 9.47495)
			(xy 237.739969 9.55924) (xy 237.763436 9.641716) (xy 237.794412 9.721675) (xy 237.832634 9.798435)
			(xy 237.877775 9.871341) (xy 237.929451 9.93977) (xy 237.98722 10.00314) (xy 238.05059 10.060909)
			(xy 238.119019 10.112585) (xy 238.191925 10.157726) (xy 238.268685 10.195948) (xy 238.348644 10.226924)
			(xy 238.43112 10.250391) (xy 238.51541 10.266147) (xy 238.600793 10.274059) (xy 238.686543 10.274059)
			(xy 238.771926 10.266147) (xy 238.856216 10.250391) (xy 238.938692 10.226924) (xy 239.018651 10.195948)
			(xy 239.095411 10.157726) (xy 239.168317 10.112585) (xy 239.236746 10.060909) (xy 239.300116 10.00314)
			(xy 239.357885 9.93977) (xy 239.409561 9.871341) (xy 239.454702 9.798435) (xy 239.492924 9.721675)
			(xy 239.5239 9.641716) (xy 239.547367 9.55924) (xy 239.563123 9.47495) (xy 239.571035 9.389567) (xy 239.57153 9.346692)
			(xy 239.571035 9.303817) (xy 244.066301 9.303817) (xy 244.066301 9.389567) (xy 244.074213 9.47495)
			(xy 244.089969 9.55924) (xy 244.113436 9.641716) (xy 244.144412 9.721675) (xy 244.182634 9.798435)
			(xy 244.227775 9.871341) (xy 244.279451 9.93977) (xy 244.33722 10.00314) (xy 244.40059 10.060909)
			(xy 244.469019 10.112585) (xy 244.541925 10.157726) (xy 244.618685 10.195948) (xy 244.698644 10.226924)
			(xy 244.78112 10.250391) (xy 244.86541 10.266147) (xy 244.950793 10.274059) (xy 245.036543 10.274059)
			(xy 245.121926 10.266147) (xy 245.206216 10.250391) (xy 245.288692 10.226924) (xy 245.368651 10.195948)
			(xy 245.445411 10.157726) (xy 245.518317 10.112585) (xy 245.586746 10.060909) (xy 245.650116 10.00314)
			(xy 245.707885 9.93977) (xy 245.759561 9.871341) (xy 245.804702 9.798435) (xy 245.842924 9.721675)
			(xy 245.8739 9.641716) (xy 245.897367 9.55924) (xy 245.913123 9.47495) (xy 245.921035 9.389567) (xy 245.92153 9.346692)
			(xy 245.921117 9.310929) (xy 251.524757 9.310929) (xy 251.524757 9.396679) (xy 251.532669 9.482062)
			(xy 251.548425 9.566352) (xy 251.571892 9.648828) (xy 251.602868 9.728787) (xy 251.64109 9.805547)
			(xy 251.686231 9.878453) (xy 251.737907 9.946882) (xy 251.795676 10.010252) (xy 251.859046 10.068021)
			(xy 251.927475 10.119697) (xy 252.000381 10.164838) (xy 252.077141 10.20306) (xy 252.1571 10.234036)
			(xy 252.239576 10.257503) (xy 252.323866 10.273259) (xy 252.409249 10.281171) (xy 252.494999 10.281171)
			(xy 252.580382 10.273259) (xy 252.664672 10.257503) (xy 252.747148 10.234036) (xy 252.827107 10.20306)
			(xy 252.84931 10.192004) (xy 256.459736 10.192004) (xy 256.459736 11.055604) (xy 256.460222 11.082873)
			(xy 256.467984 11.136857) (xy 256.483349 11.189187) (xy 256.506006 11.238797) (xy 256.535492 11.284678)
			(xy 256.571207 11.325895) (xy 256.612424 11.36161) (xy 256.658305 11.391096) (xy 256.707915 11.413753)
			(xy 256.760245 11.429118) (xy 256.814229 11.43688) (xy 256.868767 11.43688) (xy 256.922751 11.429118)
			(xy 256.975081 11.413753) (xy 257.024691 11.391096) (xy 257.070572 11.36161) (xy 257.111789 11.325895)
			(xy 257.147504 11.284678) (xy 257.17699 11.238797) (xy 257.199647 11.189187) (xy 257.215012 11.136857)
			(xy 257.222774 11.082873) (xy 257.22326 11.055604) (xy 257.22326 10.192004) (xy 257.222774 10.164735)
			(xy 257.215012 10.110751) (xy 257.199647 10.058421) (xy 257.17699 10.008811) (xy 257.147504 9.96293)
			(xy 257.111789 9.921713) (xy 257.070572 9.885998) (xy 257.024691 9.856512) (xy 256.975081 9.833855)
			(xy 256.922751 9.81849) (xy 256.868767 9.810728) (xy 256.814229 9.810728) (xy 256.760245 9.81849)
			(xy 256.707915 9.833855) (xy 256.658305 9.856512) (xy 256.612424 9.885998) (xy 256.571207 9.921713)
			(xy 256.535492 9.96293) (xy 256.506006 10.008811) (xy 256.483349 10.058421) (xy 256.467984 10.110751)
			(xy 256.460222 10.164735) (xy 256.459736 10.192004) (xy 252.84931 10.192004) (xy 252.903867 10.164838)
			(xy 252.976773 10.119697) (xy 253.045202 10.068021) (xy 253.108572 10.010252) (xy 253.166341 9.946882)
			(xy 253.218017 9.878453) (xy 253.263158 9.805547) (xy 253.30138 9.728787) (xy 253.332356 9.648828)
			(xy 253.355823 9.566352) (xy 253.371579 9.482062) (xy 253.379491 9.396679) (xy 253.379986 9.353804)
			(xy 253.379491 9.310929) (xy 257.874757 9.310929) (xy 257.874757 9.396679) (xy 257.882669 9.482062)
			(xy 257.898425 9.566352) (xy 257.921892 9.648828) (xy 257.952868 9.728787) (xy 257.99109 9.805547)
			(xy 258.036231 9.878453) (xy 258.087907 9.946882) (xy 258.145676 10.010252) (xy 258.209046 10.068021)
			(xy 258.277475 10.119697) (xy 258.350381 10.164838) (xy 258.427141 10.20306) (xy 258.5071 10.234036)
			(xy 258.589576 10.257503) (xy 258.673866 10.273259) (xy 258.759249 10.281171) (xy 258.844999 10.281171)
			(xy 258.930382 10.273259) (xy 259.014672 10.257503) (xy 259.097148 10.234036) (xy 259.177107 10.20306)
			(xy 259.253867 10.164838) (xy 259.326773 10.119697) (xy 259.395202 10.068021) (xy 259.458572 10.010252)
			(xy 259.516341 9.946882) (xy 259.568017 9.878453) (xy 259.613158 9.805547) (xy 259.65138 9.728787)
			(xy 259.682356 9.648828) (xy 259.705823 9.566352) (xy 259.721579 9.482062) (xy 259.729491 9.396679)
			(xy 259.729986 9.353804) (xy 259.72979 9.336837) (xy 309.725301 9.336837) (xy 309.725301 9.422587)
			(xy 309.733213 9.50797) (xy 309.748969 9.59226) (xy 309.772436 9.674736) (xy 309.803412 9.754695)
			(xy 309.841634 9.831455) (xy 309.886775 9.904361) (xy 309.938451 9.97279) (xy 309.99622 10.03616)
			(xy 310.05959 10.093929) (xy 310.128019 10.145605) (xy 310.200925 10.190746) (xy 310.277685 10.228968)
			(xy 310.357644 10.259944) (xy 310.44012 10.283411) (xy 310.52441 10.299167) (xy 310.609793 10.307079)
			(xy 310.695543 10.307079) (xy 310.780926 10.299167) (xy 310.865216 10.283411) (xy 310.947692 10.259944)
			(xy 311.027651 10.228968) (xy 311.049854 10.217912) (xy 312.231532 10.217912) (xy 312.231532 11.081512)
			(xy 312.232018 11.108781) (xy 312.23978 11.162765) (xy 312.255145 11.215095) (xy 312.277802 11.264705)
			(xy 312.307288 11.310586) (xy 312.343003 11.351803) (xy 312.38422 11.387518) (xy 312.430101 11.417004)
			(xy 312.479711 11.439661) (xy 312.532041 11.455026) (xy 312.586025 11.462788) (xy 312.640563 11.462788)
			(xy 312.694547 11.455026) (xy 312.746877 11.439661) (xy 312.796487 11.417004) (xy 312.842368 11.387518)
			(xy 312.883585 11.351803) (xy 312.9193 11.310586) (xy 312.948786 11.264705) (xy 312.971443 11.215095)
			(xy 312.986808 11.162765) (xy 312.99457 11.108781) (xy 312.995056 11.081512) (xy 312.995056 10.217912)
			(xy 312.99457 10.190643) (xy 312.986808 10.136659) (xy 312.971443 10.084329) (xy 312.948786 10.034719)
			(xy 312.9193 9.988838) (xy 312.883585 9.947621) (xy 312.842368 9.911906) (xy 312.796487 9.88242)
			(xy 312.746877 9.859763) (xy 312.694547 9.844398) (xy 312.640563 9.836636) (xy 312.586025 9.836636)
			(xy 312.532041 9.844398) (xy 312.479711 9.859763) (xy 312.430101 9.88242) (xy 312.38422 9.911906)
			(xy 312.343003 9.947621) (xy 312.307288 9.988838) (xy 312.277802 10.034719) (xy 312.255145 10.084329)
			(xy 312.23978 10.136659) (xy 312.232018 10.190643) (xy 312.231532 10.217912) (xy 311.049854 10.217912)
			(xy 311.104411 10.190746) (xy 311.177317 10.145605) (xy 311.245746 10.093929) (xy 311.309116 10.03616)
			(xy 311.366885 9.97279) (xy 311.418561 9.904361) (xy 311.463702 9.831455) (xy 311.501924 9.754695)
			(xy 311.5329 9.674736) (xy 311.556367 9.59226) (xy 311.572123 9.50797) (xy 311.580035 9.422587) (xy 311.58053 9.379712)
			(xy 311.580035 9.336837) (xy 316.075301 9.336837) (xy 316.075301 9.422587) (xy 316.083213 9.50797)
			(xy 316.098969 9.59226) (xy 316.122436 9.674736) (xy 316.153412 9.754695) (xy 316.191634 9.831455)
			(xy 316.236775 9.904361) (xy 316.288451 9.97279) (xy 316.34622 10.03616) (xy 316.40959 10.093929)
			(xy 316.478019 10.145605) (xy 316.550925 10.190746) (xy 316.627685 10.228968) (xy 316.707644 10.259944)
			(xy 316.79012 10.283411) (xy 316.87441 10.299167) (xy 316.959793 10.307079) (xy 317.045543 10.307079)
			(xy 317.130926 10.299167) (xy 317.215216 10.283411) (xy 317.297692 10.259944) (xy 317.377651 10.228968)
			(xy 317.454411 10.190746) (xy 317.527317 10.145605) (xy 317.595746 10.093929) (xy 317.659116 10.03616)
			(xy 317.716885 9.97279) (xy 317.768561 9.904361) (xy 317.813702 9.831455) (xy 317.851924 9.754695)
			(xy 317.8829 9.674736) (xy 317.906367 9.59226) (xy 317.922123 9.50797) (xy 317.930035 9.422587) (xy 317.93053 9.379712)
			(xy 317.930117 9.343949) (xy 324.295757 9.343949) (xy 324.295757 9.429699) (xy 324.303669 9.515082)
			(xy 324.319425 9.599372) (xy 324.342892 9.681848) (xy 324.373868 9.761807) (xy 324.41209 9.838567)
			(xy 324.457231 9.911473) (xy 324.508907 9.979902) (xy 324.566676 10.043272) (xy 324.630046 10.101041)
			(xy 324.698475 10.152717) (xy 324.771381 10.197858) (xy 324.848141 10.23608) (xy 324.9281 10.267056)
			(xy 325.010576 10.290523) (xy 325.094866 10.306279) (xy 325.180249 10.314191) (xy 325.265999 10.314191)
			(xy 325.351382 10.306279) (xy 325.435672 10.290523) (xy 325.518148 10.267056) (xy 325.598107 10.23608)
			(xy 325.62031 10.225024) (xy 329.230736 10.225024) (xy 329.230736 11.088624) (xy 329.231222 11.115893)
			(xy 329.238984 11.169877) (xy 329.254349 11.222207) (xy 329.277006 11.271817) (xy 329.306492 11.317698)
			(xy 329.342207 11.358915) (xy 329.383424 11.39463) (xy 329.429305 11.424116) (xy 329.478915 11.446773)
			(xy 329.531245 11.462138) (xy 329.585229 11.4699) (xy 329.639767 11.4699) (xy 329.693751 11.462138)
			(xy 329.746081 11.446773) (xy 329.795691 11.424116) (xy 329.841572 11.39463) (xy 329.882789 11.358915)
			(xy 329.918504 11.317698) (xy 329.94799 11.271817) (xy 329.970647 11.222207) (xy 329.986012 11.169877)
			(xy 329.993774 11.115893) (xy 329.99426 11.088624) (xy 329.99426 10.225024) (xy 329.993774 10.197755)
			(xy 329.986012 10.143771) (xy 329.970647 10.091441) (xy 329.94799 10.041831) (xy 329.918504 9.99595)
			(xy 329.882789 9.954733) (xy 329.841572 9.919018) (xy 329.795691 9.889532) (xy 329.746081 9.866875)
			(xy 329.693751 9.85151) (xy 329.639767 9.843748) (xy 329.585229 9.843748) (xy 329.531245 9.85151)
			(xy 329.478915 9.866875) (xy 329.429305 9.889532) (xy 329.383424 9.919018) (xy 329.342207 9.954733)
			(xy 329.306492 9.99595) (xy 329.277006 10.041831) (xy 329.254349 10.091441) (xy 329.238984 10.143771)
			(xy 329.231222 10.197755) (xy 329.230736 10.225024) (xy 325.62031 10.225024) (xy 325.674867 10.197858)
			(xy 325.747773 10.152717) (xy 325.816202 10.101041) (xy 325.879572 10.043272) (xy 325.937341 9.979902)
			(xy 325.989017 9.911473) (xy 326.034158 9.838567) (xy 326.07238 9.761807) (xy 326.103356 9.681848)
			(xy 326.126823 9.599372) (xy 326.142579 9.515082) (xy 326.150491 9.429699) (xy 326.150986 9.386824)
			(xy 326.150491 9.343949) (xy 330.645757 9.343949) (xy 330.645757 9.429699) (xy 330.653669 9.515082)
			(xy 330.669425 9.599372) (xy 330.692892 9.681848) (xy 330.723868 9.761807) (xy 330.76209 9.838567)
			(xy 330.807231 9.911473) (xy 330.858907 9.979902) (xy 330.916676 10.043272) (xy 330.980046 10.101041)
			(xy 331.048475 10.152717) (xy 331.121381 10.197858) (xy 331.198141 10.23608) (xy 331.2781 10.267056)
			(xy 331.360576 10.290523) (xy 331.444866 10.306279) (xy 331.530249 10.314191) (xy 331.615999 10.314191)
			(xy 331.701382 10.306279) (xy 331.785672 10.290523) (xy 331.868148 10.267056) (xy 331.948107 10.23608)
			(xy 332.024867 10.197858) (xy 332.097773 10.152717) (xy 332.166202 10.101041) (xy 332.229572 10.043272)
			(xy 332.287341 9.979902) (xy 332.339017 9.911473) (xy 332.384158 9.838567) (xy 332.42238 9.761807)
			(xy 332.453356 9.681848) (xy 332.476823 9.599372) (xy 332.492579 9.515082) (xy 332.500491 9.429699)
			(xy 332.500986 9.386824) (xy 332.50079 9.369857) (xy 382.496301 9.369857) (xy 382.496301 9.455607)
			(xy 382.504213 9.54099) (xy 382.519969 9.62528) (xy 382.543436 9.707756) (xy 382.574412 9.787715)
			(xy 382.612634 9.864475) (xy 382.657775 9.937381) (xy 382.709451 10.00581) (xy 382.76722 10.06918)
			(xy 382.83059 10.126949) (xy 382.899019 10.178625) (xy 382.971925 10.223766) (xy 383.048685 10.261988)
			(xy 383.128644 10.292964) (xy 383.21112 10.316431) (xy 383.29541 10.332187) (xy 383.380793 10.340099)
			(xy 383.466543 10.340099) (xy 383.551926 10.332187) (xy 383.636216 10.316431) (xy 383.718692 10.292964)
			(xy 383.798651 10.261988) (xy 383.820854 10.250932) (xy 385.002532 10.250932) (xy 385.002532 11.114532)
			(xy 385.003018 11.141801) (xy 385.01078 11.195785) (xy 385.026145 11.248115) (xy 385.048802 11.297725)
			(xy 385.078288 11.343606) (xy 385.114003 11.384823) (xy 385.15522 11.420538) (xy 385.201101 11.450024)
			(xy 385.250711 11.472681) (xy 385.303041 11.488046) (xy 385.357025 11.495808) (xy 385.411563 11.495808)
			(xy 385.465547 11.488046) (xy 385.517877 11.472681) (xy 385.567487 11.450024) (xy 385.613368 11.420538)
			(xy 385.654585 11.384823) (xy 385.6903 11.343606) (xy 385.719786 11.297725) (xy 385.742443 11.248115)
			(xy 385.757808 11.195785) (xy 385.76557 11.141801) (xy 385.766056 11.114532) (xy 385.766056 10.250932)
			(xy 385.76557 10.223663) (xy 385.757808 10.169679) (xy 385.742443 10.117349) (xy 385.719786 10.067739)
			(xy 385.6903 10.021858) (xy 385.654585 9.980641) (xy 385.613368 9.944926) (xy 385.567487 9.91544)
			(xy 385.517877 9.892783) (xy 385.465547 9.877418) (xy 385.411563 9.869656) (xy 385.357025 9.869656)
			(xy 385.303041 9.877418) (xy 385.250711 9.892783) (xy 385.201101 9.91544) (xy 385.15522 9.944926)
			(xy 385.114003 9.980641) (xy 385.078288 10.021858) (xy 385.048802 10.067739) (xy 385.026145 10.117349)
			(xy 385.01078 10.169679) (xy 385.003018 10.223663) (xy 385.002532 10.250932) (xy 383.820854 10.250932)
			(xy 383.875411 10.223766) (xy 383.948317 10.178625) (xy 384.016746 10.126949) (xy 384.080116 10.06918)
			(xy 384.137885 10.00581) (xy 384.189561 9.937381) (xy 384.234702 9.864475) (xy 384.272924 9.787715)
			(xy 384.3039 9.707756) (xy 384.327367 9.62528) (xy 384.343123 9.54099) (xy 384.351035 9.455607) (xy 384.35153 9.412732)
			(xy 384.351035 9.369857) (xy 388.846301 9.369857) (xy 388.846301 9.455607) (xy 388.854213 9.54099)
			(xy 388.869969 9.62528) (xy 388.893436 9.707756) (xy 388.924412 9.787715) (xy 388.962634 9.864475)
			(xy 389.007775 9.937381) (xy 389.059451 10.00581) (xy 389.11722 10.06918) (xy 389.18059 10.126949)
			(xy 389.249019 10.178625) (xy 389.321925 10.223766) (xy 389.398685 10.261988) (xy 389.478644 10.292964)
			(xy 389.56112 10.316431) (xy 389.64541 10.332187) (xy 389.730793 10.340099) (xy 389.816543 10.340099)
			(xy 389.901926 10.332187) (xy 389.986216 10.316431) (xy 390.068692 10.292964) (xy 390.148651 10.261988)
			(xy 390.225411 10.223766) (xy 390.298317 10.178625) (xy 390.366746 10.126949) (xy 390.430116 10.06918)
			(xy 390.487885 10.00581) (xy 390.539561 9.937381) (xy 390.584702 9.864475) (xy 390.622924 9.787715)
			(xy 390.6539 9.707756) (xy 390.677367 9.62528) (xy 390.693123 9.54099) (xy 390.701035 9.455607) (xy 390.70153 9.412732)
			(xy 390.701117 9.376969) (xy 396.558757 9.376969) (xy 396.558757 9.462719) (xy 396.566669 9.548102)
			(xy 396.582425 9.632392) (xy 396.605892 9.714868) (xy 396.636868 9.794827) (xy 396.67509 9.871587)
			(xy 396.720231 9.944493) (xy 396.771907 10.012922) (xy 396.829676 10.076292) (xy 396.893046 10.134061)
			(xy 396.961475 10.185737) (xy 397.034381 10.230878) (xy 397.111141 10.2691) (xy 397.1911 10.300076)
			(xy 397.273576 10.323543) (xy 397.357866 10.339299) (xy 397.443249 10.347211) (xy 397.528999 10.347211)
			(xy 397.614382 10.339299) (xy 397.698672 10.323543) (xy 397.781148 10.300076) (xy 397.861107 10.2691)
			(xy 397.88331 10.258044) (xy 401.493736 10.258044) (xy 401.493736 11.121644) (xy 401.494222 11.148913)
			(xy 401.501984 11.202897) (xy 401.517349 11.255227) (xy 401.540006 11.304837) (xy 401.569492 11.350718)
			(xy 401.605207 11.391935) (xy 401.646424 11.42765) (xy 401.692305 11.457136) (xy 401.741915 11.479793)
			(xy 401.794245 11.495158) (xy 401.848229 11.50292) (xy 401.902767 11.50292) (xy 401.956751 11.495158)
			(xy 402.009081 11.479793) (xy 402.058691 11.457136) (xy 402.104572 11.42765) (xy 402.145789 11.391935)
			(xy 402.181504 11.350718) (xy 402.21099 11.304837) (xy 402.233647 11.255227) (xy 402.249012 11.202897)
			(xy 402.256774 11.148913) (xy 402.25726 11.121644) (xy 402.25726 10.258044) (xy 402.256774 10.230775)
			(xy 402.249012 10.176791) (xy 402.233647 10.124461) (xy 402.21099 10.074851) (xy 402.181504 10.02897)
			(xy 402.145789 9.987753) (xy 402.104572 9.952038) (xy 402.058691 9.922552) (xy 402.009081 9.899895)
			(xy 401.956751 9.88453) (xy 401.902767 9.876768) (xy 401.848229 9.876768) (xy 401.794245 9.88453)
			(xy 401.741915 9.899895) (xy 401.692305 9.922552) (xy 401.646424 9.952038) (xy 401.605207 9.987753)
			(xy 401.569492 10.02897) (xy 401.540006 10.074851) (xy 401.517349 10.124461) (xy 401.501984 10.176791)
			(xy 401.494222 10.230775) (xy 401.493736 10.258044) (xy 397.88331 10.258044) (xy 397.937867 10.230878)
			(xy 398.010773 10.185737) (xy 398.079202 10.134061) (xy 398.142572 10.076292) (xy 398.200341 10.012922)
			(xy 398.252017 9.944493) (xy 398.297158 9.871587) (xy 398.33538 9.794827) (xy 398.366356 9.714868)
			(xy 398.389823 9.632392) (xy 398.405579 9.548102) (xy 398.413491 9.462719) (xy 398.413986 9.419844)
			(xy 398.413491 9.376969) (xy 402.908757 9.376969) (xy 402.908757 9.462719) (xy 402.916669 9.548102)
			(xy 402.932425 9.632392) (xy 402.955892 9.714868) (xy 402.986868 9.794827) (xy 403.02509 9.871587)
			(xy 403.070231 9.944493) (xy 403.121907 10.012922) (xy 403.179676 10.076292) (xy 403.243046 10.134061)
			(xy 403.311475 10.185737) (xy 403.384381 10.230878) (xy 403.461141 10.2691) (xy 403.5411 10.300076)
			(xy 403.623576 10.323543) (xy 403.707866 10.339299) (xy 403.793249 10.347211) (xy 403.878999 10.347211)
			(xy 403.964382 10.339299) (xy 404.048672 10.323543) (xy 404.131148 10.300076) (xy 404.211107 10.2691)
			(xy 404.287867 10.230878) (xy 404.360773 10.185737) (xy 404.429202 10.134061) (xy 404.492572 10.076292)
			(xy 404.550341 10.012922) (xy 404.602017 9.944493) (xy 404.647158 9.871587) (xy 404.68538 9.794827)
			(xy 404.716356 9.714868) (xy 404.739823 9.632392) (xy 404.755579 9.548102) (xy 404.763491 9.462719)
			(xy 404.763986 9.419844) (xy 404.76379 9.402877) (xy 454.759301 9.402877) (xy 454.759301 9.488627)
			(xy 454.767213 9.57401) (xy 454.782969 9.6583) (xy 454.806436 9.740776) (xy 454.837412 9.820735)
			(xy 454.875634 9.897495) (xy 454.920775 9.970401) (xy 454.972451 10.03883) (xy 455.03022 10.1022)
			(xy 455.09359 10.159969) (xy 455.162019 10.211645) (xy 455.234925 10.256786) (xy 455.311685 10.295008)
			(xy 455.391644 10.325984) (xy 455.47412 10.349451) (xy 455.55841 10.365207) (xy 455.643793 10.373119)
			(xy 455.729543 10.373119) (xy 455.814926 10.365207) (xy 455.899216 10.349451) (xy 455.981692 10.325984)
			(xy 456.061651 10.295008) (xy 456.083854 10.283952) (xy 457.265532 10.283952) (xy 457.265532 11.147552)
			(xy 457.266018 11.174821) (xy 457.27378 11.228805) (xy 457.289145 11.281135) (xy 457.311802 11.330745)
			(xy 457.341288 11.376626) (xy 457.377003 11.417843) (xy 457.41822 11.453558) (xy 457.464101 11.483044)
			(xy 457.513711 11.505701) (xy 457.566041 11.521066) (xy 457.620025 11.528828) (xy 457.674563 11.528828)
			(xy 457.728547 11.521066) (xy 457.780877 11.505701) (xy 457.830487 11.483044) (xy 457.876368 11.453558)
			(xy 457.917585 11.417843) (xy 457.9533 11.376626) (xy 457.982786 11.330745) (xy 458.005443 11.281135)
			(xy 458.020808 11.228805) (xy 458.02857 11.174821) (xy 458.029056 11.147552) (xy 458.029056 10.283952)
			(xy 458.02857 10.256683) (xy 458.020808 10.202699) (xy 458.005443 10.150369) (xy 457.982786 10.100759)
			(xy 457.9533 10.054878) (xy 457.917585 10.013661) (xy 457.876368 9.977946) (xy 457.830487 9.94846)
			(xy 457.780877 9.925803) (xy 457.728547 9.910438) (xy 457.674563 9.902676) (xy 457.620025 9.902676)
			(xy 457.566041 9.910438) (xy 457.513711 9.925803) (xy 457.464101 9.94846) (xy 457.41822 9.977946)
			(xy 457.377003 10.013661) (xy 457.341288 10.054878) (xy 457.311802 10.100759) (xy 457.289145 10.150369)
			(xy 457.27378 10.202699) (xy 457.266018 10.256683) (xy 457.265532 10.283952) (xy 456.083854 10.283952)
			(xy 456.138411 10.256786) (xy 456.211317 10.211645) (xy 456.279746 10.159969) (xy 456.343116 10.1022)
			(xy 456.400885 10.03883) (xy 456.452561 9.970401) (xy 456.497702 9.897495) (xy 456.535924 9.820735)
			(xy 456.5669 9.740776) (xy 456.590367 9.6583) (xy 456.606123 9.57401) (xy 456.614035 9.488627) (xy 456.61453 9.445752)
			(xy 456.614035 9.402877) (xy 461.109301 9.402877) (xy 461.109301 9.488627) (xy 461.117213 9.57401)
			(xy 461.132969 9.6583) (xy 461.156436 9.740776) (xy 461.187412 9.820735) (xy 461.225634 9.897495)
			(xy 461.270775 9.970401) (xy 461.322451 10.03883) (xy 461.38022 10.1022) (xy 461.44359 10.159969)
			(xy 461.512019 10.211645) (xy 461.584925 10.256786) (xy 461.661685 10.295008) (xy 461.741644 10.325984)
			(xy 461.82412 10.349451) (xy 461.90841 10.365207) (xy 461.993793 10.373119) (xy 462.079543 10.373119)
			(xy 462.164926 10.365207) (xy 462.249216 10.349451) (xy 462.331692 10.325984) (xy 462.411651 10.295008)
			(xy 462.488411 10.256786) (xy 462.561317 10.211645) (xy 462.629746 10.159969) (xy 462.693116 10.1022)
			(xy 462.750885 10.03883) (xy 462.802561 9.970401) (xy 462.847702 9.897495) (xy 462.885924 9.820735)
			(xy 462.9169 9.740776) (xy 462.940367 9.6583) (xy 462.956123 9.57401) (xy 462.964035 9.488627) (xy 462.96453 9.445752)
			(xy 462.964035 9.402877) (xy 462.956123 9.317494) (xy 462.940367 9.233204) (xy 462.9169 9.150728)
			(xy 462.885924 9.070769) (xy 462.847702 8.994009) (xy 462.802561 8.921103) (xy 462.750885 8.852674)
			(xy 462.693116 8.789304) (xy 462.629746 8.731535) (xy 462.561317 8.679859) (xy 462.488411 8.634718)
			(xy 462.411651 8.596496) (xy 462.331692 8.56552) (xy 462.249216 8.542053) (xy 462.164926 8.526297)
			(xy 462.079543 8.518385) (xy 461.993793 8.518385) (xy 461.90841 8.526297) (xy 461.82412 8.542053)
			(xy 461.741644 8.56552) (xy 461.661685 8.596496) (xy 461.584925 8.634718) (xy 461.512019 8.679859)
			(xy 461.44359 8.731535) (xy 461.38022 8.789304) (xy 461.322451 8.852674) (xy 461.270775 8.921103)
			(xy 461.225634 8.994009) (xy 461.187412 9.070769) (xy 461.156436 9.150728) (xy 461.132969 9.233204)
			(xy 461.117213 9.317494) (xy 461.109301 9.402877) (xy 456.614035 9.402877) (xy 456.606123 9.317494)
			(xy 456.590367 9.233204) (xy 456.5669 9.150728) (xy 456.535924 9.070769) (xy 456.497702 8.994009)
			(xy 456.452561 8.921103) (xy 456.400885 8.852674) (xy 456.343116 8.789304) (xy 456.279746 8.731535)
			(xy 456.211317 8.679859) (xy 456.138411 8.634718) (xy 456.061651 8.596496) (xy 455.981692 8.56552)
			(xy 455.899216 8.542053) (xy 455.814926 8.526297) (xy 455.729543 8.518385) (xy 455.643793 8.518385)
			(xy 455.55841 8.526297) (xy 455.47412 8.542053) (xy 455.391644 8.56552) (xy 455.311685 8.596496)
			(xy 455.234925 8.634718) (xy 455.162019 8.679859) (xy 455.09359 8.731535) (xy 455.03022 8.789304)
			(xy 454.972451 8.852674) (xy 454.920775 8.921103) (xy 454.875634 8.994009) (xy 454.837412 9.070769)
			(xy 454.806436 9.150728) (xy 454.782969 9.233204) (xy 454.767213 9.317494) (xy 454.759301 9.402877)
			(xy 404.76379 9.402877) (xy 404.763491 9.376969) (xy 404.755579 9.291586) (xy 404.739823 9.207296)
			(xy 404.716356 9.12482) (xy 404.68538 9.044861) (xy 404.647158 8.968101) (xy 404.602017 8.895195)
			(xy 404.550341 8.826766) (xy 404.492572 8.763396) (xy 404.429202 8.705627) (xy 404.360773 8.653951)
			(xy 404.287867 8.60881) (xy 404.211107 8.570588) (xy 404.131148 8.539612) (xy 404.048672 8.516145)
			(xy 403.964382 8.500389) (xy 403.878999 8.492477) (xy 403.793249 8.492477) (xy 403.707866 8.500389)
			(xy 403.623576 8.516145) (xy 403.5411 8.539612) (xy 403.461141 8.570588) (xy 403.384381 8.60881)
			(xy 403.311475 8.653951) (xy 403.243046 8.705627) (xy 403.179676 8.763396) (xy 403.121907 8.826766)
			(xy 403.070231 8.895195) (xy 403.02509 8.968101) (xy 402.986868 9.044861) (xy 402.955892 9.12482)
			(xy 402.932425 9.207296) (xy 402.916669 9.291586) (xy 402.908757 9.376969) (xy 398.413491 9.376969)
			(xy 398.405579 9.291586) (xy 398.389823 9.207296) (xy 398.366356 9.12482) (xy 398.33538 9.044861)
			(xy 398.297158 8.968101) (xy 398.252017 8.895195) (xy 398.200341 8.826766) (xy 398.142572 8.763396)
			(xy 398.079202 8.705627) (xy 398.010773 8.653951) (xy 397.937867 8.60881) (xy 397.861107 8.570588)
			(xy 397.781148 8.539612) (xy 397.698672 8.516145) (xy 397.614382 8.500389) (xy 397.528999 8.492477)
			(xy 397.443249 8.492477) (xy 397.357866 8.500389) (xy 397.273576 8.516145) (xy 397.1911 8.539612)
			(xy 397.111141 8.570588) (xy 397.034381 8.60881) (xy 396.961475 8.653951) (xy 396.893046 8.705627)
			(xy 396.829676 8.763396) (xy 396.771907 8.826766) (xy 396.720231 8.895195) (xy 396.67509 8.968101)
			(xy 396.636868 9.044861) (xy 396.605892 9.12482) (xy 396.582425 9.207296) (xy 396.566669 9.291586)
			(xy 396.558757 9.376969) (xy 390.701117 9.376969) (xy 390.701035 9.369857) (xy 390.693123 9.284474)
			(xy 390.677367 9.200184) (xy 390.6539 9.117708) (xy 390.622924 9.037749) (xy 390.584702 8.960989)
			(xy 390.539561 8.888083) (xy 390.487885 8.819654) (xy 390.430116 8.756284) (xy 390.366746 8.698515)
			(xy 390.298317 8.646839) (xy 390.225411 8.601698) (xy 390.148651 8.563476) (xy 390.068692 8.5325)
			(xy 389.986216 8.509033) (xy 389.901926 8.493277) (xy 389.816543 8.485365) (xy 389.730793 8.485365)
			(xy 389.64541 8.493277) (xy 389.56112 8.509033) (xy 389.478644 8.5325) (xy 389.398685 8.563476) (xy 389.321925 8.601698)
			(xy 389.249019 8.646839) (xy 389.18059 8.698515) (xy 389.11722 8.756284) (xy 389.059451 8.819654)
			(xy 389.007775 8.888083) (xy 388.962634 8.960989) (xy 388.924412 9.037749) (xy 388.893436 9.117708)
			(xy 388.869969 9.200184) (xy 388.854213 9.284474) (xy 388.846301 9.369857) (xy 384.351035 9.369857)
			(xy 384.343123 9.284474) (xy 384.327367 9.200184) (xy 384.3039 9.117708) (xy 384.272924 9.037749)
			(xy 384.234702 8.960989) (xy 384.189561 8.888083) (xy 384.137885 8.819654) (xy 384.080116 8.756284)
			(xy 384.016746 8.698515) (xy 383.948317 8.646839) (xy 383.875411 8.601698) (xy 383.798651 8.563476)
			(xy 383.718692 8.5325) (xy 383.636216 8.509033) (xy 383.551926 8.493277) (xy 383.466543 8.485365)
			(xy 383.380793 8.485365) (xy 383.29541 8.493277) (xy 383.21112 8.509033) (xy 383.128644 8.5325) (xy 383.048685 8.563476)
			(xy 382.971925 8.601698) (xy 382.899019 8.646839) (xy 382.83059 8.698515) (xy 382.76722 8.756284)
			(xy 382.709451 8.819654) (xy 382.657775 8.888083) (xy 382.612634 8.960989) (xy 382.574412 9.037749)
			(xy 382.543436 9.117708) (xy 382.519969 9.200184) (xy 382.504213 9.284474) (xy 382.496301 9.369857)
			(xy 332.50079 9.369857) (xy 332.500491 9.343949) (xy 332.492579 9.258566) (xy 332.476823 9.174276)
			(xy 332.453356 9.0918) (xy 332.42238 9.011841) (xy 332.384158 8.935081) (xy 332.339017 8.862175)
			(xy 332.287341 8.793746) (xy 332.229572 8.730376) (xy 332.166202 8.672607) (xy 332.097773 8.620931)
			(xy 332.024867 8.57579) (xy 331.948107 8.537568) (xy 331.868148 8.506592) (xy 331.785672 8.483125)
			(xy 331.701382 8.467369) (xy 331.615999 8.459457) (xy 331.530249 8.459457) (xy 331.444866 8.467369)
			(xy 331.360576 8.483125) (xy 331.2781 8.506592) (xy 331.198141 8.537568) (xy 331.121381 8.57579)
			(xy 331.048475 8.620931) (xy 330.980046 8.672607) (xy 330.916676 8.730376) (xy 330.858907 8.793746)
			(xy 330.807231 8.862175) (xy 330.76209 8.935081) (xy 330.723868 9.011841) (xy 330.692892 9.0918)
			(xy 330.669425 9.174276) (xy 330.653669 9.258566) (xy 330.645757 9.343949) (xy 326.150491 9.343949)
			(xy 326.142579 9.258566) (xy 326.126823 9.174276) (xy 326.103356 9.0918) (xy 326.07238 9.011841)
			(xy 326.034158 8.935081) (xy 325.989017 8.862175) (xy 325.937341 8.793746) (xy 325.879572 8.730376)
			(xy 325.816202 8.672607) (xy 325.747773 8.620931) (xy 325.674867 8.57579) (xy 325.598107 8.537568)
			(xy 325.518148 8.506592) (xy 325.435672 8.483125) (xy 325.351382 8.467369) (xy 325.265999 8.459457)
			(xy 325.180249 8.459457) (xy 325.094866 8.467369) (xy 325.010576 8.483125) (xy 324.9281 8.506592)
			(xy 324.848141 8.537568) (xy 324.771381 8.57579) (xy 324.698475 8.620931) (xy 324.630046 8.672607)
			(xy 324.566676 8.730376) (xy 324.508907 8.793746) (xy 324.457231 8.862175) (xy 324.41209 8.935081)
			(xy 324.373868 9.011841) (xy 324.342892 9.0918) (xy 324.319425 9.174276) (xy 324.303669 9.258566)
			(xy 324.295757 9.343949) (xy 317.930117 9.343949) (xy 317.930035 9.336837) (xy 317.922123 9.251454)
			(xy 317.906367 9.167164) (xy 317.8829 9.084688) (xy 317.851924 9.004729) (xy 317.813702 8.927969)
			(xy 317.768561 8.855063) (xy 317.716885 8.786634) (xy 317.659116 8.723264) (xy 317.595746 8.665495)
			(xy 317.527317 8.613819) (xy 317.454411 8.568678) (xy 317.377651 8.530456) (xy 317.297692 8.49948)
			(xy 317.215216 8.476013) (xy 317.130926 8.460257) (xy 317.045543 8.452345) (xy 316.959793 8.452345)
			(xy 316.87441 8.460257) (xy 316.79012 8.476013) (xy 316.707644 8.49948) (xy 316.627685 8.530456)
			(xy 316.550925 8.568678) (xy 316.478019 8.613819) (xy 316.40959 8.665495) (xy 316.34622 8.723264)
			(xy 316.288451 8.786634) (xy 316.236775 8.855063) (xy 316.191634 8.927969) (xy 316.153412 9.004729)
			(xy 316.122436 9.084688) (xy 316.098969 9.167164) (xy 316.083213 9.251454) (xy 316.075301 9.336837)
			(xy 311.580035 9.336837) (xy 311.572123 9.251454) (xy 311.556367 9.167164) (xy 311.5329 9.084688)
			(xy 311.501924 9.004729) (xy 311.463702 8.927969) (xy 311.418561 8.855063) (xy 311.366885 8.786634)
			(xy 311.309116 8.723264) (xy 311.245746 8.665495) (xy 311.177317 8.613819) (xy 311.104411 8.568678)
			(xy 311.027651 8.530456) (xy 310.947692 8.49948) (xy 310.865216 8.476013) (xy 310.780926 8.460257)
			(xy 310.695543 8.452345) (xy 310.609793 8.452345) (xy 310.52441 8.460257) (xy 310.44012 8.476013)
			(xy 310.357644 8.49948) (xy 310.277685 8.530456) (xy 310.200925 8.568678) (xy 310.128019 8.613819)
			(xy 310.05959 8.665495) (xy 309.99622 8.723264) (xy 309.938451 8.786634) (xy 309.886775 8.855063)
			(xy 309.841634 8.927969) (xy 309.803412 9.004729) (xy 309.772436 9.084688) (xy 309.748969 9.167164)
			(xy 309.733213 9.251454) (xy 309.725301 9.336837) (xy 259.72979 9.336837) (xy 259.729491 9.310929)
			(xy 259.721579 9.225546) (xy 259.705823 9.141256) (xy 259.682356 9.05878) (xy 259.65138 8.978821)
			(xy 259.613158 8.902061) (xy 259.568017 8.829155) (xy 259.516341 8.760726) (xy 259.458572 8.697356)
			(xy 259.395202 8.639587) (xy 259.326773 8.587911) (xy 259.253867 8.54277) (xy 259.177107 8.504548)
			(xy 259.097148 8.473572) (xy 259.014672 8.450105) (xy 258.930382 8.434349) (xy 258.844999 8.426437)
			(xy 258.759249 8.426437) (xy 258.673866 8.434349) (xy 258.589576 8.450105) (xy 258.5071 8.473572)
			(xy 258.427141 8.504548) (xy 258.350381 8.54277) (xy 258.277475 8.587911) (xy 258.209046 8.639587)
			(xy 258.145676 8.697356) (xy 258.087907 8.760726) (xy 258.036231 8.829155) (xy 257.99109 8.902061)
			(xy 257.952868 8.978821) (xy 257.921892 9.05878) (xy 257.898425 9.141256) (xy 257.882669 9.225546)
			(xy 257.874757 9.310929) (xy 253.379491 9.310929) (xy 253.371579 9.225546) (xy 253.355823 9.141256)
			(xy 253.332356 9.05878) (xy 253.30138 8.978821) (xy 253.263158 8.902061) (xy 253.218017 8.829155)
			(xy 253.166341 8.760726) (xy 253.108572 8.697356) (xy 253.045202 8.639587) (xy 252.976773 8.587911)
			(xy 252.903867 8.54277) (xy 252.827107 8.504548) (xy 252.747148 8.473572) (xy 252.664672 8.450105)
			(xy 252.580382 8.434349) (xy 252.494999 8.426437) (xy 252.409249 8.426437) (xy 252.323866 8.434349)
			(xy 252.239576 8.450105) (xy 252.1571 8.473572) (xy 252.077141 8.504548) (xy 252.000381 8.54277)
			(xy 251.927475 8.587911) (xy 251.859046 8.639587) (xy 251.795676 8.697356) (xy 251.737907 8.760726)
			(xy 251.686231 8.829155) (xy 251.64109 8.902061) (xy 251.602868 8.978821) (xy 251.571892 9.05878)
			(xy 251.548425 9.141256) (xy 251.532669 9.225546) (xy 251.524757 9.310929) (xy 245.921117 9.310929)
			(xy 245.921035 9.303817) (xy 245.913123 9.218434) (xy 245.897367 9.134144) (xy 245.8739 9.051668)
			(xy 245.842924 8.971709) (xy 245.804702 8.894949) (xy 245.759561 8.822043) (xy 245.707885 8.753614)
			(xy 245.650116 8.690244) (xy 245.586746 8.632475) (xy 245.518317 8.580799) (xy 245.445411 8.535658)
			(xy 245.368651 8.497436) (xy 245.288692 8.46646) (xy 245.206216 8.442993) (xy 245.121926 8.427237)
			(xy 245.036543 8.419325) (xy 244.950793 8.419325) (xy 244.86541 8.427237) (xy 244.78112 8.442993)
			(xy 244.698644 8.46646) (xy 244.618685 8.497436) (xy 244.541925 8.535658) (xy 244.469019 8.580799)
			(xy 244.40059 8.632475) (xy 244.33722 8.690244) (xy 244.279451 8.753614) (xy 244.227775 8.822043)
			(xy 244.182634 8.894949) (xy 244.144412 8.971709) (xy 244.113436 9.051668) (xy 244.089969 9.134144)
			(xy 244.074213 9.218434) (xy 244.066301 9.303817) (xy 239.571035 9.303817) (xy 239.563123 9.218434)
			(xy 239.547367 9.134144) (xy 239.5239 9.051668) (xy 239.492924 8.971709) (xy 239.454702 8.894949)
			(xy 239.409561 8.822043) (xy 239.357885 8.753614) (xy 239.300116 8.690244) (xy 239.236746 8.632475)
			(xy 239.168317 8.580799) (xy 239.095411 8.535658) (xy 239.018651 8.497436) (xy 238.938692 8.46646)
			(xy 238.856216 8.442993) (xy 238.771926 8.427237) (xy 238.686543 8.419325) (xy 238.600793 8.419325)
			(xy 238.51541 8.427237) (xy 238.43112 8.442993) (xy 238.348644 8.46646) (xy 238.268685 8.497436)
			(xy 238.191925 8.535658) (xy 238.119019 8.580799) (xy 238.05059 8.632475) (xy 237.98722 8.690244)
			(xy 237.929451 8.753614) (xy 237.877775 8.822043) (xy 237.832634 8.894949) (xy 237.794412 8.971709)
			(xy 237.763436 9.051668) (xy 237.739969 9.134144) (xy 237.724213 9.218434) (xy 237.716301 9.303817)
			(xy 187.719832 9.303817) (xy 187.712579 9.225546) (xy 187.696823 9.141256) (xy 187.673356 9.05878)
			(xy 187.64238 8.978821) (xy 187.604158 8.902061) (xy 187.559017 8.829155) (xy 187.507341 8.760726)
			(xy 187.449572 8.697356) (xy 187.386202 8.639587) (xy 187.317773 8.587911) (xy 187.244867 8.54277)
			(xy 187.168107 8.504548) (xy 187.088148 8.473572) (xy 187.005672 8.450105) (xy 186.921382 8.434349)
			(xy 186.835999 8.426437) (xy 186.750249 8.426437) (xy 186.664866 8.434349) (xy 186.580576 8.450105)
			(xy 186.4981 8.473572) (xy 186.418141 8.504548) (xy 186.341381 8.54277) (xy 186.268475 8.587911)
			(xy 186.200046 8.639587) (xy 186.136676 8.697356) (xy 186.078907 8.760726) (xy 186.027231 8.829155)
			(xy 185.98209 8.902061) (xy 185.943868 8.978821) (xy 185.912892 9.05878) (xy 185.889425 9.141256)
			(xy 185.873669 9.225546) (xy 185.865757 9.310929) (xy 181.370491 9.310929) (xy 181.362579 9.225546)
			(xy 181.346823 9.141256) (xy 181.323356 9.05878) (xy 181.29238 8.978821) (xy 181.254158 8.902061)
			(xy 181.209017 8.829155) (xy 181.157341 8.760726) (xy 181.099572 8.697356) (xy 181.036202 8.639587)
			(xy 180.967773 8.587911) (xy 180.894867 8.54277) (xy 180.818107 8.504548) (xy 180.738148 8.473572)
			(xy 180.655672 8.450105) (xy 180.571382 8.434349) (xy 180.485999 8.426437) (xy 180.400249 8.426437)
			(xy 180.314866 8.434349) (xy 180.230576 8.450105) (xy 180.1481 8.473572) (xy 180.068141 8.504548)
			(xy 179.991381 8.54277) (xy 179.918475 8.587911) (xy 179.850046 8.639587) (xy 179.786676 8.697356)
			(xy 179.728907 8.760726) (xy 179.677231 8.829155) (xy 179.63209 8.902061) (xy 179.593868 8.978821)
			(xy 179.562892 9.05878) (xy 179.539425 9.141256) (xy 179.523669 9.225546) (xy 179.515757 9.310929)
			(xy 158.621984 9.310929) (xy 158.621984 8.377682) (xy 158.62149 8.307329) (xy 158.6136 8.166844)
			(xy 158.597845 8.027022) (xy 158.574274 7.888303) (xy 158.542963 7.751125) (xy 158.50401 7.615918)
			(xy 158.457537 7.483107) (xy 158.40369 7.353112) (xy 158.342638 7.22634) (xy 158.274575 7.103191)
			(xy 158.199714 6.984051) (xy 158.11829 6.869297) (xy 158.039844 6.770929) (xy 179.515757 6.770929)
			(xy 179.515757 6.856679) (xy 179.523669 6.942062) (xy 179.539425 7.026352) (xy 179.562892 7.108828)
			(xy 179.593868 7.188787) (xy 179.63209 7.265547) (xy 179.677231 7.338453) (xy 179.728907 7.406882)
			(xy 179.786676 7.470252) (xy 179.850046 7.528021) (xy 179.918475 7.579697) (xy 179.991381 7.624838)
			(xy 180.068141 7.66306) (xy 180.1481 7.694036) (xy 180.230576 7.717503) (xy 180.314866 7.733259)
			(xy 180.400249 7.741171) (xy 180.485999 7.741171) (xy 180.571382 7.733259) (xy 180.655672 7.717503)
			(xy 180.738148 7.694036) (xy 180.818107 7.66306) (xy 180.894867 7.624838) (xy 180.967773 7.579697)
			(xy 181.036202 7.528021) (xy 181.099572 7.470252) (xy 181.157341 7.406882) (xy 181.209017 7.338453)
			(xy 181.254158 7.265547) (xy 181.29238 7.188787) (xy 181.323356 7.108828) (xy 181.346823 7.026352)
			(xy 181.362579 6.942062) (xy 181.370491 6.856679) (xy 181.370986 6.813804) (xy 181.370491 6.770929)
			(xy 185.865757 6.770929) (xy 185.865757 6.856679) (xy 185.873669 6.942062) (xy 185.889425 7.026352)
			(xy 185.912892 7.108828) (xy 185.943868 7.188787) (xy 185.98209 7.265547) (xy 186.027231 7.338453)
			(xy 186.078907 7.406882) (xy 186.136676 7.470252) (xy 186.200046 7.528021) (xy 186.268475 7.579697)
			(xy 186.341381 7.624838) (xy 186.418141 7.66306) (xy 186.4981 7.694036) (xy 186.580576 7.717503)
			(xy 186.664866 7.733259) (xy 186.750249 7.741171) (xy 186.835999 7.741171) (xy 186.921382 7.733259)
			(xy 187.005672 7.717503) (xy 187.088148 7.694036) (xy 187.168107 7.66306) (xy 187.244867 7.624838)
			(xy 187.317773 7.579697) (xy 187.386202 7.528021) (xy 187.449572 7.470252) (xy 187.507341 7.406882)
			(xy 187.559017 7.338453) (xy 187.604158 7.265547) (xy 187.64238 7.188787) (xy 187.673356 7.108828)
			(xy 187.696823 7.026352) (xy 187.712579 6.942062) (xy 187.720491 6.856679) (xy 187.720986 6.813804)
			(xy 187.720491 6.770929) (xy 187.719832 6.763817) (xy 237.716301 6.763817) (xy 237.716301 6.849567)
			(xy 237.724213 6.93495) (xy 237.739969 7.01924) (xy 237.763436 7.101716) (xy 237.794412 7.181675)
			(xy 237.832634 7.258435) (xy 237.877775 7.331341) (xy 237.929451 7.39977) (xy 237.98722 7.46314)
			(xy 238.05059 7.520909) (xy 238.119019 7.572585) (xy 238.191925 7.617726) (xy 238.268685 7.655948)
			(xy 238.348644 7.686924) (xy 238.43112 7.710391) (xy 238.51541 7.726147) (xy 238.600793 7.734059)
			(xy 238.686543 7.734059) (xy 238.771926 7.726147) (xy 238.856216 7.710391) (xy 238.938692 7.686924)
			(xy 239.018651 7.655948) (xy 239.095411 7.617726) (xy 239.168317 7.572585) (xy 239.236746 7.520909)
			(xy 239.300116 7.46314) (xy 239.357885 7.39977) (xy 239.409561 7.331341) (xy 239.454702 7.258435)
			(xy 239.492924 7.181675) (xy 239.5239 7.101716) (xy 239.547367 7.01924) (xy 239.563123 6.93495) (xy 239.571035 6.849567)
			(xy 239.57153 6.806692) (xy 239.571035 6.763817) (xy 244.066301 6.763817) (xy 244.066301 6.849567)
			(xy 244.074213 6.93495) (xy 244.089969 7.01924) (xy 244.113436 7.101716) (xy 244.144412 7.181675)
			(xy 244.182634 7.258435) (xy 244.227775 7.331341) (xy 244.279451 7.39977) (xy 244.33722 7.46314)
			(xy 244.40059 7.520909) (xy 244.469019 7.572585) (xy 244.541925 7.617726) (xy 244.618685 7.655948)
			(xy 244.698644 7.686924) (xy 244.78112 7.710391) (xy 244.86541 7.726147) (xy 244.950793 7.734059)
			(xy 245.036543 7.734059) (xy 245.121926 7.726147) (xy 245.206216 7.710391) (xy 245.288692 7.686924)
			(xy 245.368651 7.655948) (xy 245.445411 7.617726) (xy 245.518317 7.572585) (xy 245.586746 7.520909)
			(xy 245.650116 7.46314) (xy 245.707885 7.39977) (xy 245.759561 7.331341) (xy 245.804702 7.258435)
			(xy 245.842924 7.181675) (xy 245.8739 7.101716) (xy 245.897367 7.01924) (xy 245.913123 6.93495) (xy 245.921035 6.849567)
			(xy 245.92153 6.806692) (xy 245.921117 6.770929) (xy 251.524757 6.770929) (xy 251.524757 6.856679)
			(xy 251.532669 6.942062) (xy 251.548425 7.026352) (xy 251.571892 7.108828) (xy 251.602868 7.188787)
			(xy 251.64109 7.265547) (xy 251.686231 7.338453) (xy 251.737907 7.406882) (xy 251.795676 7.470252)
			(xy 251.859046 7.528021) (xy 251.927475 7.579697) (xy 252.000381 7.624838) (xy 252.077141 7.66306)
			(xy 252.1571 7.694036) (xy 252.239576 7.717503) (xy 252.323866 7.733259) (xy 252.409249 7.741171)
			(xy 252.494999 7.741171) (xy 252.580382 7.733259) (xy 252.664672 7.717503) (xy 252.747148 7.694036)
			(xy 252.827107 7.66306) (xy 252.84931 7.652004) (xy 256.459736 7.652004) (xy 256.459736 8.515604)
			(xy 256.460222 8.542873) (xy 256.467984 8.596857) (xy 256.483349 8.649187) (xy 256.506006 8.698797)
			(xy 256.535492 8.744678) (xy 256.571207 8.785895) (xy 256.612424 8.82161) (xy 256.658305 8.851096)
			(xy 256.707915 8.873753) (xy 256.760245 8.889118) (xy 256.814229 8.89688) (xy 256.868767 8.89688)
			(xy 256.922751 8.889118) (xy 256.975081 8.873753) (xy 257.024691 8.851096) (xy 257.070572 8.82161)
			(xy 257.111789 8.785895) (xy 257.147504 8.744678) (xy 257.17699 8.698797) (xy 257.199647 8.649187)
			(xy 257.215012 8.596857) (xy 257.222774 8.542873) (xy 257.22326 8.515604) (xy 257.22326 7.652004)
			(xy 257.222774 7.624735) (xy 257.215012 7.570751) (xy 257.199647 7.518421) (xy 257.17699 7.468811)
			(xy 257.147504 7.42293) (xy 257.111789 7.381713) (xy 257.070572 7.345998) (xy 257.024691 7.316512)
			(xy 256.975081 7.293855) (xy 256.922751 7.27849) (xy 256.868767 7.270728) (xy 256.814229 7.270728)
			(xy 256.760245 7.27849) (xy 256.707915 7.293855) (xy 256.658305 7.316512) (xy 256.612424 7.345998)
			(xy 256.571207 7.381713) (xy 256.535492 7.42293) (xy 256.506006 7.468811) (xy 256.483349 7.518421)
			(xy 256.467984 7.570751) (xy 256.460222 7.624735) (xy 256.459736 7.652004) (xy 252.84931 7.652004)
			(xy 252.903867 7.624838) (xy 252.976773 7.579697) (xy 253.045202 7.528021) (xy 253.108572 7.470252)
			(xy 253.166341 7.406882) (xy 253.218017 7.338453) (xy 253.263158 7.265547) (xy 253.30138 7.188787)
			(xy 253.332356 7.108828) (xy 253.355823 7.026352) (xy 253.371579 6.942062) (xy 253.379491 6.856679)
			(xy 253.379986 6.813804) (xy 253.379491 6.770929) (xy 257.874757 6.770929) (xy 257.874757 6.856679)
			(xy 257.882669 6.942062) (xy 257.898425 7.026352) (xy 257.921892 7.108828) (xy 257.952868 7.188787)
			(xy 257.99109 7.265547) (xy 258.036231 7.338453) (xy 258.087907 7.406882) (xy 258.145676 7.470252)
			(xy 258.209046 7.528021) (xy 258.277475 7.579697) (xy 258.350381 7.624838) (xy 258.427141 7.66306)
			(xy 258.5071 7.694036) (xy 258.589576 7.717503) (xy 258.673866 7.733259) (xy 258.759249 7.741171)
			(xy 258.844999 7.741171) (xy 258.930382 7.733259) (xy 259.014672 7.717503) (xy 259.097148 7.694036)
			(xy 259.177107 7.66306) (xy 259.253867 7.624838) (xy 259.326773 7.579697) (xy 259.395202 7.528021)
			(xy 259.458572 7.470252) (xy 259.516341 7.406882) (xy 259.568017 7.338453) (xy 259.613158 7.265547)
			(xy 259.65138 7.188787) (xy 259.682356 7.108828) (xy 259.705823 7.026352) (xy 259.721579 6.942062)
			(xy 259.729491 6.856679) (xy 259.729986 6.813804) (xy 259.72979 6.796837) (xy 309.725301 6.796837)
			(xy 309.725301 6.882587) (xy 309.733213 6.96797) (xy 309.748969 7.05226) (xy 309.772436 7.134736)
			(xy 309.803412 7.214695) (xy 309.841634 7.291455) (xy 309.886775 7.364361) (xy 309.938451 7.43279)
			(xy 309.99622 7.49616) (xy 310.05959 7.553929) (xy 310.128019 7.605605) (xy 310.200925 7.650746)
			(xy 310.277685 7.688968) (xy 310.357644 7.719944) (xy 310.44012 7.743411) (xy 310.52441 7.759167)
			(xy 310.609793 7.767079) (xy 310.695543 7.767079) (xy 310.780926 7.759167) (xy 310.865216 7.743411)
			(xy 310.947692 7.719944) (xy 311.027651 7.688968) (xy 311.049854 7.677912) (xy 312.231532 7.677912)
			(xy 312.231532 8.541512) (xy 312.232018 8.568781) (xy 312.23978 8.622765) (xy 312.255145 8.675095)
			(xy 312.277802 8.724705) (xy 312.307288 8.770586) (xy 312.343003 8.811803) (xy 312.38422 8.847518)
			(xy 312.430101 8.877004) (xy 312.479711 8.899661) (xy 312.532041 8.915026) (xy 312.586025 8.922788)
			(xy 312.640563 8.922788) (xy 312.694547 8.915026) (xy 312.746877 8.899661) (xy 312.796487 8.877004)
			(xy 312.842368 8.847518) (xy 312.883585 8.811803) (xy 312.9193 8.770586) (xy 312.948786 8.724705)
			(xy 312.971443 8.675095) (xy 312.986808 8.622765) (xy 312.99457 8.568781) (xy 312.995056 8.541512)
			(xy 312.995056 7.677912) (xy 312.99457 7.650643) (xy 312.986808 7.596659) (xy 312.971443 7.544329)
			(xy 312.948786 7.494719) (xy 312.9193 7.448838) (xy 312.883585 7.407621) (xy 312.842368 7.371906)
			(xy 312.796487 7.34242) (xy 312.746877 7.319763) (xy 312.694547 7.304398) (xy 312.640563 7.296636)
			(xy 312.586025 7.296636) (xy 312.532041 7.304398) (xy 312.479711 7.319763) (xy 312.430101 7.34242)
			(xy 312.38422 7.371906) (xy 312.343003 7.407621) (xy 312.307288 7.448838) (xy 312.277802 7.494719)
			(xy 312.255145 7.544329) (xy 312.23978 7.596659) (xy 312.232018 7.650643) (xy 312.231532 7.677912)
			(xy 311.049854 7.677912) (xy 311.104411 7.650746) (xy 311.177317 7.605605) (xy 311.245746 7.553929)
			(xy 311.309116 7.49616) (xy 311.366885 7.43279) (xy 311.418561 7.364361) (xy 311.463702 7.291455)
			(xy 311.501924 7.214695) (xy 311.5329 7.134736) (xy 311.556367 7.05226) (xy 311.572123 6.96797) (xy 311.580035 6.882587)
			(xy 311.58053 6.839712) (xy 311.580035 6.796837) (xy 316.075301 6.796837) (xy 316.075301 6.882587)
			(xy 316.083213 6.96797) (xy 316.098969 7.05226) (xy 316.122436 7.134736) (xy 316.153412 7.214695)
			(xy 316.191634 7.291455) (xy 316.236775 7.364361) (xy 316.288451 7.43279) (xy 316.34622 7.49616)
			(xy 316.40959 7.553929) (xy 316.478019 7.605605) (xy 316.550925 7.650746) (xy 316.627685 7.688968)
			(xy 316.707644 7.719944) (xy 316.79012 7.743411) (xy 316.87441 7.759167) (xy 316.959793 7.767079)
			(xy 317.045543 7.767079) (xy 317.130926 7.759167) (xy 317.215216 7.743411) (xy 317.297692 7.719944)
			(xy 317.377651 7.688968) (xy 317.454411 7.650746) (xy 317.527317 7.605605) (xy 317.595746 7.553929)
			(xy 317.659116 7.49616) (xy 317.716885 7.43279) (xy 317.768561 7.364361) (xy 317.813702 7.291455)
			(xy 317.851924 7.214695) (xy 317.8829 7.134736) (xy 317.906367 7.05226) (xy 317.922123 6.96797) (xy 317.930035 6.882587)
			(xy 317.93053 6.839712) (xy 317.930117 6.803949) (xy 324.295757 6.803949) (xy 324.295757 6.889699)
			(xy 324.303669 6.975082) (xy 324.319425 7.059372) (xy 324.342892 7.141848) (xy 324.373868 7.221807)
			(xy 324.41209 7.298567) (xy 324.457231 7.371473) (xy 324.508907 7.439902) (xy 324.566676 7.503272)
			(xy 324.630046 7.561041) (xy 324.698475 7.612717) (xy 324.771381 7.657858) (xy 324.848141 7.69608)
			(xy 324.9281 7.727056) (xy 325.010576 7.750523) (xy 325.094866 7.766279) (xy 325.180249 7.774191)
			(xy 325.265999 7.774191) (xy 325.351382 7.766279) (xy 325.435672 7.750523) (xy 325.518148 7.727056)
			(xy 325.598107 7.69608) (xy 325.62031 7.685024) (xy 329.230736 7.685024) (xy 329.230736 8.548624)
			(xy 329.231222 8.575893) (xy 329.238984 8.629877) (xy 329.254349 8.682207) (xy 329.277006 8.731817)
			(xy 329.306492 8.777698) (xy 329.342207 8.818915) (xy 329.383424 8.85463) (xy 329.429305 8.884116)
			(xy 329.478915 8.906773) (xy 329.531245 8.922138) (xy 329.585229 8.9299) (xy 329.639767 8.9299) (xy 329.693751 8.922138)
			(xy 329.746081 8.906773) (xy 329.795691 8.884116) (xy 329.841572 8.85463) (xy 329.882789 8.818915)
			(xy 329.918504 8.777698) (xy 329.94799 8.731817) (xy 329.970647 8.682207) (xy 329.986012 8.629877)
			(xy 329.993774 8.575893) (xy 329.99426 8.548624) (xy 329.99426 7.685024) (xy 329.993774 7.657755)
			(xy 329.986012 7.603771) (xy 329.970647 7.551441) (xy 329.94799 7.501831) (xy 329.918504 7.45595)
			(xy 329.882789 7.414733) (xy 329.841572 7.379018) (xy 329.795691 7.349532) (xy 329.746081 7.326875)
			(xy 329.693751 7.31151) (xy 329.639767 7.303748) (xy 329.585229 7.303748) (xy 329.531245 7.31151)
			(xy 329.478915 7.326875) (xy 329.429305 7.349532) (xy 329.383424 7.379018) (xy 329.342207 7.414733)
			(xy 329.306492 7.45595) (xy 329.277006 7.501831) (xy 329.254349 7.551441) (xy 329.238984 7.603771)
			(xy 329.231222 7.657755) (xy 329.230736 7.685024) (xy 325.62031 7.685024) (xy 325.674867 7.657858)
			(xy 325.747773 7.612717) (xy 325.816202 7.561041) (xy 325.879572 7.503272) (xy 325.937341 7.439902)
			(xy 325.989017 7.371473) (xy 326.034158 7.298567) (xy 326.07238 7.221807) (xy 326.103356 7.141848)
			(xy 326.126823 7.059372) (xy 326.142579 6.975082) (xy 326.150491 6.889699) (xy 326.150986 6.846824)
			(xy 326.150491 6.803949) (xy 330.645757 6.803949) (xy 330.645757 6.889699) (xy 330.653669 6.975082)
			(xy 330.669425 7.059372) (xy 330.692892 7.141848) (xy 330.723868 7.221807) (xy 330.76209 7.298567)
			(xy 330.807231 7.371473) (xy 330.858907 7.439902) (xy 330.916676 7.503272) (xy 330.980046 7.561041)
			(xy 331.048475 7.612717) (xy 331.121381 7.657858) (xy 331.198141 7.69608) (xy 331.2781 7.727056)
			(xy 331.360576 7.750523) (xy 331.444866 7.766279) (xy 331.530249 7.774191) (xy 331.615999 7.774191)
			(xy 331.701382 7.766279) (xy 331.785672 7.750523) (xy 331.868148 7.727056) (xy 331.948107 7.69608)
			(xy 332.024867 7.657858) (xy 332.097773 7.612717) (xy 332.166202 7.561041) (xy 332.229572 7.503272)
			(xy 332.287341 7.439902) (xy 332.339017 7.371473) (xy 332.384158 7.298567) (xy 332.42238 7.221807)
			(xy 332.453356 7.141848) (xy 332.476823 7.059372) (xy 332.492579 6.975082) (xy 332.500491 6.889699)
			(xy 332.500986 6.846824) (xy 332.50079 6.829857) (xy 382.496301 6.829857) (xy 382.496301 6.915607)
			(xy 382.504213 7.00099) (xy 382.519969 7.08528) (xy 382.543436 7.167756) (xy 382.574412 7.247715)
			(xy 382.612634 7.324475) (xy 382.657775 7.397381) (xy 382.709451 7.46581) (xy 382.76722 7.52918)
			(xy 382.83059 7.586949) (xy 382.899019 7.638625) (xy 382.971925 7.683766) (xy 383.048685 7.721988)
			(xy 383.128644 7.752964) (xy 383.21112 7.776431) (xy 383.29541 7.792187) (xy 383.380793 7.800099)
			(xy 383.466543 7.800099) (xy 383.551926 7.792187) (xy 383.636216 7.776431) (xy 383.718692 7.752964)
			(xy 383.798651 7.721988) (xy 383.820854 7.710932) (xy 385.002532 7.710932) (xy 385.002532 8.574532)
			(xy 385.003018 8.601801) (xy 385.01078 8.655785) (xy 385.026145 8.708115) (xy 385.048802 8.757725)
			(xy 385.078288 8.803606) (xy 385.114003 8.844823) (xy 385.15522 8.880538) (xy 385.201101 8.910024)
			(xy 385.250711 8.932681) (xy 385.303041 8.948046) (xy 385.357025 8.955808) (xy 385.411563 8.955808)
			(xy 385.465547 8.948046) (xy 385.517877 8.932681) (xy 385.567487 8.910024) (xy 385.613368 8.880538)
			(xy 385.654585 8.844823) (xy 385.6903 8.803606) (xy 385.719786 8.757725) (xy 385.742443 8.708115)
			(xy 385.757808 8.655785) (xy 385.76557 8.601801) (xy 385.766056 8.574532) (xy 385.766056 7.710932)
			(xy 385.76557 7.683663) (xy 385.757808 7.629679) (xy 385.742443 7.577349) (xy 385.719786 7.527739)
			(xy 385.6903 7.481858) (xy 385.654585 7.440641) (xy 385.613368 7.404926) (xy 385.567487 7.37544)
			(xy 385.517877 7.352783) (xy 385.465547 7.337418) (xy 385.411563 7.329656) (xy 385.357025 7.329656)
			(xy 385.303041 7.337418) (xy 385.250711 7.352783) (xy 385.201101 7.37544) (xy 385.15522 7.404926)
			(xy 385.114003 7.440641) (xy 385.078288 7.481858) (xy 385.048802 7.527739) (xy 385.026145 7.577349)
			(xy 385.01078 7.629679) (xy 385.003018 7.683663) (xy 385.002532 7.710932) (xy 383.820854 7.710932)
			(xy 383.875411 7.683766) (xy 383.948317 7.638625) (xy 384.016746 7.586949) (xy 384.080116 7.52918)
			(xy 384.137885 7.46581) (xy 384.189561 7.397381) (xy 384.234702 7.324475) (xy 384.272924 7.247715)
			(xy 384.3039 7.167756) (xy 384.327367 7.08528) (xy 384.343123 7.00099) (xy 384.351035 6.915607) (xy 384.35153 6.872732)
			(xy 384.351035 6.829857) (xy 388.846301 6.829857) (xy 388.846301 6.915607) (xy 388.854213 7.00099)
			(xy 388.869969 7.08528) (xy 388.893436 7.167756) (xy 388.924412 7.247715) (xy 388.962634 7.324475)
			(xy 389.007775 7.397381) (xy 389.059451 7.46581) (xy 389.11722 7.52918) (xy 389.18059 7.586949) (xy 389.249019 7.638625)
			(xy 389.321925 7.683766) (xy 389.398685 7.721988) (xy 389.478644 7.752964) (xy 389.56112 7.776431)
			(xy 389.64541 7.792187) (xy 389.730793 7.800099) (xy 389.816543 7.800099) (xy 389.901926 7.792187)
			(xy 389.986216 7.776431) (xy 390.068692 7.752964) (xy 390.148651 7.721988) (xy 390.225411 7.683766)
			(xy 390.298317 7.638625) (xy 390.366746 7.586949) (xy 390.430116 7.52918) (xy 390.487885 7.46581)
			(xy 390.539561 7.397381) (xy 390.584702 7.324475) (xy 390.622924 7.247715) (xy 390.6539 7.167756)
			(xy 390.677367 7.08528) (xy 390.693123 7.00099) (xy 390.701035 6.915607) (xy 390.70153 6.872732)
			(xy 390.701117 6.836969) (xy 396.558757 6.836969) (xy 396.558757 6.922719) (xy 396.566669 7.008102)
			(xy 396.582425 7.092392) (xy 396.605892 7.174868) (xy 396.636868 7.254827) (xy 396.67509 7.331587)
			(xy 396.720231 7.404493) (xy 396.771907 7.472922) (xy 396.829676 7.536292) (xy 396.893046 7.594061)
			(xy 396.961475 7.645737) (xy 397.034381 7.690878) (xy 397.111141 7.7291) (xy 397.1911 7.760076) (xy 397.273576 7.783543)
			(xy 397.357866 7.799299) (xy 397.443249 7.807211) (xy 397.528999 7.807211) (xy 397.614382 7.799299)
			(xy 397.698672 7.783543) (xy 397.781148 7.760076) (xy 397.861107 7.7291) (xy 397.88331 7.718044)
			(xy 401.493736 7.718044) (xy 401.493736 8.581644) (xy 401.494222 8.608913) (xy 401.501984 8.662897)
			(xy 401.517349 8.715227) (xy 401.540006 8.764837) (xy 401.569492 8.810718) (xy 401.605207 8.851935)
			(xy 401.646424 8.88765) (xy 401.692305 8.917136) (xy 401.741915 8.939793) (xy 401.794245 8.955158)
			(xy 401.848229 8.96292) (xy 401.902767 8.96292) (xy 401.956751 8.955158) (xy 402.009081 8.939793)
			(xy 402.058691 8.917136) (xy 402.104572 8.88765) (xy 402.145789 8.851935) (xy 402.181504 8.810718)
			(xy 402.21099 8.764837) (xy 402.233647 8.715227) (xy 402.249012 8.662897) (xy 402.256774 8.608913)
			(xy 402.25726 8.581644) (xy 402.25726 7.718044) (xy 402.256774 7.690775) (xy 402.249012 7.636791)
			(xy 402.233647 7.584461) (xy 402.21099 7.534851) (xy 402.181504 7.48897) (xy 402.145789 7.447753)
			(xy 402.104572 7.412038) (xy 402.058691 7.382552) (xy 402.009081 7.359895) (xy 401.956751 7.34453)
			(xy 401.902767 7.336768) (xy 401.848229 7.336768) (xy 401.794245 7.34453) (xy 401.741915 7.359895)
			(xy 401.692305 7.382552) (xy 401.646424 7.412038) (xy 401.605207 7.447753) (xy 401.569492 7.48897)
			(xy 401.540006 7.534851) (xy 401.517349 7.584461) (xy 401.501984 7.636791) (xy 401.494222 7.690775)
			(xy 401.493736 7.718044) (xy 397.88331 7.718044) (xy 397.937867 7.690878) (xy 398.010773 7.645737)
			(xy 398.079202 7.594061) (xy 398.142572 7.536292) (xy 398.200341 7.472922) (xy 398.252017 7.404493)
			(xy 398.297158 7.331587) (xy 398.33538 7.254827) (xy 398.366356 7.174868) (xy 398.389823 7.092392)
			(xy 398.405579 7.008102) (xy 398.413491 6.922719) (xy 398.413986 6.879844) (xy 398.413491 6.836969)
			(xy 402.908757 6.836969) (xy 402.908757 6.922719) (xy 402.916669 7.008102) (xy 402.932425 7.092392)
			(xy 402.955892 7.174868) (xy 402.986868 7.254827) (xy 403.02509 7.331587) (xy 403.070231 7.404493)
			(xy 403.121907 7.472922) (xy 403.179676 7.536292) (xy 403.243046 7.594061) (xy 403.311475 7.645737)
			(xy 403.384381 7.690878) (xy 403.461141 7.7291) (xy 403.5411 7.760076) (xy 403.623576 7.783543) (xy 403.707866 7.799299)
			(xy 403.793249 7.807211) (xy 403.878999 7.807211) (xy 403.964382 7.799299) (xy 404.048672 7.783543)
			(xy 404.131148 7.760076) (xy 404.211107 7.7291) (xy 404.287867 7.690878) (xy 404.360773 7.645737)
			(xy 404.429202 7.594061) (xy 404.492572 7.536292) (xy 404.550341 7.472922) (xy 404.602017 7.404493)
			(xy 404.647158 7.331587) (xy 404.68538 7.254827) (xy 404.716356 7.174868) (xy 404.739823 7.092392)
			(xy 404.755579 7.008102) (xy 404.763491 6.922719) (xy 404.763986 6.879844) (xy 404.76379 6.862877)
			(xy 454.759301 6.862877) (xy 454.759301 6.948627) (xy 454.767213 7.03401) (xy 454.782969 7.1183)
			(xy 454.806436 7.200776) (xy 454.837412 7.280735) (xy 454.875634 7.357495) (xy 454.920775 7.430401)
			(xy 454.972451 7.49883) (xy 455.03022 7.5622) (xy 455.09359 7.619969) (xy 455.162019 7.671645) (xy 455.234925 7.716786)
			(xy 455.311685 7.755008) (xy 455.391644 7.785984) (xy 455.47412 7.809451) (xy 455.55841 7.825207)
			(xy 455.643793 7.833119) (xy 455.729543 7.833119) (xy 455.814926 7.825207) (xy 455.899216 7.809451)
			(xy 455.981692 7.785984) (xy 456.061651 7.755008) (xy 456.083854 7.743952) (xy 457.265532 7.743952)
			(xy 457.265532 8.607552) (xy 457.266018 8.634821) (xy 457.27378 8.688805) (xy 457.289145 8.741135)
			(xy 457.311802 8.790745) (xy 457.341288 8.836626) (xy 457.377003 8.877843) (xy 457.41822 8.913558)
			(xy 457.464101 8.943044) (xy 457.513711 8.965701) (xy 457.566041 8.981066) (xy 457.620025 8.988828)
			(xy 457.674563 8.988828) (xy 457.728547 8.981066) (xy 457.780877 8.965701) (xy 457.830487 8.943044)
			(xy 457.876368 8.913558) (xy 457.917585 8.877843) (xy 457.9533 8.836626) (xy 457.982786 8.790745)
			(xy 458.005443 8.741135) (xy 458.020808 8.688805) (xy 458.02857 8.634821) (xy 458.029056 8.607552)
			(xy 458.029056 7.743952) (xy 458.02857 7.716683) (xy 458.020808 7.662699) (xy 458.005443 7.610369)
			(xy 457.982786 7.560759) (xy 457.9533 7.514878) (xy 457.917585 7.473661) (xy 457.876368 7.437946)
			(xy 457.830487 7.40846) (xy 457.780877 7.385803) (xy 457.728547 7.370438) (xy 457.674563 7.362676)
			(xy 457.620025 7.362676) (xy 457.566041 7.370438) (xy 457.513711 7.385803) (xy 457.464101 7.40846)
			(xy 457.41822 7.437946) (xy 457.377003 7.473661) (xy 457.341288 7.514878) (xy 457.311802 7.560759)
			(xy 457.289145 7.610369) (xy 457.27378 7.662699) (xy 457.266018 7.716683) (xy 457.265532 7.743952)
			(xy 456.083854 7.743952) (xy 456.138411 7.716786) (xy 456.211317 7.671645) (xy 456.279746 7.619969)
			(xy 456.343116 7.5622) (xy 456.400885 7.49883) (xy 456.452561 7.430401) (xy 456.497702 7.357495)
			(xy 456.535924 7.280735) (xy 456.5669 7.200776) (xy 456.590367 7.1183) (xy 456.606123 7.03401) (xy 456.614035 6.948627)
			(xy 456.61453 6.905752) (xy 456.614035 6.862877) (xy 461.109301 6.862877) (xy 461.109301 6.948627)
			(xy 461.117213 7.03401) (xy 461.132969 7.1183) (xy 461.156436 7.200776) (xy 461.187412 7.280735)
			(xy 461.225634 7.357495) (xy 461.270775 7.430401) (xy 461.322451 7.49883) (xy 461.38022 7.5622) (xy 461.44359 7.619969)
			(xy 461.512019 7.671645) (xy 461.584925 7.716786) (xy 461.661685 7.755008) (xy 461.741644 7.785984)
			(xy 461.82412 7.809451) (xy 461.90841 7.825207) (xy 461.993793 7.833119) (xy 462.079543 7.833119)
			(xy 462.164926 7.825207) (xy 462.249216 7.809451) (xy 462.331692 7.785984) (xy 462.411651 7.755008)
			(xy 462.488411 7.716786) (xy 462.561317 7.671645) (xy 462.629746 7.619969) (xy 462.693116 7.5622)
			(xy 462.750885 7.49883) (xy 462.802561 7.430401) (xy 462.847702 7.357495) (xy 462.885924 7.280735)
			(xy 462.9169 7.200776) (xy 462.940367 7.1183) (xy 462.956123 7.03401) (xy 462.964035 6.948627) (xy 462.96453 6.905752)
			(xy 462.964035 6.862877) (xy 462.956123 6.777494) (xy 462.940367 6.693204) (xy 462.9169 6.610728)
			(xy 462.885924 6.530769) (xy 462.847702 6.454009) (xy 462.802561 6.381103) (xy 462.750885 6.312674)
			(xy 462.693116 6.249304) (xy 462.629746 6.191535) (xy 462.561317 6.139859) (xy 462.488411 6.094718)
			(xy 462.411651 6.056496) (xy 462.331692 6.02552) (xy 462.249216 6.002053) (xy 462.164926 5.986297)
			(xy 462.079543 5.978385) (xy 461.993793 5.978385) (xy 461.90841 5.986297) (xy 461.82412 6.002053)
			(xy 461.741644 6.02552) (xy 461.661685 6.056496) (xy 461.584925 6.094718) (xy 461.512019 6.139859)
			(xy 461.44359 6.191535) (xy 461.38022 6.249304) (xy 461.322451 6.312674) (xy 461.270775 6.381103)
			(xy 461.225634 6.454009) (xy 461.187412 6.530769) (xy 461.156436 6.610728) (xy 461.132969 6.693204)
			(xy 461.117213 6.777494) (xy 461.109301 6.862877) (xy 456.614035 6.862877) (xy 456.606123 6.777494)
			(xy 456.590367 6.693204) (xy 456.5669 6.610728) (xy 456.535924 6.530769) (xy 456.497702 6.454009)
			(xy 456.452561 6.381103) (xy 456.400885 6.312674) (xy 456.343116 6.249304) (xy 456.279746 6.191535)
			(xy 456.211317 6.139859) (xy 456.138411 6.094718) (xy 456.061651 6.056496) (xy 455.981692 6.02552)
			(xy 455.899216 6.002053) (xy 455.814926 5.986297) (xy 455.729543 5.978385) (xy 455.643793 5.978385)
			(xy 455.55841 5.986297) (xy 455.47412 6.002053) (xy 455.391644 6.02552) (xy 455.311685 6.056496)
			(xy 455.234925 6.094718) (xy 455.162019 6.139859) (xy 455.09359 6.191535) (xy 455.03022 6.249304)
			(xy 454.972451 6.312674) (xy 454.920775 6.381103) (xy 454.875634 6.454009) (xy 454.837412 6.530769)
			(xy 454.806436 6.610728) (xy 454.782969 6.693204) (xy 454.767213 6.777494) (xy 454.759301 6.862877)
			(xy 404.76379 6.862877) (xy 404.763491 6.836969) (xy 404.755579 6.751586) (xy 404.739823 6.667296)
			(xy 404.716356 6.58482) (xy 404.68538 6.504861) (xy 404.647158 6.428101) (xy 404.602017 6.355195)
			(xy 404.550341 6.286766) (xy 404.492572 6.223396) (xy 404.429202 6.165627) (xy 404.360773 6.113951)
			(xy 404.287867 6.06881) (xy 404.211107 6.030588) (xy 404.131148 5.999612) (xy 404.048672 5.976145)
			(xy 403.964382 5.960389) (xy 403.878999 5.952477) (xy 403.793249 5.952477) (xy 403.707866 5.960389)
			(xy 403.623576 5.976145) (xy 403.5411 5.999612) (xy 403.461141 6.030588) (xy 403.384381 6.06881)
			(xy 403.311475 6.113951) (xy 403.243046 6.165627) (xy 403.179676 6.223396) (xy 403.121907 6.286766)
			(xy 403.070231 6.355195) (xy 403.02509 6.428101) (xy 402.986868 6.504861) (xy 402.955892 6.58482)
			(xy 402.932425 6.667296) (xy 402.916669 6.751586) (xy 402.908757 6.836969) (xy 398.413491 6.836969)
			(xy 398.405579 6.751586) (xy 398.389823 6.667296) (xy 398.366356 6.58482) (xy 398.33538 6.504861)
			(xy 398.297158 6.428101) (xy 398.252017 6.355195) (xy 398.200341 6.286766) (xy 398.142572 6.223396)
			(xy 398.079202 6.165627) (xy 398.010773 6.113951) (xy 397.937867 6.06881) (xy 397.861107 6.030588)
			(xy 397.781148 5.999612) (xy 397.698672 5.976145) (xy 397.614382 5.960389) (xy 397.528999 5.952477)
			(xy 397.443249 5.952477) (xy 397.357866 5.960389) (xy 397.273576 5.976145) (xy 397.1911 5.999612)
			(xy 397.111141 6.030588) (xy 397.034381 6.06881) (xy 396.961475 6.113951) (xy 396.893046 6.165627)
			(xy 396.829676 6.223396) (xy 396.771907 6.286766) (xy 396.720231 6.355195) (xy 396.67509 6.428101)
			(xy 396.636868 6.504861) (xy 396.605892 6.58482) (xy 396.582425 6.667296) (xy 396.566669 6.751586)
			(xy 396.558757 6.836969) (xy 390.701117 6.836969) (xy 390.701035 6.829857) (xy 390.693123 6.744474)
			(xy 390.677367 6.660184) (xy 390.6539 6.577708) (xy 390.622924 6.497749) (xy 390.584702 6.420989)
			(xy 390.539561 6.348083) (xy 390.487885 6.279654) (xy 390.430116 6.216284) (xy 390.366746 6.158515)
			(xy 390.298317 6.106839) (xy 390.225411 6.061698) (xy 390.148651 6.023476) (xy 390.068692 5.9925)
			(xy 389.986216 5.969033) (xy 389.901926 5.953277) (xy 389.816543 5.945365) (xy 389.730793 5.945365)
			(xy 389.64541 5.953277) (xy 389.56112 5.969033) (xy 389.478644 5.9925) (xy 389.398685 6.023476) (xy 389.321925 6.061698)
			(xy 389.249019 6.106839) (xy 389.18059 6.158515) (xy 389.11722 6.216284) (xy 389.059451 6.279654)
			(xy 389.007775 6.348083) (xy 388.962634 6.420989) (xy 388.924412 6.497749) (xy 388.893436 6.577708)
			(xy 388.869969 6.660184) (xy 388.854213 6.744474) (xy 388.846301 6.829857) (xy 384.351035 6.829857)
			(xy 384.343123 6.744474) (xy 384.327367 6.660184) (xy 384.3039 6.577708) (xy 384.272924 6.497749)
			(xy 384.234702 6.420989) (xy 384.189561 6.348083) (xy 384.137885 6.279654) (xy 384.080116 6.216284)
			(xy 384.016746 6.158515) (xy 383.948317 6.106839) (xy 383.875411 6.061698) (xy 383.798651 6.023476)
			(xy 383.718692 5.9925) (xy 383.636216 5.969033) (xy 383.551926 5.953277) (xy 383.466543 5.945365)
			(xy 383.380793 5.945365) (xy 383.29541 5.953277) (xy 383.21112 5.969033) (xy 383.128644 5.9925) (xy 383.048685 6.023476)
			(xy 382.971925 6.061698) (xy 382.899019 6.106839) (xy 382.83059 6.158515) (xy 382.76722 6.216284)
			(xy 382.709451 6.279654) (xy 382.657775 6.348083) (xy 382.612634 6.420989) (xy 382.574412 6.497749)
			(xy 382.543436 6.577708) (xy 382.519969 6.660184) (xy 382.504213 6.744474) (xy 382.496301 6.829857)
			(xy 332.50079 6.829857) (xy 332.500491 6.803949) (xy 332.492579 6.718566) (xy 332.476823 6.634276)
			(xy 332.453356 6.5518) (xy 332.42238 6.471841) (xy 332.384158 6.395081) (xy 332.339017 6.322175)
			(xy 332.287341 6.253746) (xy 332.229572 6.190376) (xy 332.166202 6.132607) (xy 332.097773 6.080931)
			(xy 332.024867 6.03579) (xy 331.948107 5.997568) (xy 331.868148 5.966592) (xy 331.785672 5.943125)
			(xy 331.701382 5.927369) (xy 331.615999 5.919457) (xy 331.530249 5.919457) (xy 331.444866 5.927369)
			(xy 331.360576 5.943125) (xy 331.2781 5.966592) (xy 331.198141 5.997568) (xy 331.121381 6.03579)
			(xy 331.048475 6.080931) (xy 330.980046 6.132607) (xy 330.916676 6.190376) (xy 330.858907 6.253746)
			(xy 330.807231 6.322175) (xy 330.76209 6.395081) (xy 330.723868 6.471841) (xy 330.692892 6.5518)
			(xy 330.669425 6.634276) (xy 330.653669 6.718566) (xy 330.645757 6.803949) (xy 326.150491 6.803949)
			(xy 326.142579 6.718566) (xy 326.126823 6.634276) (xy 326.103356 6.5518) (xy 326.07238 6.471841)
			(xy 326.034158 6.395081) (xy 325.989017 6.322175) (xy 325.937341 6.253746) (xy 325.879572 6.190376)
			(xy 325.816202 6.132607) (xy 325.747773 6.080931) (xy 325.674867 6.03579) (xy 325.598107 5.997568)
			(xy 325.518148 5.966592) (xy 325.435672 5.943125) (xy 325.351382 5.927369) (xy 325.265999 5.919457)
			(xy 325.180249 5.919457) (xy 325.094866 5.927369) (xy 325.010576 5.943125) (xy 324.9281 5.966592)
			(xy 324.848141 5.997568) (xy 324.771381 6.03579) (xy 324.698475 6.080931) (xy 324.630046 6.132607)
			(xy 324.566676 6.190376) (xy 324.508907 6.253746) (xy 324.457231 6.322175) (xy 324.41209 6.395081)
			(xy 324.373868 6.471841) (xy 324.342892 6.5518) (xy 324.319425 6.634276) (xy 324.303669 6.718566)
			(xy 324.295757 6.803949) (xy 317.930117 6.803949) (xy 317.930035 6.796837) (xy 317.922123 6.711454)
			(xy 317.906367 6.627164) (xy 317.8829 6.544688) (xy 317.851924 6.464729) (xy 317.813702 6.387969)
			(xy 317.768561 6.315063) (xy 317.716885 6.246634) (xy 317.659116 6.183264) (xy 317.595746 6.125495)
			(xy 317.527317 6.073819) (xy 317.454411 6.028678) (xy 317.377651 5.990456) (xy 317.297692 5.95948)
			(xy 317.215216 5.936013) (xy 317.130926 5.920257) (xy 317.045543 5.912345) (xy 316.959793 5.912345)
			(xy 316.87441 5.920257) (xy 316.79012 5.936013) (xy 316.707644 5.95948) (xy 316.627685 5.990456)
			(xy 316.550925 6.028678) (xy 316.478019 6.073819) (xy 316.40959 6.125495) (xy 316.34622 6.183264)
			(xy 316.288451 6.246634) (xy 316.236775 6.315063) (xy 316.191634 6.387969) (xy 316.153412 6.464729)
			(xy 316.122436 6.544688) (xy 316.098969 6.627164) (xy 316.083213 6.711454) (xy 316.075301 6.796837)
			(xy 311.580035 6.796837) (xy 311.572123 6.711454) (xy 311.556367 6.627164) (xy 311.5329 6.544688)
			(xy 311.501924 6.464729) (xy 311.463702 6.387969) (xy 311.418561 6.315063) (xy 311.366885 6.246634)
			(xy 311.309116 6.183264) (xy 311.245746 6.125495) (xy 311.177317 6.073819) (xy 311.104411 6.028678)
			(xy 311.027651 5.990456) (xy 310.947692 5.95948) (xy 310.865216 5.936013) (xy 310.780926 5.920257)
			(xy 310.695543 5.912345) (xy 310.609793 5.912345) (xy 310.52441 5.920257) (xy 310.44012 5.936013)
			(xy 310.357644 5.95948) (xy 310.277685 5.990456) (xy 310.200925 6.028678) (xy 310.128019 6.073819)
			(xy 310.05959 6.125495) (xy 309.99622 6.183264) (xy 309.938451 6.246634) (xy 309.886775 6.315063)
			(xy 309.841634 6.387969) (xy 309.803412 6.464729) (xy 309.772436 6.544688) (xy 309.748969 6.627164)
			(xy 309.733213 6.711454) (xy 309.725301 6.796837) (xy 259.72979 6.796837) (xy 259.729491 6.770929)
			(xy 259.721579 6.685546) (xy 259.705823 6.601256) (xy 259.682356 6.51878) (xy 259.65138 6.438821)
			(xy 259.613158 6.362061) (xy 259.568017 6.289155) (xy 259.516341 6.220726) (xy 259.458572 6.157356)
			(xy 259.395202 6.099587) (xy 259.326773 6.047911) (xy 259.253867 6.00277) (xy 259.177107 5.964548)
			(xy 259.097148 5.933572) (xy 259.014672 5.910105) (xy 258.930382 5.894349) (xy 258.844999 5.886437)
			(xy 258.759249 5.886437) (xy 258.673866 5.894349) (xy 258.589576 5.910105) (xy 258.5071 5.933572)
			(xy 258.427141 5.964548) (xy 258.350381 6.00277) (xy 258.277475 6.047911) (xy 258.209046 6.099587)
			(xy 258.145676 6.157356) (xy 258.087907 6.220726) (xy 258.036231 6.289155) (xy 257.99109 6.362061)
			(xy 257.952868 6.438821) (xy 257.921892 6.51878) (xy 257.898425 6.601256) (xy 257.882669 6.685546)
			(xy 257.874757 6.770929) (xy 253.379491 6.770929) (xy 253.371579 6.685546) (xy 253.355823 6.601256)
			(xy 253.332356 6.51878) (xy 253.30138 6.438821) (xy 253.263158 6.362061) (xy 253.218017 6.289155)
			(xy 253.166341 6.220726) (xy 253.108572 6.157356) (xy 253.045202 6.099587) (xy 252.976773 6.047911)
			(xy 252.903867 6.00277) (xy 252.827107 5.964548) (xy 252.747148 5.933572) (xy 252.664672 5.910105)
			(xy 252.580382 5.894349) (xy 252.494999 5.886437) (xy 252.409249 5.886437) (xy 252.323866 5.894349)
			(xy 252.239576 5.910105) (xy 252.1571 5.933572) (xy 252.077141 5.964548) (xy 252.000381 6.00277)
			(xy 251.927475 6.047911) (xy 251.859046 6.099587) (xy 251.795676 6.157356) (xy 251.737907 6.220726)
			(xy 251.686231 6.289155) (xy 251.64109 6.362061) (xy 251.602868 6.438821) (xy 251.571892 6.51878)
			(xy 251.548425 6.601256) (xy 251.532669 6.685546) (xy 251.524757 6.770929) (xy 245.921117 6.770929)
			(xy 245.921035 6.763817) (xy 245.913123 6.678434) (xy 245.897367 6.594144) (xy 245.8739 6.511668)
			(xy 245.842924 6.431709) (xy 245.804702 6.354949) (xy 245.759561 6.282043) (xy 245.707885 6.213614)
			(xy 245.650116 6.150244) (xy 245.586746 6.092475) (xy 245.518317 6.040799) (xy 245.445411 5.995658)
			(xy 245.368651 5.957436) (xy 245.288692 5.92646) (xy 245.206216 5.902993) (xy 245.121926 5.887237)
			(xy 245.036543 5.879325) (xy 244.950793 5.879325) (xy 244.86541 5.887237) (xy 244.78112 5.902993)
			(xy 244.698644 5.92646) (xy 244.618685 5.957436) (xy 244.541925 5.995658) (xy 244.469019 6.040799)
			(xy 244.40059 6.092475) (xy 244.33722 6.150244) (xy 244.279451 6.213614) (xy 244.227775 6.282043)
			(xy 244.182634 6.354949) (xy 244.144412 6.431709) (xy 244.113436 6.511668) (xy 244.089969 6.594144)
			(xy 244.074213 6.678434) (xy 244.066301 6.763817) (xy 239.571035 6.763817) (xy 239.563123 6.678434)
			(xy 239.547367 6.594144) (xy 239.5239 6.511668) (xy 239.492924 6.431709) (xy 239.454702 6.354949)
			(xy 239.409561 6.282043) (xy 239.357885 6.213614) (xy 239.300116 6.150244) (xy 239.236746 6.092475)
			(xy 239.168317 6.040799) (xy 239.095411 5.995658) (xy 239.018651 5.957436) (xy 238.938692 5.92646)
			(xy 238.856216 5.902993) (xy 238.771926 5.887237) (xy 238.686543 5.879325) (xy 238.600793 5.879325)
			(xy 238.51541 5.887237) (xy 238.43112 5.902993) (xy 238.348644 5.92646) (xy 238.268685 5.957436)
			(xy 238.191925 5.995658) (xy 238.119019 6.040799) (xy 238.05059 6.092475) (xy 237.98722 6.150244)
			(xy 237.929451 6.213614) (xy 237.877775 6.282043) (xy 237.832634 6.354949) (xy 237.794412 6.431709)
			(xy 237.763436 6.511668) (xy 237.739969 6.594144) (xy 237.724213 6.678434) (xy 237.716301 6.763817)
			(xy 187.719832 6.763817) (xy 187.712579 6.685546) (xy 187.696823 6.601256) (xy 187.673356 6.51878)
			(xy 187.64238 6.438821) (xy 187.604158 6.362061) (xy 187.559017 6.289155) (xy 187.507341 6.220726)
			(xy 187.449572 6.157356) (xy 187.386202 6.099587) (xy 187.317773 6.047911) (xy 187.244867 6.00277)
			(xy 187.168107 5.964548) (xy 187.088148 5.933572) (xy 187.005672 5.910105) (xy 186.921382 5.894349)
			(xy 186.835999 5.886437) (xy 186.750249 5.886437) (xy 186.664866 5.894349) (xy 186.580576 5.910105)
			(xy 186.4981 5.933572) (xy 186.418141 5.964548) (xy 186.341381 6.00277) (xy 186.268475 6.047911)
			(xy 186.200046 6.099587) (xy 186.136676 6.157356) (xy 186.078907 6.220726) (xy 186.027231 6.289155)
			(xy 185.98209 6.362061) (xy 185.943868 6.438821) (xy 185.912892 6.51878) (xy 185.889425 6.601256)
			(xy 185.873669 6.685546) (xy 185.865757 6.770929) (xy 181.370491 6.770929) (xy 181.362579 6.685546)
			(xy 181.346823 6.601256) (xy 181.323356 6.51878) (xy 181.29238 6.438821) (xy 181.254158 6.362061)
			(xy 181.209017 6.289155) (xy 181.157341 6.220726) (xy 181.099572 6.157356) (xy 181.036202 6.099587)
			(xy 180.967773 6.047911) (xy 180.894867 6.00277) (xy 180.818107 5.964548) (xy 180.738148 5.933572)
			(xy 180.655672 5.910105) (xy 180.571382 5.894349) (xy 180.485999 5.886437) (xy 180.400249 5.886437)
			(xy 180.314866 5.894349) (xy 180.230576 5.910105) (xy 180.1481 5.933572) (xy 180.068141 5.964548)
			(xy 179.991381 6.00277) (xy 179.918475 6.047911) (xy 179.850046 6.099587) (xy 179.786676 6.157356)
			(xy 179.728907 6.220726) (xy 179.677231 6.289155) (xy 179.63209 6.362061) (xy 179.593868 6.438821)
			(xy 179.562892 6.51878) (xy 179.539425 6.601256) (xy 179.523669 6.685546) (xy 179.515757 6.770929)
			(xy 158.039844 6.770929) (xy 158.030561 6.759289) (xy 157.936801 6.654373) (xy 157.837306 6.554879)
			(xy 157.732388 6.46112) (xy 157.622379 6.373391) (xy 157.507624 6.291969) (xy 157.388483 6.21711)
			(xy 157.265333 6.149048) (xy 157.138561 6.087998) (xy 157.008565 6.034153) (xy 156.875754 5.987681)
			(xy 156.740546 5.948729) (xy 156.603367 5.91742) (xy 156.464649 5.893851) (xy 156.324827 5.878098)
			(xy 156.184341 5.870209) (xy 156.113988 5.869686) (xy 17.493996 5.869686) (xy 17.423642 5.870179)
			(xy 17.283156 5.878069) (xy 17.143333 5.893824) (xy 17.004613 5.917393) (xy 16.867433 5.948703) (xy 16.732225 5.987656)
			(xy 16.599413 6.034129) (xy 16.469416 6.087976) (xy 16.342643 6.149026) (xy 16.219492 6.217089) (xy 16.100351 6.29195)
			(xy 15.985596 6.373373) (xy 15.875586 6.461103) (xy 15.770668 6.554863) (xy 15.671172 6.654358) (xy 15.577412 6.759275)
			(xy 15.489682 6.869284) (xy 15.408258 6.98404) (xy 15.333396 7.10318) (xy 15.265333 7.22633) (xy 15.204281 7.353103)
			(xy 15.150434 7.4831) (xy 15.103961 7.615912) (xy 15.065007 7.75112) (xy 15.033696 7.8883) (xy 15.010125 8.027019)
			(xy 14.99437 8.166842) (xy 14.98648 8.307328) (xy 14.986 8.377682) (xy 14.986 24.157686) (xy 14.985478 24.213493)
			(xy 14.977137 24.324795) (xy 14.960501 24.435162) (xy 14.935664 24.543977) (xy 14.902765 24.650632)
			(xy 14.861988 24.754531) (xy 14.81356 24.855091) (xy 14.757753 24.951752) (xy 14.694879 25.043971)
			(xy 14.625289 25.131234) (xy 14.549372 25.213053) (xy 14.467553 25.28897) (xy 14.38029 25.35856)
			(xy 14.28807 25.421434) (xy 14.19141 25.477241) (xy 14.090849 25.525669) (xy 13.986951 25.566446)
			(xy 13.880295 25.599345) (xy 13.77148 25.624182) (xy 13.661113 25.640817) (xy 13.549811 25.649158)
			(xy 13.494004 25.649682) (xy 1.999996 25.649682) (xy 1.944189 25.64916) (xy 1.832887 25.640819) (xy 1.72252 25.624184)
			(xy 1.613704 25.599347) (xy 1.507049 25.566448) (xy 1.40315 25.525671) (xy 1.30259 25.477243) (xy 1.205929 25.421436)
			(xy 1.113709 25.358562) (xy 1.026446 25.288971) (xy 0.944627 25.213055) (xy 0.86871 25.131236) (xy 0.79912 25.043972)
			(xy 0.736245 24.951753) (xy 0.680438 24.855092) (xy 0.63201 24.754532) (xy 0.591233 24.650633) (xy 0.558334 24.543978)
			(xy 0.533497 24.435162) (xy 0.516861 24.324795) (xy 0.50852 24.213493) (xy 0.508 24.157686) (xy 0.508 21.093122)
			(xy 2.904225 21.093122) (xy 2.904225 21.222262) (xy 2.912175 21.351157) (xy 2.928045 21.479317) (xy 2.951774 21.606258)
			(xy 2.983273 21.731497) (xy 3.022422 21.85456) (xy 3.069073 21.974979) (xy 3.123048 22.092298) (xy 3.184143 22.206072)
			(xy 3.252126 22.315869) (xy 3.32674 22.421272) (xy 3.407701 22.521882) (xy 3.494701 22.617317) (xy 3.587412 22.707216)
			(xy 3.685482 22.791237) (xy 3.788537 22.869061) (xy 3.896188 22.940393) (xy 4.008027 23.004963) (xy 4.123628 23.062525)
			(xy 4.242553 23.112862) (xy 4.364352 23.155782) (xy 4.488562 23.191123) (xy 4.614711 23.21875) (xy 4.742323 23.238559)
			(xy 4.870912 23.250475) (xy 4.99999 23.254452) (xy 5.129068 23.250475) (xy 5.257657 23.238559) (xy 5.385269 23.21875)
			(xy 5.511418 23.191123) (xy 5.635628 23.155782) (xy 5.757427 23.112862) (xy 5.876352 23.062525) (xy 5.991953 23.004963)
			(xy 6.103792 22.940393) (xy 6.211443 22.869061) (xy 6.314498 22.791237) (xy 6.412568 22.707216) (xy 6.505279 22.617317)
			(xy 6.592279 22.521882) (xy 6.67324 22.421272) (xy 6.747854 22.315869) (xy 6.815837 22.206072) (xy 6.876932 22.092298)
			(xy 6.930907 21.974979) (xy 6.977558 21.85456) (xy 7.016707 21.731497) (xy 7.048206 21.606258) (xy 7.071935 21.479317)
			(xy 7.087805 21.351157) (xy 7.095755 21.222262) (xy 7.096252 21.157692) (xy 7.095755 21.093122) (xy 7.087805 20.964227)
			(xy 7.071935 20.836067) (xy 7.048206 20.709126) (xy 7.016707 20.583887) (xy 6.977558 20.460824) (xy 6.930907 20.340405)
			(xy 6.876932 20.223086) (xy 6.815837 20.109312) (xy 6.747854 19.999515) (xy 6.67324 19.894112) (xy 6.592279 19.793502)
			(xy 6.505279 19.698067) (xy 6.412568 19.608168) (xy 6.314498 19.524147) (xy 6.211443 19.446323) (xy 6.103792 19.374991)
			(xy 5.991953 19.310421) (xy 5.876352 19.252859) (xy 5.757427 19.202522) (xy 5.635628 19.159602) (xy 5.511418 19.124261)
			(xy 5.385269 19.096634) (xy 5.257657 19.076825) (xy 5.129068 19.064909) (xy 4.99999 19.060933) (xy 4.870912 19.064909)
			(xy 4.742323 19.076825) (xy 4.614711 19.096634) (xy 4.488562 19.124261) (xy 4.364352 19.159602) (xy 4.242553 19.202522)
			(xy 4.123628 19.252859) (xy 4.008027 19.310421) (xy 3.896188 19.374991) (xy 3.788537 19.446323) (xy 3.685482 19.524147)
			(xy 3.587412 19.608168) (xy 3.494701 19.698067) (xy 3.407701 19.793502) (xy 3.32674 19.894112) (xy 3.252126 19.999515)
			(xy 3.184143 20.109312) (xy 3.123048 20.223086) (xy 3.069073 20.340405) (xy 3.022422 20.460824) (xy 2.983273 20.583887)
			(xy 2.951774 20.709126) (xy 2.928045 20.836067) (xy 2.912175 20.964227) (xy 2.904225 21.093122) (xy 0.508 21.093122)
			(xy 0.508 3.999992) (xy 0.508522 3.944185) (xy 0.516863 3.832883) (xy 0.533498 3.722516) (xy 0.558335 3.6137)
			(xy 0.591234 3.507045) (xy 0.632011 3.403146) (xy 0.680438 3.302586) (xy 0.736246 3.205925) (xy 0.79912 3.113705)
			(xy 0.86871 3.026442) (xy 0.944627 2.944623) (xy 1.026446 2.868706) (xy 1.113709 2.799116) (xy 1.205929 2.736242)
			(xy 1.30259 2.680434) (xy 1.40315 2.632007) (xy 1.507049 2.59123) (xy 1.613704 2.558331) (xy 1.72252 2.533494)
			(xy 1.832887 2.516859) (xy 1.944189 2.508518) (xy 1.999996 2.507996) (xy 7.964932 2.507996) (xy 8.035286 2.507503)
			(xy 8.175772 2.499613) (xy 8.315594 2.483859) (xy 8.454314 2.460289) (xy 8.591493 2.428979) (xy 8.726701 2.390026)
			(xy 8.859513 2.343553) (xy 8.989509 2.289707) (xy 9.116282 2.228656) (xy 9.239433 2.160593) (xy 9.358573 2.085732)
			(xy 9.473329 2.004309) (xy 9.583338 1.916579) (xy 9.688255 1.822819) (xy 9.78775 1.723324) (xy 9.88151 1.618406)
			(xy 9.96924 1.508397) (xy 10.050663 1.393641) (xy 10.125524 1.274501) (xy 10.193587 1.151351) (xy 10.254637 1.024578)
			(xy 10.308484 0.894581) (xy 10.354957 0.76177) (xy 10.393909 0.626561) (xy 10.42522 0.489382) (xy 10.448789 0.350662)
			(xy 10.464543 0.21084) (xy 10.472433 0.070354) (xy 10.472928 0) (xy 10.472928 -8.850122) (xy 10.47345 -8.905929)
			(xy 10.481791 -9.017231) (xy 10.498426 -9.127599) (xy 10.523263 -9.236414) (xy 10.556162 -9.34307)
			(xy 10.596939 -9.446968) (xy 10.645366 -9.547529) (xy 10.701173 -9.64419) (xy 10.764048 -9.73641)
			(xy 10.833638 -9.823673) (xy 10.909555 -9.905492) (xy 10.991374 -9.981409) (xy 11.078637 -10.051)
			(xy 11.170857 -10.113875) (xy 11.267517 -10.169682) (xy 11.368078 -10.21811) (xy 11.471977 -10.258887)
			(xy 11.578632 -10.291786) (xy 11.687448 -10.316623) (xy 11.797815 -10.333259) (xy 11.909117 -10.3416)
			(xy 11.964924 -10.342118)
		)
		(stroke
			(width 0)
			(type solid)
		)
		(fill yes)
		(layer "In6.Cu")
		(net "COUPON_GND2")
	)
	(gr_poly
		(pts
			(xy 200.481692 -418.081968) (xy 200.538276 -418.081432) (xy 200.651116 -418.072836) (xy 200.76298 -418.055715)
			(xy 200.873227 -418.030169) (xy 200.98122 -417.996343) (xy 201.086341 -417.954433) (xy 201.187984 -417.904678)
			(xy 201.285565 -417.847366) (xy 201.378524 -417.782825) (xy 201.466326 -417.711427) (xy 201.548466 -417.633582)
			(xy 201.586846 -417.592002) (xy 201.634058 -417.54062) (xy 201.733379 -417.442584) (xy 201.837997 -417.350223)
			(xy 201.947589 -417.26382) (xy 202.061814 -417.183644) (xy 202.18032 -417.109943) (xy 202.302741 -417.042944)
			(xy 202.428697 -416.982855) (xy 202.557798 -416.929861) (xy 202.689647 -416.884127) (xy 202.823834 -416.845794)
			(xy 202.959945 -416.81498) (xy 203.097558 -416.791782) (xy 203.236248 -416.77627) (xy 203.375587 -416.768492)
			(xy 203.445364 -416.768026) (xy 271.794732 -416.768026) (xy 271.864502 -416.768512) (xy 272.003824 -416.776289)
			(xy 272.142499 -416.791801) (xy 272.280097 -416.814999) (xy 272.416192 -416.845812) (xy 272.550363 -416.884144)
			(xy 272.682195 -416.929877) (xy 272.811281 -416.982869) (xy 272.937221 -417.042957) (xy 273.059624 -417.109954)
			(xy 273.178113 -417.183654) (xy 273.292321 -417.263827) (xy 273.401895 -417.350227) (xy 273.434939 -417.379404)
			(xy 313.073796 -417.379404) (xy 313.073796 -394.27912) (xy 326.479662 -394.27912) (xy 326.525636 -394.325094)
			(xy 326.525636 -397.823826) (xy 330.929171 -397.823826) (xy 330.929175 -397.756517) (xy 330.937223 -397.689692)
			(xy 330.953201 -397.624307) (xy 330.976879 -397.561301) (xy 331.007918 -397.501576) (xy 331.045873 -397.44599)
			(xy 331.067664 -397.420338) (xy 331.073477 -397.413205) (xy 331.07998 -397.396005) (xy 331.080364 -397.38681)
			(xy 331.080364 -396.893542) (xy 331.079919 -396.884359) (xy 331.073428 -396.867175) (xy 331.067664 -396.860014)
			(xy 331.045866 -396.83437) (xy 331.007916 -396.778783) (xy 330.976881 -396.719059) (xy 330.953208 -396.656053)
			(xy 330.937235 -396.59067) (xy 330.929191 -396.523846) (xy 330.929192 -396.456539) (xy 330.937238 -396.389716)
			(xy 330.953213 -396.324333) (xy 330.976888 -396.261328) (xy 331.007923 -396.201604) (xy 331.045875 -396.146018)
			(xy 331.067664 -396.120366) (xy 331.073465 -396.113225) (xy 331.079975 -396.096031) (xy 331.080364 -396.086838)
			(xy 331.080364 -395.92885) (xy 331.080805 -395.918678) (xy 331.088579 -395.89988) (xy 331.10296 -395.885492)
			(xy 331.121755 -395.87771) (xy 331.131926 -395.877288) (xy 331.848206 -395.877288) (xy 331.858384 -395.87766)
			(xy 331.877189 -395.885456) (xy 331.891575 -395.899859) (xy 331.899351 -395.918671) (xy 331.899768 -395.92885)
			(xy 331.899768 -396.086838) (xy 331.900167 -396.096026) (xy 331.906689 -396.11321) (xy 331.912468 -396.120366)
			(xy 331.934246 -396.146026) (xy 331.972195 -396.201612) (xy 332.003228 -396.261334) (xy 332.026901 -396.324338)
			(xy 332.042874 -396.389719) (xy 332.050919 -396.45654) (xy 332.05092 -396.523845) (xy 332.042877 -396.590666)
			(xy 332.026905 -396.656048) (xy 332.003234 -396.719052) (xy 331.972202 -396.778775) (xy 331.934255 -396.834362)
			(xy 331.912468 -396.860014) (xy 331.906679 -396.867164) (xy 331.90016 -396.884351) (xy 331.899768 -396.893542)
			(xy 331.899768 -397.38681) (xy 331.90018 -397.395997) (xy 331.906693 -397.413181) (xy 331.912468 -397.420338)
			(xy 331.934218 -397.446021) (xy 331.972167 -397.501603) (xy 332.00059 -397.556296) (xy 333.128836 -397.556296)
			(xy 333.136911 -397.489358) (xy 333.152946 -397.423869) (xy 333.17671 -397.360773) (xy 333.20786 -397.300977)
			(xy 333.245948 -397.245343) (xy 333.267812 -397.219678) (xy 333.273602 -397.212528) (xy 333.28012 -397.195341)
			(xy 333.280512 -397.18615) (xy 333.280512 -397.028924) (xy 333.280936 -397.018802) (xy 333.288678 -397.000096)
			(xy 333.302993 -396.985781) (xy 333.321698 -396.978037) (xy 333.33182 -396.977616) (xy 334.0481 -396.977616)
			(xy 334.058224 -396.978016) (xy 334.076931 -396.985768) (xy 334.091246 -397.000089) (xy 334.098988 -397.018799)
			(xy 334.099408 -397.028924) (xy 334.099408 -397.18615) (xy 334.09984 -397.195335) (xy 334.106338 -397.21252)
			(xy 334.112108 -397.219678) (xy 334.133982 -397.245335) (xy 334.172069 -397.300971) (xy 334.203219 -397.360769)
			(xy 334.226982 -397.423866) (xy 334.243017 -397.489356) (xy 334.251092 -397.556295) (xy 334.251091 -397.62372)
			(xy 334.243014 -397.690658) (xy 334.226978 -397.756148) (xy 334.203213 -397.819245) (xy 334.200796 -397.823884)
			(xy 335.328964 -397.823884) (xy 335.328968 -397.756459) (xy 335.337047 -397.689518) (xy 335.353085 -397.624028)
			(xy 335.376852 -397.560929) (xy 335.408005 -397.501132) (xy 335.446095 -397.445496) (xy 335.46796 -397.41983)
			(xy 335.473776 -397.412699) (xy 335.480277 -397.395497) (xy 335.48066 -397.386302) (xy 335.48066 -396.89405)
			(xy 335.480213 -396.884867) (xy 335.473723 -396.867683) (xy 335.46796 -396.860522) (xy 335.446088 -396.834864)
			(xy 335.408002 -396.779228) (xy 335.376854 -396.71943) (xy 335.353092 -396.656332) (xy 335.337058 -396.590843)
			(xy 335.328984 -396.523904) (xy 335.328985 -396.456481) (xy 335.337061 -396.389542) (xy 335.353096 -396.324053)
			(xy 335.37686 -396.260956) (xy 335.40801 -396.201159) (xy 335.446097 -396.145524) (xy 335.46796 -396.119858)
			(xy 335.473764 -396.112719) (xy 335.480273 -396.095523) (xy 335.48066 -396.08633) (xy 335.48066 -395.92885)
			(xy 335.481168 -395.918724) (xy 335.488883 -395.9) (xy 335.503164 -395.885642) (xy 335.521845 -395.877824)
			(xy 335.531968 -395.877288) (xy 336.248248 -395.877288) (xy 336.258404 -395.877682) (xy 336.277155 -395.885491)
			(xy 336.291476 -395.899896) (xy 336.299176 -395.918692) (xy 336.299556 -395.92885) (xy 336.299556 -396.08633)
			(xy 336.299962 -396.095517) (xy 336.30648 -396.112701) (xy 336.312256 -396.119858) (xy 336.334112 -396.145531)
			(xy 336.372204 -396.201163) (xy 336.403357 -396.260958) (xy 336.427124 -396.324054) (xy 336.443161 -396.389542)
			(xy 336.451239 -396.456481) (xy 336.45124 -396.523904) (xy 336.443164 -396.590843) (xy 336.427128 -396.656332)
			(xy 336.403363 -396.719428) (xy 336.372211 -396.779224) (xy 336.334121 -396.834858) (xy 336.312256 -396.860522)
			(xy 336.306462 -396.867669) (xy 336.299947 -396.884858) (xy 336.299556 -396.89405) (xy 336.299556 -397.386302)
			(xy 336.299975 -397.395488) (xy 336.306484 -397.412672) (xy 336.312256 -397.41983) (xy 336.334084 -397.445525)
			(xy 336.372177 -397.501154) (xy 336.40094 -397.556356) (xy 337.529156 -397.556356) (xy 337.537198 -397.489535)
			(xy 337.553169 -397.424153) (xy 337.576839 -397.361149) (xy 337.607869 -397.301426) (xy 337.645814 -397.245839)
			(xy 337.6676 -397.220186) (xy 337.673385 -397.213033) (xy 337.679907 -397.195848) (xy 337.6803 -397.186658)
			(xy 337.6803 -397.028924) (xy 337.680741 -397.018771) (xy 337.688529 -397.000019) (xy 337.70292 -396.985695)
			(xy 337.721708 -396.977995) (xy 337.731862 -396.977616) (xy 338.448142 -396.977616) (xy 338.458268 -396.978091)
			(xy 338.476986 -396.985829) (xy 338.49134 -397.000118) (xy 338.499162 -397.0188) (xy 338.499704 -397.028924)
			(xy 338.499704 -397.186658) (xy 338.500133 -397.195843) (xy 338.506634 -397.213028) (xy 338.512404 -397.220186)
			(xy 338.5342 -397.245831) (xy 338.572146 -397.301419) (xy 338.603176 -397.361144) (xy 338.626847 -397.42415)
			(xy 338.642818 -397.489532) (xy 338.65086 -397.556355) (xy 338.650859 -397.62366) (xy 338.642815 -397.690483)
			(xy 338.626842 -397.755865) (xy 338.60317 -397.81887) (xy 338.600595 -397.823826) (xy 339.729259 -397.823826)
			(xy 339.729263 -397.756517) (xy 339.737311 -397.689692) (xy 339.753288 -397.624308) (xy 339.776965 -397.561301)
			(xy 339.808004 -397.501577) (xy 339.845958 -397.44599) (xy 339.867748 -397.420338) (xy 339.873559 -397.413204)
			(xy 339.880064 -397.396005) (xy 339.880448 -397.38681) (xy 339.880448 -396.893542) (xy 339.880007 -396.884358)
			(xy 339.873513 -396.867174) (xy 339.867748 -396.860014) (xy 339.84595 -396.83437) (xy 339.808001 -396.778783)
			(xy 339.776968 -396.719058) (xy 339.753295 -396.656052) (xy 339.737322 -396.590669) (xy 339.729279 -396.523845)
			(xy 339.72928 -396.456539) (xy 339.737325 -396.389716) (xy 339.753299 -396.324333) (xy 339.776974 -396.261328)
			(xy 339.808009 -396.201604) (xy 339.845959 -396.146018) (xy 339.867748 -396.120366) (xy 339.873547 -396.113223)
			(xy 339.880059 -396.096031) (xy 339.880448 -396.086838) (xy 339.880448 -395.92885) (xy 339.880905 -395.91868)
			(xy 339.888675 -395.899885) (xy 339.903051 -395.885498) (xy 339.921841 -395.877713) (xy 339.93201 -395.877288)
			(xy 340.64829 -395.877288) (xy 340.658467 -395.877673) (xy 340.677271 -395.885464) (xy 340.691658 -395.899862)
			(xy 340.699435 -395.918672) (xy 340.699852 -395.92885) (xy 340.699852 -396.086838) (xy 340.700255 -396.096026)
			(xy 340.706775 -396.113209) (xy 340.712552 -396.120366) (xy 340.73433 -396.146026) (xy 340.77228 -396.201611)
			(xy 340.803314 -396.261334) (xy 340.826988 -396.324337) (xy 340.842962 -396.389718) (xy 340.851007 -396.45654)
			(xy 340.851007 -396.523845) (xy 340.842964 -396.590667) (xy 340.826992 -396.656048) (xy 340.80332 -396.719053)
			(xy 340.772287 -396.778776) (xy 340.734339 -396.834362) (xy 340.712552 -396.860014) (xy 340.706761 -396.867163)
			(xy 340.700244 -396.884351) (xy 340.699852 -396.893542) (xy 340.699852 -397.38681) (xy 340.700268 -397.395996)
			(xy 340.706779 -397.41318) (xy 340.712552 -397.420338) (xy 340.734302 -397.446021) (xy 340.772253 -397.501603)
			(xy 340.800676 -397.556296) (xy 341.928924 -397.556296) (xy 341.936999 -397.489359) (xy 341.953033 -397.42387)
			(xy 341.976796 -397.360774) (xy 342.007946 -397.300978) (xy 342.046033 -397.245343) (xy 342.067896 -397.219678)
			(xy 342.073684 -397.212527) (xy 342.080204 -397.195341) (xy 342.080596 -397.18615) (xy 342.080596 -397.028924)
			(xy 342.081035 -397.018804) (xy 342.088775 -397.000101) (xy 342.103084 -396.985786) (xy 342.121784 -396.978039)
			(xy 342.131904 -396.977616) (xy 342.848184 -396.977616) (xy 342.858307 -396.978029) (xy 342.877014 -396.985775)
			(xy 342.891329 -397.000093) (xy 342.899072 -397.0188) (xy 342.899492 -397.028924) (xy 342.899492 -397.18615)
			(xy 342.899928 -397.195334) (xy 342.906424 -397.212519) (xy 342.912192 -397.219678) (xy 342.934066 -397.245335)
			(xy 342.972155 -397.300971) (xy 343.003306 -397.360768) (xy 343.02707 -397.423866) (xy 343.043105 -397.489356)
			(xy 343.05118 -397.556295) (xy 343.051179 -397.62372) (xy 343.043102 -397.690659) (xy 343.027065 -397.756149)
			(xy 343.0033 -397.819246) (xy 343.000914 -397.823825) (xy 344.12905 -397.823825) (xy 344.129054 -397.756517)
			(xy 344.137101 -397.689692) (xy 344.153078 -397.624308) (xy 344.176755 -397.561302) (xy 344.207793 -397.501577)
			(xy 344.245746 -397.44599) (xy 344.267536 -397.420338) (xy 344.273346 -397.413202) (xy 344.279852 -397.396004)
			(xy 344.280236 -397.38681) (xy 344.280236 -396.893542) (xy 344.279797 -396.884358) (xy 344.273303 -396.867174)
			(xy 344.267536 -396.860014) (xy 344.245738 -396.83437) (xy 344.20779 -396.778782) (xy 344.176757 -396.719058)
			(xy 344.153085 -396.656052) (xy 344.137113 -396.590669) (xy 344.12907 -396.523845) (xy 344.129071 -396.45654)
			(xy 344.137116 -396.389716) (xy 344.15309 -396.324334) (xy 344.176764 -396.261329) (xy 344.207798 -396.201605)
			(xy 344.245748 -396.146018) (xy 344.267536 -396.120366) (xy 344.273334 -396.113222) (xy 344.279847 -396.09603)
			(xy 344.280236 -396.086838) (xy 344.280236 -395.92885) (xy 344.280705 -395.918682) (xy 344.288473 -395.899889)
			(xy 344.302845 -395.885502) (xy 344.32163 -395.877715) (xy 344.331798 -395.877288) (xy 345.048078 -395.877288)
			(xy 345.058254 -395.877683) (xy 345.077058 -395.88547) (xy 345.091445 -395.899866) (xy 345.099222 -395.918673)
			(xy 345.09964 -395.92885) (xy 345.09964 -396.086838) (xy 345.100045 -396.096025) (xy 345.106564 -396.113209)
			(xy 345.11234 -396.120366) (xy 345.134118 -396.146026) (xy 345.172069 -396.201611) (xy 345.203104 -396.261333)
			(xy 345.226778 -396.324337) (xy 345.242752 -396.389718) (xy 345.250798 -396.45654) (xy 345.250798 -396.523845)
			(xy 345.242755 -396.590667) (xy 345.226782 -396.656049) (xy 345.20311 -396.719053) (xy 345.172077 -396.778776)
			(xy 345.134128 -396.834362) (xy 345.11234 -396.860014) (xy 345.106548 -396.867162) (xy 345.100032 -396.884351)
			(xy 345.09964 -396.893542) (xy 345.09964 -397.38681) (xy 345.100059 -397.395996) (xy 345.106568 -397.41318)
			(xy 345.11234 -397.420338) (xy 345.134091 -397.446021) (xy 345.172042 -397.501602) (xy 345.200497 -397.556355)
			(xy 346.32922 -397.556355) (xy 346.337264 -397.489532) (xy 346.353237 -397.42415) (xy 346.37691 -397.361146)
			(xy 346.407945 -397.301423) (xy 346.445896 -397.245838) (xy 346.467684 -397.220186) (xy 346.473467 -397.213031)
			(xy 346.47999 -397.195848) (xy 346.480384 -397.186658) (xy 346.480384 -397.028924) (xy 346.480841 -397.018773)
			(xy 346.488625 -397.000025) (xy 346.503011 -396.985701) (xy 346.521794 -396.977997) (xy 346.531946 -396.977616)
			(xy 347.248226 -396.977616) (xy 347.258351 -396.978104) (xy 347.277069 -396.985836) (xy 347.291423 -397.000121)
			(xy 347.299246 -397.018801) (xy 347.299788 -397.028924) (xy 347.299788 -397.186658) (xy 347.300221 -397.195843)
			(xy 347.306719 -397.213027) (xy 347.312488 -397.220186) (xy 347.334285 -397.24583) (xy 347.372232 -397.301419)
			(xy 347.403263 -397.361143) (xy 347.426934 -397.424149) (xy 347.442905 -397.489532) (xy 347.450948 -397.556355)
			(xy 347.450947 -397.62366) (xy 347.442903 -397.690483) (xy 347.426929 -397.755865) (xy 347.403257 -397.81887)
			(xy 347.400682 -397.823826) (xy 374.92908 -397.823826) (xy 374.929084 -397.756517) (xy 374.937132 -397.689691)
			(xy 374.95311 -397.624306) (xy 374.976789 -397.5613) (xy 375.007829 -397.501576) (xy 375.045785 -397.445989)
			(xy 375.067576 -397.420338) (xy 375.073379 -397.413197) (xy 375.07989 -397.396003) (xy 375.080276 -397.38681)
			(xy 375.080276 -396.893542) (xy 375.079851 -396.884356) (xy 375.073348 -396.867171) (xy 375.067576 -396.860014)
			(xy 375.045777 -396.83437) (xy 375.007826 -396.778784) (xy 374.976792 -396.719059) (xy 374.953118 -396.656053)
			(xy 374.937144 -396.59067) (xy 374.9291 -396.523846) (xy 374.929101 -396.456539) (xy 374.937147 -396.389715)
			(xy 374.953122 -396.324332) (xy 374.976798 -396.261327) (xy 375.007834 -396.201604) (xy 375.045787 -396.146018)
			(xy 375.067576 -396.120366) (xy 375.073367 -396.113216) (xy 375.079886 -396.096029) (xy 375.080276 -396.086838)
			(xy 375.080276 -395.92885) (xy 375.080706 -395.918677) (xy 375.088481 -395.899876) (xy 375.102866 -395.885488)
			(xy 375.121665 -395.877708) (xy 375.131838 -395.877288) (xy 375.848118 -395.877288) (xy 375.858297 -395.87765)
			(xy 375.877102 -395.885451) (xy 375.891487 -395.899856) (xy 375.899263 -395.91867) (xy 375.89968 -395.92885)
			(xy 375.89968 -396.086838) (xy 375.900076 -396.096027) (xy 375.9066 -396.113211) (xy 375.91238 -396.120366)
			(xy 375.934157 -396.146026) (xy 375.972105 -396.201612) (xy 376.003138 -396.261335) (xy 376.02681 -396.324338)
			(xy 376.042784 -396.389719) (xy 376.050828 -396.456541) (xy 376.050829 -396.523844) (xy 376.042786 -396.590666)
			(xy 376.026815 -396.656047) (xy 376.003144 -396.719051) (xy 375.972113 -396.778775) (xy 375.934167 -396.834362)
			(xy 375.91238 -396.860014) (xy 375.906593 -396.867166) (xy 375.900073 -396.884351) (xy 375.89968 -396.893542)
			(xy 375.89968 -397.38681) (xy 375.90009 -397.395997) (xy 375.906604 -397.413181) (xy 375.91238 -397.420338)
			(xy 375.93413 -397.446021) (xy 375.972078 -397.501604) (xy 376.0005 -397.556296) (xy 377.128745 -397.556296)
			(xy 377.136821 -397.489358) (xy 377.152856 -397.423869) (xy 377.17662 -397.360772) (xy 377.207771 -397.300977)
			(xy 377.24586 -397.245343) (xy 377.267724 -397.219678) (xy 377.273515 -397.212529) (xy 377.280032 -397.195341)
			(xy 377.280424 -397.18615) (xy 377.280424 -397.028924) (xy 377.280836 -397.0188) (xy 377.288581 -397.000092)
			(xy 377.302899 -396.985776) (xy 377.321608 -396.978034) (xy 377.331732 -396.977616) (xy 378.048012 -396.977616)
			(xy 378.058137 -396.978006) (xy 378.076844 -396.985761) (xy 378.091159 -397.000086) (xy 378.098901 -397.018798)
			(xy 378.09932 -397.028924) (xy 378.09932 -397.18615) (xy 378.09975 -397.195335) (xy 378.10625 -397.21252)
			(xy 378.11202 -397.219678) (xy 378.133893 -397.245335) (xy 378.17198 -397.300972) (xy 378.203129 -397.360769)
			(xy 378.226892 -397.423867) (xy 378.242926 -397.489357) (xy 378.251001 -397.556295) (xy 378.251 -397.62372)
			(xy 378.242924 -397.690658) (xy 378.226888 -397.756147) (xy 378.203123 -397.819245) (xy 378.200706 -397.823885)
			(xy 379.328873 -397.823885) (xy 379.328877 -397.756458) (xy 379.336956 -397.689518) (xy 379.352995 -397.624027)
			(xy 379.376762 -397.560929) (xy 379.407915 -397.501131) (xy 379.446007 -397.445496) (xy 379.467872 -397.41983)
			(xy 379.47369 -397.4127) (xy 379.48019 -397.395498) (xy 379.480572 -397.386302) (xy 379.480572 -396.89405)
			(xy 379.480144 -396.884865) (xy 379.473643 -396.86768) (xy 379.467872 -396.860522) (xy 379.445999 -396.834864)
			(xy 379.407913 -396.779228) (xy 379.376764 -396.719431) (xy 379.353002 -396.656333) (xy 379.336968 -396.590843)
			(xy 379.328893 -396.523904) (xy 379.328894 -396.456481) (xy 379.33697 -396.389542) (xy 379.353006 -396.324053)
			(xy 379.37677 -396.260956) (xy 379.40792 -396.201159) (xy 379.446008 -396.145524) (xy 379.467872 -396.119858)
			(xy 379.473678 -396.11272) (xy 379.480185 -396.095524) (xy 379.480572 -396.08633) (xy 379.480572 -395.92885)
			(xy 379.481069 -395.918723) (xy 379.488786 -395.899996) (xy 379.50307 -395.885637) (xy 379.521755 -395.877822)
			(xy 379.53188 -395.877288) (xy 380.24816 -395.877288) (xy 380.258278 -395.877749) (xy 380.276979 -395.885481)
			(xy 380.291294 -395.899784) (xy 380.299043 -395.918478) (xy 380.299468 -395.928596) (xy 380.299468 -396.08633)
			(xy 380.299871 -396.095518) (xy 380.30639 -396.112702) (xy 380.312168 -396.119858) (xy 380.334023 -396.145531)
			(xy 380.372114 -396.201163) (xy 380.403267 -396.260958) (xy 380.427033 -396.324054) (xy 380.443071 -396.389543)
			(xy 380.451148 -396.456481) (xy 380.451149 -396.523904) (xy 380.443073 -396.590842) (xy 380.427038 -396.656331)
			(xy 380.403273 -396.719428) (xy 380.372122 -396.779224) (xy 380.334032 -396.834857) (xy 380.312168 -396.860522)
			(xy 380.306375 -396.86767) (xy 380.299859 -396.884858) (xy 380.299468 -396.89405) (xy 380.299468 -397.386302)
			(xy 380.299884 -397.395488) (xy 380.306394 -397.412672) (xy 380.312168 -397.41983) (xy 380.333996 -397.445525)
			(xy 380.372088 -397.501155) (xy 380.40085 -397.556356) (xy 381.529065 -397.556356) (xy 381.537108 -397.489534)
			(xy 381.553079 -397.424153) (xy 381.576749 -397.361149) (xy 381.60778 -397.301425) (xy 381.645726 -397.245838)
			(xy 381.667512 -397.220186) (xy 381.673298 -397.213034) (xy 381.679819 -397.195849) (xy 381.680212 -397.186658)
			(xy 381.680212 -397.028924) (xy 381.680636 -397.018802) (xy 381.688378 -397.000096) (xy 381.702693 -396.985781)
			(xy 381.721398 -396.978037) (xy 381.73152 -396.977616) (xy 382.448054 -396.977616) (xy 382.458175 -396.978164)
			(xy 382.47689 -396.985872) (xy 382.491247 -397.000139) (xy 382.499072 -397.018806) (xy 382.499616 -397.028924)
			(xy 382.499616 -397.186658) (xy 382.500043 -397.195844) (xy 382.506544 -397.213028) (xy 382.512316 -397.220186)
			(xy 382.534115 -397.245829) (xy 382.572066 -397.301416) (xy 382.603102 -397.36114) (xy 382.626776 -397.424146)
			(xy 382.642749 -397.48953) (xy 382.650793 -397.556354) (xy 382.650793 -397.623661) (xy 382.642747 -397.690485)
			(xy 382.626771 -397.755868) (xy 382.603096 -397.818873) (xy 382.600522 -397.823826) (xy 383.729168 -397.823826)
			(xy 383.729172 -397.756517) (xy 383.73722 -397.689692) (xy 383.753198 -397.624307) (xy 383.776876 -397.561301)
			(xy 383.807914 -397.501576) (xy 383.845869 -397.44599) (xy 383.86766 -397.420338) (xy 383.873473 -397.413205)
			(xy 383.879976 -397.396005) (xy 383.88036 -397.38681) (xy 383.88036 -396.893542) (xy 383.879916 -396.884359)
			(xy 383.873425 -396.867175) (xy 383.86766 -396.860014) (xy 383.845862 -396.83437) (xy 383.807912 -396.778783)
			(xy 383.776878 -396.719058) (xy 383.753205 -396.656053) (xy 383.737232 -396.590669) (xy 383.729188 -396.523846)
			(xy 383.729189 -396.456539) (xy 383.737235 -396.389716) (xy 383.753209 -396.324333) (xy 383.776884 -396.261328)
			(xy 383.80792 -396.201604) (xy 383.845871 -396.146018) (xy 383.86766 -396.120366) (xy 383.873461 -396.113224)
			(xy 383.879971 -396.096031) (xy 383.88036 -396.086838) (xy 383.88036 -395.92885) (xy 383.880805 -395.918679)
			(xy 383.888578 -395.899881) (xy 383.902958 -395.885494) (xy 383.921751 -395.877711) (xy 383.931922 -395.877288)
			(xy 384.648202 -395.877288) (xy 384.65838 -395.877663) (xy 384.677184 -395.885458) (xy 384.691571 -395.899859)
			(xy 384.699347 -395.918672) (xy 384.699764 -395.92885) (xy 384.699764 -396.086838) (xy 384.700164 -396.096026)
			(xy 384.706686 -396.11321) (xy 384.712464 -396.120366) (xy 384.734242 -396.146026) (xy 384.772191 -396.201612)
			(xy 384.803224 -396.261334) (xy 384.826898 -396.324337) (xy 384.842871 -396.389719) (xy 384.850916 -396.45654)
			(xy 384.850917 -396.523845) (xy 384.842874 -396.590666) (xy 384.826902 -396.656048) (xy 384.803231 -396.719052)
			(xy 384.772199 -396.778776) (xy 384.734251 -396.834362) (xy 384.712464 -396.860014) (xy 384.706674 -396.867164)
			(xy 384.700156 -396.884351) (xy 384.699764 -396.893542) (xy 384.699764 -397.38681) (xy 384.700177 -397.395997)
			(xy 384.70669 -397.413181) (xy 384.712464 -397.420338) (xy 384.734214 -397.446021) (xy 384.772164 -397.501603)
			(xy 384.800587 -397.556296) (xy 385.928833 -397.556296) (xy 385.936908 -397.489358) (xy 385.952943 -397.42387)
			(xy 385.976706 -397.360773) (xy 386.007856 -397.300977) (xy 386.045944 -397.245343) (xy 386.067808 -397.219678)
			(xy 386.073597 -397.212528) (xy 386.080116 -397.195341) (xy 386.080508 -397.18615) (xy 386.080508 -397.028924)
			(xy 386.080936 -397.018802) (xy 386.088677 -397.000097) (xy 386.102991 -396.985782) (xy 386.121694 -396.978037)
			(xy 386.131816 -396.977616) (xy 386.848096 -396.977616) (xy 386.85822 -396.97802) (xy 386.876927 -396.985769)
			(xy 386.891242 -397.00009) (xy 386.898984 -397.0188) (xy 386.899404 -397.028924) (xy 386.899404 -397.18615)
			(xy 386.899837 -397.195335) (xy 386.906335 -397.212519) (xy 386.912104 -397.219678) (xy 386.933978 -397.245335)
			(xy 386.972066 -397.300971) (xy 387.003216 -397.360768) (xy 387.026979 -397.423866) (xy 387.043014 -397.489356)
			(xy 387.051089 -397.556295) (xy 387.051088 -397.62372) (xy 387.043011 -397.690659) (xy 387.026975 -397.756148)
			(xy 387.00321 -397.819245) (xy 387.000823 -397.823826) (xy 388.128959 -397.823826) (xy 388.128963 -397.756517)
			(xy 388.137011 -397.689692) (xy 388.152988 -397.624308) (xy 388.176665 -397.561301) (xy 388.207704 -397.501577)
			(xy 388.245658 -397.44599) (xy 388.267448 -397.420338) (xy 388.273259 -397.413204) (xy 388.279764 -397.396005)
			(xy 388.280148 -397.38681) (xy 388.280148 -396.893542) (xy 388.279707 -396.884358) (xy 388.273213 -396.867174)
			(xy 388.267448 -396.860014) (xy 388.24565 -396.83437) (xy 388.207701 -396.778783) (xy 388.176668 -396.719058)
			(xy 388.152995 -396.656052) (xy 388.137022 -396.590669) (xy 388.128979 -396.523845) (xy 388.12898 -396.456539)
			(xy 388.137025 -396.389716) (xy 388.152999 -396.324333) (xy 388.176674 -396.261328) (xy 388.207709 -396.201604)
			(xy 388.245659 -396.146018) (xy 388.267448 -396.120366) (xy 388.273247 -396.113223) (xy 388.279759 -396.096031)
			(xy 388.280148 -396.086838) (xy 388.280148 -395.92885) (xy 388.280605 -395.91868) (xy 388.288375 -395.899885)
			(xy 388.302751 -395.885498) (xy 388.321541 -395.877713) (xy 388.33171 -395.877288) (xy 389.04799 -395.877288)
			(xy 389.058167 -395.877673) (xy 389.076971 -395.885464) (xy 389.091358 -395.899862) (xy 389.099135 -395.918672)
			(xy 389.099552 -395.92885) (xy 389.099552 -396.086838) (xy 389.099955 -396.096026) (xy 389.106475 -396.113209)
			(xy 389.112252 -396.120366) (xy 389.13403 -396.146026) (xy 389.17198 -396.201611) (xy 389.203014 -396.261334)
			(xy 389.226688 -396.324337) (xy 389.242662 -396.389718) (xy 389.250707 -396.45654) (xy 389.250707 -396.523845)
			(xy 389.242664 -396.590667) (xy 389.226692 -396.656048) (xy 389.20302 -396.719053) (xy 389.171987 -396.778776)
			(xy 389.134039 -396.834362) (xy 389.112252 -396.860014) (xy 389.106461 -396.867163) (xy 389.099944 -396.884351)
			(xy 389.099552 -396.893542) (xy 389.099552 -397.38681) (xy 389.099968 -397.395996) (xy 389.106479 -397.41318)
			(xy 389.112252 -397.420338) (xy 389.134002 -397.446021) (xy 389.171953 -397.501603) (xy 389.200407 -397.556356)
			(xy 390.329153 -397.556356) (xy 390.337195 -397.489535) (xy 390.353166 -397.424153) (xy 390.376836 -397.36115)
			(xy 390.407865 -397.301426) (xy 390.44581 -397.245839) (xy 390.467596 -397.220186) (xy 390.473381 -397.213032)
			(xy 390.479903 -397.195848) (xy 390.480296 -397.186658) (xy 390.480296 -397.028924) (xy 390.480735 -397.018804)
			(xy 390.488475 -397.000101) (xy 390.502784 -396.985786) (xy 390.521484 -396.978039) (xy 390.531604 -396.977616)
			(xy 391.248138 -396.977616) (xy 391.258264 -396.978095) (xy 391.276982 -396.985831) (xy 391.291336 -397.000119)
			(xy 391.299158 -397.0188) (xy 391.2997 -397.028924) (xy 391.2997 -397.186658) (xy 391.30013 -397.195843)
			(xy 391.30663 -397.213028) (xy 391.3124 -397.220186) (xy 391.334196 -397.245831) (xy 391.372142 -397.301419)
			(xy 391.403173 -397.361144) (xy 391.426844 -397.424149) (xy 391.442815 -397.489532) (xy 391.450857 -397.556355)
			(xy 391.450856 -397.62366) (xy 391.442812 -397.690483) (xy 391.426839 -397.755865) (xy 391.403167 -397.81887)
			(xy 391.372135 -397.878594) (xy 391.334187 -397.934181) (xy 391.3124 -397.959834) (xy 391.306606 -397.966981)
			(xy 391.30009 -397.98417) (xy 391.2997 -397.993362) (xy 391.2997 -398.486884) (xy 391.300118 -398.49607)
			(xy 391.306626 -398.513255) (xy 391.3124 -398.520412) (xy 391.334222 -398.546036) (xy 391.372167 -398.601627)
			(xy 391.403197 -398.661355) (xy 391.426866 -398.724363) (xy 391.442835 -398.789748) (xy 391.450876 -398.856574)
			(xy 391.450872 -398.923881) (xy 391.442825 -398.990705) (xy 391.42685 -399.056089) (xy 391.403175 -399.119095)
			(xy 391.372139 -399.178819) (xy 391.334189 -399.234407) (xy 391.3124 -399.26006) (xy 391.306595 -399.2672)
			(xy 391.300086 -399.284394) (xy 391.2997 -399.293588) (xy 391.2997 -399.451576) (xy 391.299265 -399.461697)
			(xy 391.291524 -399.4804) (xy 391.277214 -399.494715) (xy 391.258513 -399.502461) (xy 391.248392 -399.502884)
			(xy 390.531858 -399.502884) (xy 390.521732 -399.502409) (xy 390.503014 -399.494671) (xy 390.48866 -399.480382)
			(xy 390.480838 -399.4617) (xy 390.480296 -399.451576) (xy 390.480296 -399.293588) (xy 390.479892 -399.2844)
			(xy 390.473374 -399.267216) (xy 390.467596 -399.26006) (xy 390.445845 -399.234378) (xy 390.407898 -399.178795)
			(xy 390.376865 -399.119075) (xy 390.353192 -399.056075) (xy 390.337218 -398.990696) (xy 390.329172 -398.923878)
			(xy 390.329169 -398.856576) (xy 390.337209 -398.789757) (xy 390.353176 -398.724377) (xy 390.376843 -398.661374)
			(xy 390.40787 -398.601652) (xy 390.445812 -398.546065) (xy 390.467596 -398.520412) (xy 390.473412 -398.51328)
			(xy 390.479915 -398.49608) (xy 390.480296 -398.486884) (xy 390.480296 -397.993362) (xy 390.479905 -397.984173)
			(xy 390.473378 -397.966988) (xy 390.467596 -397.959834) (xy 390.445819 -397.934173) (xy 390.407873 -397.878587)
			(xy 390.376842 -397.818864) (xy 390.35317 -397.755861) (xy 390.337198 -397.69048) (xy 390.329154 -397.623659)
			(xy 390.329153 -397.556356) (xy 389.200407 -397.556356) (xy 389.202988 -397.561322) (xy 389.226664 -397.624322)
			(xy 389.24264 -397.689701) (xy 389.250687 -397.75652) (xy 389.25069 -397.823823) (xy 389.24265 -397.890643)
			(xy 389.226681 -397.956023) (xy 389.203012 -398.019026) (xy 389.171982 -398.078748) (xy 389.134038 -398.134334)
			(xy 389.112252 -398.159986) (xy 389.10643 -398.167113) (xy 389.099932 -398.184318) (xy 389.099552 -398.193514)
			(xy 389.099552 -398.351502) (xy 389.099138 -398.361675) (xy 389.09135 -398.380472) (xy 389.076962 -398.394857)
			(xy 389.058163 -398.40264) (xy 389.04799 -398.403064) (xy 388.33171 -398.403064) (xy 388.321539 -398.402628)
			(xy 388.302745 -398.394847) (xy 388.28836 -398.380465) (xy 388.280574 -398.361673) (xy 388.280148 -398.351502)
			(xy 388.280148 -398.193514) (xy 388.27972 -398.184329) (xy 388.273218 -398.167145) (xy 388.267448 -398.159986)
			(xy 388.245622 -398.134365) (xy 388.207674 -398.078774) (xy 388.176642 -398.019046) (xy 388.152971 -397.956038)
			(xy 388.137 -397.890652) (xy 388.128959 -397.823826) (xy 387.000823 -397.823826) (xy 386.972058 -397.879042)
			(xy 386.933968 -397.934677) (xy 386.912104 -397.960342) (xy 386.906308 -397.967487) (xy 386.899793 -397.984678)
			(xy 386.899404 -397.99387) (xy 386.899404 -398.486376) (xy 386.899825 -398.495562) (xy 386.906331 -398.512747)
			(xy 386.912104 -398.519904) (xy 386.934003 -398.54554) (xy 386.972091 -398.601179) (xy 387.003239 -398.660979)
			(xy 387.027001 -398.72408) (xy 387.043034 -398.789572) (xy 387.051107 -398.856514) (xy 387.051104 -398.92394)
			(xy 387.043025 -398.990881) (xy 387.026985 -399.056372) (xy 387.003217 -399.11947) (xy 386.972063 -399.179268)
			(xy 386.93397 -399.234903) (xy 386.912104 -399.260568) (xy 386.906297 -399.267706) (xy 386.899788 -399.284902)
			(xy 386.899404 -399.294096) (xy 386.899404 -399.451576) (xy 386.898965 -399.461696) (xy 386.891225 -399.480399)
			(xy 386.876916 -399.494714) (xy 386.858216 -399.502461) (xy 386.848096 -399.502884) (xy 386.131816 -399.502884)
			(xy 386.121693 -399.502471) (xy 386.102986 -399.494725) (xy 386.088671 -399.480407) (xy 386.080928 -399.4617)
			(xy 386.080508 -399.451576) (xy 386.080508 -399.294096) (xy 386.080098 -399.284909) (xy 386.073584 -399.267725)
			(xy 386.067808 -399.260568) (xy 386.045979 -399.234874) (xy 386.007889 -399.179244) (xy 385.976736 -399.119451)
			(xy 385.95297 -399.056358) (xy 385.936931 -398.990873) (xy 385.928852 -398.923938) (xy 385.928849 -398.856517)
			(xy 385.936922 -398.789581) (xy 385.952954 -398.724093) (xy 385.976714 -398.660998) (xy 386.007861 -398.601203)
			(xy 386.045946 -398.545569) (xy 386.067808 -398.519904) (xy 386.073586 -398.512746) (xy 386.080112 -398.495565)
			(xy 386.080508 -398.486376) (xy 386.080508 -397.99387) (xy 386.080111 -397.984681) (xy 386.073588 -397.967497)
			(xy 386.067808 -397.960342) (xy 386.045954 -397.934669) (xy 386.007864 -397.879036) (xy 385.976712 -397.819241)
			(xy 385.952947 -397.756145) (xy 385.936911 -397.690657) (xy 385.928834 -397.623719) (xy 385.928833 -397.556296)
			(xy 384.800587 -397.556296) (xy 384.803199 -397.561322) (xy 384.826873 -397.624323) (xy 384.842849 -397.689701)
			(xy 384.850896 -397.75652) (xy 384.850899 -397.823822) (xy 384.842859 -397.890642) (xy 384.82689 -397.956022)
			(xy 384.803222 -398.019025) (xy 384.772193 -398.078748) (xy 384.734249 -398.134334) (xy 384.712464 -398.159986)
			(xy 384.706644 -398.167114) (xy 384.700144 -398.184318) (xy 384.699764 -398.193514) (xy 384.699764 -398.351502)
			(xy 384.699268 -398.36166) (xy 384.691494 -398.380428) (xy 384.677128 -398.394794) (xy 384.65836 -398.402568)
			(xy 384.648202 -398.403064) (xy 383.931922 -398.403064) (xy 383.921752 -398.402618) (xy 383.902958 -398.394841)
			(xy 383.888573 -398.380462) (xy 383.880787 -398.361672) (xy 383.88036 -398.351502) (xy 383.88036 -398.193514)
			(xy 383.87993 -398.184329) (xy 383.873429 -398.167145) (xy 383.86766 -398.159986) (xy 383.845834 -398.134365)
			(xy 383.807885 -398.078775) (xy 383.776852 -398.019047) (xy 383.753181 -397.956038) (xy 383.73721 -397.890652)
			(xy 383.729168 -397.823826) (xy 382.600522 -397.823826) (xy 382.572059 -397.878597) (xy 382.534106 -397.934182)
			(xy 382.512316 -397.959834) (xy 382.506524 -397.966983) (xy 382.500006 -397.98417) (xy 382.499616 -397.993362)
			(xy 382.499616 -398.486884) (xy 382.50003 -398.496071) (xy 382.506541 -398.513255) (xy 382.512316 -398.520412)
			(xy 382.53414 -398.546034) (xy 382.572091 -398.601624) (xy 382.603125 -398.661351) (xy 382.626798 -398.72436)
			(xy 382.64277 -398.789746) (xy 382.650812 -398.856573) (xy 382.650808 -398.923881) (xy 382.64276 -398.990707)
			(xy 382.626782 -399.056092) (xy 382.603103 -399.119098) (xy 382.572063 -399.178822) (xy 382.534107 -399.234408)
			(xy 382.512316 -399.26006) (xy 382.506513 -399.267201) (xy 382.500002 -399.284395) (xy 382.499616 -399.293588)
			(xy 382.499616 -399.451576) (xy 382.499165 -399.461695) (xy 382.491428 -399.480395) (xy 382.477122 -399.49471)
			(xy 382.458427 -399.502459) (xy 382.448308 -399.502884) (xy 381.731774 -399.502884) (xy 381.721649 -399.502396)
			(xy 381.702931 -399.494664) (xy 381.688577 -399.480379) (xy 381.680754 -399.461699) (xy 381.680212 -399.451576)
			(xy 381.680212 -399.293588) (xy 381.679805 -399.284401) (xy 381.673289 -399.267216) (xy 381.667512 -399.26006)
			(xy 381.64576 -399.234378) (xy 381.607812 -399.178796) (xy 381.576779 -399.119076) (xy 381.553105 -399.056075)
			(xy 381.537131 -398.990697) (xy 381.529084 -398.923878) (xy 381.529081 -398.856576) (xy 381.537121 -398.789757)
			(xy 381.553089 -398.724377) (xy 381.576757 -398.661374) (xy 381.607784 -398.601651) (xy 381.645727 -398.546064)
			(xy 381.667512 -398.520412) (xy 381.67333 -398.513282) (xy 381.679831 -398.49608) (xy 381.680212 -398.486884)
			(xy 381.680212 -397.993362) (xy 381.679818 -397.984173) (xy 381.673293 -397.966989) (xy 381.667512 -397.959834)
			(xy 381.645735 -397.934173) (xy 381.607788 -397.878588) (xy 381.576755 -397.818865) (xy 381.553083 -397.755862)
			(xy 381.53711 -397.690481) (xy 381.529066 -397.623659) (xy 381.529065 -397.556356) (xy 380.40085 -397.556356)
			(xy 380.403242 -397.560947) (xy 380.42701 -397.62404) (xy 380.443049 -397.689525) (xy 380.451128 -397.756461)
			(xy 380.451131 -397.823882) (xy 380.443059 -397.890818) (xy 380.427026 -397.956306) (xy 380.403265 -398.019401)
			(xy 380.372117 -398.079196) (xy 380.334031 -398.134829) (xy 380.312168 -398.160494) (xy 380.306387 -398.16765)
			(xy 380.299864 -398.184832) (xy 380.299468 -398.194022) (xy 380.299468 -398.351502) (xy 380.298975 -398.361628)
			(xy 380.291248 -398.380347) (xy 380.276964 -398.394703) (xy 380.258283 -398.402524) (xy 380.24816 -398.403064)
			(xy 379.53188 -398.403064) (xy 379.521752 -398.4027) (xy 379.503041 -398.394938) (xy 379.488726 -398.380605)
			(xy 379.480988 -398.361885) (xy 379.480572 -398.351756) (xy 379.480572 -398.194022) (xy 379.480158 -398.184835)
			(xy 379.473648 -398.16765) (xy 379.467872 -398.160494) (xy 379.445972 -398.134859) (xy 379.407886 -398.07922)
			(xy 379.376738 -398.019419) (xy 379.352978 -397.956318) (xy 379.336946 -397.890826) (xy 379.328873 -397.823885)
			(xy 378.200706 -397.823885) (xy 378.171972 -397.879041) (xy 378.133884 -397.934676) (xy 378.11202 -397.960342)
			(xy 378.106225 -397.967489) (xy 378.099709 -397.984678) (xy 378.09932 -397.99387) (xy 378.09932 -398.486376)
			(xy 378.099737 -398.495563) (xy 378.106245 -398.512747) (xy 378.11202 -398.519904) (xy 378.133919 -398.54554)
			(xy 378.172005 -398.60118) (xy 378.203153 -398.66098) (xy 378.226914 -398.724081) (xy 378.242947 -398.789573)
			(xy 378.251019 -398.856514) (xy 378.251016 -398.92394) (xy 378.242937 -398.99088) (xy 378.226898 -399.056371)
			(xy 378.203131 -399.11947) (xy 378.171977 -399.179267) (xy 378.133885 -399.234902) (xy 378.11202 -399.260568)
			(xy 378.106214 -399.267707) (xy 378.099704 -399.284902) (xy 378.09932 -399.294096) (xy 378.09932 -399.451576)
			(xy 378.098865 -399.461694) (xy 378.091128 -399.480394) (xy 378.076824 -399.494708) (xy 378.05813 -399.502458)
			(xy 378.048012 -399.502884) (xy 377.331732 -399.502884) (xy 377.32161 -399.502458) (xy 377.302903 -399.494717)
			(xy 377.288587 -399.480403) (xy 377.280844 -399.461698) (xy 377.280424 -399.451576) (xy 377.280424 -399.294096)
			(xy 377.280011 -399.284909) (xy 377.273499 -399.267725) (xy 377.267724 -399.260568) (xy 377.245895 -399.234874)
			(xy 377.207803 -399.179244) (xy 377.17665 -399.119452) (xy 377.152882 -399.056359) (xy 377.136844 -398.990873)
			(xy 377.128765 -398.923938) (xy 377.128761 -398.856516) (xy 377.136834 -398.78958) (xy 377.152866 -398.724093)
			(xy 377.176627 -398.660997) (xy 377.207775 -398.601202) (xy 377.245861 -398.545569) (xy 377.267724 -398.519904)
			(xy 377.273504 -398.512747) (xy 377.280028 -398.495565) (xy 377.280424 -398.486376) (xy 377.280424 -397.99387)
			(xy 377.280023 -397.984682) (xy 377.273502 -397.967498) (xy 377.267724 -397.960342) (xy 377.245869 -397.934669)
			(xy 377.207778 -397.879036) (xy 377.176626 -397.819241) (xy 377.15286 -397.756145) (xy 377.136823 -397.690657)
			(xy 377.128746 -397.623719) (xy 377.128745 -397.556296) (xy 376.0005 -397.556296) (xy 376.003112 -397.561323)
			(xy 376.026786 -397.624324) (xy 376.042761 -397.689702) (xy 376.050808 -397.756521) (xy 376.050811 -397.823822)
			(xy 376.042771 -397.890642) (xy 376.026803 -397.956022) (xy 376.003135 -398.019025) (xy 375.972108 -398.078747)
			(xy 375.934165 -398.134333) (xy 375.91238 -398.159986) (xy 375.906562 -398.167116) (xy 375.900061 -398.184318)
			(xy 375.89968 -398.193514) (xy 375.89968 -398.351502) (xy 375.899169 -398.361658) (xy 375.891397 -398.380423)
			(xy 375.877037 -398.394788) (xy 375.858274 -398.402565) (xy 375.848118 -398.403064) (xy 375.131838 -398.403064)
			(xy 375.121669 -398.402605) (xy 375.102876 -398.394833) (xy 375.08849 -398.380458) (xy 375.080703 -398.361671)
			(xy 375.080276 -398.351502) (xy 375.080276 -398.193514) (xy 375.079865 -398.184327) (xy 375.073352 -398.167142)
			(xy 375.067576 -398.159986) (xy 375.04575 -398.134365) (xy 375.007799 -398.078775) (xy 374.976766 -398.019048)
			(xy 374.953093 -397.956039) (xy 374.937122 -397.890652) (xy 374.92908 -397.823826) (xy 347.400682 -397.823826)
			(xy 347.372224 -397.878594) (xy 347.334276 -397.934182) (xy 347.312488 -397.959834) (xy 347.306693 -397.96698)
			(xy 347.300178 -397.98417) (xy 347.299788 -397.993362) (xy 347.299788 -398.486884) (xy 347.300209 -398.49607)
			(xy 347.306715 -398.513254) (xy 347.312488 -398.520412) (xy 347.33431 -398.546035) (xy 347.372256 -398.601627)
			(xy 347.403286 -398.661354) (xy 347.426956 -398.724363) (xy 347.442926 -398.789748) (xy 347.450967 -398.856573)
			(xy 347.450963 -398.923881) (xy 347.442916 -398.990705) (xy 347.42694 -399.056089) (xy 347.403264 -399.119095)
			(xy 347.372228 -399.17882) (xy 347.334277 -399.234407) (xy 347.312488 -399.26006) (xy 347.306682 -399.267199)
			(xy 347.300173 -399.284394) (xy 347.299788 -399.293588) (xy 347.299788 -399.451576) (xy 347.299359 -399.46173)
			(xy 347.291569 -399.480484) (xy 347.277174 -399.494809) (xy 347.258382 -399.502507) (xy 347.248226 -399.502884)
			(xy 346.531946 -399.502884) (xy 346.521825 -399.502336) (xy 346.50311 -399.494628) (xy 346.488753 -399.480361)
			(xy 346.480928 -399.461694) (xy 346.480384 -399.451576) (xy 346.480384 -399.293588) (xy 346.479983 -399.2844)
			(xy 346.473463 -399.267215) (xy 346.467684 -399.26006) (xy 346.44593 -399.234379) (xy 346.407977 -399.178798)
			(xy 346.37694 -399.119079) (xy 346.353263 -399.056078) (xy 346.337287 -398.990699) (xy 346.329239 -398.923879)
			(xy 346.329236 -398.856576) (xy 346.337277 -398.789755) (xy 346.353247 -398.724374) (xy 346.376918 -398.661371)
			(xy 346.40795 -398.601648) (xy 346.445897 -398.546064) (xy 346.467684 -398.520412) (xy 346.473499 -398.513279)
			(xy 346.480003 -398.496079) (xy 346.480384 -398.486884) (xy 346.480384 -397.993362) (xy 346.479996 -397.984172)
			(xy 346.473467 -397.966988) (xy 346.467684 -397.959834) (xy 346.445905 -397.934174) (xy 346.407953 -397.87859)
			(xy 346.376917 -397.818868) (xy 346.353241 -397.755864) (xy 346.337266 -397.690483) (xy 346.329221 -397.62366)
			(xy 346.32922 -397.556355) (xy 345.200497 -397.556355) (xy 345.203078 -397.561321) (xy 345.226754 -397.624322)
			(xy 345.24273 -397.689701) (xy 345.250778 -397.75652) (xy 345.250781 -397.823823) (xy 345.242741 -397.890643)
			(xy 345.226771 -397.956023) (xy 345.203102 -398.019026) (xy 345.172072 -398.078749) (xy 345.134126 -398.134334)
			(xy 345.11234 -398.159986) (xy 345.106517 -398.167112) (xy 345.10002 -398.184318) (xy 345.09964 -398.193514)
			(xy 345.09964 -398.351502) (xy 345.099237 -398.361676) (xy 345.091447 -398.380475) (xy 345.077055 -398.394861)
			(xy 345.058253 -398.402642) (xy 345.048078 -398.403064) (xy 344.331798 -398.403064) (xy 344.32164 -398.402568)
			(xy 344.302872 -398.394794) (xy 344.288506 -398.380428) (xy 344.280732 -398.36166) (xy 344.280236 -398.351502)
			(xy 344.280236 -398.193514) (xy 344.279811 -398.184329) (xy 344.273307 -398.167144) (xy 344.267536 -398.159986)
			(xy 344.245711 -398.134365) (xy 344.207763 -398.078774) (xy 344.176732 -398.019046) (xy 344.153061 -397.956037)
			(xy 344.137091 -397.890651) (xy 344.12905 -397.823825) (xy 343.000914 -397.823825) (xy 342.972147 -397.879042)
			(xy 342.934057 -397.934677) (xy 342.912192 -397.960342) (xy 342.906394 -397.967486) (xy 342.899881 -397.984678)
			(xy 342.899492 -397.99387) (xy 342.899492 -398.486376) (xy 342.899916 -398.495562) (xy 342.90642 -398.512746)
			(xy 342.912192 -398.519904) (xy 342.934092 -398.54554) (xy 342.97218 -398.601178) (xy 343.003329 -398.660979)
			(xy 343.027092 -398.724079) (xy 343.043125 -398.789572) (xy 343.051198 -398.856514) (xy 343.051195 -398.92394)
			(xy 343.043115 -398.990881) (xy 343.027076 -399.056372) (xy 343.003307 -399.119471) (xy 342.972152 -399.179268)
			(xy 342.934058 -399.234903) (xy 342.912192 -399.260568) (xy 342.906383 -399.267704) (xy 342.899876 -399.284902)
			(xy 342.899492 -399.294096) (xy 342.899492 -399.451576) (xy 342.899064 -399.461698) (xy 342.891323 -399.480403)
			(xy 342.877009 -399.494718) (xy 342.858306 -399.502463) (xy 342.848184 -399.502884) (xy 342.131904 -399.502884)
			(xy 342.12178 -399.50248) (xy 342.103073 -399.494731) (xy 342.088758 -399.48041) (xy 342.081016 -399.4617)
			(xy 342.080596 -399.451576) (xy 342.080596 -399.294096) (xy 342.080189 -399.284909) (xy 342.073673 -399.267724)
			(xy 342.067896 -399.260568) (xy 342.046068 -399.234874) (xy 342.007978 -399.179243) (xy 341.976826 -399.119451)
			(xy 341.95306 -399.056358) (xy 341.937022 -398.990872) (xy 341.928943 -398.923937) (xy 341.92894 -398.856517)
			(xy 341.937012 -398.789581) (xy 341.953044 -398.724094) (xy 341.976804 -398.660999) (xy 342.00795 -398.601203)
			(xy 342.046034 -398.545569) (xy 342.067896 -398.519904) (xy 342.073673 -398.512745) (xy 342.080199 -398.495565)
			(xy 342.080596 -398.486376) (xy 342.080596 -397.99387) (xy 342.080201 -397.984681) (xy 342.073677 -397.967497)
			(xy 342.067896 -397.960342) (xy 342.046042 -397.934669) (xy 342.007953 -397.879035) (xy 341.976802 -397.81924)
			(xy 341.953038 -397.756144) (xy 341.937002 -397.690656) (xy 341.928925 -397.623719) (xy 341.928924 -397.556296)
			(xy 340.800676 -397.556296) (xy 340.803288 -397.561322) (xy 340.826964 -397.624322) (xy 340.84294 -397.689701)
			(xy 340.850987 -397.75652) (xy 340.85099 -397.823823) (xy 340.84295 -397.890643) (xy 340.826981 -397.956023)
			(xy 340.803312 -398.019026) (xy 340.772282 -398.078748) (xy 340.734338 -398.134334) (xy 340.712552 -398.159986)
			(xy 340.70673 -398.167113) (xy 340.700232 -398.184318) (xy 340.699852 -398.193514) (xy 340.699852 -398.351502)
			(xy 340.699438 -398.361675) (xy 340.69165 -398.380472) (xy 340.677262 -398.394857) (xy 340.658463 -398.40264)
			(xy 340.64829 -398.403064) (xy 339.93201 -398.403064) (xy 339.921839 -398.402628) (xy 339.903045 -398.394847)
			(xy 339.88866 -398.380465) (xy 339.880874 -398.361673) (xy 339.880448 -398.351502) (xy 339.880448 -398.193514)
			(xy 339.88002 -398.184329) (xy 339.873518 -398.167145) (xy 339.867748 -398.159986) (xy 339.845922 -398.134365)
			(xy 339.807974 -398.078774) (xy 339.776942 -398.019046) (xy 339.753271 -397.956038) (xy 339.7373 -397.890652)
			(xy 339.729259 -397.823826) (xy 338.600595 -397.823826) (xy 338.572138 -397.878594) (xy 338.534191 -397.934181)
			(xy 338.512404 -397.959834) (xy 338.506611 -397.966982) (xy 338.500094 -397.98417) (xy 338.499704 -397.993362)
			(xy 338.499704 -398.486884) (xy 338.500121 -398.49607) (xy 338.50663 -398.513255) (xy 338.512404 -398.520412)
			(xy 338.534226 -398.546036) (xy 338.572171 -398.601627) (xy 338.6032 -398.661355) (xy 338.626869 -398.724363)
			(xy 338.642838 -398.789748) (xy 338.650879 -398.856574) (xy 338.650875 -398.923881) (xy 338.642828 -398.990705)
			(xy 338.626853 -399.056089) (xy 338.603178 -399.119094) (xy 338.572143 -399.178819) (xy 338.534193 -399.234407)
			(xy 338.512404 -399.26006) (xy 338.5066 -399.2672) (xy 338.50009 -399.284394) (xy 338.499704 -399.293588)
			(xy 338.499704 -399.451576) (xy 338.499259 -399.461728) (xy 338.491472 -399.480479) (xy 338.477082 -399.494803)
			(xy 338.458296 -399.502505) (xy 338.448142 -399.502884) (xy 337.731862 -399.502884) (xy 337.721736 -399.502405)
			(xy 337.703018 -399.494669) (xy 337.688664 -399.480381) (xy 337.680842 -399.4617) (xy 337.6803 -399.451576)
			(xy 337.6803 -399.293588) (xy 337.679895 -399.2844) (xy 337.673378 -399.267216) (xy 337.6676 -399.26006)
			(xy 337.645849 -399.234378) (xy 337.607901 -399.178795) (xy 337.576869 -399.119075) (xy 337.553196 -399.056075)
			(xy 337.537221 -398.990697) (xy 337.529175 -398.923878) (xy 337.529172 -398.856576) (xy 337.537212 -398.789757)
			(xy 337.55318 -398.724377) (xy 337.576847 -398.661374) (xy 337.607874 -398.601651) (xy 337.645816 -398.546065)
			(xy 337.6676 -398.520412) (xy 337.673416 -398.513281) (xy 337.679919 -398.49608) (xy 337.6803 -398.486884)
			(xy 337.6803 -397.993362) (xy 337.679908 -397.984173) (xy 337.673382 -397.966989) (xy 337.6676 -397.959834)
			(xy 337.645823 -397.934173) (xy 337.607877 -397.878587) (xy 337.576845 -397.818864) (xy 337.553174 -397.755861)
			(xy 337.537201 -397.69048) (xy 337.529157 -397.623659) (xy 337.529156 -397.556356) (xy 336.40094 -397.556356)
			(xy 336.403332 -397.560946) (xy 336.4271 -397.624039) (xy 336.443139 -397.689525) (xy 336.451219 -397.756461)
			(xy 336.451222 -397.823882) (xy 336.44315 -397.890819) (xy 336.427117 -397.956306) (xy 336.403355 -398.019402)
			(xy 336.372206 -398.079196) (xy 336.334119 -398.13483) (xy 336.312256 -398.160494) (xy 336.306474 -398.167649)
			(xy 336.299952 -398.184832) (xy 336.299556 -398.194022) (xy 336.299556 -398.351502) (xy 336.299075 -398.361629)
			(xy 336.291346 -398.380351) (xy 336.277058 -398.394708) (xy 336.258373 -398.402526) (xy 336.248248 -398.403064)
			(xy 335.531968 -398.403064) (xy 335.521807 -398.402704) (xy 335.503047 -398.394891) (xy 335.488724 -398.380475)
			(xy 335.481032 -398.361665) (xy 335.48066 -398.351502) (xy 335.48066 -398.194022) (xy 335.480226 -398.184838)
			(xy 335.473727 -398.167654) (xy 335.46796 -398.160494) (xy 335.44606 -398.134859) (xy 335.407975 -398.079219)
			(xy 335.376828 -398.019418) (xy 335.353068 -397.956318) (xy 335.337036 -397.890825) (xy 335.328964 -397.823884)
			(xy 334.200796 -397.823884) (xy 334.172062 -397.879042) (xy 334.133972 -397.934677) (xy 334.112108 -397.960342)
			(xy 334.106312 -397.967488) (xy 334.099797 -397.984678) (xy 334.099408 -397.99387) (xy 334.099408 -398.486376)
			(xy 334.099828 -398.495562) (xy 334.106335 -398.512747) (xy 334.112108 -398.519904) (xy 334.134007 -398.54554)
			(xy 334.172094 -398.601179) (xy 334.203243 -398.660979) (xy 334.227005 -398.72408) (xy 334.243037 -398.789573)
			(xy 334.25111 -398.856514) (xy 334.251107 -398.92394) (xy 334.243028 -398.990881) (xy 334.226989 -399.056372)
			(xy 334.203221 -399.11947) (xy 334.172066 -399.179267) (xy 334.133974 -399.234903) (xy 334.112108 -399.260568)
			(xy 334.106301 -399.267706) (xy 334.099792 -399.284902) (xy 334.099408 -399.294096) (xy 334.099408 -399.451576)
			(xy 334.098965 -399.461696) (xy 334.091226 -399.480398) (xy 334.076918 -399.494712) (xy 334.05822 -399.50246)
			(xy 334.0481 -399.502884) (xy 333.33182 -399.502884) (xy 333.321697 -399.502467) (xy 333.302991 -399.494723)
			(xy 333.288675 -399.480406) (xy 333.280932 -399.461699) (xy 333.280512 -399.451576) (xy 333.280512 -399.294096)
			(xy 333.280101 -399.284909) (xy 333.273587 -399.267725) (xy 333.267812 -399.260568) (xy 333.245983 -399.234874)
			(xy 333.207892 -399.179244) (xy 333.176739 -399.119452) (xy 333.152973 -399.056358) (xy 333.136934 -398.990873)
			(xy 333.128855 -398.923938) (xy 333.128852 -398.856516) (xy 333.136925 -398.78958) (xy 333.152957 -398.724093)
			(xy 333.176717 -398.660998) (xy 333.207865 -398.601203) (xy 333.24595 -398.545569) (xy 333.267812 -398.519904)
			(xy 333.273591 -398.512746) (xy 333.280116 -398.495565) (xy 333.280512 -398.486376) (xy 333.280512 -397.99387)
			(xy 333.280114 -397.984682) (xy 333.273592 -397.967497) (xy 333.267812 -397.960342) (xy 333.245957 -397.934669)
			(xy 333.207868 -397.879036) (xy 333.176716 -397.819241) (xy 333.152951 -397.756145) (xy 333.136914 -397.690657)
			(xy 333.128837 -397.623719) (xy 333.128836 -397.556296) (xy 332.00059 -397.556296) (xy 332.003202 -397.561323)
			(xy 332.026877 -397.624323) (xy 332.042852 -397.689701) (xy 332.050899 -397.75652) (xy 332.050902 -397.823822)
			(xy 332.042862 -397.890642) (xy 332.026893 -397.956022) (xy 332.003225 -398.019025) (xy 331.972197 -398.078748)
			(xy 331.934253 -398.134334) (xy 331.912468 -398.159986) (xy 331.906648 -398.167115) (xy 331.900148 -398.184318)
			(xy 331.899768 -398.193514) (xy 331.899768 -398.351502) (xy 331.899268 -398.361659) (xy 331.891494 -398.380427)
			(xy 331.877131 -398.394792) (xy 331.858363 -398.402568) (xy 331.848206 -398.403064) (xy 331.131926 -398.403064)
			(xy 331.121756 -398.402615) (xy 331.102963 -398.394839) (xy 331.088577 -398.380461) (xy 331.080791 -398.361671)
			(xy 331.080364 -398.351502) (xy 331.080364 -398.193514) (xy 331.079933 -398.184329) (xy 331.073432 -398.167146)
			(xy 331.067664 -398.159986) (xy 331.045838 -398.134365) (xy 331.007889 -398.078775) (xy 330.976856 -398.019047)
			(xy 330.953184 -397.956038) (xy 330.937213 -397.890652) (xy 330.929171 -397.823826) (xy 326.525636 -397.823826)
			(xy 326.525636 -401.723737) (xy 330.929183 -401.723737) (xy 330.929184 -401.65643) (xy 330.937231 -401.589605)
			(xy 330.953207 -401.524221) (xy 330.976884 -401.461216) (xy 331.007921 -401.401492) (xy 331.045874 -401.345906)
			(xy 331.067664 -401.320254) (xy 331.07347 -401.313116) (xy 331.079977 -401.29592) (xy 331.080364 -401.286726)
			(xy 331.080364 -400.793458) (xy 331.07996 -400.78427) (xy 331.073441 -400.767087) (xy 331.067664 -400.75993)
			(xy 331.045882 -400.734273) (xy 331.007931 -400.678688) (xy 330.976896 -400.618965) (xy 330.953222 -400.555961)
			(xy 330.937248 -400.490579) (xy 330.929203 -400.423757) (xy 330.929202 -400.356452) (xy 330.937246 -400.289629)
			(xy 330.953219 -400.224247) (xy 330.976892 -400.161243) (xy 331.007926 -400.10152) (xy 331.045876 -400.045934)
			(xy 331.067664 -400.020282) (xy 331.073459 -400.013136) (xy 331.079973 -399.995946) (xy 331.080364 -399.986754)
			(xy 331.080364 -399.828766) (xy 331.080806 -399.818603) (xy 331.088597 -399.799828) (xy 331.102978 -399.785463)
			(xy 331.121762 -399.777694) (xy 331.131926 -399.777204) (xy 331.848206 -399.777204) (xy 331.85836 -399.777728)
			(xy 331.877123 -399.785498) (xy 331.891486 -399.799854) (xy 331.899267 -399.818612) (xy 331.899768 -399.828766)
			(xy 331.899768 -399.986754) (xy 331.900208 -399.995938) (xy 331.906702 -400.013122) (xy 331.912468 -400.020282)
			(xy 331.934262 -400.045929) (xy 331.97221 -400.101517) (xy 332.003242 -400.161241) (xy 332.026915 -400.224246)
			(xy 332.042887 -400.289629) (xy 332.05093 -400.356452) (xy 332.05093 -400.423757) (xy 332.042885 -400.49058)
			(xy 332.026912 -400.555963) (xy 332.003239 -400.618967) (xy 331.972205 -400.678691) (xy 331.934256 -400.734278)
			(xy 331.912468 -400.75993) (xy 331.906672 -400.767076) (xy 331.900158 -400.784266) (xy 331.899768 -400.793458)
			(xy 331.899768 -401.286726) (xy 331.900173 -401.295914) (xy 331.906691 -401.313098) (xy 331.912468 -401.320254)
			(xy 331.934234 -401.345924) (xy 331.972183 -401.401508) (xy 332.003216 -401.461229) (xy 332.02689 -401.524231)
			(xy 332.042864 -401.589611) (xy 332.05091 -401.656432) (xy 332.050912 -401.723735) (xy 332.04287 -401.790556)
			(xy 332.0269 -401.855937) (xy 332.00323 -401.91894) (xy 331.9722 -401.978663) (xy 331.934254 -402.03425)
			(xy 331.912468 -402.059902) (xy 331.906684 -402.067056) (xy 331.900163 -402.08424) (xy 331.899768 -402.09343)
			(xy 331.899768 -402.251418) (xy 331.899282 -402.261576) (xy 331.891502 -402.280345) (xy 331.877135 -402.294709)
			(xy 331.858364 -402.302484) (xy 331.848206 -402.30298) (xy 331.131926 -402.30298) (xy 331.121758 -402.302515)
			(xy 331.102968 -402.294742) (xy 331.088583 -402.280369) (xy 331.080794 -402.261585) (xy 331.080364 -402.251418)
			(xy 331.080364 -402.09343) (xy 331.079925 -402.084246) (xy 331.07343 -402.067062) (xy 331.067664 -402.059902)
			(xy 331.045854 -402.034268) (xy 331.007904 -401.97868) (xy 330.97687 -401.918954) (xy 330.953197 -401.855947)
			(xy 330.937225 -401.790562) (xy 330.929183 -401.723737) (xy 326.525636 -401.723737) (xy 326.525636 -402.823878)
			(xy 333.128796 -402.823878) (xy 333.128801 -402.75645) (xy 333.136882 -402.689508) (xy 333.152922 -402.624016)
			(xy 333.176693 -402.560918) (xy 333.20785 -402.50112) (xy 333.245945 -402.445485) (xy 333.267812 -402.41982)
			(xy 333.273626 -402.412687) (xy 333.28013 -402.395487) (xy 333.280512 -402.386292) (xy 333.280512 -401.89404)
			(xy 333.28008 -401.884855) (xy 333.273581 -401.867671) (xy 333.267812 -401.860512) (xy 333.245928 -401.834863)
			(xy 333.207839 -401.779227) (xy 333.176689 -401.719428) (xy 333.152925 -401.656329) (xy 333.136891 -401.590838)
			(xy 333.128816 -401.523898) (xy 333.128818 -401.456472) (xy 333.136896 -401.389532) (xy 333.152934 -401.324042)
			(xy 333.176701 -401.260944) (xy 333.207855 -401.201148) (xy 333.245946 -401.145513) (xy 333.267812 -401.119848)
			(xy 333.273615 -401.112707) (xy 333.280125 -401.095513) (xy 333.280512 -401.08632) (xy 333.280512 -400.92884)
			(xy 333.280949 -400.918719) (xy 333.288686 -400.900014) (xy 333.302997 -400.885698) (xy 333.321699 -400.877953)
			(xy 333.33182 -400.877532) (xy 334.0481 -400.877532) (xy 334.058226 -400.877917) (xy 334.076936 -400.885671)
			(xy 334.091252 -400.899997) (xy 334.098991 -400.918713) (xy 334.099408 -400.92884) (xy 334.099408 -401.08632)
			(xy 334.099807 -401.095508) (xy 334.106328 -401.112693) (xy 334.112108 -401.119848) (xy 334.133952 -401.14553)
			(xy 334.172041 -401.201162) (xy 334.203192 -401.260956) (xy 334.226957 -401.324051) (xy 334.242994 -401.389538)
			(xy 334.251071 -401.456474) (xy 334.251073 -401.523896) (xy 334.242999 -401.590833) (xy 334.226966 -401.656321)
			(xy 334.203204 -401.719417) (xy 334.200923 -401.723796) (xy 335.328975 -401.723796) (xy 335.328977 -401.656371)
			(xy 335.337055 -401.589432) (xy 335.353091 -401.523942) (xy 335.376856 -401.460845) (xy 335.408007 -401.401048)
			(xy 335.446096 -401.345412) (xy 335.46796 -401.319746) (xy 335.473769 -401.31261) (xy 335.480275 -401.295412)
			(xy 335.48066 -401.286218) (xy 335.48066 -400.793966) (xy 335.480253 -400.784779) (xy 335.473735 -400.767595)
			(xy 335.46796 -400.760438) (xy 335.446103 -400.734767) (xy 335.408017 -400.679133) (xy 335.376868 -400.619337)
			(xy 335.353106 -400.556241) (xy 335.337071 -400.490753) (xy 335.328995 -400.423816) (xy 335.328995 -400.356393)
			(xy 335.337069 -400.289456) (xy 335.353103 -400.223968) (xy 335.376865 -400.160872) (xy 335.408012 -400.101075)
			(xy 335.446098 -400.04544) (xy 335.46796 -400.019774) (xy 335.473757 -400.01263) (xy 335.48027 -399.995438)
			(xy 335.48066 -399.986246) (xy 335.48066 -399.828766) (xy 335.481099 -399.818635) (xy 335.488842 -399.799909)
			(xy 335.503143 -399.785553) (xy 335.521839 -399.777739) (xy 335.531968 -399.777204) (xy 336.248248 -399.777204)
			(xy 336.258406 -399.777583) (xy 336.27716 -399.785395) (xy 336.291482 -399.799804) (xy 336.299179 -399.818606)
			(xy 336.299556 -399.828766) (xy 336.299556 -399.986246) (xy 336.300002 -399.995429) (xy 336.306492 -400.012613)
			(xy 336.312256 -400.019774) (xy 336.334127 -400.045434) (xy 336.372219 -400.101068) (xy 336.403372 -400.160864)
			(xy 336.427138 -400.223962) (xy 336.443174 -400.289452) (xy 336.45125 -400.356392) (xy 336.451249 -400.423817)
			(xy 336.443172 -400.490756) (xy 336.427135 -400.556246) (xy 336.403368 -400.619344) (xy 336.372214 -400.67914)
			(xy 336.334122 -400.734774) (xy 336.312256 -400.760438) (xy 336.306455 -400.76758) (xy 336.299944 -400.784773)
			(xy 336.299556 -400.793966) (xy 336.299556 -401.286218) (xy 336.299967 -401.295405) (xy 336.306481 -401.312589)
			(xy 336.312256 -401.319746) (xy 336.3341 -401.345428) (xy 336.372192 -401.401059) (xy 336.403346 -401.460853)
			(xy 336.427114 -401.523948) (xy 336.443152 -401.589435) (xy 336.45123 -401.656372) (xy 336.451232 -401.723795)
			(xy 336.443158 -401.790732) (xy 336.427123 -401.856221) (xy 336.40336 -401.919317) (xy 336.372209 -401.979112)
			(xy 336.33412 -402.034746) (xy 336.312256 -402.06041) (xy 336.306467 -402.06756) (xy 336.299949 -402.084747)
			(xy 336.299556 -402.093938) (xy 336.299556 -402.251418) (xy 336.299088 -402.261546) (xy 336.291354 -402.280269)
			(xy 336.277062 -402.294625) (xy 336.258374 -402.302443) (xy 336.248248 -402.30298) (xy 335.531968 -402.30298)
			(xy 335.521809 -402.302604) (xy 335.503052 -402.294794) (xy 335.488729 -402.280384) (xy 335.481034 -402.261579)
			(xy 335.48066 -402.251418) (xy 335.48066 -402.093938) (xy 335.480218 -402.084754) (xy 335.473725 -402.06757)
			(xy 335.46796 -402.06041) (xy 335.446076 -402.034762) (xy 335.40799 -401.979124) (xy 335.376843 -401.919325)
			(xy 335.353082 -401.856226) (xy 335.337049 -401.790735) (xy 335.328975 -401.723796) (xy 334.200923 -401.723796)
			(xy 334.172056 -401.779212) (xy 334.13397 -401.834847) (xy 334.112108 -401.860512) (xy 334.106325 -401.867667)
			(xy 334.099802 -401.88485) (xy 334.099408 -401.89404) (xy 334.099408 -402.386292) (xy 334.09982 -402.395479)
			(xy 334.106332 -402.412663) (xy 334.112108 -402.41982) (xy 334.133925 -402.445524) (xy 334.172014 -402.501153)
			(xy 334.203166 -402.560944) (xy 334.226933 -402.624036) (xy 334.242972 -402.68952) (xy 334.251051 -402.756454)
			(xy 334.251055 -402.823818) (xy 337.529116 -402.823818) (xy 337.52912 -402.75651) (xy 337.537169 -402.689685)
			(xy 337.553145 -402.6243) (xy 337.576822 -402.561294) (xy 337.607859 -402.501569) (xy 337.645811 -402.445981)
			(xy 337.6676 -402.420328) (xy 337.67341 -402.413192) (xy 337.679917 -402.395994) (xy 337.6803 -402.3868)
			(xy 337.6803 -401.893532) (xy 337.679874 -401.884346) (xy 337.673371 -401.867162) (xy 337.6676 -401.860004)
			(xy 337.645794 -401.834367) (xy 337.607848 -401.778778) (xy 337.576818 -401.719052) (xy 337.553148 -401.656045)
			(xy 337.537178 -401.590662) (xy 337.529136 -401.523838) (xy 337.529137 -401.456532) (xy 337.537183 -401.389709)
			(xy 337.553157 -401.324326) (xy 337.57683 -401.261321) (xy 337.607864 -401.201596) (xy 337.645812 -401.146009)
			(xy 337.6676 -401.120356) (xy 337.673398 -401.113212) (xy 337.679912 -401.09602) (xy 337.6803 -401.086828)
			(xy 337.6803 -400.92884) (xy 337.680755 -400.918688) (xy 337.688537 -400.899937) (xy 337.702924 -400.885612)
			(xy 337.721709 -400.877911) (xy 337.731862 -400.877532) (xy 338.448142 -400.877532) (xy 338.45827 -400.877992)
			(xy 338.476991 -400.885732) (xy 338.491346 -400.900026) (xy 338.499165 -400.918714) (xy 338.499704 -400.92884)
			(xy 338.499704 -401.086828) (xy 338.5001 -401.096017) (xy 338.506623 -401.113201) (xy 338.512404 -401.120356)
			(xy 338.534171 -401.146025) (xy 338.572117 -401.20161) (xy 338.603149 -401.261332) (xy 338.626821 -401.324334)
			(xy 338.642794 -401.389714) (xy 338.650839 -401.456534) (xy 338.650841 -401.523836) (xy 338.6428 -401.590657)
			(xy 338.62683 -401.656037) (xy 338.603161 -401.719041) (xy 338.600721 -401.723737) (xy 339.72927 -401.723737)
			(xy 339.729272 -401.65643) (xy 339.737319 -401.589606) (xy 339.753294 -401.524222) (xy 339.77697 -401.461217)
			(xy 339.808006 -401.401492) (xy 339.845959 -401.345906) (xy 339.867748 -401.320254) (xy 339.873553 -401.313115)
			(xy 339.880061 -401.295919) (xy 339.880448 -401.286726) (xy 339.880448 -400.793458) (xy 339.880047 -400.78427)
			(xy 339.873526 -400.767086) (xy 339.867748 -400.75993) (xy 339.845966 -400.734273) (xy 339.808017 -400.678687)
			(xy 339.776983 -400.618965) (xy 339.753309 -400.555961) (xy 339.737335 -400.490579) (xy 339.729291 -400.423757)
			(xy 339.72929 -400.356452) (xy 339.737334 -400.28963) (xy 339.753306 -400.224248) (xy 339.776979 -400.161244)
			(xy 339.808012 -400.10152) (xy 339.845961 -400.045934) (xy 339.867748 -400.020282) (xy 339.873541 -400.013134)
			(xy 339.880056 -399.995946) (xy 339.880448 -399.986754) (xy 339.880448 -399.828766) (xy 339.880906 -399.818605)
			(xy 339.888693 -399.799833) (xy 339.90307 -399.785469) (xy 339.921848 -399.777697) (xy 339.93201 -399.777204)
			(xy 340.64829 -399.777204) (xy 340.658443 -399.777741) (xy 340.677205 -399.785506) (xy 340.69157 -399.799858)
			(xy 340.699351 -399.818613) (xy 340.699852 -399.828766) (xy 340.699852 -399.986754) (xy 340.700295 -399.995937)
			(xy 340.706787 -400.013121) (xy 340.712552 -400.020282) (xy 340.734346 -400.045929) (xy 340.772295 -400.101516)
			(xy 340.803329 -400.16124) (xy 340.827002 -400.224245) (xy 340.842975 -400.289628) (xy 340.851018 -400.356452)
			(xy 340.851018 -400.423757) (xy 340.842973 -400.490581) (xy 340.826999 -400.555963) (xy 340.803325 -400.618968)
			(xy 340.772291 -400.678692) (xy 340.734341 -400.734278) (xy 340.712552 -400.75993) (xy 340.706754 -400.767074)
			(xy 340.700242 -400.784266) (xy 340.699852 -400.793458) (xy 340.699852 -401.286726) (xy 340.70026 -401.295913)
			(xy 340.706777 -401.313097) (xy 340.712552 -401.320254) (xy 340.734318 -401.345924) (xy 340.772268 -401.401508)
			(xy 340.803303 -401.461229) (xy 340.826977 -401.524231) (xy 340.842952 -401.589611) (xy 340.850998 -401.656432)
			(xy 340.851 -401.723735) (xy 340.842958 -401.790556) (xy 340.826987 -401.855937) (xy 340.803316 -401.918941)
			(xy 340.772285 -401.978664) (xy 340.734338 -402.03425) (xy 340.712552 -402.059902) (xy 340.706766 -402.067055)
			(xy 340.700246 -402.08424) (xy 340.699852 -402.09343) (xy 340.699852 -402.251418) (xy 340.699381 -402.261578)
			(xy 340.691599 -402.28035) (xy 340.677226 -402.294715) (xy 340.65845 -402.302487) (xy 340.64829 -402.30298)
			(xy 339.93201 -402.30298) (xy 339.921855 -402.302459) (xy 339.90309 -402.294691) (xy 339.888725 -402.280334)
			(xy 339.880947 -402.261573) (xy 339.880448 -402.251418) (xy 339.880448 -402.09343) (xy 339.880013 -402.084246)
			(xy 339.873515 -402.067062) (xy 339.867748 -402.059902) (xy 339.845938 -402.034268) (xy 339.807989 -401.978679)
			(xy 339.776957 -401.918953) (xy 339.753285 -401.855946) (xy 339.737313 -401.790562) (xy 339.72927 -401.723737)
			(xy 338.600721 -401.723737) (xy 338.572133 -401.778764) (xy 338.534189 -401.834351) (xy 338.512404 -401.860004)
			(xy 338.506624 -401.867161) (xy 338.500099 -401.884342) (xy 338.499704 -401.893532) (xy 338.499704 -402.3868)
			(xy 338.500113 -402.395987) (xy 338.506628 -402.413172) (xy 338.512404 -402.420328) (xy 338.534143 -402.44602)
			(xy 338.572091 -402.501601) (xy 338.603124 -402.56132) (xy 338.626797 -402.624319) (xy 338.642772 -402.689696)
			(xy 338.65082 -402.756514) (xy 338.650824 -402.823814) (xy 338.650816 -402.823878) (xy 341.928884 -402.823878)
			(xy 341.928889 -402.75645) (xy 341.936969 -402.689509) (xy 341.95301 -402.624017) (xy 341.976779 -402.560918)
			(xy 342.007935 -402.501121) (xy 342.046029 -402.445485) (xy 342.067896 -402.41982) (xy 342.073709 -402.412686)
			(xy 342.080214 -402.395487) (xy 342.080596 -402.386292) (xy 342.080596 -401.89404) (xy 342.080168 -401.884855)
			(xy 342.073667 -401.86767) (xy 342.067896 -401.860512) (xy 342.046013 -401.834863) (xy 342.007925 -401.779226)
			(xy 341.976775 -401.719428) (xy 341.953012 -401.656329) (xy 341.936978 -401.590838) (xy 341.928904 -401.523898)
			(xy 341.928906 -401.456472) (xy 341.936984 -401.389533) (xy 341.953021 -401.324043) (xy 341.976787 -401.260945)
			(xy 342.00794 -401.201148) (xy 342.046031 -401.145513) (xy 342.067896 -401.119848) (xy 342.073697 -401.112706)
			(xy 342.080209 -401.095513) (xy 342.080596 -401.08632) (xy 342.080596 -400.92884) (xy 342.081049 -400.918721)
			(xy 342.088783 -400.900019) (xy 342.103088 -400.885703) (xy 342.121785 -400.877956) (xy 342.131904 -400.877532)
			(xy 342.848184 -400.877532) (xy 342.858309 -400.87793) (xy 342.877019 -400.885679) (xy 342.891335 -400.900001)
			(xy 342.899075 -400.918714) (xy 342.899492 -400.92884) (xy 342.899492 -401.08632) (xy 342.899894 -401.095508)
			(xy 342.906413 -401.112692) (xy 342.912192 -401.119848) (xy 342.934037 -401.145529) (xy 342.972126 -401.201161)
			(xy 343.003278 -401.260955) (xy 343.027044 -401.32405) (xy 343.043081 -401.389537) (xy 343.051159 -401.456474)
			(xy 343.051161 -401.523896) (xy 343.043087 -401.590833) (xy 343.027053 -401.656321) (xy 343.003291 -401.719417)
			(xy 343.001041 -401.723737) (xy 344.129061 -401.723737) (xy 344.129063 -401.65643) (xy 344.13711 -401.589606)
			(xy 344.153085 -401.524223) (xy 344.17676 -401.461217) (xy 344.207796 -401.401493) (xy 344.245747 -401.345906)
			(xy 344.267536 -401.320254) (xy 344.273339 -401.313114) (xy 344.279849 -401.295919) (xy 344.280236 -401.286726)
			(xy 344.280236 -400.793458) (xy 344.279838 -400.78427) (xy 344.273315 -400.767086) (xy 344.267536 -400.75993)
			(xy 344.245754 -400.734273) (xy 344.207805 -400.678687) (xy 344.176772 -400.618964) (xy 344.153099 -400.55596)
			(xy 344.137126 -400.490579) (xy 344.129081 -400.423757) (xy 344.129081 -400.356452) (xy 344.137124 -400.28963)
			(xy 344.153096 -400.224248) (xy 344.176768 -400.161244) (xy 344.207801 -400.101521) (xy 344.245749 -400.045934)
			(xy 344.267536 -400.020282) (xy 344.273327 -400.013133) (xy 344.279844 -399.995945) (xy 344.280236 -399.986754)
			(xy 344.280236 -399.828766) (xy 344.280705 -399.818606) (xy 344.288491 -399.799837) (xy 344.302864 -399.785473)
			(xy 344.321638 -399.777699) (xy 344.331798 -399.777204) (xy 345.048078 -399.777204) (xy 345.05823 -399.77775)
			(xy 345.076992 -399.785511) (xy 345.091357 -399.799861) (xy 345.099139 -399.818614) (xy 345.09964 -399.828766)
			(xy 345.09964 -399.986754) (xy 345.100086 -399.995937) (xy 345.106576 -400.013121) (xy 345.11234 -400.020282)
			(xy 345.134134 -400.045929) (xy 345.172084 -400.101516) (xy 345.203118 -400.16124) (xy 345.226792 -400.224245)
			(xy 345.242765 -400.289628) (xy 345.250809 -400.356452) (xy 345.250808 -400.423757) (xy 345.242763 -400.490581)
			(xy 345.226789 -400.555964) (xy 345.203115 -400.618968) (xy 345.172079 -400.678692) (xy 345.134129 -400.734278)
			(xy 345.11234 -400.75993) (xy 345.106541 -400.767073) (xy 345.100029 -400.784265) (xy 345.09964 -400.793458)
			(xy 345.09964 -401.286726) (xy 345.100051 -401.295913) (xy 345.106566 -401.313096) (xy 345.11234 -401.320254)
			(xy 345.134107 -401.345924) (xy 345.172057 -401.401507) (xy 345.203093 -401.461228) (xy 345.226768 -401.52423)
			(xy 345.242743 -401.589611) (xy 345.250789 -401.656432) (xy 345.250791 -401.723735) (xy 345.242749 -401.790557)
			(xy 345.226778 -401.855938) (xy 345.203106 -401.918942) (xy 345.172074 -401.978664) (xy 345.134127 -402.03425)
			(xy 345.11234 -402.059902) (xy 345.106553 -402.067053) (xy 345.100034 -402.084239) (xy 345.09964 -402.09343)
			(xy 345.09964 -402.251418) (xy 345.09925 -402.261593) (xy 345.091455 -402.280393) (xy 345.077059 -402.294778)
			(xy 345.058254 -402.302558) (xy 345.048078 -402.30298) (xy 344.331798 -402.30298) (xy 344.321642 -402.302469)
			(xy 344.302877 -402.294697) (xy 344.288512 -402.280337) (xy 344.280735 -402.261574) (xy 344.280236 -402.251418)
			(xy 344.280236 -402.09343) (xy 344.279803 -402.084245) (xy 344.273304 -402.067061) (xy 344.267536 -402.059902)
			(xy 344.245727 -402.034268) (xy 344.207779 -401.978679) (xy 344.176746 -401.918953) (xy 344.153075 -401.855946)
			(xy 344.137104 -401.790561) (xy 344.129061 -401.723737) (xy 343.001041 -401.723737) (xy 342.972142 -401.779213)
			(xy 342.934055 -401.834847) (xy 342.912192 -401.860512) (xy 342.906407 -401.867665) (xy 342.899886 -401.88485)
			(xy 342.899492 -401.89404) (xy 342.899492 -402.386292) (xy 342.899908 -402.395479) (xy 342.906418 -402.412663)
			(xy 342.912192 -402.41982) (xy 342.934009 -402.445524) (xy 342.9721 -402.501153) (xy 343.003253 -402.560944)
			(xy 343.02702 -402.624035) (xy 343.043059 -402.68952) (xy 343.051139 -402.756454) (xy 343.051143 -402.823819)
			(xy 346.329179 -402.823819) (xy 346.329184 -402.756509) (xy 346.337233 -402.689682) (xy 346.353213 -402.624297)
			(xy 346.376893 -402.56129) (xy 346.407934 -402.501566) (xy 346.445892 -402.445979) (xy 346.467684 -402.420328)
			(xy 346.473492 -402.413191) (xy 346.48 -402.395994) (xy 346.480384 -402.3868) (xy 346.480384 -401.893532)
			(xy 346.479962 -401.884346) (xy 346.473457 -401.867161) (xy 346.467684 -401.860004) (xy 346.445875 -401.834369)
			(xy 346.407924 -401.778781) (xy 346.376889 -401.719055) (xy 346.353216 -401.656049) (xy 346.337243 -401.590664)
			(xy 346.3292 -401.523839) (xy 346.329201 -401.456531) (xy 346.337248 -401.389707) (xy 346.353225 -401.324323)
			(xy 346.376902 -401.261317) (xy 346.40794 -401.201593) (xy 346.445894 -401.146008) (xy 346.467684 -401.120356)
			(xy 346.47348 -401.11321) (xy 346.479995 -401.09602) (xy 346.480384 -401.086828) (xy 346.480384 -400.92884)
			(xy 346.480854 -400.91869) (xy 346.488634 -400.899942) (xy 346.503015 -400.885618) (xy 346.521795 -400.877914)
			(xy 346.531946 -400.877532) (xy 347.248226 -400.877532) (xy 347.258353 -400.878005) (xy 347.277074 -400.88574)
			(xy 347.291429 -400.90003) (xy 347.299249 -400.918715) (xy 347.299788 -400.92884) (xy 347.299788 -401.086828)
			(xy 347.300187 -401.096016) (xy 347.306709 -401.1132) (xy 347.312488 -401.120356) (xy 347.334255 -401.146025)
			(xy 347.372203 -401.201609) (xy 347.403236 -401.261331) (xy 347.426908 -401.324333) (xy 347.442882 -401.389713)
			(xy 347.450927 -401.456533) (xy 347.450929 -401.523836) (xy 347.442887 -401.590657) (xy 347.426917 -401.656038)
			(xy 347.403248 -401.719042) (xy 347.400809 -401.723737) (xy 374.929092 -401.723737) (xy 374.929094 -401.65643)
			(xy 374.937141 -401.589605) (xy 374.953117 -401.524221) (xy 374.976794 -401.461216) (xy 375.007832 -401.401492)
			(xy 375.045786 -401.345906) (xy 375.067576 -401.320254) (xy 375.073372 -401.313108) (xy 375.079888 -401.295918)
			(xy 375.080276 -401.286726) (xy 375.080276 -400.793458) (xy 375.079891 -400.784268) (xy 375.07336 -400.767084)
			(xy 375.067576 -400.75993) (xy 375.045793 -400.734273) (xy 375.007842 -400.678688) (xy 374.976806 -400.618966)
			(xy 374.953131 -400.555962) (xy 374.937157 -400.49058) (xy 374.929112 -400.423757) (xy 374.929111 -400.356452)
			(xy 374.937155 -400.289629) (xy 374.953129 -400.224247) (xy 374.976802 -400.161242) (xy 375.007837 -400.101519)
			(xy 375.045788 -400.045934) (xy 375.067576 -400.020282) (xy 375.07336 -400.013128) (xy 375.079883 -399.995944)
			(xy 375.080276 -399.986754) (xy 375.080276 -399.828766) (xy 375.080637 -399.818587) (xy 375.08844 -399.799785)
			(xy 375.102845 -399.7854) (xy 375.121659 -399.777623) (xy 375.131838 -399.777204) (xy 375.848118 -399.777204)
			(xy 375.858273 -399.777718) (xy 375.877036 -399.785492) (xy 375.891399 -399.799851) (xy 375.899179 -399.818611)
			(xy 375.89968 -399.828766) (xy 375.89968 -399.986754) (xy 375.900117 -399.995938) (xy 375.906612 -400.013123)
			(xy 375.91238 -400.020282) (xy 375.934173 -400.045929) (xy 375.972121 -400.101517) (xy 376.003152 -400.161241)
			(xy 376.026824 -400.224247) (xy 376.042796 -400.289629) (xy 376.050839 -400.356452) (xy 376.050839 -400.423757)
			(xy 376.042794 -400.49058) (xy 376.026821 -400.555962) (xy 376.003149 -400.618967) (xy 375.972116 -400.678691)
			(xy 375.934168 -400.734278) (xy 375.91238 -400.75993) (xy 375.906586 -400.767077) (xy 375.90007 -400.784266)
			(xy 375.89968 -400.793458) (xy 375.89968 -401.286726) (xy 375.900082 -401.295914) (xy 375.906602 -401.313098)
			(xy 375.91238 -401.320254) (xy 375.934146 -401.345924) (xy 375.972094 -401.401508) (xy 376.003127 -401.46123)
			(xy 376.0268 -401.524232) (xy 376.042774 -401.589612) (xy 376.05082 -401.656432) (xy 376.050822 -401.723735)
			(xy 376.04278 -401.790556) (xy 376.02681 -401.855937) (xy 376.003141 -401.91894) (xy 375.972111 -401.978663)
			(xy 375.934166 -402.03425) (xy 375.91238 -402.059902) (xy 375.906598 -402.067057) (xy 375.900075 -402.08424)
			(xy 375.89968 -402.09343) (xy 375.89968 -402.251418) (xy 375.899182 -402.261575) (xy 375.891405 -402.280341)
			(xy 375.877041 -402.294705) (xy 375.858275 -402.302482) (xy 375.848118 -402.30298) (xy 375.131838 -402.30298)
			(xy 375.121671 -402.302505) (xy 375.102881 -402.294736) (xy 375.088495 -402.280366) (xy 375.080706 -402.261584)
			(xy 375.080276 -402.251418) (xy 375.080276 -402.09343) (xy 375.079857 -402.084244) (xy 375.07335 -402.067059)
			(xy 375.067576 -402.059902) (xy 375.045766 -402.034268) (xy 375.007815 -401.97868) (xy 374.976781 -401.918954)
			(xy 374.953108 -401.855947) (xy 374.937135 -401.790562) (xy 374.929092 -401.723737) (xy 347.400809 -401.723737)
			(xy 347.372218 -401.778765) (xy 347.334274 -401.834352) (xy 347.312488 -401.860004) (xy 347.306706 -401.867159)
			(xy 347.300183 -401.884342) (xy 347.299788 -401.893532) (xy 347.299788 -402.3868) (xy 347.300201 -402.395987)
			(xy 347.306713 -402.413171) (xy 347.312488 -402.420328) (xy 347.334227 -402.44602) (xy 347.372176 -402.501601)
			(xy 347.40321 -402.561319) (xy 347.426884 -402.624319) (xy 347.442859 -402.689696) (xy 347.450907 -402.756514)
			(xy 347.450911 -402.823814) (xy 347.450903 -402.823878) (xy 377.128705 -402.823878) (xy 377.12871 -402.75645)
			(xy 377.136791 -402.689508) (xy 377.152832 -402.624016) (xy 377.176603 -402.560917) (xy 377.20776 -402.50112)
			(xy 377.245856 -402.445485) (xy 377.267724 -402.41982) (xy 377.27354 -402.412689) (xy 377.280042 -402.395487)
			(xy 377.280424 -402.386292) (xy 377.280424 -401.89404) (xy 377.279989 -401.884856) (xy 377.273492 -401.867671)
			(xy 377.267724 -401.860512) (xy 377.24584 -401.834863) (xy 377.20775 -401.779227) (xy 377.176599 -401.719429)
			(xy 377.152835 -401.65633) (xy 377.1368 -401.590838) (xy 377.128725 -401.523898) (xy 377.128727 -401.456472)
			(xy 377.136805 -401.389532) (xy 377.152843 -401.324042) (xy 377.176611 -401.260944) (xy 377.207765 -401.201147)
			(xy 377.245858 -401.145513) (xy 377.267724 -401.119848) (xy 377.273528 -401.112708) (xy 377.280037 -401.095513)
			(xy 377.280424 -401.08632) (xy 377.280424 -400.92884) (xy 377.280849 -400.918717) (xy 377.288589 -400.90001)
			(xy 377.302903 -400.885693) (xy 377.321609 -400.877951) (xy 377.331732 -400.877532) (xy 378.048012 -400.877532)
			(xy 378.058139 -400.877907) (xy 378.076849 -400.885665) (xy 378.091164 -400.899994) (xy 378.098904 -400.918712)
			(xy 378.09932 -400.92884) (xy 378.09932 -401.08632) (xy 378.099716 -401.095509) (xy 378.106239 -401.112693)
			(xy 378.11202 -401.119848) (xy 378.133864 -401.14553) (xy 378.171952 -401.201162) (xy 378.203102 -401.260957)
			(xy 378.226866 -401.324051) (xy 378.242903 -401.389538) (xy 378.25098 -401.456474) (xy 378.250982 -401.523896)
			(xy 378.242908 -401.590832) (xy 378.226875 -401.65632) (xy 378.203114 -401.719416) (xy 378.200833 -401.723796)
			(xy 379.328885 -401.723796) (xy 379.328887 -401.656371) (xy 379.336964 -401.589432) (xy 379.353001 -401.523942)
			(xy 379.376766 -401.460844) (xy 379.407918 -401.401047) (xy 379.446008 -401.345412) (xy 379.467872 -401.319746)
			(xy 379.473683 -401.312611) (xy 379.480187 -401.295412) (xy 379.480572 -401.286218) (xy 379.480572 -400.793966)
			(xy 379.480184 -400.784776) (xy 379.473656 -400.767592) (xy 379.467872 -400.760438) (xy 379.446015 -400.734767)
			(xy 379.407928 -400.679133) (xy 379.376778 -400.619337) (xy 379.353015 -400.556241) (xy 379.33698 -400.490753)
			(xy 379.328904 -400.423816) (xy 379.328904 -400.356393) (xy 379.336979 -400.289456) (xy 379.353013 -400.223967)
			(xy 379.376775 -400.160871) (xy 379.407923 -400.101075) (xy 379.446009 -400.04544) (xy 379.467872 -400.019774)
			(xy 379.473671 -400.012631) (xy 379.480182 -399.995438) (xy 379.480572 -399.986246) (xy 379.480572 -399.828766)
			(xy 379.481 -399.818633) (xy 379.488744 -399.799905) (xy 379.503049 -399.785549) (xy 379.521749 -399.777737)
			(xy 379.53188 -399.777204) (xy 380.24816 -399.777204) (xy 380.25828 -399.777649) (xy 380.276984 -399.785385)
			(xy 380.2913 -399.799693) (xy 380.299045 -399.818392) (xy 380.299468 -399.828512) (xy 380.299468 -399.986246)
			(xy 380.299911 -399.99543) (xy 380.306403 -400.012614) (xy 380.312168 -400.019774) (xy 380.334039 -400.045434)
			(xy 380.37213 -400.101068) (xy 380.403282 -400.160865) (xy 380.427047 -400.223963) (xy 380.443083 -400.289453)
			(xy 380.451159 -400.356392) (xy 380.451158 -400.423817) (xy 380.443082 -400.490756) (xy 380.427044 -400.556246)
			(xy 380.403278 -400.619343) (xy 380.372125 -400.679139) (xy 380.334033 -400.734773) (xy 380.312168 -400.760438)
			(xy 380.306369 -400.767581) (xy 380.299856 -400.784773) (xy 380.299468 -400.793966) (xy 380.299468 -401.286218)
			(xy 380.299877 -401.295405) (xy 380.306392 -401.312589) (xy 380.312168 -401.319746) (xy 380.334011 -401.345429)
			(xy 380.372103 -401.40106) (xy 380.403256 -401.460853) (xy 380.427023 -401.523948) (xy 380.443061 -401.589435)
			(xy 380.451139 -401.656372) (xy 380.451141 -401.723795) (xy 380.443067 -401.790732) (xy 380.427033 -401.85622)
			(xy 380.40327 -401.919316) (xy 380.37212 -401.979112) (xy 380.334032 -402.034745) (xy 380.312168 -402.06041)
			(xy 380.306381 -402.067562) (xy 380.299861 -402.084747) (xy 380.299468 -402.093938) (xy 380.299468 -402.251418)
			(xy 380.298989 -402.261545) (xy 380.291256 -402.280265) (xy 380.276968 -402.29462) (xy 380.258284 -402.30244)
			(xy 380.24816 -402.30298) (xy 379.53188 -402.30298) (xy 379.521754 -402.3026) (xy 379.503046 -402.294842)
			(xy 379.488731 -402.280514) (xy 379.48099 -402.261799) (xy 379.480572 -402.251672) (xy 379.480572 -402.093938)
			(xy 379.48015 -402.084752) (xy 379.473645 -402.067567) (xy 379.467872 -402.06041) (xy 379.445987 -402.034762)
			(xy 379.407901 -401.979124) (xy 379.376753 -401.919326) (xy 379.352991 -401.856227) (xy 379.336958 -401.790736)
			(xy 379.328885 -401.723796) (xy 378.200833 -401.723796) (xy 378.171967 -401.779212) (xy 378.133882 -401.834846)
			(xy 378.11202 -401.860512) (xy 378.106238 -401.867668) (xy 378.099714 -401.88485) (xy 378.09932 -401.89404)
			(xy 378.09932 -402.386292) (xy 378.099729 -402.395479) (xy 378.106243 -402.412664) (xy 378.11202 -402.41982)
			(xy 378.133836 -402.445524) (xy 378.171925 -402.501154) (xy 378.203077 -402.560945) (xy 378.226843 -402.624037)
			(xy 378.242881 -402.689521) (xy 378.25096 -402.756454) (xy 378.250965 -402.823818) (xy 381.529025 -402.823818)
			(xy 381.529029 -402.75651) (xy 381.537078 -402.689684) (xy 381.553055 -402.6243) (xy 381.576732 -402.561293)
			(xy 381.607769 -402.501568) (xy 381.645722 -402.445981) (xy 381.667512 -402.420328) (xy 381.673323 -402.413193)
			(xy 381.679829 -402.395995) (xy 381.680212 -402.3868) (xy 381.680212 -401.893532) (xy 381.679784 -401.884347)
			(xy 381.673282 -401.867162) (xy 381.667512 -401.860004) (xy 381.645705 -401.834368) (xy 381.607759 -401.778778)
			(xy 381.576728 -401.719052) (xy 381.553058 -401.656046) (xy 381.537087 -401.590662) (xy 381.529045 -401.523838)
			(xy 381.529046 -401.456532) (xy 381.537092 -401.389708) (xy 381.553066 -401.324325) (xy 381.57674 -401.26132)
			(xy 381.607774 -401.201596) (xy 381.645724 -401.146009) (xy 381.667512 -401.120356) (xy 381.673311 -401.113213)
			(xy 381.679824 -401.096021) (xy 381.680212 -401.086828) (xy 381.680212 -400.92884) (xy 381.680649 -400.918719)
			(xy 381.688386 -400.900014) (xy 381.702697 -400.885698) (xy 381.721399 -400.877953) (xy 381.73152 -400.877532)
			(xy 382.448054 -400.877532) (xy 382.458177 -400.878064) (xy 382.476895 -400.885775) (xy 382.491253 -400.900048)
			(xy 382.499075 -400.91872) (xy 382.499616 -400.92884) (xy 382.499616 -401.086828) (xy 382.500009 -401.096017)
			(xy 382.506534 -401.113201) (xy 382.512316 -401.120356) (xy 382.534085 -401.146024) (xy 382.572038 -401.201607)
			(xy 382.603074 -401.261328) (xy 382.62675 -401.32433) (xy 382.642726 -401.389711) (xy 382.650772 -401.456533)
			(xy 382.650774 -401.523837) (xy 382.642731 -401.590659) (xy 382.626759 -401.656041) (xy 382.603087 -401.719045)
			(xy 382.600649 -401.723737) (xy 383.729179 -401.723737) (xy 383.729181 -401.65643) (xy 383.737228 -401.589605)
			(xy 383.753204 -401.524222) (xy 383.77688 -401.461216) (xy 383.807917 -401.401492) (xy 383.84587 -401.345906)
			(xy 383.86766 -401.320254) (xy 383.873466 -401.313116) (xy 383.879973 -401.29592) (xy 383.88036 -401.286726)
			(xy 383.88036 -400.793458) (xy 383.879957 -400.78427) (xy 383.873437 -400.767087) (xy 383.86766 -400.75993)
			(xy 383.845878 -400.734273) (xy 383.807927 -400.678688) (xy 383.776893 -400.618965) (xy 383.753219 -400.555961)
			(xy 383.737245 -400.490579) (xy 383.7292 -400.423757) (xy 383.729199 -400.356452) (xy 383.737243 -400.28963)
			(xy 383.753216 -400.224247) (xy 383.776889 -400.161243) (xy 383.807923 -400.10152) (xy 383.845872 -400.045934)
			(xy 383.86766 -400.020282) (xy 383.873454 -400.013135) (xy 383.879969 -399.995946) (xy 383.88036 -399.986754)
			(xy 383.88036 -399.828766) (xy 383.880806 -399.818603) (xy 383.888596 -399.799829) (xy 383.902976 -399.785464)
			(xy 383.921759 -399.777695) (xy 383.931922 -399.777204) (xy 384.648202 -399.777204) (xy 384.658356 -399.777731)
			(xy 384.677118 -399.7855) (xy 384.691482 -399.799855) (xy 384.699263 -399.818613) (xy 384.699764 -399.828766)
			(xy 384.699764 -399.986754) (xy 384.700205 -399.995938) (xy 384.706698 -400.013122) (xy 384.712464 -400.020282)
			(xy 384.734258 -400.045929) (xy 384.772206 -400.101516) (xy 384.803239 -400.161241) (xy 384.826911 -400.224246)
			(xy 384.842884 -400.289629) (xy 384.850927 -400.356452) (xy 384.850927 -400.423757) (xy 384.842882 -400.49058)
			(xy 384.826909 -400.555963) (xy 384.803235 -400.618968) (xy 384.772201 -400.678691) (xy 384.734252 -400.734278)
			(xy 384.712464 -400.75993) (xy 384.706668 -400.767075) (xy 384.700154 -400.784266) (xy 384.699764 -400.793458)
			(xy 384.699764 -401.286726) (xy 384.70017 -401.295913) (xy 384.706687 -401.313097) (xy 384.712464 -401.320254)
			(xy 384.73423 -401.345924) (xy 384.772179 -401.401508) (xy 384.803213 -401.461229) (xy 384.826887 -401.524231)
			(xy 384.842861 -401.589611) (xy 384.850907 -401.656432) (xy 384.850909 -401.723735) (xy 384.842867 -401.790556)
			(xy 384.826897 -401.855937) (xy 384.803227 -401.918941) (xy 384.772196 -401.978663) (xy 384.73425 -402.03425)
			(xy 384.712464 -402.059902) (xy 384.706679 -402.067056) (xy 384.700158 -402.08424) (xy 384.699764 -402.09343)
			(xy 384.699764 -402.251418) (xy 384.699282 -402.261577) (xy 384.691502 -402.280346) (xy 384.677133 -402.294711)
			(xy 384.658361 -402.302485) (xy 384.648202 -402.30298) (xy 383.931922 -402.30298) (xy 383.921754 -402.302518)
			(xy 383.902963 -402.294744) (xy 383.888578 -402.28037) (xy 383.88079 -402.261586) (xy 383.88036 -402.251418)
			(xy 383.88036 -402.09343) (xy 383.879922 -402.084246) (xy 383.873426 -402.067062) (xy 383.86766 -402.059902)
			(xy 383.84585 -402.034268) (xy 383.8079 -401.97868) (xy 383.776867 -401.918954) (xy 383.753194 -401.855947)
			(xy 383.737222 -401.790562) (xy 383.729179 -401.723737) (xy 382.600649 -401.723737) (xy 382.572053 -401.778767)
			(xy 382.534104 -401.834352) (xy 382.512316 -401.860004) (xy 382.506537 -401.867162) (xy 382.500011 -401.884343)
			(xy 382.499616 -401.893532) (xy 382.499616 -402.3868) (xy 382.500023 -402.395988) (xy 382.506538 -402.413172)
			(xy 382.512316 -402.420328) (xy 382.534058 -402.446018) (xy 382.572011 -402.501598) (xy 382.603049 -402.561316)
			(xy 382.626726 -402.624316) (xy 382.642704 -402.689694) (xy 382.650753 -402.756513) (xy 382.650757 -402.823815)
			(xy 382.650749 -402.823878) (xy 385.928793 -402.823878) (xy 385.928798 -402.75645) (xy 385.936878 -402.689508)
			(xy 385.952919 -402.624017) (xy 385.976689 -402.560918) (xy 386.007846 -402.50112) (xy 386.045941 -402.445485)
			(xy 386.067808 -402.41982) (xy 386.073622 -402.412687) (xy 386.080126 -402.395487) (xy 386.080508 -402.386292)
			(xy 386.080508 -401.89404) (xy 386.080077 -401.884855) (xy 386.073578 -401.867671) (xy 386.067808 -401.860512)
			(xy 386.045924 -401.834863) (xy 386.007835 -401.779226) (xy 385.976685 -401.719428) (xy 385.952922 -401.656329)
			(xy 385.936887 -401.590838) (xy 385.928813 -401.523898) (xy 385.928815 -401.456472) (xy 385.936893 -401.389533)
			(xy 385.952931 -401.324042) (xy 385.976697 -401.260944) (xy 386.007851 -401.201148) (xy 386.045943 -401.145513)
			(xy 386.067808 -401.119848) (xy 386.07361 -401.112707) (xy 386.080121 -401.095513) (xy 386.080508 -401.08632)
			(xy 386.080508 -400.92884) (xy 386.080949 -400.918719) (xy 386.088686 -400.900015) (xy 386.102995 -400.885699)
			(xy 386.121695 -400.877954) (xy 386.131816 -400.877532) (xy 386.848096 -400.877532) (xy 386.858222 -400.87792)
			(xy 386.876932 -400.885673) (xy 386.891247 -400.899998) (xy 386.898987 -400.918714) (xy 386.899404 -400.92884)
			(xy 386.899404 -401.08632) (xy 386.899804 -401.095508) (xy 386.906325 -401.112692) (xy 386.912104 -401.119848)
			(xy 386.933948 -401.14553) (xy 386.972037 -401.201162) (xy 387.003189 -401.260956) (xy 387.026954 -401.324051)
			(xy 387.04299 -401.389538) (xy 387.051068 -401.456474) (xy 387.05107 -401.523896) (xy 387.042996 -401.590833)
			(xy 387.026963 -401.656321) (xy 387.003201 -401.719417) (xy 387.000951 -401.723737) (xy 388.12897 -401.723737)
			(xy 388.128972 -401.65643) (xy 388.137019 -401.589606) (xy 388.152994 -401.524222) (xy 388.17667 -401.461217)
			(xy 388.207706 -401.401492) (xy 388.245659 -401.345906) (xy 388.267448 -401.320254) (xy 388.273253 -401.313115)
			(xy 388.279761 -401.295919) (xy 388.280148 -401.286726) (xy 388.280148 -400.793458) (xy 388.279747 -400.78427)
			(xy 388.273226 -400.767086) (xy 388.267448 -400.75993) (xy 388.245666 -400.734273) (xy 388.207717 -400.678687)
			(xy 388.176683 -400.618965) (xy 388.153009 -400.555961) (xy 388.137035 -400.490579) (xy 388.128991 -400.423757)
			(xy 388.12899 -400.356452) (xy 388.137034 -400.28963) (xy 388.153006 -400.224248) (xy 388.176679 -400.161244)
			(xy 388.207712 -400.10152) (xy 388.245661 -400.045934) (xy 388.267448 -400.020282) (xy 388.273241 -400.013134)
			(xy 388.279756 -399.995946) (xy 388.280148 -399.986754) (xy 388.280148 -399.828766) (xy 388.280606 -399.818605)
			(xy 388.288393 -399.799833) (xy 388.30277 -399.785469) (xy 388.321548 -399.777697) (xy 388.33171 -399.777204)
			(xy 389.04799 -399.777204) (xy 389.058143 -399.777741) (xy 389.076905 -399.785506) (xy 389.09127 -399.799858)
			(xy 389.099051 -399.818613) (xy 389.099552 -399.828766) (xy 389.099552 -399.986754) (xy 389.099995 -399.995937)
			(xy 389.106487 -400.013121) (xy 389.112252 -400.020282) (xy 389.134046 -400.045929) (xy 389.171995 -400.101516)
			(xy 389.203029 -400.16124) (xy 389.226702 -400.224245) (xy 389.242675 -400.289628) (xy 389.250718 -400.356452)
			(xy 389.250718 -400.423757) (xy 389.242673 -400.490581) (xy 389.226699 -400.555963) (xy 389.203025 -400.618968)
			(xy 389.171991 -400.678692) (xy 389.134041 -400.734278) (xy 389.112252 -400.75993) (xy 389.106454 -400.767074)
			(xy 389.099942 -400.784266) (xy 389.099552 -400.793458) (xy 389.099552 -401.286726) (xy 389.09996 -401.295913)
			(xy 389.106477 -401.313097) (xy 389.112252 -401.320254) (xy 389.134018 -401.345924) (xy 389.171968 -401.401508)
			(xy 389.203003 -401.461229) (xy 389.226677 -401.524231) (xy 389.242652 -401.589611) (xy 389.250698 -401.656432)
			(xy 389.2507 -401.723735) (xy 389.242658 -401.790556) (xy 389.226687 -401.855937) (xy 389.203016 -401.918941)
			(xy 389.171985 -401.978664) (xy 389.134038 -402.03425) (xy 389.112252 -402.059902) (xy 389.106466 -402.067055)
			(xy 389.099946 -402.08424) (xy 389.099552 -402.09343) (xy 389.099552 -402.251418) (xy 389.099081 -402.261578)
			(xy 389.091299 -402.28035) (xy 389.076926 -402.294715) (xy 389.05815 -402.302487) (xy 389.04799 -402.30298)
			(xy 388.33171 -402.30298) (xy 388.321555 -402.302459) (xy 388.30279 -402.294691) (xy 388.288425 -402.280334)
			(xy 388.280647 -402.261573) (xy 388.280148 -402.251418) (xy 388.280148 -402.09343) (xy 388.279713 -402.084246)
			(xy 388.273215 -402.067062) (xy 388.267448 -402.059902) (xy 388.245638 -402.034268) (xy 388.207689 -401.978679)
			(xy 388.176657 -401.918953) (xy 388.152985 -401.855946) (xy 388.137013 -401.790562) (xy 388.12897 -401.723737)
			(xy 387.000951 -401.723737) (xy 386.972053 -401.779212) (xy 386.933967 -401.834847) (xy 386.912104 -401.860512)
			(xy 386.90632 -401.867666) (xy 386.899798 -401.88485) (xy 386.899404 -401.89404) (xy 386.899404 -402.386292)
			(xy 386.899817 -402.395479) (xy 386.906329 -402.412663) (xy 386.912104 -402.41982) (xy 386.933921 -402.445524)
			(xy 386.972011 -402.501153) (xy 387.003163 -402.560944) (xy 387.02693 -402.624036) (xy 387.042968 -402.68952)
			(xy 387.051048 -402.756454) (xy 387.051052 -402.823818) (xy 390.329113 -402.823818) (xy 390.329117 -402.75651)
			(xy 390.337166 -402.689685) (xy 390.353142 -402.6243) (xy 390.376819 -402.561294) (xy 390.407855 -402.501569)
			(xy 390.445807 -402.445981) (xy 390.467596 -402.420328) (xy 390.473405 -402.413192) (xy 390.479912 -402.395994)
			(xy 390.480296 -402.3868) (xy 390.480296 -401.893532) (xy 390.479871 -401.884346) (xy 390.473368 -401.867162)
			(xy 390.467596 -401.860004) (xy 390.44579 -401.834367) (xy 390.407845 -401.778778) (xy 390.376815 -401.719052)
			(xy 390.353145 -401.656045) (xy 390.337174 -401.590661) (xy 390.329133 -401.523838) (xy 390.329134 -401.456532)
			(xy 390.33718 -401.389709) (xy 390.353154 -401.324326) (xy 390.376827 -401.261321) (xy 390.40786 -401.201596)
			(xy 390.445808 -401.146009) (xy 390.467596 -401.120356) (xy 390.473393 -401.113211) (xy 390.479908 -401.09602)
			(xy 390.480296 -401.086828) (xy 390.480296 -400.92884) (xy 390.480749 -400.918721) (xy 390.488483 -400.900019)
			(xy 390.502788 -400.885703) (xy 390.521485 -400.877956) (xy 390.531604 -400.877532) (xy 391.248138 -400.877532)
			(xy 391.258266 -400.877995) (xy 391.276987 -400.885734) (xy 391.291341 -400.900027) (xy 391.299161 -400.918714)
			(xy 391.2997 -400.92884) (xy 391.2997 -401.086828) (xy 391.300096 -401.096017) (xy 391.30662 -401.113201)
			(xy 391.3124 -401.120356) (xy 391.334167 -401.146025) (xy 391.372114 -401.20161) (xy 391.403146 -401.261331)
			(xy 391.426818 -401.324334) (xy 391.442791 -401.389713) (xy 391.450836 -401.456534) (xy 391.450838 -401.523836)
			(xy 391.442797 -401.590657) (xy 391.426827 -401.656038) (xy 391.403158 -401.719041) (xy 391.372129 -401.778764)
			(xy 391.334185 -401.834351) (xy 391.3124 -401.860004) (xy 391.306619 -401.86716) (xy 391.300095 -401.884342)
			(xy 391.2997 -401.893532) (xy 391.2997 -402.3868) (xy 391.30011 -402.395987) (xy 391.306624 -402.413171)
			(xy 391.3124 -402.420328) (xy 391.334139 -402.446019) (xy 391.372087 -402.501601) (xy 391.40312 -402.56132)
			(xy 391.426794 -402.624319) (xy 391.442769 -402.689696) (xy 391.450817 -402.756514) (xy 391.450821 -402.823814)
			(xy 391.442782 -402.890633) (xy 391.426815 -402.956012) (xy 391.40315 -403.019014) (xy 391.372124 -403.078737)
			(xy 391.334184 -403.134323) (xy 391.3124 -403.159976) (xy 391.306589 -403.167111) (xy 391.300083 -403.184309)
			(xy 391.2997 -403.193504) (xy 391.2997 -403.351492) (xy 391.299277 -403.361614) (xy 391.291532 -403.380317)
			(xy 391.277217 -403.394632) (xy 391.258514 -403.402377) (xy 391.248392 -403.4028) (xy 390.531858 -403.4028)
			(xy 390.521734 -403.402309) (xy 390.503019 -403.394575) (xy 390.488666 -403.380291) (xy 390.480841 -403.361614)
			(xy 390.480296 -403.351492) (xy 390.480296 -403.193504) (xy 390.479885 -403.184317) (xy 390.473372 -403.167133)
			(xy 390.467596 -403.159976) (xy 390.445763 -403.134362) (xy 390.407818 -403.078769) (xy 390.376789 -403.01904)
			(xy 390.353121 -402.95603) (xy 390.337153 -402.890644) (xy 390.329113 -402.823818) (xy 387.051052 -402.823818)
			(xy 387.051052 -402.823874) (xy 387.042981 -402.890809) (xy 387.026951 -402.956295) (xy 387.003193 -403.01939)
			(xy 386.972048 -403.079185) (xy 386.933965 -403.134819) (xy 386.912104 -403.160484) (xy 386.90629 -403.167617)
			(xy 386.899785 -403.184817) (xy 386.899404 -403.194012) (xy 386.899404 -403.351492) (xy 386.898978 -403.361613)
			(xy 386.891233 -403.380316) (xy 386.87692 -403.394631) (xy 386.858217 -403.402377) (xy 386.848096 -403.4028)
			(xy 386.131816 -403.4028) (xy 386.121695 -403.402371) (xy 386.102991 -403.394628) (xy 386.088676 -403.380315)
			(xy 386.080931 -403.361613) (xy 386.080508 -403.351492) (xy 386.080508 -403.194012) (xy 386.08009 -403.184826)
			(xy 386.073582 -403.167641) (xy 386.067808 -403.160484) (xy 386.045897 -403.134858) (xy 386.007809 -403.079218)
			(xy 385.97666 -403.019416) (xy 385.952898 -402.956314) (xy 385.936865 -402.89082) (xy 385.928793 -402.823878)
			(xy 382.650749 -402.823878) (xy 382.642717 -402.890635) (xy 382.626748 -402.956015) (xy 382.603078 -403.019018)
			(xy 382.572048 -403.07874) (xy 382.534102 -403.134324) (xy 382.512316 -403.159976) (xy 382.506507 -403.167112)
			(xy 382.499999 -403.18431) (xy 382.499616 -403.193504) (xy 382.499616 -403.351492) (xy 382.499109 -403.361598)
			(xy 382.491377 -403.380273) (xy 382.477087 -403.394568) (xy 382.458414 -403.402306) (xy 382.448308 -403.4028)
			(xy 381.731774 -403.4028) (xy 381.721651 -403.402296) (xy 381.702936 -403.394567) (xy 381.688582 -403.380287)
			(xy 381.680757 -403.361613) (xy 381.680212 -403.351492) (xy 381.680212 -403.193504) (xy 381.679797 -403.184317)
			(xy 381.673286 -403.167133) (xy 381.667512 -403.159976) (xy 381.645678 -403.134362) (xy 381.607732 -403.07877)
			(xy 381.576703 -403.019041) (xy 381.553034 -402.956031) (xy 381.537065 -402.890644) (xy 381.529025 -402.823818)
			(xy 378.250965 -402.823818) (xy 378.250965 -402.823874) (xy 378.242894 -402.890808) (xy 378.226864 -402.956294)
			(xy 378.203106 -403.019389) (xy 378.171962 -403.079184) (xy 378.13388 -403.134818) (xy 378.11202 -403.160484)
			(xy 378.106208 -403.167618) (xy 378.099702 -403.184817) (xy 378.09932 -403.194012) (xy 378.09932 -403.351492)
			(xy 378.098809 -403.361598) (xy 378.091078 -403.380272) (xy 378.076789 -403.394566) (xy 378.058118 -403.402305)
			(xy 378.048012 -403.4028) (xy 377.331732 -403.4028) (xy 377.321612 -403.402358) (xy 377.302909 -403.39462)
			(xy 377.288593 -403.380312) (xy 377.280847 -403.361612) (xy 377.280424 -403.351492) (xy 377.280424 -403.194012)
			(xy 377.280002 -403.184826) (xy 377.273496 -403.167642) (xy 377.267724 -403.160484) (xy 377.245812 -403.134858)
			(xy 377.207723 -403.079218) (xy 377.176573 -403.019417) (xy 377.152811 -402.956315) (xy 377.136778 -402.890821)
			(xy 377.128705 -402.823878) (xy 347.450903 -402.823878) (xy 347.442872 -402.890633) (xy 347.426905 -402.956012)
			(xy 347.403239 -403.019015) (xy 347.372213 -403.078737) (xy 347.334272 -403.134323) (xy 347.312488 -403.159976)
			(xy 347.306675 -403.16711) (xy 347.300171 -403.184309) (xy 347.299788 -403.193504) (xy 347.299788 -403.351492)
			(xy 347.299372 -403.361647) (xy 347.291576 -403.380402) (xy 347.277178 -403.394726) (xy 347.258383 -403.402424)
			(xy 347.248226 -403.4028) (xy 346.531946 -403.4028) (xy 346.521827 -403.402237) (xy 346.503115 -403.394532)
			(xy 346.488758 -403.380269) (xy 346.48093 -403.361607) (xy 346.480384 -403.351492) (xy 346.480384 -403.193504)
			(xy 346.479975 -403.184317) (xy 346.473461 -403.167132) (xy 346.467684 -403.159976) (xy 346.445847 -403.134364)
			(xy 346.407897 -403.078772) (xy 346.376863 -403.019044) (xy 346.353191 -402.956034) (xy 346.33722 -402.890646)
			(xy 346.329179 -402.823819) (xy 343.051143 -402.823819) (xy 343.051143 -402.823874) (xy 343.043072 -402.890809)
			(xy 343.027042 -402.956296) (xy 343.003282 -403.019391) (xy 342.972137 -403.079185) (xy 342.934053 -403.134819)
			(xy 342.912192 -403.160484) (xy 342.906376 -403.167616) (xy 342.899873 -403.184817) (xy 342.899492 -403.194012)
			(xy 342.899492 -403.351492) (xy 342.899077 -403.361615) (xy 342.89133 -403.38032) (xy 342.877013 -403.394635)
			(xy 342.858307 -403.402379) (xy 342.848184 -403.4028) (xy 342.131904 -403.4028) (xy 342.121782 -403.402381)
			(xy 342.103078 -403.394634) (xy 342.088764 -403.380318) (xy 342.081019 -403.361614) (xy 342.080596 -403.351492)
			(xy 342.080596 -403.194012) (xy 342.080181 -403.184825) (xy 342.073671 -403.167641) (xy 342.067896 -403.160484)
			(xy 342.045985 -403.134858) (xy 342.007898 -403.079217) (xy 341.97675 -403.019416) (xy 341.952988 -402.956314)
			(xy 341.936956 -402.89082) (xy 341.928884 -402.823878) (xy 338.650816 -402.823878) (xy 338.642785 -402.890633)
			(xy 338.626819 -402.956012) (xy 338.603153 -403.019014) (xy 338.572128 -403.078737) (xy 338.534188 -403.134323)
			(xy 338.512404 -403.159976) (xy 338.506593 -403.167111) (xy 338.500087 -403.184309) (xy 338.499704 -403.193504)
			(xy 338.499704 -403.351492) (xy 338.499272 -403.361645) (xy 338.49148 -403.380397) (xy 338.477086 -403.39472)
			(xy 338.458297 -403.402421) (xy 338.448142 -403.4028) (xy 337.731862 -403.4028) (xy 337.721738 -403.402306)
			(xy 337.703023 -403.394573) (xy 337.68867 -403.38029) (xy 337.680845 -403.361614) (xy 337.6803 -403.351492)
			(xy 337.6803 -403.193504) (xy 337.679888 -403.184317) (xy 337.673375 -403.167133) (xy 337.6676 -403.159976)
			(xy 337.645766 -403.134362) (xy 337.607822 -403.078769) (xy 337.576793 -403.01904) (xy 337.553124 -402.956031)
			(xy 337.537156 -402.890644) (xy 337.529116 -402.823818) (xy 334.251055 -402.823818) (xy 334.251055 -402.823874)
			(xy 334.242984 -402.890809) (xy 334.226954 -402.956295) (xy 334.203196 -403.01939) (xy 334.172051 -403.079185)
			(xy 334.133969 -403.134819) (xy 334.112108 -403.160484) (xy 334.106294 -403.167617) (xy 334.09979 -403.184817)
			(xy 334.099408 -403.194012) (xy 334.099408 -403.351492) (xy 334.098978 -403.361613) (xy 334.091234 -403.380315)
			(xy 334.076922 -403.394629) (xy 334.058221 -403.402376) (xy 334.0481 -403.4028) (xy 333.33182 -403.4028)
			(xy 333.321699 -403.402368) (xy 333.302996 -403.394626) (xy 333.288681 -403.380315) (xy 333.280935 -403.361613)
			(xy 333.280512 -403.351492) (xy 333.280512 -403.194012) (xy 333.280093 -403.184826) (xy 333.273585 -403.167642)
			(xy 333.267812 -403.160484) (xy 333.2459 -403.134858) (xy 333.207812 -403.079218) (xy 333.176663 -403.019417)
			(xy 333.152901 -402.956315) (xy 333.136869 -402.890821) (xy 333.128796 -402.823878) (xy 326.525636 -402.823878)
			(xy 326.525636 -405.623648) (xy 330.929194 -405.623648) (xy 330.929195 -405.556343) (xy 330.93724 -405.489519)
			(xy 330.953214 -405.424136) (xy 330.976889 -405.361131) (xy 331.007924 -405.301408) (xy 331.045875 -405.245822)
			(xy 331.067664 -405.22017) (xy 331.073464 -405.213027) (xy 331.079975 -405.195835) (xy 331.080364 -405.186642)
			(xy 331.080364 -404.693374) (xy 331.079952 -404.684187) (xy 331.073438 -404.667004) (xy 331.067664 -404.659846)
			(xy 331.045897 -404.634176) (xy 331.007946 -404.578593) (xy 330.976911 -404.518872) (xy 330.953235 -404.45587)
			(xy 330.93726 -404.390489) (xy 330.929214 -404.323668) (xy 330.929212 -404.256365) (xy 330.937254 -404.189543)
			(xy 330.953226 -404.124162) (xy 330.976897 -404.061158) (xy 331.007929 -404.001435) (xy 331.045877 -403.94585)
			(xy 331.067664 -403.920198) (xy 331.073452 -403.913047) (xy 331.07997 -403.895861) (xy 331.080364 -403.88667)
			(xy 331.080364 -403.728682) (xy 331.08075 -403.718506) (xy 331.088546 -403.699706) (xy 331.102943 -403.685321)
			(xy 331.12175 -403.677541) (xy 331.131926 -403.67712) (xy 331.848206 -403.67712) (xy 331.858362 -403.677628)
			(xy 331.877128 -403.685401) (xy 331.891492 -403.699762) (xy 331.899269 -403.718526) (xy 331.899768 -403.728682)
			(xy 331.899768 -403.88667) (xy 331.9002 -403.895855) (xy 331.906699 -403.913039) (xy 331.912468 -403.920198)
			(xy 331.934277 -403.945832) (xy 331.972225 -404.001422) (xy 332.003257 -404.061148) (xy 332.026928 -404.124154)
			(xy 332.042899 -404.189539) (xy 332.050942 -404.256363) (xy 332.05094 -404.32367) (xy 332.042893 -404.390494)
			(xy 332.026918 -404.455877) (xy 332.003243 -404.518883) (xy 331.972208 -404.578607) (xy 331.934257 -404.634194)
			(xy 331.912468 -404.659846) (xy 331.906665 -404.666987) (xy 331.900155 -404.684181) (xy 331.899768 -404.693374)
			(xy 331.899768 -405.186642) (xy 331.900165 -405.19583) (xy 331.906689 -405.213014) (xy 331.912468 -405.22017)
			(xy 331.93425 -405.245827) (xy 331.972198 -405.301413) (xy 332.003231 -405.361136) (xy 332.026904 -405.42414)
			(xy 332.042877 -405.489521) (xy 332.050922 -405.556343) (xy 332.050923 -405.623648) (xy 332.042879 -405.69047)
			(xy 332.026907 -405.755852) (xy 332.003235 -405.818856) (xy 331.972203 -405.878579) (xy 331.934255 -405.934166)
			(xy 331.912468 -405.959818) (xy 331.906677 -405.966967) (xy 331.90016 -405.984155) (xy 331.899768 -405.993346)
			(xy 331.899768 -406.151334) (xy 331.899295 -406.161493) (xy 331.89151 -406.180262) (xy 331.877138 -406.194626)
			(xy 331.858365 -406.2024) (xy 331.848206 -406.202896) (xy 331.131926 -406.202896) (xy 331.121774 -406.202346)
			(xy 331.103012 -406.194587) (xy 331.088647 -406.180238) (xy 331.080865 -406.161485) (xy 331.080364 -406.151334)
			(xy 331.080364 -405.993346) (xy 331.079918 -405.984163) (xy 331.073428 -405.966979) (xy 331.067664 -405.959818)
			(xy 331.04587 -405.934171) (xy 331.007919 -405.878584) (xy 330.976885 -405.81886) (xy 330.953212 -405.755855)
			(xy 330.937238 -405.690472) (xy 330.929194 -405.623648) (xy 326.525636 -405.623648) (xy 326.525636 -406.723789)
			(xy 333.128808 -406.723789) (xy 333.128811 -406.656363) (xy 333.13689 -406.589422) (xy 333.152929 -406.523931)
			(xy 333.176697 -406.460833) (xy 333.207852 -406.401036) (xy 333.245946 -406.345401) (xy 333.267812 -406.319736)
			(xy 333.27362 -406.312599) (xy 333.280127 -406.295402) (xy 333.280512 -406.286208) (xy 333.280512 -405.793956)
			(xy 333.28012 -405.784767) (xy 333.273594 -405.767583) (xy 333.267812 -405.760428) (xy 333.245944 -405.734766)
			(xy 333.207854 -405.679131) (xy 333.176703 -405.619335) (xy 333.152939 -405.556238) (xy 333.136903 -405.490748)
			(xy 333.128827 -405.423809) (xy 333.128828 -405.356385) (xy 333.136904 -405.289446) (xy 333.15294 -405.223957)
			(xy 333.176706 -405.16086) (xy 333.207857 -405.101063) (xy 333.245947 -405.045429) (xy 333.267812 -405.019764)
			(xy 333.273608 -405.012618) (xy 333.280123 -404.995428) (xy 333.280512 -404.986236) (xy 333.280512 -404.828756)
			(xy 333.280949 -404.818643) (xy 333.288704 -404.799961) (xy 333.303015 -404.785668) (xy 333.321706 -404.777937)
			(xy 333.33182 -404.777448) (xy 334.0481 -404.777448) (xy 334.058202 -404.777984) (xy 334.076871 -404.785712)
			(xy 334.091163 -404.799993) (xy 334.098907 -404.818654) (xy 334.099408 -404.828756) (xy 334.099408 -404.986236)
			(xy 334.099799 -404.995425) (xy 334.106326 -405.01261) (xy 334.112108 -405.019764) (xy 334.133968 -405.045433)
			(xy 334.172056 -405.101067) (xy 334.203206 -405.160863) (xy 334.226971 -405.223959) (xy 334.243006 -405.289448)
			(xy 334.251082 -405.356385) (xy 334.251082 -405.423809) (xy 334.243007 -405.490746) (xy 334.226972 -405.556235)
			(xy 334.203209 -405.619332) (xy 334.20093 -405.623707) (xy 335.328987 -405.623707) (xy 335.328987 -405.556284)
			(xy 335.337063 -405.489346) (xy 335.353098 -405.423857) (xy 335.376861 -405.36076) (xy 335.40801 -405.300963)
			(xy 335.446097 -405.245328) (xy 335.46796 -405.219662) (xy 335.473763 -405.212521) (xy 335.480272 -405.195327)
			(xy 335.48066 -405.186134) (xy 335.48066 -404.693882) (xy 335.480245 -404.684696) (xy 335.473733 -404.667512)
			(xy 335.46796 -404.660354) (xy 335.446119 -404.63467) (xy 335.408032 -404.579037) (xy 335.376883 -404.519243)
			(xy 335.353119 -404.456149) (xy 335.337083 -404.390663) (xy 335.329006 -404.323727) (xy 335.329004 -404.256306)
			(xy 335.337078 -404.18937) (xy 335.353109 -404.123883) (xy 335.376869 -404.060787) (xy 335.408015 -404.000991)
			(xy 335.446099 -403.945356) (xy 335.46796 -403.91969) (xy 335.473751 -403.912541) (xy 335.480267 -403.895353)
			(xy 335.48066 -403.886162) (xy 335.48066 -403.728682) (xy 335.481112 -403.718552) (xy 335.48885 -403.699826)
			(xy 335.503147 -403.68547) (xy 335.52184 -403.677655) (xy 335.531968 -403.67712) (xy 336.248248 -403.67712)
			(xy 336.258408 -403.677483) (xy 336.277165 -403.685298) (xy 336.291487 -403.699713) (xy 336.299182 -403.71852)
			(xy 336.299556 -403.728682) (xy 336.299556 -403.886162) (xy 336.299995 -403.895346) (xy 336.30649 -403.91253)
			(xy 336.312256 -403.91969) (xy 336.334143 -403.945337) (xy 336.372234 -404.000973) (xy 336.403386 -404.060771)
			(xy 336.427151 -404.123871) (xy 336.443186 -404.189362) (xy 336.451261 -404.256303) (xy 336.451259 -404.32373)
			(xy 336.443181 -404.39067) (xy 336.427141 -404.456161) (xy 336.403373 -404.519259) (xy 336.372217 -404.579056)
			(xy 336.334123 -404.634689) (xy 336.312256 -404.660354) (xy 336.306449 -404.667491) (xy 336.299941 -404.684688)
			(xy 336.299556 -404.693882) (xy 336.299556 -405.186134) (xy 336.29996 -405.195322) (xy 336.306479 -405.212505)
			(xy 336.312256 -405.219662) (xy 336.334116 -405.245331) (xy 336.372207 -405.300964) (xy 336.403361 -405.360759)
			(xy 336.427127 -405.423856) (xy 336.443164 -405.489345) (xy 336.451242 -405.556283) (xy 336.451242 -405.623708)
			(xy 336.443166 -405.690646) (xy 336.42713 -405.756135) (xy 336.403365 -405.819232) (xy 336.372212 -405.879028)
			(xy 336.334121 -405.934662) (xy 336.312256 -405.960326) (xy 336.30646 -405.967472) (xy 336.299946 -405.984662)
			(xy 336.299556 -405.993854) (xy 336.299556 -406.151334) (xy 336.299101 -406.161463) (xy 336.291362 -406.180186)
			(xy 336.277066 -406.194541) (xy 336.258375 -406.202359) (xy 336.248248 -406.202896) (xy 335.531968 -406.202896)
			(xy 335.521811 -406.202505) (xy 335.503057 -406.194698) (xy 335.488735 -406.180292) (xy 335.481037 -406.161493)
			(xy 335.48066 -406.151334) (xy 335.48066 -405.993854) (xy 335.48021 -405.984671) (xy 335.473722 -405.967487)
			(xy 335.46796 -405.960326) (xy 335.446092 -405.934665) (xy 335.408006 -405.879029) (xy 335.376857 -405.819232)
			(xy 335.353095 -405.756134) (xy 335.337062 -405.690645) (xy 335.328987 -405.623707) (xy 334.20093 -405.623707)
			(xy 334.172059 -405.679128) (xy 334.133971 -405.734763) (xy 334.112108 -405.760428) (xy 334.106318 -405.767578)
			(xy 334.099799 -405.784765) (xy 334.099408 -405.793956) (xy 334.099408 -406.286208) (xy 334.099813 -406.295396)
			(xy 334.10633 -406.31258) (xy 334.112108 -406.319736) (xy 334.13394 -406.345427) (xy 334.172029 -406.401058)
			(xy 334.203181 -406.460851) (xy 334.226947 -406.523944) (xy 334.242984 -406.58943) (xy 334.251062 -406.656365)
			(xy 334.251065 -406.723729) (xy 337.529127 -406.723729) (xy 337.52913 -406.656423) (xy 337.537177 -406.589598)
			(xy 337.553152 -406.524215) (xy 337.576827 -406.461209) (xy 337.607861 -406.401484) (xy 337.645812 -406.345897)
			(xy 337.6676 -406.320244) (xy 337.673403 -406.313103) (xy 337.679914 -406.295909) (xy 337.6803 -406.286716)
			(xy 337.6803 -405.793448) (xy 337.679867 -405.784263) (xy 337.673369 -405.767079) (xy 337.6676 -405.75992)
			(xy 337.64581 -405.734271) (xy 337.607863 -405.678683) (xy 337.576832 -405.618958) (xy 337.553162 -405.555954)
			(xy 337.53719 -405.490572) (xy 337.529147 -405.423749) (xy 337.529147 -405.356445) (xy 337.537191 -405.289622)
			(xy 337.553163 -405.224241) (xy 337.576835 -405.161236) (xy 337.607866 -405.101512) (xy 337.645813 -405.045925)
			(xy 337.6676 -405.020272) (xy 337.673391 -405.013123) (xy 337.679909 -404.995935) (xy 337.6803 -404.986744)
			(xy 337.6803 -404.828756) (xy 337.680686 -404.818599) (xy 337.688496 -404.799846) (xy 337.702903 -404.785524)
			(xy 337.721703 -404.777826) (xy 337.731862 -404.777448) (xy 338.448142 -404.777448) (xy 338.458272 -404.777892)
			(xy 338.476996 -404.785635) (xy 338.491351 -404.799934) (xy 338.499167 -404.818628) (xy 338.499704 -404.828756)
			(xy 338.499704 -404.986744) (xy 338.500092 -404.995934) (xy 338.506621 -405.013118) (xy 338.512404 -405.020272)
			(xy 338.534186 -405.045928) (xy 338.572133 -405.101515) (xy 338.603164 -405.161238) (xy 338.626835 -405.224242)
			(xy 338.642807 -405.289624) (xy 338.650851 -405.356445) (xy 338.650851 -405.423749) (xy 338.642808 -405.490571)
			(xy 338.626837 -405.555952) (xy 338.603166 -405.618956) (xy 338.600728 -405.623648) (xy 339.729282 -405.623648)
			(xy 339.729282 -405.556343) (xy 339.737327 -405.489519) (xy 339.753301 -405.424137) (xy 339.776975 -405.361132)
			(xy 339.808009 -405.301408) (xy 339.845959 -405.245822) (xy 339.867748 -405.22017) (xy 339.873546 -405.213026)
			(xy 339.880058 -405.195834) (xy 339.880448 -405.186642) (xy 339.880448 -404.693374) (xy 339.88004 -404.684187)
			(xy 339.873523 -404.667003) (xy 339.867748 -404.659846) (xy 339.845982 -404.634176) (xy 339.808032 -404.578592)
			(xy 339.776997 -404.518871) (xy 339.753323 -404.455869) (xy 339.737348 -404.390489) (xy 339.729302 -404.323668)
			(xy 339.7293 -404.256365) (xy 339.737342 -404.189544) (xy 339.753313 -404.124163) (xy 339.776984 -404.061159)
			(xy 339.808015 -404.001436) (xy 339.845962 -403.94585) (xy 339.867748 -403.920198) (xy 339.873534 -403.913045)
			(xy 339.880054 -403.89586) (xy 339.880448 -403.88667) (xy 339.880448 -403.728682) (xy 339.880919 -403.718522)
			(xy 339.888701 -403.69975) (xy 339.903074 -403.685385) (xy 339.92185 -403.677613) (xy 339.93201 -403.67712)
			(xy 340.64829 -403.67712) (xy 340.658445 -403.677641) (xy 340.67721 -403.685409) (xy 340.691575 -403.699766)
			(xy 340.699353 -403.718527) (xy 340.699852 -403.728682) (xy 340.699852 -403.88667) (xy 340.700287 -403.895854)
			(xy 340.706785 -403.913038) (xy 340.712552 -403.920198) (xy 340.734362 -403.945832) (xy 340.772311 -404.001421)
			(xy 340.803343 -404.061147) (xy 340.827015 -404.124154) (xy 340.842987 -404.189538) (xy 340.85103 -404.256363)
			(xy 340.851028 -404.32367) (xy 340.842981 -404.390494) (xy 340.827006 -404.455878) (xy 340.80333 -404.518883)
			(xy 340.772294 -404.578608) (xy 340.734341 -404.634194) (xy 340.712552 -404.659846) (xy 340.706747 -404.666985)
			(xy 340.700239 -404.684181) (xy 340.699852 -404.693374) (xy 340.699852 -405.186642) (xy 340.700253 -405.19583)
			(xy 340.706774 -405.213014) (xy 340.712552 -405.22017) (xy 340.734334 -405.245827) (xy 340.772283 -405.301413)
			(xy 340.803317 -405.361135) (xy 340.826991 -405.424139) (xy 340.842965 -405.489521) (xy 340.851009 -405.556343)
			(xy 340.85101 -405.623648) (xy 340.842966 -405.69047) (xy 340.826994 -405.755852) (xy 340.803321 -405.818856)
			(xy 340.772288 -405.87858) (xy 340.734339 -405.934166) (xy 340.712552 -405.959818) (xy 340.706759 -405.966966)
			(xy 340.700244 -405.984154) (xy 340.699852 -405.993346) (xy 340.699852 -406.151334) (xy 340.699394 -406.161495)
			(xy 340.691607 -406.180267) (xy 340.67723 -406.194631) (xy 340.658452 -406.202403) (xy 340.64829 -406.202896)
			(xy 339.93201 -406.202896) (xy 339.921857 -406.202359) (xy 339.903095 -406.194594) (xy 339.88873 -406.180242)
			(xy 339.880949 -406.161487) (xy 339.880448 -406.151334) (xy 339.880448 -405.993346) (xy 339.880005 -405.984163)
			(xy 339.873513 -405.966979) (xy 339.867748 -405.959818) (xy 339.845954 -405.934171) (xy 339.808005 -405.878584)
			(xy 339.776971 -405.81886) (xy 339.753298 -405.755855) (xy 339.737325 -405.690472) (xy 339.729282 -405.623648)
			(xy 338.600728 -405.623648) (xy 338.572136 -405.67868) (xy 338.53419 -405.734267) (xy 338.512404 -405.75992)
			(xy 338.506617 -405.767072) (xy 338.500096 -405.784257) (xy 338.499704 -405.793448) (xy 338.499704 -406.286716)
			(xy 338.500106 -406.295904) (xy 338.506625 -406.313088) (xy 338.512404 -406.320244) (xy 338.534159 -406.345923)
			(xy 338.572106 -406.401506) (xy 338.603138 -406.461227) (xy 338.626811 -406.524228) (xy 338.642785 -406.589606)
			(xy 338.650831 -406.656425) (xy 338.650834 -406.723727) (xy 338.650827 -406.723789) (xy 341.928896 -406.723789)
			(xy 341.928898 -406.656363) (xy 341.936977 -406.589423) (xy 341.953016 -406.523932) (xy 341.976784 -406.460834)
			(xy 342.007938 -406.401036) (xy 342.04603 -406.345401) (xy 342.067896 -406.319736) (xy 342.073702 -406.312597)
			(xy 342.080211 -406.295402) (xy 342.080596 -406.286208) (xy 342.080596 -405.793956) (xy 342.080208 -405.784766)
			(xy 342.073679 -405.767582) (xy 342.067896 -405.760428) (xy 342.046028 -405.734766) (xy 342.00794 -405.679131)
			(xy 341.97679 -405.619334) (xy 341.953026 -405.556237) (xy 341.936991 -405.490748) (xy 341.928915 -405.423809)
			(xy 341.928916 -405.356385) (xy 341.936992 -405.289447) (xy 341.953028 -405.223957) (xy 341.976792 -405.16086)
			(xy 342.007943 -405.101064) (xy 342.046032 -405.045429) (xy 342.067896 -405.019764) (xy 342.07369 -405.012617)
			(xy 342.080206 -404.995428) (xy 342.080596 -404.986236) (xy 342.080596 -404.828756) (xy 342.081049 -404.818645)
			(xy 342.0888 -404.799967) (xy 342.103107 -404.785673) (xy 342.121793 -404.77794) (xy 342.131904 -404.777448)
			(xy 342.848184 -404.777448) (xy 342.858285 -404.777997) (xy 342.876953 -404.78572) (xy 342.891247 -404.799996)
			(xy 342.898991 -404.818655) (xy 342.899492 -404.828756) (xy 342.899492 -404.986236) (xy 342.899886 -404.995425)
			(xy 342.906411 -405.012609) (xy 342.912192 -405.019764) (xy 342.934052 -405.045432) (xy 342.972142 -405.101066)
			(xy 343.003293 -405.160862) (xy 343.027058 -405.223958) (xy 343.043094 -405.289447) (xy 343.05117 -405.356385)
			(xy 343.05117 -405.423809) (xy 343.043095 -405.490747) (xy 343.02706 -405.556236) (xy 343.003295 -405.619333)
			(xy 343.001047 -405.623648) (xy 344.129073 -405.623648) (xy 344.129073 -405.556343) (xy 344.137118 -405.48952)
			(xy 344.153091 -405.424137) (xy 344.176765 -405.361132) (xy 344.207799 -405.301409) (xy 344.245748 -405.245822)
			(xy 344.267536 -405.22017) (xy 344.273332 -405.213025) (xy 344.279846 -405.195834) (xy 344.280236 -405.186642)
			(xy 344.280236 -404.693374) (xy 344.27983 -404.684187) (xy 344.273313 -404.667003) (xy 344.267536 -404.659846)
			(xy 344.24577 -404.634176) (xy 344.207821 -404.578592) (xy 344.176787 -404.518871) (xy 344.153113 -404.455869)
			(xy 344.137139 -404.390489) (xy 344.129093 -404.323668) (xy 344.129091 -404.256365) (xy 344.137133 -404.189544)
			(xy 344.153103 -404.124163) (xy 344.176773 -404.061159) (xy 344.207804 -404.001437) (xy 344.24575 -403.94585)
			(xy 344.267536 -403.920198) (xy 344.273321 -403.913044) (xy 344.279842 -403.89586) (xy 344.280236 -403.88667)
			(xy 344.280236 -403.728682) (xy 344.280718 -403.718523) (xy 344.288498 -403.699754) (xy 344.302867 -403.685389)
			(xy 344.321639 -403.677615) (xy 344.331798 -403.67712) (xy 345.048078 -403.67712) (xy 345.058246 -403.677582)
			(xy 345.077037 -403.685356) (xy 345.091422 -403.69973) (xy 345.09921 -403.718514) (xy 345.09964 -403.728682)
			(xy 345.09964 -403.88667) (xy 345.100078 -403.895854) (xy 345.106574 -403.913038) (xy 345.11234 -403.920198)
			(xy 345.13415 -403.945832) (xy 345.1721 -404.00142) (xy 345.203133 -404.061146) (xy 345.226806 -404.124153)
			(xy 345.242778 -404.189538) (xy 345.250821 -404.256363) (xy 345.250819 -404.32367) (xy 345.242772 -404.390495)
			(xy 345.226796 -404.455878) (xy 345.20312 -404.518884) (xy 345.172083 -404.578608) (xy 345.13413 -404.634194)
			(xy 345.11234 -404.659846) (xy 345.106534 -404.666984) (xy 345.100027 -404.68418) (xy 345.09964 -404.693374)
			(xy 345.09964 -405.186642) (xy 345.100043 -405.19583) (xy 345.106563 -405.213013) (xy 345.11234 -405.22017)
			(xy 345.134122 -405.245827) (xy 345.172073 -405.301412) (xy 345.203107 -405.361135) (xy 345.226781 -405.424139)
			(xy 345.242755 -405.489521) (xy 345.2508 -405.556343) (xy 345.250801 -405.623648) (xy 345.242757 -405.69047)
			(xy 345.226784 -405.755853) (xy 345.203111 -405.818857) (xy 345.172077 -405.87858) (xy 345.134128 -405.934166)
			(xy 345.11234 -405.959818) (xy 345.106546 -405.966965) (xy 345.100031 -405.984154) (xy 345.09964 -405.993346)
			(xy 345.09964 -406.151334) (xy 345.099194 -406.161497) (xy 345.091404 -406.180271) (xy 345.077024 -406.194636)
			(xy 345.058241 -406.202405) (xy 345.048078 -406.202896) (xy 344.331798 -406.202896) (xy 344.321644 -406.202369)
			(xy 344.302882 -406.1946) (xy 344.288518 -406.180245) (xy 344.280737 -406.161487) (xy 344.280236 -406.151334)
			(xy 344.280236 -405.993346) (xy 344.279795 -405.984162) (xy 344.273302 -405.966978) (xy 344.267536 -405.959818)
			(xy 344.245742 -405.934171) (xy 344.207794 -405.878584) (xy 344.176761 -405.818859) (xy 344.153089 -405.755854)
			(xy 344.137116 -405.690471) (xy 344.129073 -405.623648) (xy 343.001047 -405.623648) (xy 342.972145 -405.679129)
			(xy 342.934056 -405.734763) (xy 342.912192 -405.760428) (xy 342.9064 -405.767576) (xy 342.899883 -405.784765)
			(xy 342.899492 -405.793956) (xy 342.899492 -406.286208) (xy 342.8999 -406.295395) (xy 342.906416 -406.312579)
			(xy 342.912192 -406.319736) (xy 342.934025 -406.345427) (xy 342.972115 -406.401058) (xy 343.003268 -406.46085)
			(xy 343.027034 -406.523944) (xy 343.043072 -406.58943) (xy 343.05115 -406.656365) (xy 343.051153 -406.72373)
			(xy 346.329191 -406.72373) (xy 346.329194 -406.656422) (xy 346.337242 -406.589596) (xy 346.35322 -406.524212)
			(xy 346.376898 -406.461206) (xy 346.407937 -406.401482) (xy 346.445893 -406.345896) (xy 346.467684 -406.320244)
			(xy 346.473485 -406.313102) (xy 346.479998 -406.295909) (xy 346.480384 -406.286716) (xy 346.480384 -405.793448)
			(xy 346.479955 -405.784263) (xy 346.473455 -405.767078) (xy 346.467684 -405.75992) (xy 346.445891 -405.734272)
			(xy 346.407939 -405.678686) (xy 346.376904 -405.618962) (xy 346.353229 -405.555957) (xy 346.337255 -405.490574)
			(xy 346.329211 -405.42375) (xy 346.329211 -405.356444) (xy 346.337256 -405.28962) (xy 346.353231 -405.224237)
			(xy 346.376906 -405.161232) (xy 346.407942 -405.101509) (xy 346.445895 -405.045924) (xy 346.467684 -405.020272)
			(xy 346.473473 -405.013121) (xy 346.479993 -404.995935) (xy 346.480384 -404.986744) (xy 346.480384 -404.828756)
			(xy 346.480785 -404.818601) (xy 346.488592 -404.799851) (xy 346.502995 -404.78553) (xy 346.521789 -404.777829)
			(xy 346.531946 -404.777448) (xy 347.248226 -404.777448) (xy 347.258355 -404.777905) (xy 347.277079 -404.785643)
			(xy 347.291434 -404.799938) (xy 347.299251 -404.818629) (xy 347.299788 -404.828756) (xy 347.299788 -404.986744)
			(xy 347.30018 -404.995933) (xy 347.306706 -405.013117) (xy 347.312488 -405.020272) (xy 347.334271 -405.045928)
			(xy 347.372218 -405.101514) (xy 347.40325 -405.161238) (xy 347.426922 -405.224242) (xy 347.442894 -405.289623)
			(xy 347.450938 -405.356445) (xy 347.450939 -405.423749) (xy 347.442895 -405.490571) (xy 347.426924 -405.555953)
			(xy 347.403253 -405.618957) (xy 347.400815 -405.623649) (xy 374.929103 -405.623649) (xy 374.929104 -405.556342)
			(xy 374.937149 -405.489519) (xy 374.953124 -405.424136) (xy 374.976799 -405.361131) (xy 375.007835 -405.301407)
			(xy 375.045787 -405.245822) (xy 375.067576 -405.22017) (xy 375.073365 -405.213019) (xy 375.079885 -405.195833)
			(xy 375.080276 -405.186642) (xy 375.080276 -404.693374) (xy 375.079884 -404.684185) (xy 375.073358 -404.667)
			(xy 375.067576 -404.659846) (xy 375.045809 -404.634177) (xy 375.007857 -404.578593) (xy 374.976821 -404.518873)
			(xy 374.953145 -404.45587) (xy 374.937169 -404.39049) (xy 374.929123 -404.323669) (xy 374.929121 -404.256365)
			(xy 374.937164 -404.189543) (xy 374.953135 -404.124161) (xy 374.976807 -404.061158) (xy 375.00784 -404.001435)
			(xy 375.045789 -403.94585) (xy 375.067576 -403.920198) (xy 375.073353 -403.913039) (xy 375.07988 -403.895859)
			(xy 375.080276 -403.88667) (xy 375.080276 -403.728682) (xy 375.08065 -403.718505) (xy 375.088448 -403.699702)
			(xy 375.102849 -403.685317) (xy 375.12166 -403.677539) (xy 375.131838 -403.67712) (xy 375.848118 -403.67712)
			(xy 375.858275 -403.677618) (xy 375.877041 -403.685395) (xy 375.891405 -403.699759) (xy 375.899182 -403.718525)
			(xy 375.89968 -403.728682) (xy 375.89968 -403.88667) (xy 375.900109 -403.895855) (xy 375.90661 -403.913039)
			(xy 375.91238 -403.920198) (xy 375.934189 -403.945833) (xy 375.972136 -404.001422) (xy 376.003167 -404.061148)
			(xy 376.026838 -404.124155) (xy 376.042809 -404.189539) (xy 376.050851 -404.256363) (xy 376.050849 -404.32367)
			(xy 376.042803 -404.390494) (xy 376.026828 -404.455877) (xy 376.003154 -404.518882) (xy 375.972119 -404.578606)
			(xy 375.934169 -404.634194) (xy 375.91238 -404.659846) (xy 375.906579 -404.666988) (xy 375.900068 -404.684181)
			(xy 375.89968 -404.693374) (xy 375.89968 -405.186642) (xy 375.900074 -405.195831) (xy 375.9066 -405.213015)
			(xy 375.91238 -405.22017) (xy 375.934161 -405.245827) (xy 375.972109 -405.301413) (xy 376.003142 -405.361136)
			(xy 376.026814 -405.42414) (xy 376.042787 -405.489522) (xy 376.050831 -405.556343) (xy 376.050832 -405.623648)
			(xy 376.042788 -405.690469) (xy 376.026817 -405.755851) (xy 376.003145 -405.818855) (xy 375.972114 -405.878579)
			(xy 375.934167 -405.934166) (xy 375.91238 -405.959818) (xy 375.906591 -405.966968) (xy 375.900072 -405.984155)
			(xy 375.89968 -405.993346) (xy 375.89968 -406.151334) (xy 375.899195 -406.161492) (xy 375.891413 -406.180258)
			(xy 375.877045 -406.194622) (xy 375.858276 -406.202398) (xy 375.848118 -406.202896) (xy 375.131838 -406.202896)
			(xy 375.121673 -406.202406) (xy 375.102886 -406.19464) (xy 375.088501 -406.180275) (xy 375.080708 -406.161498)
			(xy 375.080276 -406.151334) (xy 375.080276 -405.993346) (xy 375.079849 -405.984161) (xy 375.073347 -405.966976)
			(xy 375.067576 -405.959818) (xy 375.045781 -405.934171) (xy 375.00783 -405.878585) (xy 374.976795 -405.818861)
			(xy 374.953121 -405.755856) (xy 374.937148 -405.690472) (xy 374.929103 -405.623649) (xy 347.400815 -405.623649)
			(xy 347.372221 -405.678681) (xy 347.334275 -405.734268) (xy 347.312488 -405.75992) (xy 347.306699 -405.767071)
			(xy 347.30018 -405.784257) (xy 347.299788 -405.793448) (xy 347.299788 -406.286716) (xy 347.300193 -406.295904)
			(xy 347.30671 -406.313088) (xy 347.312488 -406.320244) (xy 347.334244 -406.345922) (xy 347.372192 -406.401506)
			(xy 347.403225 -406.461226) (xy 347.426898 -406.524227) (xy 347.442873 -406.589606) (xy 347.450919 -406.656425)
			(xy 347.450922 -406.723727) (xy 347.450915 -406.723789) (xy 377.128717 -406.723789) (xy 377.12872 -406.656363)
			(xy 377.136799 -406.589422) (xy 377.152839 -406.523931) (xy 377.176607 -406.460832) (xy 377.207763 -406.401035)
			(xy 377.245857 -406.345401) (xy 377.267724 -406.319736) (xy 377.273533 -406.3126) (xy 377.280039 -406.295402)
			(xy 377.280424 -406.286208) (xy 377.280424 -405.793956) (xy 377.28003 -405.784767) (xy 377.273504 -405.767583)
			(xy 377.267724 -405.760428) (xy 377.245855 -405.734766) (xy 377.207765 -405.679132) (xy 377.176613 -405.619335)
			(xy 377.152848 -405.556238) (xy 377.136812 -405.490748) (xy 377.128736 -405.423809) (xy 377.128737 -405.356385)
			(xy 377.136813 -405.289446) (xy 377.15285 -405.223956) (xy 377.176616 -405.160859) (xy 377.207768 -405.101063)
			(xy 377.245859 -405.045429) (xy 377.267724 -405.019764) (xy 377.273521 -405.012619) (xy 377.280035 -404.995428)
			(xy 377.280424 -404.986236) (xy 377.280424 -404.828756) (xy 377.28085 -404.818641) (xy 377.288606 -404.799958)
			(xy 377.302922 -404.785664) (xy 377.321617 -404.777935) (xy 377.331732 -404.777448) (xy 378.048012 -404.777448)
			(xy 378.058115 -404.777974) (xy 378.076783 -404.785706) (xy 378.091076 -404.79999) (xy 378.098819 -404.818653)
			(xy 378.09932 -404.828756) (xy 378.09932 -404.986236) (xy 378.099709 -404.995426) (xy 378.106237 -405.01261)
			(xy 378.11202 -405.019764) (xy 378.133879 -405.045433) (xy 378.171967 -405.101067) (xy 378.203117 -405.160863)
			(xy 378.22688 -405.22396) (xy 378.242915 -405.289448) (xy 378.250991 -405.356386) (xy 378.250992 -405.423808)
			(xy 378.242916 -405.490746) (xy 378.226882 -405.556235) (xy 378.203119 -405.619331) (xy 378.200839 -405.623707)
			(xy 379.328896 -405.623707) (xy 379.328896 -405.556284) (xy 379.336972 -405.489346) (xy 379.353008 -405.423856)
			(xy 379.376771 -405.360759) (xy 379.407921 -405.300963) (xy 379.446009 -405.245328) (xy 379.467872 -405.219662)
			(xy 379.473676 -405.212522) (xy 379.480184 -405.195327) (xy 379.480572 -405.186134) (xy 379.480572 -404.693882)
			(xy 379.480177 -404.684693) (xy 379.473653 -404.667509) (xy 379.467872 -404.660354) (xy 379.446031 -404.63467)
			(xy 379.407943 -404.579038) (xy 379.376793 -404.519244) (xy 379.353029 -404.45615) (xy 379.336993 -404.390663)
			(xy 379.328915 -404.323727) (xy 379.328913 -404.256306) (xy 379.336987 -404.18937) (xy 379.353019 -404.123882)
			(xy 379.376779 -404.060786) (xy 379.407926 -404.00099) (xy 379.44601 -403.945356) (xy 379.467872 -403.91969)
			(xy 379.473664 -403.912542) (xy 379.480179 -403.895353) (xy 379.480572 -403.886162) (xy 379.480572 -403.728682)
			(xy 379.481013 -403.71855) (xy 379.488752 -403.699822) (xy 379.503053 -403.685466) (xy 379.52175 -403.677653)
			(xy 379.53188 -403.67712) (xy 380.24816 -403.67712) (xy 380.258282 -403.677549) (xy 380.276989 -403.685288)
			(xy 380.291305 -403.699601) (xy 380.299048 -403.718306) (xy 380.299468 -403.728428) (xy 380.299468 -403.886162)
			(xy 380.299904 -403.895346) (xy 380.306401 -403.91253) (xy 380.312168 -403.91969) (xy 380.334055 -403.945337)
			(xy 380.372145 -404.000973) (xy 380.403296 -404.060772) (xy 380.427061 -404.123871) (xy 380.443096 -404.189363)
			(xy 380.45117 -404.256303) (xy 380.451168 -404.32373) (xy 380.44309 -404.39067) (xy 380.427051 -404.456161)
			(xy 380.403283 -404.519259) (xy 380.372128 -404.579055) (xy 380.334034 -404.634689) (xy 380.312168 -404.660354)
			(xy 380.306362 -404.667492) (xy 380.299854 -404.684688) (xy 380.299468 -404.693882) (xy 380.299468 -405.186134)
			(xy 380.299869 -405.195322) (xy 380.30639 -405.212506) (xy 380.312168 -405.219662) (xy 380.334027 -405.245332)
			(xy 380.372118 -405.300965) (xy 380.403271 -405.36076) (xy 380.427037 -405.423856) (xy 380.443074 -405.489345)
			(xy 380.451151 -405.556284) (xy 380.451151 -405.623707) (xy 380.443075 -405.690646) (xy 380.42704 -405.756135)
			(xy 380.403275 -405.819232) (xy 380.372123 -405.879028) (xy 380.334033 -405.934661) (xy 380.312168 -405.960326)
			(xy 380.306374 -405.967473) (xy 380.299858 -405.984662) (xy 380.299468 -405.993854) (xy 380.299468 -406.151334)
			(xy 380.299002 -406.161462) (xy 380.291264 -406.180182) (xy 380.276972 -406.194537) (xy 380.258286 -406.202357)
			(xy 380.24816 -406.202896) (xy 379.53188 -406.202896) (xy 379.521769 -406.202431) (xy 379.50309 -406.194686)
			(xy 379.488796 -406.180383) (xy 379.481062 -406.161699) (xy 379.480572 -406.151588) (xy 379.480572 -405.993854)
			(xy 379.480142 -405.984669) (xy 379.473643 -405.967484) (xy 379.467872 -405.960326) (xy 379.446003 -405.934665)
			(xy 379.407916 -405.879029) (xy 379.376768 -405.819232) (xy 379.353005 -405.756135) (xy 379.336971 -405.690646)
			(xy 379.328896 -405.623707) (xy 378.200839 -405.623707) (xy 378.17197 -405.679128) (xy 378.133883 -405.734762)
			(xy 378.11202 -405.760428) (xy 378.106231 -405.767579) (xy 378.099711 -405.784765) (xy 378.09932 -405.793956)
			(xy 378.09932 -406.286208) (xy 378.099722 -406.295396) (xy 378.106241 -406.312581) (xy 378.11202 -406.319736)
			(xy 378.133852 -406.345428) (xy 378.17194 -406.401059) (xy 378.203091 -406.460852) (xy 378.226856 -406.523945)
			(xy 378.242893 -406.589431) (xy 378.250971 -406.656366) (xy 378.250974 -406.723729) (xy 381.529036 -406.723729)
			(xy 381.529039 -406.656422) (xy 381.537086 -406.589598) (xy 381.553062 -406.524214) (xy 381.576737 -406.461209)
			(xy 381.607772 -406.401484) (xy 381.645723 -406.345897) (xy 381.667512 -406.320244) (xy 381.673316 -406.313104)
			(xy 381.679826 -406.29591) (xy 381.680212 -406.286716) (xy 381.680212 -405.793448) (xy 381.679776 -405.784264)
			(xy 381.67328 -405.767079) (xy 381.667512 -405.75992) (xy 381.645721 -405.734271) (xy 381.607774 -405.678683)
			(xy 381.576743 -405.618959) (xy 381.553071 -405.555954) (xy 381.537099 -405.490572) (xy 381.529056 -405.423749)
			(xy 381.529056 -405.356445) (xy 381.5371 -405.289622) (xy 381.553073 -405.22424) (xy 381.576745 -405.161235)
			(xy 381.607777 -405.101512) (xy 381.645725 -405.045924) (xy 381.667512 -405.020272) (xy 381.673304 -405.013124)
			(xy 381.679821 -404.995936) (xy 381.680212 -404.986744) (xy 381.680212 -404.828756) (xy 381.680649 -404.818643)
			(xy 381.688404 -404.799961) (xy 381.702715 -404.785668) (xy 381.721406 -404.777937) (xy 381.73152 -404.777448)
			(xy 382.448054 -404.777448) (xy 382.458179 -404.777965) (xy 382.4769 -404.785679) (xy 382.491258 -404.799956)
			(xy 382.499078 -404.818634) (xy 382.499616 -404.828756) (xy 382.499616 -404.986744) (xy 382.500001 -404.995934)
			(xy 382.506532 -405.013118) (xy 382.512316 -405.020272) (xy 382.534101 -405.045927) (xy 382.572053 -405.101512)
			(xy 382.603089 -405.161235) (xy 382.626764 -405.224239) (xy 382.642738 -405.289621) (xy 382.650784 -405.356444)
			(xy 382.650784 -405.42375) (xy 382.64274 -405.490573) (xy 382.626766 -405.555955) (xy 382.603091 -405.61896)
			(xy 382.600655 -405.623648) (xy 383.729191 -405.623648) (xy 383.729192 -405.556343) (xy 383.737237 -405.489519)
			(xy 383.753211 -405.424136) (xy 383.776885 -405.361132) (xy 383.807921 -405.301408) (xy 383.845871 -405.245822)
			(xy 383.86766 -405.22017) (xy 383.873459 -405.213027) (xy 383.879971 -405.195835) (xy 383.88036 -405.186642)
			(xy 383.88036 -404.693374) (xy 383.879949 -404.684187) (xy 383.873434 -404.667004) (xy 383.86766 -404.659846)
			(xy 383.845893 -404.634176) (xy 383.807943 -404.578593) (xy 383.776907 -404.518872) (xy 383.753232 -404.45587)
			(xy 383.737257 -404.390489) (xy 383.729211 -404.323668) (xy 383.729209 -404.256365) (xy 383.737251 -404.189543)
			(xy 383.753222 -404.124162) (xy 383.776894 -404.061158) (xy 383.807926 -404.001436) (xy 383.845873 -403.94585)
			(xy 383.86766 -403.920198) (xy 383.873447 -403.913047) (xy 383.879966 -403.895861) (xy 383.88036 -403.88667)
			(xy 383.88036 -403.728682) (xy 383.88075 -403.718507) (xy 383.888545 -403.699707) (xy 383.902941 -403.685322)
			(xy 383.921746 -403.677542) (xy 383.931922 -403.67712) (xy 384.648202 -403.67712) (xy 384.658358 -403.677631)
			(xy 384.677123 -403.685403) (xy 384.691488 -403.699763) (xy 384.699265 -403.718526) (xy 384.699764 -403.728682)
			(xy 384.699764 -403.88667) (xy 384.700197 -403.895855) (xy 384.706696 -403.913039) (xy 384.712464 -403.920198)
			(xy 384.734273 -403.945832) (xy 384.772221 -404.001421) (xy 384.803254 -404.061147) (xy 384.826925 -404.124154)
			(xy 384.842896 -404.189539) (xy 384.850939 -404.256363) (xy 384.850937 -404.32367) (xy 384.84289 -404.390494)
			(xy 384.826915 -404.455877) (xy 384.80324 -404.518883) (xy 384.772204 -404.578607) (xy 384.734253 -404.634194)
			(xy 384.712464 -404.659846) (xy 384.706661 -404.666986) (xy 384.700151 -404.684181) (xy 384.699764 -404.693374)
			(xy 384.699764 -405.186642) (xy 384.700162 -405.19583) (xy 384.706685 -405.213014) (xy 384.712464 -405.22017)
			(xy 384.734246 -405.245827) (xy 384.772195 -405.301413) (xy 384.803228 -405.361136) (xy 384.826901 -405.42414)
			(xy 384.842874 -405.489521) (xy 384.850919 -405.556343) (xy 384.850919 -405.623648) (xy 384.842876 -405.69047)
			(xy 384.826904 -405.755852) (xy 384.803232 -405.818856) (xy 384.772199 -405.878579) (xy 384.734251 -405.934166)
			(xy 384.712464 -405.959818) (xy 384.706673 -405.966967) (xy 384.700156 -405.984155) (xy 384.699764 -405.993346)
			(xy 384.699764 -406.151334) (xy 384.699295 -406.161494) (xy 384.691509 -406.180263) (xy 384.677136 -406.194627)
			(xy 384.658362 -406.202401) (xy 384.648202 -406.202896) (xy 383.931922 -406.202896) (xy 383.92177 -406.20235)
			(xy 383.903008 -406.194589) (xy 383.888643 -406.180239) (xy 383.880861 -406.161486) (xy 383.88036 -406.151334)
			(xy 383.88036 -405.993346) (xy 383.879914 -405.984163) (xy 383.873424 -405.966979) (xy 383.86766 -405.959818)
			(xy 383.845866 -405.934171) (xy 383.807916 -405.878584) (xy 383.776882 -405.81886) (xy 383.753208 -405.755855)
			(xy 383.737235 -405.690472) (xy 383.729191 -405.623648) (xy 382.600655 -405.623648) (xy 382.572056 -405.678683)
			(xy 382.534105 -405.734268) (xy 382.512316 -405.75992) (xy 382.50653 -405.767073) (xy 382.500009 -405.784257)
			(xy 382.499616 -405.793448) (xy 382.499616 -406.286716) (xy 382.500015 -406.295904) (xy 382.506536 -406.313089)
			(xy 382.512316 -406.320244) (xy 382.534074 -406.345921) (xy 382.572026 -406.401503) (xy 382.603063 -406.461223)
			(xy 382.62674 -406.524224) (xy 382.642717 -406.589604) (xy 382.650764 -406.656424) (xy 382.650767 -406.723728)
			(xy 382.65076 -406.723789) (xy 385.928805 -406.723789) (xy 385.928807 -406.656363) (xy 385.936887 -406.589422)
			(xy 385.952926 -406.523931) (xy 385.976694 -406.460833) (xy 386.007849 -406.401036) (xy 386.045942 -406.345401)
			(xy 386.067808 -406.319736) (xy 386.073615 -406.312598) (xy 386.080123 -406.295402) (xy 386.080508 -406.286208)
			(xy 386.080508 -405.793956) (xy 386.080117 -405.784767) (xy 386.07359 -405.767583) (xy 386.067808 -405.760428)
			(xy 386.04594 -405.734766) (xy 386.007851 -405.679131) (xy 385.9767 -405.619335) (xy 385.952935 -405.556237)
			(xy 385.9369 -405.490748) (xy 385.928824 -405.423809) (xy 385.928825 -405.356385) (xy 385.936901 -405.289446)
			(xy 385.952937 -405.223957) (xy 385.976702 -405.16086) (xy 386.007854 -405.101064) (xy 386.045944 -405.045429)
			(xy 386.067808 -405.019764) (xy 386.073603 -405.012618) (xy 386.080118 -404.995428) (xy 386.080508 -404.986236)
			(xy 386.080508 -404.828756) (xy 386.080949 -404.818643) (xy 386.088703 -404.799963) (xy 386.103013 -404.785669)
			(xy 386.121703 -404.777938) (xy 386.131816 -404.777448) (xy 386.848096 -404.777448) (xy 386.858198 -404.777987)
			(xy 386.876866 -404.785714) (xy 386.891159 -404.799993) (xy 386.898903 -404.818654) (xy 386.899404 -404.828756)
			(xy 386.899404 -404.986236) (xy 386.899796 -404.995425) (xy 386.906322 -405.012609) (xy 386.912104 -405.019764)
			(xy 386.933964 -405.045433) (xy 386.972052 -405.101067) (xy 387.003203 -405.160862) (xy 387.026967 -405.223959)
			(xy 387.043003 -405.289448) (xy 387.051079 -405.356385) (xy 387.051079 -405.423809) (xy 387.043004 -405.490747)
			(xy 387.026969 -405.556235) (xy 387.003206 -405.619332) (xy 387.000958 -405.623648) (xy 388.128982 -405.623648)
			(xy 388.128982 -405.556343) (xy 388.137027 -405.489519) (xy 388.153001 -405.424137) (xy 388.176675 -405.361132)
			(xy 388.207709 -405.301408) (xy 388.245659 -405.245822) (xy 388.267448 -405.22017) (xy 388.273246 -405.213026)
			(xy 388.279758 -405.195834) (xy 388.280148 -405.186642) (xy 388.280148 -404.693374) (xy 388.27974 -404.684187)
			(xy 388.273223 -404.667003) (xy 388.267448 -404.659846) (xy 388.245682 -404.634176) (xy 388.207732 -404.578592)
			(xy 388.176697 -404.518871) (xy 388.153023 -404.455869) (xy 388.137048 -404.390489) (xy 388.129002 -404.323668)
			(xy 388.129 -404.256365) (xy 388.137042 -404.189544) (xy 388.153013 -404.124163) (xy 388.176684 -404.061159)
			(xy 388.207715 -404.001436) (xy 388.245662 -403.94585) (xy 388.267448 -403.920198) (xy 388.273234 -403.913045)
			(xy 388.279754 -403.89586) (xy 388.280148 -403.88667) (xy 388.280148 -403.728682) (xy 388.280619 -403.718522)
			(xy 388.288401 -403.69975) (xy 388.302774 -403.685385) (xy 388.32155 -403.677613) (xy 388.33171 -403.67712)
			(xy 389.04799 -403.67712) (xy 389.058145 -403.677641) (xy 389.07691 -403.685409) (xy 389.091275 -403.699766)
			(xy 389.099053 -403.718527) (xy 389.099552 -403.728682) (xy 389.099552 -403.88667) (xy 389.099987 -403.895854)
			(xy 389.106485 -403.913038) (xy 389.112252 -403.920198) (xy 389.134062 -403.945832) (xy 389.172011 -404.001421)
			(xy 389.203043 -404.061147) (xy 389.226715 -404.124154) (xy 389.242687 -404.189538) (xy 389.25073 -404.256363)
			(xy 389.250728 -404.32367) (xy 389.242681 -404.390494) (xy 389.226706 -404.455878) (xy 389.20303 -404.518883)
			(xy 389.171994 -404.578608) (xy 389.134041 -404.634194) (xy 389.112252 -404.659846) (xy 389.106447 -404.666985)
			(xy 389.099939 -404.684181) (xy 389.099552 -404.693374) (xy 389.099552 -405.186642) (xy 389.099953 -405.19583)
			(xy 389.106474 -405.213014) (xy 389.112252 -405.22017) (xy 389.134034 -405.245827) (xy 389.171983 -405.301413)
			(xy 389.203017 -405.361135) (xy 389.226691 -405.424139) (xy 389.242665 -405.489521) (xy 389.250709 -405.556343)
			(xy 389.25071 -405.623648) (xy 389.242666 -405.69047) (xy 389.226694 -405.755852) (xy 389.203021 -405.818856)
			(xy 389.171988 -405.87858) (xy 389.134039 -405.934166) (xy 389.112252 -405.959818) (xy 389.106459 -405.966966)
			(xy 389.099944 -405.984154) (xy 389.099552 -405.993346) (xy 389.099552 -406.151334) (xy 389.099094 -406.161495)
			(xy 389.091307 -406.180267) (xy 389.07693 -406.194631) (xy 389.058152 -406.202403) (xy 389.04799 -406.202896)
			(xy 388.33171 -406.202896) (xy 388.321557 -406.202359) (xy 388.302795 -406.194594) (xy 388.28843 -406.180242)
			(xy 388.280649 -406.161487) (xy 388.280148 -406.151334) (xy 388.280148 -405.993346) (xy 388.279705 -405.984163)
			(xy 388.273213 -405.966979) (xy 388.267448 -405.959818) (xy 388.245654 -405.934171) (xy 388.207705 -405.878584)
			(xy 388.176671 -405.81886) (xy 388.152998 -405.755855) (xy 388.137025 -405.690472) (xy 388.128982 -405.623648)
			(xy 387.000958 -405.623648) (xy 386.972056 -405.679128) (xy 386.933968 -405.734763) (xy 386.912104 -405.760428)
			(xy 386.906314 -405.767578) (xy 386.899795 -405.784765) (xy 386.899404 -405.793956) (xy 386.899404 -406.286208)
			(xy 386.89981 -406.295396) (xy 386.906326 -406.31258) (xy 386.912104 -406.319736) (xy 386.933936 -406.345427)
			(xy 386.972026 -406.401058) (xy 387.003178 -406.460851) (xy 387.026943 -406.523944) (xy 387.042981 -406.58943)
			(xy 387.051059 -406.656365) (xy 387.051062 -406.723729) (xy 390.329124 -406.723729) (xy 390.329127 -406.656423)
			(xy 390.337174 -406.589599) (xy 390.353149 -406.524215) (xy 390.376823 -406.461209) (xy 390.407858 -406.401485)
			(xy 390.445808 -406.345897) (xy 390.467596 -406.320244) (xy 390.473398 -406.313103) (xy 390.47991 -406.295909)
			(xy 390.480296 -406.286716) (xy 390.480296 -405.793448) (xy 390.479864 -405.784263) (xy 390.473366 -405.767078)
			(xy 390.467596 -405.75992) (xy 390.445806 -405.73427) (xy 390.40786 -405.678683) (xy 390.376829 -405.618958)
			(xy 390.353158 -405.555954) (xy 390.337187 -405.490571) (xy 390.329144 -405.423749) (xy 390.329144 -405.356445)
			(xy 390.337188 -405.289623) (xy 390.35316 -405.224241) (xy 390.376832 -405.161236) (xy 390.407863 -405.101512)
			(xy 390.445809 -405.045925) (xy 390.467596 -405.020272) (xy 390.473386 -405.013122) (xy 390.479905 -404.995935)
			(xy 390.480296 -404.986744) (xy 390.480296 -404.828756) (xy 390.480749 -404.818645) (xy 390.4885 -404.799967)
			(xy 390.502807 -404.785673) (xy 390.521493 -404.77794) (xy 390.531604 -404.777448) (xy 391.248138 -404.777448)
			(xy 391.258268 -404.777896) (xy 391.276992 -404.785637) (xy 391.291347 -404.799935) (xy 391.299163 -404.818628)
			(xy 391.2997 -404.828756) (xy 391.2997 -404.986744) (xy 391.300089 -404.995933) (xy 391.306617 -405.013118)
			(xy 391.3124 -405.020272) (xy 391.334183 -405.045928) (xy 391.372129 -405.101515) (xy 391.40316 -405.161238)
			(xy 391.426832 -405.224242) (xy 391.442804 -405.289623) (xy 391.450848 -405.356445) (xy 391.450848 -405.423749)
			(xy 391.442805 -405.490571) (xy 391.426833 -405.555952) (xy 391.403163 -405.618956) (xy 391.372132 -405.67868)
			(xy 391.334186 -405.734267) (xy 391.3124 -405.75992) (xy 391.306612 -405.767072) (xy 391.300092 -405.784257)
			(xy 391.2997 -405.793448) (xy 391.2997 -406.286716) (xy 391.300103 -406.295904) (xy 391.306622 -406.313088)
			(xy 391.3124 -406.320244) (xy 391.334155 -406.345923) (xy 391.372102 -406.401506) (xy 391.403135 -406.461226)
			(xy 391.426808 -406.524227) (xy 391.442782 -406.589606) (xy 391.450828 -406.656425) (xy 391.450831 -406.723727)
			(xy 391.44279 -406.790547) (xy 391.426822 -406.855927) (xy 391.403154 -406.91893) (xy 391.372127 -406.978653)
			(xy 391.334185 -407.034239) (xy 391.3124 -407.059892) (xy 391.306624 -407.067052) (xy 391.300097 -407.084231)
			(xy 391.2997 -407.09342) (xy 391.2997 -407.251408) (xy 391.299221 -407.261517) (xy 391.291481 -407.280196)
			(xy 391.277182 -407.29449) (xy 391.258501 -407.302224) (xy 391.248392 -407.302716) (xy 390.531858 -407.302716)
			(xy 390.521723 -407.302307) (xy 390.502993 -407.294557) (xy 390.488636 -407.280247) (xy 390.480826 -407.261541)
			(xy 390.480296 -407.251408) (xy 390.480296 -407.09342) (xy 390.479877 -407.084234) (xy 390.47337 -407.067049)
			(xy 390.467596 -407.059892) (xy 390.445778 -407.034265) (xy 390.407833 -406.978674) (xy 390.376804 -406.918947)
			(xy 390.353135 -406.855939) (xy 390.337165 -406.790554) (xy 390.329124 -406.723729) (xy 387.051062 -406.723729)
			(xy 387.051062 -406.723787) (xy 387.04299 -406.790723) (xy 387.026958 -406.85621) (xy 387.003197 -406.919305)
			(xy 386.972051 -406.979101) (xy 386.933966 -407.034735) (xy 386.912104 -407.0604) (xy 386.906325 -407.067558)
			(xy 386.8998 -407.084739) (xy 386.899404 -407.093928) (xy 386.899404 -407.251408) (xy 386.898921 -407.261517)
			(xy 386.891182 -407.280194) (xy 386.876884 -407.294489) (xy 386.858205 -407.302224) (xy 386.848096 -407.302716)
			(xy 386.131816 -407.302716) (xy 386.121697 -407.302271) (xy 386.102996 -407.294531) (xy 386.088682 -407.280224)
			(xy 386.080933 -407.261527) (xy 386.080508 -407.251408) (xy 386.080508 -407.093928) (xy 386.080083 -407.084742)
			(xy 386.073579 -407.067558) (xy 386.067808 -407.0604) (xy 386.045912 -407.034761) (xy 386.007824 -406.979123)
			(xy 385.976674 -406.919323) (xy 385.952912 -406.856223) (xy 385.936878 -406.79073) (xy 385.928805 -406.723789)
			(xy 382.65076 -406.723789) (xy 382.642725 -406.790549) (xy 382.626754 -406.85593) (xy 382.603083 -406.918933)
			(xy 382.572051 -406.978655) (xy 382.534103 -407.03424) (xy 382.512316 -407.059892) (xy 382.506542 -407.067053)
			(xy 382.500013 -407.084231) (xy 382.499616 -407.09342) (xy 382.499616 -407.251408) (xy 382.499122 -407.261515)
			(xy 382.491384 -407.28019) (xy 382.47709 -407.294484) (xy 382.458415 -407.302222) (xy 382.448308 -407.302716)
			(xy 381.731774 -407.302716) (xy 381.72164 -407.302294) (xy 381.70291 -407.294549) (xy 381.688553 -407.280243)
			(xy 381.680743 -407.26154) (xy 381.680212 -407.251408) (xy 381.680212 -407.09342) (xy 381.679789 -407.084234)
			(xy 381.673284 -407.06705) (xy 381.667512 -407.059892) (xy 381.645694 -407.034265) (xy 381.607748 -406.978675)
			(xy 381.576717 -406.918947) (xy 381.553047 -406.855939) (xy 381.537077 -406.790554) (xy 381.529036 -406.723729)
			(xy 378.250974 -406.723729) (xy 378.250974 -406.723786) (xy 378.242902 -406.790722) (xy 378.226871 -406.856209)
			(xy 378.203111 -406.919305) (xy 378.171965 -406.9791) (xy 378.133881 -407.034734) (xy 378.11202 -407.0604)
			(xy 378.106243 -407.067559) (xy 378.099716 -407.084739) (xy 378.09932 -407.093928) (xy 378.09932 -407.251408)
			(xy 378.098822 -407.261515) (xy 378.091085 -407.280189) (xy 378.076793 -407.294483) (xy 378.058119 -407.302221)
			(xy 378.048012 -407.302716) (xy 377.331732 -407.302716) (xy 377.321614 -407.302258) (xy 377.302914 -407.294524)
			(xy 377.288599 -407.28022) (xy 377.280849 -407.261526) (xy 377.280424 -407.251408) (xy 377.280424 -407.093928)
			(xy 377.279995 -407.084743) (xy 377.273494 -407.067559) (xy 377.267724 -407.0604) (xy 377.245828 -407.034761)
			(xy 377.207738 -406.979123) (xy 377.176588 -406.919324) (xy 377.152824 -406.856223) (xy 377.13679 -406.790731)
			(xy 377.128717 -406.723789) (xy 347.450915 -406.723789) (xy 347.442881 -406.790547) (xy 347.426912 -406.855927)
			(xy 347.403244 -406.91893) (xy 347.372216 -406.978653) (xy 347.334273 -407.03424) (xy 347.312488 -407.059892)
			(xy 347.306711 -407.067051) (xy 347.300185 -407.084231) (xy 347.299788 -407.09342) (xy 347.299788 -407.251408)
			(xy 347.299385 -407.261564) (xy 347.291584 -407.280319) (xy 347.277182 -407.294642) (xy 347.258384 -407.30234)
			(xy 347.248226 -407.302716) (xy 346.531946 -407.302716) (xy 346.521817 -407.302234) (xy 346.503088 -407.294514)
			(xy 346.488729 -407.280225) (xy 346.480916 -407.261535) (xy 346.480384 -407.251408) (xy 346.480384 -407.09342)
			(xy 346.479968 -407.084233) (xy 346.473459 -407.067049) (xy 346.467684 -407.059892) (xy 346.445864 -407.034266)
			(xy 346.407913 -406.978677) (xy 346.376878 -406.91895) (xy 346.353205 -406.855942) (xy 346.337233 -406.790556)
			(xy 346.329191 -406.72373) (xy 343.051153 -406.72373) (xy 343.051153 -406.723787) (xy 343.04308 -406.790723)
			(xy 343.027048 -406.85621) (xy 343.003287 -406.919306) (xy 342.97214 -406.979101) (xy 342.934054 -407.034735)
			(xy 342.912192 -407.0604) (xy 342.906412 -407.067557) (xy 342.899888 -407.084738) (xy 342.899492 -407.093928)
			(xy 342.899492 -407.251408) (xy 342.89909 -407.261532) (xy 342.891338 -407.280237) (xy 342.877017 -407.294551)
			(xy 342.858308 -407.302295) (xy 342.848184 -407.302716) (xy 342.131904 -407.302716) (xy 342.121798 -407.302212)
			(xy 342.103122 -407.294479) (xy 342.088828 -407.280188) (xy 342.08109 -407.261514) (xy 342.080596 -407.251408)
			(xy 342.080596 -407.093928) (xy 342.080173 -407.084742) (xy 342.073668 -407.067558) (xy 342.067896 -407.0604)
			(xy 342.046001 -407.034761) (xy 342.007913 -406.979122) (xy 341.976764 -406.919322) (xy 341.953002 -406.856222)
			(xy 341.936969 -406.79073) (xy 341.928896 -406.723789) (xy 338.650827 -406.723789) (xy 338.642793 -406.790546)
			(xy 338.626825 -406.855926) (xy 338.603158 -406.918929) (xy 338.572131 -406.978652) (xy 338.534188 -407.034239)
			(xy 338.512404 -407.059892) (xy 338.506629 -407.067052) (xy 338.500101 -407.084231) (xy 338.499704 -407.09342)
			(xy 338.499704 -407.251408) (xy 338.499285 -407.261562) (xy 338.491487 -407.280314) (xy 338.47709 -407.294637)
			(xy 338.458298 -407.302337) (xy 338.448142 -407.302716) (xy 337.731862 -407.302716) (xy 337.721727 -407.302303)
			(xy 337.702997 -407.294555) (xy 337.688641 -407.280246) (xy 337.68083 -407.261541) (xy 337.6803 -407.251408)
			(xy 337.6803 -407.09342) (xy 337.67988 -407.084234) (xy 337.673373 -407.067049) (xy 337.6676 -407.059892)
			(xy 337.645782 -407.034265) (xy 337.607837 -406.978674) (xy 337.576807 -406.918947) (xy 337.553138 -406.855939)
			(xy 337.537168 -406.790554) (xy 337.529127 -406.723729) (xy 334.251065 -406.723729) (xy 334.251065 -406.723786)
			(xy 334.242993 -406.790722) (xy 334.226961 -406.85621) (xy 334.203201 -406.919305) (xy 334.172054 -406.9791)
			(xy 334.13397 -407.034735) (xy 334.112108 -407.0604) (xy 334.10633 -407.067558) (xy 334.099804 -407.084739)
			(xy 334.099408 -407.093928) (xy 334.099408 -407.251408) (xy 334.098921 -407.261516) (xy 334.091183 -407.280193)
			(xy 334.076886 -407.294487) (xy 334.058208 -407.302223) (xy 334.0481 -407.302716) (xy 333.33182 -407.302716)
			(xy 333.321701 -407.302268) (xy 333.303001 -407.29453) (xy 333.288686 -407.280223) (xy 333.280937 -407.261527)
			(xy 333.280512 -407.251408) (xy 333.280512 -407.093928) (xy 333.280086 -407.084743) (xy 333.273583 -407.067558)
			(xy 333.267812 -407.0604) (xy 333.245916 -407.034761) (xy 333.207828 -406.979123) (xy 333.176678 -406.919323)
			(xy 333.152915 -406.856223) (xy 333.136881 -406.790731) (xy 333.128808 -406.723789) (xy 326.525636 -406.723789)
			(xy 326.525636 -409.523827) (xy 330.929173 -409.523827) (xy 330.929176 -409.456519) (xy 330.937224 -409.389693)
			(xy 330.953202 -409.324309) (xy 330.976879 -409.261303) (xy 331.007918 -409.201578) (xy 331.045873 -409.145992)
			(xy 331.067664 -409.12034) (xy 331.073476 -409.113206) (xy 331.07998 -409.096007) (xy 331.080364 -409.086812)
			(xy 331.080364 -408.593544) (xy 331.079919 -408.584361) (xy 331.073428 -408.567177) (xy 331.067664 -408.560016)
			(xy 331.045868 -408.534371) (xy 331.007918 -408.478784) (xy 330.976883 -408.419059) (xy 330.95321 -408.356054)
			(xy 330.937237 -408.290671) (xy 330.929193 -408.223847) (xy 330.929194 -408.156541) (xy 330.937239 -408.089717)
			(xy 330.953213 -408.024334) (xy 330.976888 -407.96133) (xy 331.007924 -407.901606) (xy 331.045875 -407.84602)
			(xy 331.067664 -407.820368) (xy 331.073464 -407.813226) (xy 331.079975 -407.796033) (xy 331.080364 -407.78684)
			(xy 331.080364 -407.628852) (xy 331.080782 -407.618699) (xy 331.088586 -407.599953) (xy 331.102983 -407.585633)
			(xy 331.121771 -407.577928) (xy 331.131926 -407.577544) (xy 331.848206 -407.577544) (xy 331.858334 -407.578022)
			(xy 331.877056 -407.585752) (xy 331.891412 -407.600041) (xy 331.89923 -407.618727) (xy 331.899768 -407.628852)
			(xy 331.899768 -407.78684) (xy 331.900166 -407.796028) (xy 331.906689 -407.813212) (xy 331.912468 -407.820368)
			(xy 331.934248 -407.846027) (xy 331.972196 -407.901612) (xy 332.00323 -407.961335) (xy 332.026903 -408.024339)
			(xy 332.042876 -408.08972) (xy 332.050921 -408.156542) (xy 332.050921 -408.223846) (xy 332.042878 -408.290668)
			(xy 332.026906 -408.35605) (xy 332.003235 -408.419054) (xy 331.972203 -408.478777) (xy 331.934255 -408.534364)
			(xy 331.912468 -408.560016) (xy 331.906678 -408.567166) (xy 331.90016 -408.584353) (xy 331.899768 -408.593544)
			(xy 331.899768 -409.086812) (xy 331.900179 -409.095999) (xy 331.906693 -409.113183) (xy 331.912468 -409.12034)
			(xy 331.93422 -409.146022) (xy 331.972169 -409.201604) (xy 332.003204 -409.261323) (xy 332.026878 -409.324324)
			(xy 332.042853 -409.389703) (xy 332.0509 -409.456522) (xy 332.050904 -409.523824) (xy 332.042863 -409.590644)
			(xy 332.026894 -409.656024) (xy 332.003226 -409.719027) (xy 331.972197 -409.77875) (xy 331.934253 -409.834336)
			(xy 331.912468 -409.859988) (xy 331.906647 -409.867116) (xy 331.900148 -409.88432) (xy 331.899768 -409.893516)
			(xy 331.899768 -410.051504) (xy 331.899381 -410.061662) (xy 331.891578 -410.080421) (xy 331.87717 -410.094745)
			(xy 331.858367 -410.102439) (xy 331.848206 -410.102812) (xy 331.131926 -410.102812) (xy 331.121807 -410.102254)
			(xy 331.103097 -410.094544) (xy 331.088741 -410.08028) (xy 331.080912 -410.061619) (xy 331.080364 -410.051504)
			(xy 331.080364 -409.893516) (xy 331.079932 -409.884331) (xy 331.073432 -409.867148) (xy 331.067664 -409.859988)
			(xy 331.04584 -409.834365) (xy 331.007891 -409.778775) (xy 330.976857 -409.719048) (xy 330.953186 -409.656039)
			(xy 330.937214 -409.590653) (xy 330.929173 -409.523827) (xy 326.525636 -409.523827) (xy 326.525636 -410.623701)
			(xy 333.128819 -410.623701) (xy 333.12882 -410.556275) (xy 333.136898 -410.489336) (xy 333.152936 -410.423846)
			(xy 333.176702 -410.360748) (xy 333.207855 -410.300952) (xy 333.245947 -410.245317) (xy 333.267812 -410.219652)
			(xy 333.273613 -410.21251) (xy 333.280125 -410.195317) (xy 333.280512 -410.186124) (xy 333.280512 -409.693872)
			(xy 333.280113 -409.684684) (xy 333.273591 -409.6675) (xy 333.267812 -409.660344) (xy 333.245959 -409.634669)
			(xy 333.20787 -409.579036) (xy 333.176718 -409.519242) (xy 333.152952 -409.456146) (xy 333.136916 -409.390658)
			(xy 333.128839 -409.32372) (xy 333.128837 -409.256298) (xy 333.136912 -409.18936) (xy 333.152947 -409.123871)
			(xy 333.17671 -409.060775) (xy 333.20786 -409.000979) (xy 333.245948 -408.945345) (xy 333.267812 -408.91968)
			(xy 333.273601 -408.912529) (xy 333.28012 -408.895343) (xy 333.280512 -408.886152) (xy 333.280512 -408.728672)
			(xy 333.280962 -408.71856) (xy 333.288711 -408.699879) (xy 333.303019 -408.685585) (xy 333.321708 -408.677853)
			(xy 333.33182 -408.677364) (xy 334.0481 -408.677364) (xy 334.058204 -408.677884) (xy 334.076876 -408.685615)
			(xy 334.091169 -408.699901) (xy 334.09891 -408.718568) (xy 334.099408 -408.728672) (xy 334.099408 -408.886152)
			(xy 334.099839 -408.895337) (xy 334.106338 -408.912522) (xy 334.112108 -408.91968) (xy 334.133983 -408.945336)
			(xy 334.172071 -409.000972) (xy 334.203221 -409.060769) (xy 334.226984 -409.123867) (xy 334.243019 -409.189358)
			(xy 334.251093 -409.256297) (xy 334.251092 -409.323721) (xy 334.243015 -409.39066) (xy 334.226979 -409.45615)
			(xy 334.203214 -409.519247) (xy 334.200797 -409.523886) (xy 335.328966 -409.523886) (xy 335.328969 -409.45646)
			(xy 335.337048 -409.38952) (xy 335.353086 -409.32403) (xy 335.376852 -409.260931) (xy 335.408005 -409.201134)
			(xy 335.446095 -409.145498) (xy 335.46796 -409.119832) (xy 335.473775 -409.1127) (xy 335.480277 -409.095499)
			(xy 335.48066 -409.086304) (xy 335.48066 -408.594052) (xy 335.480211 -408.584869) (xy 335.473723 -408.567685)
			(xy 335.46796 -408.560524) (xy 335.44609 -408.534865) (xy 335.408004 -408.479228) (xy 335.376856 -408.419431)
			(xy 335.353094 -408.356333) (xy 335.33706 -408.290844) (xy 335.328985 -408.223906) (xy 335.328986 -408.156482)
			(xy 335.337062 -408.089544) (xy 335.353097 -408.024055) (xy 335.376861 -407.960958) (xy 335.40801 -407.901161)
			(xy 335.446097 -407.845526) (xy 335.46796 -407.81986) (xy 335.473763 -407.81272) (xy 335.480272 -407.795525)
			(xy 335.48066 -407.786332) (xy 335.48066 -407.628852) (xy 335.481145 -407.618745) (xy 335.488891 -407.600074)
			(xy 335.503187 -407.585782) (xy 335.521861 -407.578042) (xy 335.531968 -407.577544) (xy 336.248248 -407.577544)
			(xy 336.258353 -407.578045) (xy 336.277021 -407.585788) (xy 336.291312 -407.600079) (xy 336.299055 -407.618747)
			(xy 336.299556 -407.628852) (xy 336.299556 -407.786332) (xy 336.299961 -407.79552) (xy 336.306479 -407.812703)
			(xy 336.312256 -407.81986) (xy 336.334114 -407.845531) (xy 336.372205 -407.901164) (xy 336.403359 -407.960959)
			(xy 336.427126 -408.024055) (xy 336.443163 -408.089544) (xy 336.45124 -408.156482) (xy 336.451241 -408.223906)
			(xy 336.443165 -408.290844) (xy 336.427129 -408.356334) (xy 336.403364 -408.41943) (xy 336.372212 -408.479226)
			(xy 336.334121 -408.53486) (xy 336.312256 -408.560524) (xy 336.306461 -408.56767) (xy 336.299947 -408.58486)
			(xy 336.299556 -408.594052) (xy 336.299556 -409.086304) (xy 336.299974 -409.09549) (xy 336.306483 -409.112674)
			(xy 336.312256 -409.119832) (xy 336.334086 -409.145526) (xy 336.372179 -409.201155) (xy 336.403334 -409.260947)
			(xy 336.427102 -409.32404) (xy 336.443141 -409.389526) (xy 336.45122 -409.456462) (xy 336.451224 -409.523884)
			(xy 336.443151 -409.59082) (xy 336.427118 -409.656308) (xy 336.403356 -409.719404) (xy 336.372207 -409.779198)
			(xy 336.334119 -409.834832) (xy 336.312256 -409.860496) (xy 336.306473 -409.867651) (xy 336.299951 -409.884834)
			(xy 336.299556 -409.894024) (xy 336.299556 -410.051504) (xy 336.299019 -410.061606) (xy 336.291291 -410.080274)
			(xy 336.277011 -410.094566) (xy 336.25835 -410.102311) (xy 336.248248 -410.102812) (xy 335.531968 -410.102812)
			(xy 335.521859 -410.102341) (xy 335.503182 -410.094595) (xy 335.488889 -410.080294) (xy 335.481153 -410.061614)
			(xy 335.48066 -410.051504) (xy 335.48066 -409.894024) (xy 335.480225 -409.88484) (xy 335.473727 -409.867656)
			(xy 335.46796 -409.860496) (xy 335.446062 -409.834859) (xy 335.407977 -409.77922) (xy 335.37683 -409.719419)
			(xy 335.35307 -409.656319) (xy 335.337038 -409.590827) (xy 335.328966 -409.523886) (xy 334.200797 -409.523886)
			(xy 334.172062 -409.579044) (xy 334.133972 -409.634679) (xy 334.112108 -409.660344) (xy 334.106311 -409.667489)
			(xy 334.099796 -409.68468) (xy 334.099408 -409.693872) (xy 334.099408 -410.186124) (xy 334.099805 -410.195313)
			(xy 334.106328 -410.212497) (xy 334.112108 -410.219652) (xy 334.133956 -410.24533) (xy 334.172045 -410.300963)
			(xy 334.203196 -410.360758) (xy 334.22696 -410.423853) (xy 334.242997 -410.48934) (xy 334.251074 -410.556277)
			(xy 334.251075 -410.623641) (xy 337.529138 -410.623641) (xy 337.52914 -410.556335) (xy 337.537185 -410.489512)
			(xy 337.553158 -410.42413) (xy 337.576831 -410.361125) (xy 337.607864 -410.3014) (xy 337.645813 -410.245813)
			(xy 337.6676 -410.22016) (xy 337.673396 -410.213014) (xy 337.679911 -410.195824) (xy 337.6803 -410.186632)
			(xy 337.6803 -409.693364) (xy 337.679907 -409.684175) (xy 337.673382 -409.666991) (xy 337.6676 -409.659836)
			(xy 337.645825 -409.634174) (xy 337.607879 -409.578588) (xy 337.576847 -409.518865) (xy 337.553175 -409.455862)
			(xy 337.537203 -409.390482) (xy 337.529158 -409.323661) (xy 337.529157 -409.256357) (xy 337.537199 -409.189536)
			(xy 337.55317 -409.124155) (xy 337.57684 -409.061151) (xy 337.607869 -409.001428) (xy 337.645814 -408.945841)
			(xy 337.6676 -408.920188) (xy 337.673384 -408.913034) (xy 337.679906 -408.89585) (xy 337.6803 -408.88666)
			(xy 337.6803 -408.728672) (xy 337.680699 -408.718516) (xy 337.688503 -408.699763) (xy 337.702907 -408.685441)
			(xy 337.721704 -408.677742) (xy 337.731862 -408.677364) (xy 338.448142 -408.677364) (xy 338.458274 -408.677793)
			(xy 338.477001 -408.685539) (xy 338.491357 -408.699843) (xy 338.49917 -408.718542) (xy 338.499704 -408.728672)
			(xy 338.499704 -408.88666) (xy 338.500132 -408.895845) (xy 338.506633 -408.91303) (xy 338.512404 -408.920188)
			(xy 338.534202 -408.945831) (xy 338.572148 -409.00142) (xy 338.603178 -409.061145) (xy 338.626848 -409.124151)
			(xy 338.642819 -409.189534) (xy 338.650862 -409.256356) (xy 338.650861 -409.323662) (xy 338.642816 -409.390484)
			(xy 338.626843 -409.455867) (xy 338.603171 -409.518871) (xy 338.600596 -409.523827) (xy 339.729261 -409.523827)
			(xy 339.729264 -409.456519) (xy 339.737312 -409.389694) (xy 339.753289 -409.324309) (xy 339.776966 -409.261303)
			(xy 339.808004 -409.201579) (xy 339.845958 -409.145992) (xy 339.867748 -409.12034) (xy 339.873559 -409.113205)
			(xy 339.880064 -409.096006) (xy 339.880448 -409.086812) (xy 339.880448 -408.593544) (xy 339.880006 -408.58436)
			(xy 339.873513 -408.567176) (xy 339.867748 -408.560016) (xy 339.845952 -408.534371) (xy 339.808003 -408.478783)
			(xy 339.776969 -408.419059) (xy 339.753297 -408.356054) (xy 339.737324 -408.29067) (xy 339.72928 -408.223847)
			(xy 339.729281 -408.156541) (xy 339.737326 -408.089718) (xy 339.7533 -408.024335) (xy 339.776974 -407.96133)
			(xy 339.808009 -407.901606) (xy 339.845959 -407.84602) (xy 339.867748 -407.820368) (xy 339.873547 -407.813224)
			(xy 339.880059 -407.796032) (xy 339.880448 -407.78684) (xy 339.880448 -407.628852) (xy 339.880881 -407.618701)
			(xy 339.888683 -407.599958) (xy 339.903075 -407.585638) (xy 339.921857 -407.577931) (xy 339.93201 -407.577544)
			(xy 340.64829 -407.577544) (xy 340.658417 -407.578035) (xy 340.677138 -407.58576) (xy 340.691495 -407.600045)
			(xy 340.699314 -407.618728) (xy 340.699852 -407.628852) (xy 340.699852 -407.78684) (xy 340.700254 -407.796028)
			(xy 340.706775 -407.813211) (xy 340.712552 -407.820368) (xy 340.734332 -407.846027) (xy 340.772282 -407.901612)
			(xy 340.803316 -407.961335) (xy 340.826989 -408.024338) (xy 340.842963 -408.08972) (xy 340.851008 -408.156542)
			(xy 340.851009 -408.223846) (xy 340.842965 -408.290668) (xy 340.826993 -408.35605) (xy 340.803321 -408.419054)
			(xy 340.772288 -408.478778) (xy 340.734339 -408.534364) (xy 340.712552 -408.560016) (xy 340.70676 -408.567164)
			(xy 340.700244 -408.584353) (xy 340.699852 -408.593544) (xy 340.699852 -409.086812) (xy 340.700267 -409.095998)
			(xy 340.706779 -409.113182) (xy 340.712552 -409.12034) (xy 340.734304 -409.146021) (xy 340.772255 -409.201603)
			(xy 340.80329 -409.261323) (xy 340.826965 -409.324323) (xy 340.842941 -409.389702) (xy 340.850988 -409.456522)
			(xy 340.850992 -409.523824) (xy 340.842951 -409.590644) (xy 340.826981 -409.656025) (xy 340.803312 -409.719028)
			(xy 340.772283 -409.77875) (xy 340.734338 -409.834336) (xy 340.712552 -409.859988) (xy 340.70673 -409.867115)
			(xy 340.700232 -409.88432) (xy 340.699852 -409.893516) (xy 340.699852 -410.051504) (xy 340.699383 -410.061652)
			(xy 340.691595 -410.080394) (xy 340.677214 -410.094716) (xy 340.65844 -410.102424) (xy 340.64829 -410.102812)
			(xy 339.93201 -410.102812) (xy 339.92189 -410.102267) (xy 339.903179 -410.094552) (xy 339.888824 -410.080284)
			(xy 339.880996 -410.061621) (xy 339.880448 -410.051504) (xy 339.880448 -409.893516) (xy 339.88002 -409.884331)
			(xy 339.873517 -409.867147) (xy 339.867748 -409.859988) (xy 339.845924 -409.834365) (xy 339.807976 -409.778775)
			(xy 339.776944 -409.719047) (xy 339.753273 -409.656039) (xy 339.737302 -409.590653) (xy 339.729261 -409.523827)
			(xy 338.600596 -409.523827) (xy 338.572139 -409.578596) (xy 338.534191 -409.634183) (xy 338.512404 -409.659836)
			(xy 338.50661 -409.666983) (xy 338.500094 -409.684172) (xy 338.499704 -409.693364) (xy 338.499704 -410.186632)
			(xy 338.500098 -410.195821) (xy 338.506623 -410.213005) (xy 338.512404 -410.22016) (xy 338.534175 -410.245826)
			(xy 338.572121 -410.301411) (xy 338.603153 -410.361133) (xy 338.626825 -410.424136) (xy 338.642797 -410.489516)
			(xy 338.650842 -410.556336) (xy 338.650844 -410.623639) (xy 338.650837 -410.6237) (xy 341.928907 -410.6237)
			(xy 341.928908 -410.556276) (xy 341.936986 -410.489336) (xy 341.953023 -410.423846) (xy 341.976789 -410.360749)
			(xy 342.007941 -410.300952) (xy 342.046031 -410.245317) (xy 342.067896 -410.219652) (xy 342.073695 -410.212508)
			(xy 342.080208 -410.195317) (xy 342.080596 -410.186124) (xy 342.080596 -409.693872) (xy 342.0802 -409.684683)
			(xy 342.073677 -409.667499) (xy 342.067896 -409.660344) (xy 342.046044 -409.634669) (xy 342.007955 -409.579036)
			(xy 341.976804 -409.519241) (xy 341.953039 -409.456145) (xy 341.937003 -409.390657) (xy 341.928927 -409.32372)
			(xy 341.928925 -409.256298) (xy 341.937 -409.18936) (xy 341.953034 -409.123872) (xy 341.976797 -409.060776)
			(xy 342.007946 -409.00098) (xy 342.046033 -408.945345) (xy 342.067896 -408.91968) (xy 342.073683 -408.912528)
			(xy 342.080204 -408.895343) (xy 342.080596 -408.886152) (xy 342.080596 -408.728672) (xy 342.081062 -408.718562)
			(xy 342.088808 -408.699884) (xy 342.103111 -408.68559) (xy 342.121794 -408.677856) (xy 342.131904 -408.677364)
			(xy 342.848184 -408.677364) (xy 342.858287 -408.677897) (xy 342.876958 -408.685623) (xy 342.891252 -408.699905)
			(xy 342.898994 -408.718569) (xy 342.899492 -408.728672) (xy 342.899492 -408.886152) (xy 342.899927 -408.895337)
			(xy 342.906424 -408.912521) (xy 342.912192 -408.91968) (xy 342.934068 -408.945335) (xy 342.972157 -409.000971)
			(xy 343.003308 -409.060769) (xy 343.027071 -409.123867) (xy 343.043106 -409.189357) (xy 343.051181 -409.256297)
			(xy 343.05118 -409.323721) (xy 343.043103 -409.390661) (xy 343.027066 -409.45615) (xy 343.0033 -409.519248)
			(xy 343.000914 -409.523827) (xy 344.129052 -409.523827) (xy 344.129055 -409.456519) (xy 344.137102 -409.389694)
			(xy 344.153079 -409.32431) (xy 344.176756 -409.261304) (xy 344.207793 -409.201579) (xy 344.245746 -409.145992)
			(xy 344.267536 -409.12034) (xy 344.273345 -409.113204) (xy 344.279851 -409.096006) (xy 344.280236 -409.086812)
			(xy 344.280236 -408.593544) (xy 344.279796 -408.58436) (xy 344.273302 -408.567176) (xy 344.267536 -408.560016)
			(xy 344.24574 -408.53437) (xy 344.207792 -408.478783) (xy 344.176759 -408.419058) (xy 344.153087 -408.356053)
			(xy 344.137115 -408.29067) (xy 344.129071 -408.223847) (xy 344.129072 -408.156541) (xy 344.137117 -408.089718)
			(xy 344.153091 -408.024335) (xy 344.176764 -407.961331) (xy 344.207798 -407.901607) (xy 344.245748 -407.84602)
			(xy 344.267536 -407.820368) (xy 344.273333 -407.813223) (xy 344.279847 -407.796032) (xy 344.280236 -407.78684)
			(xy 344.280236 -407.628852) (xy 344.280583 -407.61869) (xy 344.288401 -407.59993) (xy 344.302821 -407.585607)
			(xy 344.321634 -407.577916) (xy 344.331798 -407.577544) (xy 345.048078 -407.577544) (xy 345.058204 -407.578045)
			(xy 345.076925 -407.585766) (xy 345.091283 -407.600048) (xy 345.099102 -407.618729) (xy 345.09964 -407.628852)
			(xy 345.09964 -407.78684) (xy 345.100044 -407.796028) (xy 345.106563 -407.813211) (xy 345.11234 -407.820368)
			(xy 345.13412 -407.846026) (xy 345.172071 -407.901611) (xy 345.203106 -407.961334) (xy 345.22678 -408.024338)
			(xy 345.242754 -408.089719) (xy 345.250799 -408.156542) (xy 345.2508 -408.223846) (xy 345.242756 -408.290669)
			(xy 345.226783 -408.356051) (xy 345.20311 -408.419055) (xy 345.172077 -408.478778) (xy 345.134128 -408.534364)
			(xy 345.11234 -408.560016) (xy 345.106547 -408.567163) (xy 345.100032 -408.584352) (xy 345.09964 -408.593544)
			(xy 345.09964 -409.086812) (xy 345.100058 -409.095998) (xy 345.106568 -409.113182) (xy 345.11234 -409.12034)
			(xy 345.134093 -409.146021) (xy 345.172044 -409.201603) (xy 345.20308 -409.261322) (xy 345.226756 -409.324323)
			(xy 345.242732 -409.389702) (xy 345.250779 -409.456522) (xy 345.250783 -409.523824) (xy 345.242742 -409.590645)
			(xy 345.226772 -409.656025) (xy 345.203102 -409.719028) (xy 345.172072 -409.778751) (xy 345.134126 -409.834336)
			(xy 345.11234 -409.859988) (xy 345.106516 -409.867114) (xy 345.100019 -409.884319) (xy 345.09964 -409.893516)
			(xy 345.09964 -410.051504) (xy 345.099182 -410.061653) (xy 345.091393 -410.080398) (xy 345.077008 -410.09472)
			(xy 345.058229 -410.102427) (xy 345.048078 -410.102812) (xy 344.331798 -410.102812) (xy 344.321678 -410.102277)
			(xy 344.302966 -410.094558) (xy 344.288612 -410.080287) (xy 344.280784 -410.061621) (xy 344.280236 -410.051504)
			(xy 344.280236 -409.893516) (xy 344.27981 -409.884331) (xy 344.273307 -409.867146) (xy 344.267536 -409.859988)
			(xy 344.245713 -409.834365) (xy 344.207765 -409.778774) (xy 344.176734 -409.719047) (xy 344.153063 -409.656038)
			(xy 344.137093 -409.590653) (xy 344.129052 -409.523827) (xy 343.000914 -409.523827) (xy 342.972148 -409.579044)
			(xy 342.934057 -409.634679) (xy 342.912192 -409.660344) (xy 342.906393 -409.667488) (xy 342.89988 -409.684679)
			(xy 342.899492 -409.693872) (xy 342.899492 -410.186124) (xy 342.899892 -410.195312) (xy 342.906413 -410.212496)
			(xy 342.912192 -410.219652) (xy 342.934041 -410.24533) (xy 342.97213 -410.300963) (xy 343.003282 -410.360757)
			(xy 343.027048 -410.423852) (xy 343.043084 -410.48934) (xy 343.051162 -410.556277) (xy 343.051163 -410.623642)
			(xy 346.329202 -410.623642) (xy 346.329204 -410.556334) (xy 346.33725 -410.48951) (xy 346.353226 -410.424126)
			(xy 346.376903 -410.361121) (xy 346.40794 -410.301397) (xy 346.445894 -410.245812) (xy 346.467684 -410.22016)
			(xy 346.473478 -410.213013) (xy 346.479995 -410.195824) (xy 346.480384 -410.186632) (xy 346.480384 -409.693364)
			(xy 346.479995 -409.684175) (xy 346.473467 -409.66699) (xy 346.467684 -409.659836) (xy 346.445907 -409.634175)
			(xy 346.407955 -409.578591) (xy 346.376918 -409.518869) (xy 346.353243 -409.455865) (xy 346.337268 -409.390484)
			(xy 346.329222 -409.323661) (xy 346.329221 -409.256357) (xy 346.337265 -409.189534) (xy 346.353238 -409.124152)
			(xy 346.376911 -409.061148) (xy 346.407945 -409.001425) (xy 346.445896 -408.94584) (xy 346.467684 -408.920188)
			(xy 346.473466 -408.913033) (xy 346.47999 -408.89585) (xy 346.480384 -408.88666) (xy 346.480384 -408.728672)
			(xy 346.480798 -408.718518) (xy 346.4886 -408.699768) (xy 346.502999 -408.685446) (xy 346.52179 -408.677745)
			(xy 346.531946 -408.677364) (xy 347.248226 -408.677364) (xy 347.258357 -408.677806) (xy 347.277084 -408.685547)
			(xy 347.29144 -408.699847) (xy 347.299254 -408.718543) (xy 347.299788 -408.728672) (xy 347.299788 -408.88666)
			(xy 347.30022 -408.895845) (xy 347.306719 -408.913029) (xy 347.312488 -408.920188) (xy 347.334287 -408.945831)
			(xy 347.372233 -409.001419) (xy 347.403265 -409.061144) (xy 347.426936 -409.12415) (xy 347.442907 -409.189533)
			(xy 347.45095 -409.256356) (xy 347.450949 -409.323662) (xy 347.442904 -409.390485) (xy 347.42693 -409.455867)
			(xy 347.403257 -409.518872) (xy 347.400682 -409.523827) (xy 374.929082 -409.523827) (xy 374.929085 -409.456519)
			(xy 374.937133 -409.389693) (xy 374.953111 -409.324308) (xy 374.97679 -409.261302) (xy 375.007829 -409.201578)
			(xy 375.045785 -409.145991) (xy 375.067576 -409.12034) (xy 375.073378 -409.113198) (xy 375.07989 -409.096005)
			(xy 375.080276 -409.086812) (xy 375.080276 -408.593544) (xy 375.07985 -408.584358) (xy 375.073348 -408.567174)
			(xy 375.067576 -408.560016) (xy 375.045779 -408.534371) (xy 375.007828 -408.478784) (xy 374.976793 -408.41906)
			(xy 374.953119 -408.356055) (xy 374.937146 -408.290671) (xy 374.929102 -408.223847) (xy 374.929103 -408.156541)
			(xy 374.937148 -408.089717) (xy 374.953123 -408.024334) (xy 374.976798 -407.961329) (xy 375.007835 -407.901605)
			(xy 375.045787 -407.84602) (xy 375.067576 -407.820368) (xy 375.073366 -407.813218) (xy 375.079885 -407.796031)
			(xy 375.080276 -407.78684) (xy 375.080276 -407.628852) (xy 375.080682 -407.618698) (xy 375.088489 -407.599949)
			(xy 375.10289 -407.585628) (xy 375.121682 -407.577926) (xy 375.131838 -407.577544) (xy 375.848118 -407.577544)
			(xy 375.858246 -407.578012) (xy 375.876969 -407.585746) (xy 375.891325 -407.600038) (xy 375.899143 -407.618726)
			(xy 375.89968 -407.628852) (xy 375.89968 -407.78684) (xy 375.900075 -407.796029) (xy 375.9066 -407.813213)
			(xy 375.91238 -407.820368) (xy 375.934159 -407.846027) (xy 375.972107 -407.901613) (xy 376.00314 -407.961336)
			(xy 376.026812 -408.024339) (xy 376.042785 -408.08972) (xy 376.05083 -408.156542) (xy 376.05083 -408.223846)
			(xy 376.042787 -408.290668) (xy 376.026816 -408.356049) (xy 376.003145 -408.419053) (xy 375.972113 -408.478777)
			(xy 375.934167 -408.534364) (xy 375.91238 -408.560016) (xy 375.906592 -408.567167) (xy 375.900073 -408.584353)
			(xy 375.89968 -408.593544) (xy 375.89968 -409.086812) (xy 375.900089 -409.095999) (xy 375.906604 -409.113183)
			(xy 375.91238 -409.12034) (xy 375.934131 -409.146022) (xy 375.97208 -409.201604) (xy 376.003114 -409.261324)
			(xy 376.026788 -409.324325) (xy 376.042763 -409.389703) (xy 376.050809 -409.456522) (xy 376.050813 -409.523824)
			(xy 376.042772 -409.590644) (xy 376.026804 -409.656024) (xy 376.003136 -409.719026) (xy 375.972108 -409.778749)
			(xy 375.934165 -409.834335) (xy 375.91238 -409.859988) (xy 375.906561 -409.867117) (xy 375.90006 -409.88432)
			(xy 375.89968 -409.893516) (xy 375.89968 -410.051504) (xy 375.899281 -410.061661) (xy 375.891481 -410.080417)
			(xy 375.877077 -410.094741) (xy 375.858277 -410.102437) (xy 375.848118 -410.102812) (xy 375.131838 -410.102812)
			(xy 375.12172 -410.102244) (xy 375.10301 -410.094538) (xy 375.088654 -410.080277) (xy 375.080824 -410.061618)
			(xy 375.080276 -410.051504) (xy 375.080276 -409.893516) (xy 375.079864 -409.884329) (xy 375.073352 -409.867144)
			(xy 375.067576 -409.859988) (xy 375.045751 -409.834366) (xy 375.007801 -409.778776) (xy 374.976768 -409.719048)
			(xy 374.953095 -409.65604) (xy 374.937124 -409.590654) (xy 374.929082 -409.523827) (xy 347.400682 -409.523827)
			(xy 347.372224 -409.578596) (xy 347.334276 -409.634184) (xy 347.312488 -409.659836) (xy 347.306692 -409.666982)
			(xy 347.300177 -409.684172) (xy 347.299788 -409.693364) (xy 347.299788 -410.186632) (xy 347.300185 -410.195821)
			(xy 347.306708 -410.213005) (xy 347.312488 -410.22016) (xy 347.334259 -410.245825) (xy 347.372207 -410.301411)
			(xy 347.403239 -410.361133) (xy 347.426912 -410.424135) (xy 347.442885 -410.489516) (xy 347.45093 -410.556336)
			(xy 347.450931 -410.62364) (xy 347.450924 -410.623701) (xy 377.128728 -410.623701) (xy 377.128729 -410.556275)
			(xy 377.136807 -410.489335) (xy 377.152845 -410.423845) (xy 377.176612 -410.360748) (xy 377.207766 -410.300951)
			(xy 377.245858 -410.245317) (xy 377.267724 -410.219652) (xy 377.273526 -410.212511) (xy 377.280037 -410.195317)
			(xy 377.280424 -410.186124) (xy 377.280424 -409.693872) (xy 377.280022 -409.684684) (xy 377.273502 -409.6675)
			(xy 377.267724 -409.660344) (xy 377.245871 -409.634669) (xy 377.20778 -409.579037) (xy 377.176628 -409.519242)
			(xy 377.152862 -409.456146) (xy 377.136825 -409.390658) (xy 377.128748 -409.323721) (xy 377.128747 -409.256297)
			(xy 377.136822 -409.18936) (xy 377.152857 -409.123871) (xy 377.17662 -409.060774) (xy 377.207771 -409.000979)
			(xy 377.24586 -408.945345) (xy 377.267724 -408.91968) (xy 377.273514 -408.912531) (xy 377.280032 -408.895343)
			(xy 377.280424 -408.886152) (xy 377.280424 -408.728672) (xy 377.280794 -408.718545) (xy 377.288555 -408.699836)
			(xy 377.302886 -408.685522) (xy 377.321604 -408.677782) (xy 377.331732 -408.677364) (xy 378.048012 -408.677364)
			(xy 378.058117 -408.677875) (xy 378.076789 -408.685609) (xy 378.091082 -408.699898) (xy 378.098822 -408.718567)
			(xy 378.09932 -408.728672) (xy 378.09932 -408.886152) (xy 378.099749 -408.895337) (xy 378.106249 -408.912522)
			(xy 378.11202 -408.91968) (xy 378.133895 -408.945336) (xy 378.171982 -409.000972) (xy 378.203131 -409.06077)
			(xy 378.226894 -409.123868) (xy 378.242928 -409.189358) (xy 378.251002 -409.256297) (xy 378.251001 -409.323721)
			(xy 378.242925 -409.39066) (xy 378.226888 -409.456149) (xy 378.203124 -409.519247) (xy 378.200707 -409.523886)
			(xy 379.328875 -409.523886) (xy 379.328878 -409.45646) (xy 379.336957 -409.38952) (xy 379.352995 -409.324029)
			(xy 379.376762 -409.260931) (xy 379.407916 -409.201133) (xy 379.446007 -409.145498) (xy 379.467872 -409.119832)
			(xy 379.473689 -409.112701) (xy 379.480189 -409.095499) (xy 379.480572 -409.086304) (xy 379.480572 -408.594052)
			(xy 379.480143 -408.584867) (xy 379.473643 -408.567682) (xy 379.467872 -408.560524) (xy 379.446001 -408.534865)
			(xy 379.407915 -408.479229) (xy 379.376766 -408.419431) (xy 379.353003 -408.356334) (xy 379.336969 -408.290844)
			(xy 379.328894 -408.223906) (xy 379.328895 -408.156482) (xy 379.336971 -408.089544) (xy 379.353007 -408.024055)
			(xy 379.376771 -407.960958) (xy 379.407921 -407.901161) (xy 379.446009 -407.845526) (xy 379.467872 -407.81986)
			(xy 379.473677 -407.812721) (xy 379.480185 -407.795525) (xy 379.480572 -407.786332) (xy 379.480572 -407.628852)
			(xy 379.481045 -407.618744) (xy 379.488793 -407.60007) (xy 379.503093 -407.585778) (xy 379.521771 -407.57804)
			(xy 379.53188 -407.577544) (xy 380.24816 -407.577544) (xy 380.258259 -407.578117) (xy 380.276926 -407.585831)
			(xy 380.29122 -407.6001) (xy 380.298966 -407.618754) (xy 380.299468 -407.628852) (xy 380.299468 -407.786332)
			(xy 380.29987 -407.79552) (xy 380.30639 -407.812704) (xy 380.312168 -407.81986) (xy 380.334025 -407.845531)
			(xy 380.372116 -407.901164) (xy 380.403269 -407.960959) (xy 380.427035 -408.024055) (xy 380.443072 -408.089544)
			(xy 380.451149 -408.156482) (xy 380.45115 -408.223906) (xy 380.443074 -408.290844) (xy 380.427039 -408.356333)
			(xy 380.403274 -408.41943) (xy 380.372122 -408.479226) (xy 380.334033 -408.534859) (xy 380.312168 -408.560524)
			(xy 380.306375 -408.567671) (xy 380.299859 -408.58486) (xy 380.299468 -408.594052) (xy 380.299468 -409.086304)
			(xy 380.299883 -409.09549) (xy 380.306394 -409.112675) (xy 380.312168 -409.119832) (xy 380.333998 -409.145526)
			(xy 380.37209 -409.201156) (xy 380.403244 -409.260947) (xy 380.427011 -409.324041) (xy 380.44305 -409.389527)
			(xy 380.451129 -409.456462) (xy 380.451133 -409.523884) (xy 380.44306 -409.59082) (xy 380.427027 -409.656308)
			(xy 380.403266 -409.719403) (xy 380.372117 -409.779198) (xy 380.334031 -409.834831) (xy 380.312168 -409.860496)
			(xy 380.306386 -409.867652) (xy 380.299864 -409.884834) (xy 380.299468 -409.894024) (xy 380.299468 -410.051504)
			(xy 380.299086 -410.061631) (xy 380.291331 -410.08034) (xy 380.277003 -410.094656) (xy 380.258287 -410.102395)
			(xy 380.24816 -410.102812) (xy 379.53188 -410.102812) (xy 379.521771 -410.102332) (xy 379.503095 -410.09459)
			(xy 379.488801 -410.080292) (xy 379.481065 -410.061613) (xy 379.480572 -410.051504) (xy 379.480572 -409.894024)
			(xy 379.480157 -409.884837) (xy 379.473647 -409.867652) (xy 379.467872 -409.860496) (xy 379.445974 -409.834859)
			(xy 379.407888 -409.77922) (xy 379.37674 -409.71942) (xy 379.352979 -409.656319) (xy 379.336947 -409.590827)
			(xy 379.328875 -409.523886) (xy 378.200707 -409.523886) (xy 378.171973 -409.579043) (xy 378.133884 -409.634678)
			(xy 378.11202 -409.660344) (xy 378.106225 -409.66749) (xy 378.099709 -409.68468) (xy 378.09932 -409.693872)
			(xy 378.09932 -410.186124) (xy 378.099714 -410.195313) (xy 378.106239 -410.212497) (xy 378.11202 -410.219652)
			(xy 378.133868 -410.245331) (xy 378.171955 -410.300964) (xy 378.203106 -410.360758) (xy 378.22687 -410.423853)
			(xy 378.242906 -410.48934) (xy 378.250983 -410.556277) (xy 378.250984 -410.623641) (xy 381.529047 -410.623641)
			(xy 381.529049 -410.556335) (xy 381.537094 -410.489512) (xy 381.553068 -410.424129) (xy 381.576742 -410.361124)
			(xy 381.607775 -410.3014) (xy 381.645724 -410.245812) (xy 381.667512 -410.22016) (xy 381.673309 -410.213015)
			(xy 381.679823 -410.195824) (xy 381.680212 -410.186632) (xy 381.680212 -409.693364) (xy 381.679817 -409.684175)
			(xy 381.673292 -409.666991) (xy 381.667512 -409.659836) (xy 381.645737 -409.634174) (xy 381.607789 -409.578588)
			(xy 381.576757 -409.518866) (xy 381.553085 -409.455863) (xy 381.537112 -409.390482) (xy 381.529067 -409.323661)
			(xy 381.529066 -409.256357) (xy 381.537109 -409.189536) (xy 381.553079 -409.124155) (xy 381.57675 -409.061151)
			(xy 381.60778 -409.001427) (xy 381.645726 -408.94584) (xy 381.667512 -408.920188) (xy 381.673298 -408.913035)
			(xy 381.679818 -408.89585) (xy 381.680212 -408.88666) (xy 381.680212 -408.728672) (xy 381.680662 -408.71856)
			(xy 381.688411 -408.699879) (xy 381.702719 -408.685585) (xy 381.721408 -408.677853) (xy 381.73152 -408.677364)
			(xy 382.448054 -408.677364) (xy 382.458181 -408.677865) (xy 382.476905 -408.685582) (xy 382.491264 -408.699865)
			(xy 382.499081 -408.718548) (xy 382.499616 -408.728672) (xy 382.499616 -408.88666) (xy 382.500042 -408.895846)
			(xy 382.506544 -408.91303) (xy 382.512316 -408.920188) (xy 382.534117 -408.94583) (xy 382.572068 -409.001417)
			(xy 382.603103 -409.061141) (xy 382.626778 -409.124147) (xy 382.642751 -409.189531) (xy 382.650795 -409.256356)
			(xy 382.650794 -409.323662) (xy 382.642748 -409.390487) (xy 382.626772 -409.45587) (xy 382.603096 -409.518875)
			(xy 382.600523 -409.523827) (xy 383.72917 -409.523827) (xy 383.729173 -409.456519) (xy 383.737221 -409.389693)
			(xy 383.753198 -409.324309) (xy 383.776876 -409.261303) (xy 383.807915 -409.201578) (xy 383.845869 -409.145992)
			(xy 383.86766 -409.12034) (xy 383.873472 -409.113206) (xy 383.879976 -409.096007) (xy 383.88036 -409.086812)
			(xy 383.88036 -408.593544) (xy 383.879915 -408.584361) (xy 383.873424 -408.567177) (xy 383.86766 -408.560016)
			(xy 383.845864 -408.53437) (xy 383.807914 -408.478784) (xy 383.77688 -408.419059) (xy 383.753207 -408.356054)
			(xy 383.737234 -408.290671) (xy 383.72919 -408.223847) (xy 383.729191 -408.156541) (xy 383.737236 -408.089717)
			(xy 383.75321 -408.024335) (xy 383.776885 -407.96133) (xy 383.80792 -407.901606) (xy 383.845871 -407.84602)
			(xy 383.86766 -407.820368) (xy 383.87346 -407.813226) (xy 383.879971 -407.796033) (xy 383.88036 -407.78684)
			(xy 383.88036 -407.628852) (xy 383.880845 -407.618745) (xy 383.888591 -407.600074) (xy 383.902887 -407.585782)
			(xy 383.921561 -407.578042) (xy 383.931668 -407.577544) (xy 384.648202 -407.577544) (xy 384.658329 -407.578025)
			(xy 384.677051 -407.585754) (xy 384.691408 -407.600042) (xy 384.699226 -407.618727) (xy 384.699764 -407.628852)
			(xy 384.699764 -407.78684) (xy 384.700163 -407.796028) (xy 384.706685 -407.813212) (xy 384.712464 -407.820368)
			(xy 384.734244 -407.846027) (xy 384.772193 -407.901612) (xy 384.803226 -407.961335) (xy 384.826899 -408.024339)
			(xy 384.842873 -408.08972) (xy 384.850918 -408.156542) (xy 384.850918 -408.223846) (xy 384.842875 -408.290668)
			(xy 384.826903 -408.35605) (xy 384.803231 -408.419054) (xy 384.772199 -408.478778) (xy 384.734251 -408.534364)
			(xy 384.712464 -408.560016) (xy 384.706674 -408.567165) (xy 384.700156 -408.584353) (xy 384.699764 -408.593544)
			(xy 384.699764 -409.086812) (xy 384.700176 -409.095999) (xy 384.706689 -409.113183) (xy 384.712464 -409.12034)
			(xy 384.734216 -409.146021) (xy 384.772166 -409.201604) (xy 384.8032 -409.261323) (xy 384.826875 -409.324324)
			(xy 384.84285 -409.389703) (xy 384.850897 -409.456522) (xy 384.850901 -409.523824) (xy 384.84286 -409.590644)
			(xy 384.826891 -409.656024) (xy 384.803222 -409.719027) (xy 384.772194 -409.77875) (xy 384.734249 -409.834336)
			(xy 384.712464 -409.859988) (xy 384.706643 -409.867116) (xy 384.700144 -409.88432) (xy 384.699764 -409.893516)
			(xy 384.699764 -410.051504) (xy 384.699386 -410.061631) (xy 384.69163 -410.080342) (xy 384.677301 -410.094657)
			(xy 384.658584 -410.102396) (xy 384.648456 -410.102812) (xy 383.931922 -410.102812) (xy 383.921803 -410.102257)
			(xy 383.903092 -410.094546) (xy 383.888737 -410.080281) (xy 383.880908 -410.06162) (xy 383.88036 -410.051504)
			(xy 383.88036 -409.893516) (xy 383.879929 -409.884331) (xy 383.873428 -409.867147) (xy 383.86766 -409.859988)
			(xy 383.845836 -409.834365) (xy 383.807887 -409.778775) (xy 383.776854 -409.719048) (xy 383.753182 -409.656039)
			(xy 383.737211 -409.590653) (xy 383.72917 -409.523827) (xy 382.600523 -409.523827) (xy 382.572059 -409.578599)
			(xy 382.534106 -409.634184) (xy 382.512316 -409.659836) (xy 382.506523 -409.666984) (xy 382.500006 -409.684172)
			(xy 382.499616 -409.693364) (xy 382.499616 -410.186632) (xy 382.500007 -410.195821) (xy 382.506534 -410.213006)
			(xy 382.512316 -410.22016) (xy 382.534089 -410.245824) (xy 382.572042 -410.301408) (xy 382.603078 -410.36113)
			(xy 382.626754 -410.424133) (xy 382.642729 -410.489514) (xy 382.650775 -410.556336) (xy 382.650777 -410.62364)
			(xy 382.65077 -410.623701) (xy 385.928816 -410.623701) (xy 385.928817 -410.556275) (xy 385.936895 -410.489336)
			(xy 385.952932 -410.423846) (xy 385.976699 -410.360748) (xy 386.007852 -410.300952) (xy 386.045943 -410.245317)
			(xy 386.067808 -410.219652) (xy 386.073608 -410.21251) (xy 386.080121 -410.195317) (xy 386.080508 -410.186124)
			(xy 386.080508 -409.693872) (xy 386.08011 -409.684684) (xy 386.073588 -409.667499) (xy 386.067808 -409.660344)
			(xy 386.045956 -409.634669) (xy 386.007866 -409.579036) (xy 385.976714 -409.519241) (xy 385.952949 -409.456146)
			(xy 385.936913 -409.390658) (xy 385.928836 -409.32372) (xy 385.928834 -409.256298) (xy 385.936909 -409.18936)
			(xy 385.952944 -409.123871) (xy 385.976707 -409.060775) (xy 386.007857 -409.000979) (xy 386.045944 -408.945345)
			(xy 386.067808 -408.91968) (xy 386.073596 -408.912529) (xy 386.080116 -408.895343) (xy 386.080508 -408.886152)
			(xy 386.080508 -408.728672) (xy 386.080962 -408.71856) (xy 386.088711 -408.69988) (xy 386.103017 -408.685586)
			(xy 386.121704 -408.677854) (xy 386.131816 -408.677364) (xy 386.848096 -408.677364) (xy 386.8582 -408.677888)
			(xy 386.876871 -408.685617) (xy 386.891165 -408.699902) (xy 386.898906 -408.718568) (xy 386.899404 -408.728672)
			(xy 386.899404 -408.886152) (xy 386.899836 -408.895337) (xy 386.906334 -408.912522) (xy 386.912104 -408.91968)
			(xy 386.93398 -408.945336) (xy 386.972068 -409.000972) (xy 387.003218 -409.060769) (xy 387.026981 -409.123867)
			(xy 387.043016 -409.189357) (xy 387.05109 -409.256297) (xy 387.051089 -409.323721) (xy 387.043012 -409.39066)
			(xy 387.026976 -409.45615) (xy 387.00321 -409.519247) (xy 387.000824 -409.523827) (xy 388.128961 -409.523827)
			(xy 388.128964 -409.456519) (xy 388.137012 -409.389694) (xy 388.152989 -409.324309) (xy 388.176666 -409.261303)
			(xy 388.207704 -409.201579) (xy 388.245658 -409.145992) (xy 388.267448 -409.12034) (xy 388.273259 -409.113205)
			(xy 388.279764 -409.096006) (xy 388.280148 -409.086812) (xy 388.280148 -408.593544) (xy 388.279706 -408.58436)
			(xy 388.273213 -408.567176) (xy 388.267448 -408.560016) (xy 388.245652 -408.534371) (xy 388.207703 -408.478783)
			(xy 388.176669 -408.419059) (xy 388.152997 -408.356054) (xy 388.137024 -408.29067) (xy 388.12898 -408.223847)
			(xy 388.128981 -408.156541) (xy 388.137026 -408.089718) (xy 388.153 -408.024335) (xy 388.176674 -407.96133)
			(xy 388.207709 -407.901606) (xy 388.245659 -407.84602) (xy 388.267448 -407.820368) (xy 388.273247 -407.813224)
			(xy 388.279759 -407.796032) (xy 388.280148 -407.78684) (xy 388.280148 -407.628852) (xy 388.280645 -407.618747)
			(xy 388.288388 -407.600077) (xy 388.302681 -407.585786) (xy 388.321351 -407.578044) (xy 388.331456 -407.577544)
			(xy 389.04799 -407.577544) (xy 389.058117 -407.578035) (xy 389.076838 -407.58576) (xy 389.091195 -407.600045)
			(xy 389.099014 -407.618728) (xy 389.099552 -407.628852) (xy 389.099552 -407.78684) (xy 389.099954 -407.796028)
			(xy 389.106475 -407.813211) (xy 389.112252 -407.820368) (xy 389.134032 -407.846027) (xy 389.171982 -407.901612)
			(xy 389.203016 -407.961335) (xy 389.226689 -408.024338) (xy 389.242663 -408.08972) (xy 389.250708 -408.156542)
			(xy 389.250709 -408.223846) (xy 389.242665 -408.290668) (xy 389.226693 -408.35605) (xy 389.203021 -408.419054)
			(xy 389.171988 -408.478778) (xy 389.134039 -408.534364) (xy 389.112252 -408.560016) (xy 389.10646 -408.567164)
			(xy 389.099944 -408.584353) (xy 389.099552 -408.593544) (xy 389.099552 -409.086812) (xy 389.099967 -409.095998)
			(xy 389.106479 -409.113182) (xy 389.112252 -409.12034) (xy 389.134004 -409.146021) (xy 389.171955 -409.201603)
			(xy 389.20299 -409.261323) (xy 389.226665 -409.324323) (xy 389.242641 -409.389702) (xy 389.250688 -409.456522)
			(xy 389.250692 -409.523824) (xy 389.242651 -409.590644) (xy 389.226681 -409.656025) (xy 389.203012 -409.719028)
			(xy 389.171983 -409.77875) (xy 389.134038 -409.834336) (xy 389.112252 -409.859988) (xy 389.10643 -409.867115)
			(xy 389.099932 -409.88432) (xy 389.099552 -409.893516) (xy 389.099552 -410.051504) (xy 389.099019 -410.061607)
			(xy 389.09129 -410.080275) (xy 389.077008 -410.094568) (xy 389.058346 -410.102311) (xy 389.048244 -410.102812)
			(xy 388.33171 -410.102812) (xy 388.32159 -410.102267) (xy 388.302879 -410.094552) (xy 388.288524 -410.080284)
			(xy 388.280696 -410.061621) (xy 388.280148 -410.051504) (xy 388.280148 -409.893516) (xy 388.27972 -409.884331)
			(xy 388.273217 -409.867147) (xy 388.267448 -409.859988) (xy 388.245624 -409.834365) (xy 388.207676 -409.778775)
			(xy 388.176644 -409.719047) (xy 388.152973 -409.656039) (xy 388.137002 -409.590653) (xy 388.128961 -409.523827)
			(xy 387.000824 -409.523827) (xy 386.972058 -409.579044) (xy 386.933969 -409.634679) (xy 386.912104 -409.660344)
			(xy 386.906307 -409.667489) (xy 386.899792 -409.68468) (xy 386.899404 -409.693872) (xy 386.899404 -410.186124)
			(xy 386.899801 -410.195313) (xy 386.906324 -410.212497) (xy 386.912104 -410.219652) (xy 386.933952 -410.24533)
			(xy 386.972041 -410.300963) (xy 387.003192 -410.360757) (xy 387.026957 -410.423853) (xy 387.042994 -410.48934)
			(xy 387.051071 -410.556277) (xy 387.051072 -410.623641) (xy 390.329135 -410.623641) (xy 390.329137 -410.556335)
			(xy 390.337182 -410.489512) (xy 390.353155 -410.42413) (xy 390.376828 -410.361125) (xy 390.407861 -410.3014)
			(xy 390.445809 -410.245813) (xy 390.467596 -410.22016) (xy 390.473392 -410.213014) (xy 390.479907 -410.195824)
			(xy 390.480296 -410.186632) (xy 390.480296 -409.693364) (xy 390.479904 -409.684175) (xy 390.473378 -409.666991)
			(xy 390.467596 -409.659836) (xy 390.445821 -409.634174) (xy 390.407875 -409.578588) (xy 390.376844 -409.518865)
			(xy 390.353172 -409.455862) (xy 390.3372 -409.390481) (xy 390.329155 -409.323661) (xy 390.329154 -409.256357)
			(xy 390.337196 -409.189536) (xy 390.353167 -409.124155) (xy 390.376836 -409.061151) (xy 390.407866 -409.001428)
			(xy 390.44581 -408.945841) (xy 390.467596 -408.920188) (xy 390.47338 -408.913034) (xy 390.479902 -408.89585)
			(xy 390.480296 -408.88666) (xy 390.480296 -408.728672) (xy 390.480762 -408.718562) (xy 390.488508 -408.699884)
			(xy 390.502811 -408.68559) (xy 390.521494 -408.677856) (xy 390.531604 -408.677364) (xy 391.248138 -408.677364)
			(xy 391.25827 -408.677796) (xy 391.276997 -408.685541) (xy 391.291352 -408.699844) (xy 391.299166 -408.718542)
			(xy 391.2997 -408.728672) (xy 391.2997 -408.88666) (xy 391.300129 -408.895845) (xy 391.30663 -408.91303)
			(xy 391.3124 -408.920188) (xy 391.334198 -408.945831) (xy 391.372144 -409.00142) (xy 391.403175 -409.061145)
			(xy 391.426845 -409.12415) (xy 391.442816 -409.189533) (xy 391.450859 -409.256356) (xy 391.450858 -409.323662)
			(xy 391.442813 -409.390484) (xy 391.42684 -409.455867) (xy 391.403167 -409.518872) (xy 391.372135 -409.578596)
			(xy 391.334187 -409.634183) (xy 391.3124 -409.659836) (xy 391.306606 -409.666983) (xy 391.30009 -409.684172)
			(xy 391.2997 -409.693364) (xy 391.2997 -410.186632) (xy 391.300095 -410.195821) (xy 391.306619 -410.213005)
			(xy 391.3124 -410.22016) (xy 391.334171 -410.245826) (xy 391.372118 -410.301411) (xy 391.403149 -410.361133)
			(xy 391.426821 -410.424136) (xy 391.442794 -410.489516) (xy 391.450839 -410.556336) (xy 391.450841 -410.623639)
			(xy 391.442799 -410.69046) (xy 391.426828 -410.755841) (xy 391.403159 -410.818845) (xy 391.37213 -410.878568)
			(xy 391.334186 -410.934155) (xy 391.3124 -410.959808) (xy 391.306618 -410.966963) (xy 391.300094 -410.984146)
			(xy 391.2997 -410.993336) (xy 391.2997 -411.151324) (xy 391.299235 -411.161434) (xy 391.291489 -411.180113)
			(xy 391.277186 -411.194407) (xy 391.258503 -411.202141) (xy 391.248392 -411.202632) (xy 390.531858 -411.202632)
			(xy 390.521725 -411.202207) (xy 390.502998 -411.19446) (xy 390.488642 -411.180155) (xy 390.480829 -411.161455)
			(xy 390.480296 -411.151324) (xy 390.480296 -410.993336) (xy 390.479869 -410.984151) (xy 390.473367 -410.966966)
			(xy 390.467596 -410.959808) (xy 390.445794 -410.934168) (xy 390.407848 -410.878579) (xy 390.376818 -410.818853)
			(xy 390.353148 -410.755847) (xy 390.337178 -410.690464) (xy 390.329135 -410.623641) (xy 387.051072 -410.623641)
			(xy 387.051072 -410.623699) (xy 387.042998 -410.690636) (xy 387.026964 -410.756124) (xy 387.003202 -410.819221)
			(xy 386.972053 -410.879016) (xy 386.933967 -410.934651) (xy 386.912104 -410.960316) (xy 386.906319 -410.967469)
			(xy 386.899797 -410.984654) (xy 386.899404 -410.993844) (xy 386.899404 -411.151324) (xy 386.898935 -411.161434)
			(xy 386.89119 -411.180112) (xy 386.876888 -411.194406) (xy 386.858206 -411.20214) (xy 386.848096 -411.202632)
			(xy 386.131816 -411.202632) (xy 386.121712 -411.202103) (xy 386.10304 -411.194376) (xy 386.088746 -411.180093)
			(xy 386.081005 -411.161427) (xy 386.080508 -411.151324) (xy 386.080508 -410.993844) (xy 386.080075 -410.984659)
			(xy 386.073577 -410.967475) (xy 386.067808 -410.960316) (xy 386.045928 -410.934664) (xy 386.007839 -410.879028)
			(xy 385.976689 -410.81923) (xy 385.952925 -410.756131) (xy 385.936891 -410.69064) (xy 385.928816 -410.623701)
			(xy 382.65077 -410.623701) (xy 382.642733 -410.690463) (xy 382.626761 -410.755844) (xy 382.603088 -410.818848)
			(xy 382.572054 -410.878571) (xy 382.534104 -410.934156) (xy 382.512316 -410.959808) (xy 382.506535 -410.966965)
			(xy 382.500011 -410.984146) (xy 382.499616 -410.993336) (xy 382.499616 -411.151324) (xy 382.499135 -411.161432)
			(xy 382.491392 -411.180108) (xy 382.477095 -411.194401) (xy 382.458416 -411.202138) (xy 382.448308 -411.202632)
			(xy 381.731774 -411.202632) (xy 381.721642 -411.202194) (xy 381.702915 -411.194453) (xy 381.688559 -411.180151)
			(xy 381.680745 -411.161454) (xy 381.680212 -411.151324) (xy 381.680212 -410.993336) (xy 381.679782 -410.984151)
			(xy 381.673282 -410.966967) (xy 381.667512 -410.959808) (xy 381.645709 -410.934168) (xy 381.607763 -410.87858)
			(xy 381.576732 -410.818854) (xy 381.553061 -410.755848) (xy 381.53709 -410.690464) (xy 381.529047 -410.623641)
			(xy 378.250984 -410.623641) (xy 378.250984 -410.623699) (xy 378.24291 -410.690636) (xy 378.226877 -410.756124)
			(xy 378.203116 -410.81922) (xy 378.171968 -410.879016) (xy 378.133882 -410.93465) (xy 378.11202 -410.960316)
			(xy 378.106236 -410.967471) (xy 378.099713 -410.984654) (xy 378.09932 -410.993844) (xy 378.09932 -411.151324)
			(xy 378.098835 -411.161432) (xy 378.091093 -411.180107) (xy 378.076797 -411.1944) (xy 378.05812 -411.202138)
			(xy 378.048012 -411.202632) (xy 377.331732 -411.202632) (xy 377.321615 -411.202159) (xy 377.302919 -411.194427)
			(xy 377.288604 -411.180128) (xy 377.280852 -411.16144) (xy 377.280424 -411.151324) (xy 377.280424 -410.993844)
			(xy 377.279987 -410.98466) (xy 377.273491 -410.967475) (xy 377.267724 -410.960316) (xy 377.245843 -410.934664)
			(xy 377.207754 -410.879028) (xy 377.176602 -410.81923) (xy 377.152838 -410.756132) (xy 377.136803 -410.690641)
			(xy 377.128728 -410.623701) (xy 347.450924 -410.623701) (xy 347.442889 -410.690461) (xy 347.426919 -410.755842)
			(xy 347.403249 -410.818845) (xy 347.372219 -410.878569) (xy 347.334274 -410.934156) (xy 347.312488 -410.959808)
			(xy 347.306704 -410.966962) (xy 347.300182 -410.984146) (xy 347.299788 -410.993336) (xy 347.299788 -411.151324)
			(xy 347.299398 -411.161481) (xy 347.291592 -411.180236) (xy 347.277186 -411.194559) (xy 347.258386 -411.202256)
			(xy 347.248226 -411.202632) (xy 346.531946 -411.202632) (xy 346.521819 -411.202135) (xy 346.503093 -411.194417)
			(xy 346.488735 -411.180133) (xy 346.480919 -411.161449) (xy 346.480384 -411.151324) (xy 346.480384 -410.993336)
			(xy 346.47996 -410.98415) (xy 346.473456 -410.966965) (xy 346.467684 -410.959808) (xy 346.445879 -410.934169)
			(xy 346.407928 -410.878582) (xy 346.376893 -410.818857) (xy 346.353219 -410.755851) (xy 346.337246 -410.690466)
			(xy 346.329202 -410.623642) (xy 343.051163 -410.623642) (xy 343.051163 -410.623699) (xy 343.043089 -410.690637)
			(xy 343.027055 -410.756125) (xy 343.003292 -410.819221) (xy 342.972143 -410.879017) (xy 342.934055 -410.934651)
			(xy 342.912192 -410.960316) (xy 342.906405 -410.967468) (xy 342.899885 -410.984653) (xy 342.899492 -410.993844)
			(xy 342.899492 -411.151324) (xy 342.899034 -411.161435) (xy 342.891287 -411.180116) (xy 342.876982 -411.19441)
			(xy 342.858296 -411.202142) (xy 342.848184 -411.202632) (xy 342.131904 -411.202632) (xy 342.121799 -411.202112)
			(xy 342.103128 -411.194382) (xy 342.088834 -411.180096) (xy 342.081093 -411.161428) (xy 342.080596 -411.151324)
			(xy 342.080596 -410.993844) (xy 342.080166 -410.984659) (xy 342.073666 -410.967474) (xy 342.067896 -410.960316)
			(xy 342.046016 -410.934664) (xy 342.007928 -410.879027) (xy 341.976779 -410.819229) (xy 341.953016 -410.756131)
			(xy 341.936981 -410.69064) (xy 341.928907 -410.6237) (xy 338.650837 -410.6237) (xy 338.642802 -410.69046)
			(xy 338.626832 -410.755841) (xy 338.603163 -410.818845) (xy 338.572134 -410.878568) (xy 338.534189 -410.934155)
			(xy 338.512404 -410.959808) (xy 338.506622 -410.966964) (xy 338.500098 -410.984146) (xy 338.499704 -410.993336)
			(xy 338.499704 -411.151324) (xy 338.499298 -411.161479) (xy 338.491495 -411.180231) (xy 338.477094 -411.194554)
			(xy 338.458299 -411.202253) (xy 338.448142 -411.202632) (xy 337.731862 -411.202632) (xy 337.721729 -411.202204)
			(xy 337.703002 -411.194458) (xy 337.688646 -411.180154) (xy 337.680833 -411.161455) (xy 337.6803 -411.151324)
			(xy 337.6803 -410.993336) (xy 337.679873 -410.984151) (xy 337.673371 -410.966966) (xy 337.6676 -410.959808)
			(xy 337.645798 -410.934168) (xy 337.607852 -410.878579) (xy 337.576822 -410.818853) (xy 337.553151 -410.755847)
			(xy 337.537181 -410.690464) (xy 337.529138 -410.623641) (xy 334.251075 -410.623641) (xy 334.251075 -410.623699)
			(xy 334.243001 -410.690636) (xy 334.226967 -410.756124) (xy 334.203205 -410.81922) (xy 334.172057 -410.879016)
			(xy 334.133971 -410.934651) (xy 334.112108 -410.960316) (xy 334.106323 -410.96747) (xy 334.099801 -410.984654)
			(xy 334.099408 -410.993844) (xy 334.099408 -411.151324) (xy 334.098935 -411.161433) (xy 334.091191 -411.180111)
			(xy 334.07689 -411.194404) (xy 334.05821 -411.20214) (xy 334.0481 -411.202632) (xy 333.33182 -411.202632)
			(xy 333.321716 -411.202099) (xy 333.303045 -411.194374) (xy 333.28875 -411.180092) (xy 333.281009 -411.161427)
			(xy 333.280512 -411.151324) (xy 333.280512 -410.993844) (xy 333.280078 -410.984659) (xy 333.273581 -410.967475)
			(xy 333.267812 -410.960316) (xy 333.245932 -410.934664) (xy 333.207843 -410.879028) (xy 333.176692 -410.81923)
			(xy 333.152928 -410.756131) (xy 333.136894 -410.69064) (xy 333.128819 -410.623701) (xy 326.525636 -410.623701)
			(xy 326.525636 -417.379404) (xy 326.525636 -417.533836) (xy 401.074128 -417.533836) (xy 401.074128 -417.366196)
			(xy 401.074128 -394.27912) (xy 414.451292 -394.27912) (xy 414.525968 -394.353542) (xy 414.525968 -397.823826)
			(xy 418.92899 -397.823826) (xy 418.928993 -397.756517) (xy 418.937042 -397.689691) (xy 418.95302 -397.624306)
			(xy 418.9767 -397.5613) (xy 419.00774 -397.501575) (xy 419.045697 -397.44599) (xy 419.067488 -397.420338)
			(xy 419.073292 -397.413198) (xy 419.079803 -397.396004) (xy 419.080188 -397.38681) (xy 419.080188 -396.893542)
			(xy 419.07976 -396.884357) (xy 419.073259 -396.867172) (xy 419.067488 -396.860014) (xy 419.045689 -396.834371)
			(xy 419.007737 -396.778784) (xy 418.976702 -396.71906) (xy 418.953027 -396.656054) (xy 418.937054 -396.59067)
			(xy 418.92901 -396.523846) (xy 418.92901 -396.456539) (xy 418.937056 -396.389715) (xy 418.953032 -396.324332)
			(xy 418.976708 -396.261327) (xy 419.007745 -396.201603) (xy 419.045698 -396.146018) (xy 419.067488 -396.120366)
			(xy 419.07328 -396.113218) (xy 419.079798 -396.09603) (xy 419.080188 -396.086838) (xy 419.080188 -395.92885)
			(xy 419.080606 -395.918675) (xy 419.088384 -395.899872) (xy 419.102772 -395.885484) (xy 419.121575 -395.877706)
			(xy 419.13175 -395.877288) (xy 419.84803 -395.877288) (xy 419.85821 -395.87764) (xy 419.877015 -395.885445)
			(xy 419.8914 -395.899852) (xy 419.899175 -395.91867) (xy 419.899592 -395.92885) (xy 419.899592 -396.086838)
			(xy 419.899986 -396.096027) (xy 419.906511 -396.113211) (xy 419.912292 -396.120366) (xy 419.934069 -396.146027)
			(xy 419.972016 -396.201613) (xy 420.003048 -396.261335) (xy 420.02672 -396.324339) (xy 420.042693 -396.389719)
			(xy 420.050737 -396.456541) (xy 420.050738 -396.523844) (xy 420.042695 -396.590666) (xy 420.026725 -396.656047)
			(xy 420.003054 -396.719051) (xy 419.972024 -396.778774) (xy 419.934078 -396.834361) (xy 419.912292 -396.860014)
			(xy 419.906506 -396.867167) (xy 419.899985 -396.884351) (xy 419.899592 -396.893542) (xy 419.899592 -397.38681)
			(xy 419.899999 -397.395998) (xy 419.906515 -397.413182) (xy 419.912292 -397.420338) (xy 419.934041 -397.446021)
			(xy 419.971989 -397.501604) (xy 420.00041 -397.556296) (xy 421.128654 -397.556296) (xy 421.13673 -397.489357)
			(xy 421.152765 -397.423869) (xy 421.17653 -397.360772) (xy 421.207681 -397.300976) (xy 421.245771 -397.245343)
			(xy 421.267636 -397.219678) (xy 421.273429 -397.21253) (xy 421.279945 -397.195342) (xy 421.280336 -397.18615)
			(xy 421.280336 -397.028924) (xy 421.280736 -397.018799) (xy 421.288483 -397.000089) (xy 421.302805 -396.985772)
			(xy 421.321518 -396.978032) (xy 421.331644 -396.977616) (xy 422.047924 -396.977616) (xy 422.058036 -396.978066)
			(xy 422.076718 -396.985814) (xy 422.091013 -397.000122) (xy 422.098744 -397.018811) (xy 422.099232 -397.028924)
			(xy 422.099232 -397.18615) (xy 422.099681 -397.195333) (xy 422.106169 -397.212517) (xy 422.111932 -397.219678)
			(xy 422.133805 -397.245336) (xy 422.171891 -397.300972) (xy 422.203039 -397.36077) (xy 422.226802 -397.423867)
			(xy 422.242835 -397.489357) (xy 422.25091 -397.556296) (xy 422.250909 -397.623719) (xy 422.242833 -397.690658)
			(xy 422.226797 -397.756147) (xy 422.203033 -397.819244) (xy 422.200615 -397.823885) (xy 423.328782 -397.823885)
			(xy 423.328786 -397.756458) (xy 423.336865 -397.689518) (xy 423.352904 -397.624027) (xy 423.376672 -397.560928)
			(xy 423.407826 -397.501131) (xy 423.445918 -397.445496) (xy 423.467784 -397.41983) (xy 423.473591 -397.412692)
			(xy 423.4801 -397.395496) (xy 423.480484 -397.386302) (xy 423.480484 -396.89405) (xy 423.480054 -396.884865)
			(xy 423.473554 -396.86768) (xy 423.467784 -396.860522) (xy 423.445911 -396.834865) (xy 423.407823 -396.779229)
			(xy 423.376674 -396.719431) (xy 423.352911 -396.656333) (xy 423.336877 -396.590843) (xy 423.328802 -396.523905)
			(xy 423.328803 -396.45648) (xy 423.33688 -396.389542) (xy 423.352916 -396.324052) (xy 423.37668 -396.260955)
			(xy 423.407831 -396.201159) (xy 423.44592 -396.145524) (xy 423.467784 -396.119858) (xy 423.473579 -396.112712)
			(xy 423.480095 -396.095522) (xy 423.480484 -396.08633) (xy 423.480484 -395.92885) (xy 423.480969 -395.918721)
			(xy 423.488688 -395.899993) (xy 423.502976 -395.885633) (xy 423.521666 -395.87782) (xy 423.531792 -395.877288)
			(xy 424.248072 -395.877288) (xy 424.258223 -395.877744) (xy 424.276972 -395.885528) (xy 424.291296 -395.899914)
			(xy 424.298999 -395.918697) (xy 424.29938 -395.92885) (xy 424.29938 -396.08633) (xy 424.29978 -396.095518)
			(xy 424.306301 -396.112702) (xy 424.31208 -396.119858) (xy 424.333935 -396.145531) (xy 424.372025 -396.201164)
			(xy 424.403177 -396.260959) (xy 424.426943 -396.324055) (xy 424.44298 -396.389543) (xy 424.451057 -396.456481)
			(xy 424.451058 -396.523904) (xy 424.442983 -396.590842) (xy 424.426948 -396.656331) (xy 424.403184 -396.719427)
			(xy 424.372033 -396.779223) (xy 424.333944 -396.834857) (xy 424.31208 -396.860522) (xy 424.306289 -396.867671)
			(xy 424.299772 -396.884859) (xy 424.29938 -396.89405) (xy 424.29938 -397.386302) (xy 424.299793 -397.395489)
			(xy 424.306305 -397.412673) (xy 424.31208 -397.41983) (xy 424.333907 -397.445526) (xy 424.371998 -397.501155)
			(xy 424.40076 -397.556356) (xy 425.528974 -397.556356) (xy 425.537017 -397.489534) (xy 425.552988 -397.424152)
			(xy 425.576659 -397.361148) (xy 425.607691 -397.301425) (xy 425.645637 -397.245838) (xy 425.667424 -397.220186)
			(xy 425.673212 -397.213035) (xy 425.679731 -397.195849) (xy 425.680124 -397.186658) (xy 425.680124 -397.028924)
			(xy 425.680542 -397.018768) (xy 425.688334 -397.000012) (xy 425.702732 -396.985687) (xy 425.721528 -396.97799)
			(xy 425.731686 -396.977616) (xy 426.447966 -396.977616) (xy 426.458088 -396.978154) (xy 426.476803 -396.985866)
			(xy 426.49116 -397.000137) (xy 426.498984 -397.018806) (xy 426.499528 -397.028924) (xy 426.499528 -397.186658)
			(xy 426.499952 -397.195844) (xy 426.506456 -397.213029) (xy 426.512228 -397.220186) (xy 426.534026 -397.24583)
			(xy 426.571977 -397.301417) (xy 426.603012 -397.361141) (xy 426.626685 -397.424147) (xy 426.642659 -397.48953)
			(xy 426.650703 -397.556354) (xy 426.650702 -397.623661) (xy 426.642656 -397.690485) (xy 426.626681 -397.755868)
			(xy 426.603006 -397.818873) (xy 426.600432 -397.823826) (xy 427.729077 -397.823826) (xy 427.729081 -397.756517)
			(xy 427.737129 -397.689691) (xy 427.753107 -397.624307) (xy 427.776786 -397.5613) (xy 427.807825 -397.501576)
			(xy 427.845781 -397.44599) (xy 427.867572 -397.420338) (xy 427.873386 -397.413206) (xy 427.879888 -397.396005)
			(xy 427.880272 -397.38681) (xy 427.880272 -396.893542) (xy 427.879848 -396.884356) (xy 427.873344 -396.867171)
			(xy 427.867572 -396.860014) (xy 427.845774 -396.83437) (xy 427.807823 -396.778783) (xy 427.776788 -396.719059)
			(xy 427.753115 -396.656053) (xy 427.737141 -396.59067) (xy 427.729097 -396.523846) (xy 427.729098 -396.456539)
			(xy 427.737144 -396.389715) (xy 427.753119 -396.324332) (xy 427.776794 -396.261327) (xy 427.807831 -396.201604)
			(xy 427.845783 -396.146018) (xy 427.867572 -396.120366) (xy 427.873374 -396.113225) (xy 427.879883 -396.096031)
			(xy 427.880272 -396.086838) (xy 427.880272 -395.92885) (xy 427.880706 -395.918677) (xy 427.88848 -395.899877)
			(xy 427.902864 -395.885489) (xy 427.921662 -395.877709) (xy 427.931834 -395.877288) (xy 428.648114 -395.877288)
			(xy 428.658293 -395.877654) (xy 428.677097 -395.885453) (xy 428.691483 -395.899857) (xy 428.699259 -395.918671)
			(xy 428.699676 -395.92885) (xy 428.699676 -396.086838) (xy 428.700073 -396.096026) (xy 428.706596 -396.11321)
			(xy 428.712376 -396.120366) (xy 428.734154 -396.146026) (xy 428.772102 -396.201612) (xy 428.803135 -396.261335)
			(xy 428.826807 -396.324338) (xy 428.84278 -396.389719) (xy 428.850825 -396.45654) (xy 428.850826 -396.523844)
			(xy 428.842783 -396.590666) (xy 428.826812 -396.656048) (xy 428.803141 -396.719052) (xy 428.772109 -396.778775)
			(xy 428.734163 -396.834362) (xy 428.712376 -396.860014) (xy 428.706588 -396.867165) (xy 428.700069 -396.884351)
			(xy 428.699676 -396.893542) (xy 428.699676 -397.38681) (xy 428.700087 -397.395997) (xy 428.7066 -397.413181)
			(xy 428.712376 -397.420338) (xy 428.734126 -397.446021) (xy 428.772075 -397.501604) (xy 428.800497 -397.556296)
			(xy 429.928742 -397.556296) (xy 429.936817 -397.489358) (xy 429.952852 -397.423869) (xy 429.976616 -397.360773)
			(xy 430.007767 -397.300977) (xy 430.045856 -397.245343) (xy 430.06772 -397.219678) (xy 430.073511 -397.212529)
			(xy 430.080028 -397.195341) (xy 430.08042 -397.18615) (xy 430.08042 -397.028924) (xy 430.080836 -397.018801)
			(xy 430.08858 -397.000094) (xy 430.102897 -396.985778) (xy 430.121605 -396.978035) (xy 430.131728 -396.977616)
			(xy 430.848008 -396.977616) (xy 430.858133 -396.97801) (xy 430.87684 -396.985764) (xy 430.891154 -397.000087)
			(xy 430.898896 -397.018799) (xy 430.899316 -397.028924) (xy 430.899316 -397.18615) (xy 430.899746 -397.195335)
			(xy 430.906246 -397.21252) (xy 430.912016 -397.219678) (xy 430.933889 -397.245335) (xy 430.971977 -397.300971)
			(xy 431.003126 -397.360769) (xy 431.026889 -397.423867) (xy 431.042923 -397.489357) (xy 431.050998 -397.556295)
			(xy 431.050997 -397.62372) (xy 431.04292 -397.690658) (xy 431.026884 -397.756148) (xy 431.00312 -397.819245)
			(xy 431.000734 -397.823826) (xy 432.128868 -397.823826) (xy 432.128872 -397.756517) (xy 432.13692 -397.689692)
			(xy 432.152898 -397.624307) (xy 432.176576 -397.561301) (xy 432.207614 -397.501576) (xy 432.245569 -397.44599)
			(xy 432.26736 -397.420338) (xy 432.273173 -397.413205) (xy 432.279676 -397.396005) (xy 432.28006 -397.38681)
			(xy 432.28006 -396.893542) (xy 432.279616 -396.884359) (xy 432.273125 -396.867175) (xy 432.26736 -396.860014)
			(xy 432.245562 -396.83437) (xy 432.207612 -396.778783) (xy 432.176578 -396.719058) (xy 432.152905 -396.656053)
			(xy 432.136932 -396.590669) (xy 432.128888 -396.523846) (xy 432.128889 -396.456539) (xy 432.136935 -396.389716)
			(xy 432.152909 -396.324333) (xy 432.176584 -396.261328) (xy 432.20762 -396.201604) (xy 432.245571 -396.146018)
			(xy 432.26736 -396.120366) (xy 432.273161 -396.113224) (xy 432.279671 -396.096031) (xy 432.28006 -396.086838)
			(xy 432.28006 -395.92885) (xy 432.280505 -395.918679) (xy 432.288278 -395.899881) (xy 432.302658 -395.885494)
			(xy 432.321451 -395.877711) (xy 432.331622 -395.877288) (xy 433.047902 -395.877288) (xy 433.05808 -395.877663)
			(xy 433.076884 -395.885458) (xy 433.091271 -395.899859) (xy 433.099047 -395.918672) (xy 433.099464 -395.92885)
			(xy 433.099464 -396.086838) (xy 433.099864 -396.096026) (xy 433.106386 -396.11321) (xy 433.112164 -396.120366)
			(xy 433.133942 -396.146026) (xy 433.171891 -396.201612) (xy 433.202924 -396.261334) (xy 433.226598 -396.324337)
			(xy 433.242571 -396.389719) (xy 433.250616 -396.45654) (xy 433.250617 -396.523845) (xy 433.242574 -396.590666)
			(xy 433.226602 -396.656048) (xy 433.202931 -396.719052) (xy 433.171899 -396.778776) (xy 433.133951 -396.834362)
			(xy 433.112164 -396.860014) (xy 433.106374 -396.867164) (xy 433.099856 -396.884351) (xy 433.099464 -396.893542)
			(xy 433.099464 -397.38681) (xy 433.099877 -397.395997) (xy 433.10639 -397.413181) (xy 433.112164 -397.420338)
			(xy 433.133914 -397.446021) (xy 433.171864 -397.501603) (xy 433.200318 -397.556356) (xy 434.329062 -397.556356)
			(xy 434.337105 -397.489534) (xy 434.353075 -397.424153) (xy 434.376746 -397.361149) (xy 434.407776 -397.301426)
			(xy 434.445722 -397.245839) (xy 434.467508 -397.220186) (xy 434.473294 -397.213033) (xy 434.479815 -397.195849)
			(xy 434.480208 -397.186658) (xy 434.480208 -397.028924) (xy 434.480641 -397.01877) (xy 434.48843 -397.000017)
			(xy 434.502824 -396.985692) (xy 434.521614 -396.977993) (xy 434.53177 -396.977616) (xy 435.24805 -396.977616)
			(xy 435.258171 -396.978167) (xy 435.276886 -396.985874) (xy 435.291243 -397.00014) (xy 435.299068 -397.018807)
			(xy 435.299612 -397.028924) (xy 435.299612 -397.186658) (xy 435.30004 -397.195843) (xy 435.306541 -397.213028)
			(xy 435.312312 -397.220186) (xy 435.334111 -397.245829) (xy 435.372063 -397.301416) (xy 435.403098 -397.36114)
			(xy 435.426773 -397.424146) (xy 435.442746 -397.48953) (xy 435.45079 -397.556354) (xy 435.45079 -397.623661)
			(xy 435.442744 -397.690485) (xy 435.426768 -397.755868) (xy 435.403092 -397.818873) (xy 435.372055 -397.878597)
			(xy 435.334102 -397.934182) (xy 435.312312 -397.959834) (xy 435.30652 -397.966982) (xy 435.300002 -397.98417)
			(xy 435.299612 -397.993362) (xy 435.299612 -398.100042) (xy 459.541382 -398.100042) (xy 459.545364 -397.972056)
			(xy 459.557296 -397.844565) (xy 459.57713 -397.718062) (xy 459.604791 -397.593037) (xy 459.640171 -397.469974)
			(xy 459.683133 -397.349348) (xy 459.733511 -397.231627) (xy 459.791111 -397.117265) (xy 459.855709 -397.006706)
			(xy 459.927056 -396.900376) (xy 460.004875 -396.798688) (xy 460.088865 -396.702034) (xy 460.178702 -396.610789)
			(xy 460.274038 -396.525306) (xy 460.374503 -396.445915) (xy 460.479711 -396.372923) (xy 460.589252 -396.306614)
			(xy 460.702704 -396.247243) (xy 460.819628 -396.195039) (xy 460.939571 -396.150206) (xy 461.062069 -396.112917)
			(xy 461.186649 -396.083315) (xy 461.312827 -396.061516) (xy 461.440117 -396.047603) (xy 461.568026 -396.041631)
			(xy 461.696059 -396.043622) (xy 461.82372 -396.05357) (xy 461.950516 -396.071434) (xy 462.075955 -396.097147)
			(xy 462.199554 -396.130609) (xy 462.320833 -396.17169) (xy 462.439324 -396.220232) (xy 462.554568 -396.276046)
			(xy 462.666118 -396.338917) (xy 462.773545 -396.408601) (xy 462.876431 -396.484829) (xy 462.974379 -396.567306)
			(xy 463.06701 -396.655713) (xy 463.153966 -396.749708) (xy 463.23491 -396.848927) (xy 463.309529 -396.952986)
			(xy 463.377534 -397.061483) (xy 463.438662 -397.173998) (xy 463.492677 -397.290096) (xy 463.53937 -397.409327)
			(xy 463.57856 -397.531231) (xy 463.610096 -397.655335) (xy 463.633855 -397.781159) (xy 463.649745 -397.908218)
			(xy 463.657706 -398.036018) (xy 463.658204 -398.100042) (xy 463.657706 -398.164066) (xy 463.649745 -398.291866)
			(xy 463.633855 -398.418925) (xy 463.610096 -398.544749) (xy 463.57856 -398.668853) (xy 463.53937 -398.790757)
			(xy 463.492677 -398.909988) (xy 463.438662 -399.026086) (xy 463.377534 -399.138601) (xy 463.309529 -399.247098)
			(xy 463.23491 -399.351157) (xy 463.153966 -399.450376) (xy 463.06701 -399.544371) (xy 462.974379 -399.632778)
			(xy 462.876431 -399.715255) (xy 462.773545 -399.791483) (xy 462.666118 -399.861167) (xy 462.554568 -399.924038)
			(xy 462.439324 -399.979852) (xy 462.320833 -400.028394) (xy 462.199554 -400.069475) (xy 462.075955 -400.102937)
			(xy 461.950516 -400.12865) (xy 461.82372 -400.146514) (xy 461.696059 -400.156462) (xy 461.568026 -400.158453)
			(xy 461.440117 -400.152481) (xy 461.312827 -400.138568) (xy 461.186649 -400.116769) (xy 461.062069 -400.087167)
			(xy 460.939571 -400.049878) (xy 460.819628 -400.005045) (xy 460.702704 -399.952841) (xy 460.589252 -399.89347)
			(xy 460.479711 -399.827161) (xy 460.374503 -399.754169) (xy 460.274038 -399.674778) (xy 460.178702 -399.589295)
			(xy 460.088865 -399.49805) (xy 460.004875 -399.401396) (xy 459.927056 -399.299708) (xy 459.855709 -399.193378)
			(xy 459.791111 -399.082819) (xy 459.733511 -398.968457) (xy 459.683133 -398.850736) (xy 459.640171 -398.73011)
			(xy 459.604791 -398.607047) (xy 459.57713 -398.482022) (xy 459.557296 -398.355519) (xy 459.545364 -398.228028)
			(xy 459.541382 -398.100042) (xy 435.299612 -398.100042) (xy 435.299612 -398.486884) (xy 435.300027 -398.496071)
			(xy 435.306537 -398.513255) (xy 435.312312 -398.520412) (xy 435.334137 -398.546034) (xy 435.372087 -398.601624)
			(xy 435.403122 -398.661351) (xy 435.426795 -398.72436) (xy 435.442767 -398.789746) (xy 435.450809 -398.856573)
			(xy 435.450805 -398.923881) (xy 435.442757 -398.990707) (xy 435.426779 -399.056092) (xy 435.4031 -399.119098)
			(xy 435.37206 -399.178823) (xy 435.334103 -399.234408) (xy 435.312312 -399.26006) (xy 435.306509 -399.267201)
			(xy 435.299998 -399.284395) (xy 435.299612 -399.293588) (xy 435.299612 -399.451576) (xy 435.299159 -399.461727)
			(xy 435.291374 -399.480477) (xy 435.276987 -399.494801) (xy 435.258203 -399.502503) (xy 435.24805 -399.502884)
			(xy 434.53177 -399.502884) (xy 434.521644 -399.502399) (xy 434.502927 -399.494666) (xy 434.488573 -399.480379)
			(xy 434.48075 -399.461699) (xy 434.480208 -399.451576) (xy 434.480208 -399.293588) (xy 434.479802 -399.2844)
			(xy 434.473285 -399.267216) (xy 434.467508 -399.26006) (xy 434.445757 -399.234378) (xy 434.407809 -399.178795)
			(xy 434.376776 -399.119076) (xy 434.353102 -399.056075) (xy 434.337128 -398.990697) (xy 434.329081 -398.923878)
			(xy 434.329078 -398.856576) (xy 434.337118 -398.789757) (xy 434.353086 -398.724377) (xy 434.376753 -398.661374)
			(xy 434.407781 -398.601651) (xy 434.445723 -398.546064) (xy 434.467508 -398.520412) (xy 434.473325 -398.513282)
			(xy 434.479827 -398.49608) (xy 434.480208 -398.486884) (xy 434.480208 -397.993362) (xy 434.479814 -397.984173)
			(xy 434.473289 -397.966989) (xy 434.467508 -397.959834) (xy 434.445731 -397.934173) (xy 434.407784 -397.878587)
			(xy 434.376752 -397.818865) (xy 434.35308 -397.755861) (xy 434.337107 -397.690481) (xy 434.329063 -397.623659)
			(xy 434.329062 -397.556356) (xy 433.200318 -397.556356) (xy 433.202899 -397.561322) (xy 433.226573 -397.624323)
			(xy 433.242549 -397.689701) (xy 433.250596 -397.75652) (xy 433.250599 -397.823822) (xy 433.242559 -397.890642)
			(xy 433.22659 -397.956022) (xy 433.202922 -398.019025) (xy 433.171893 -398.078748) (xy 433.133949 -398.134334)
			(xy 433.112164 -398.159986) (xy 433.106344 -398.167114) (xy 433.099844 -398.184318) (xy 433.099464 -398.193514)
			(xy 433.099464 -398.351502) (xy 433.098968 -398.36166) (xy 433.091194 -398.380428) (xy 433.076828 -398.394794)
			(xy 433.05806 -398.402568) (xy 433.047902 -398.403064) (xy 432.331622 -398.403064) (xy 432.321452 -398.402618)
			(xy 432.302658 -398.394841) (xy 432.288273 -398.380462) (xy 432.280487 -398.361672) (xy 432.28006 -398.351502)
			(xy 432.28006 -398.193514) (xy 432.27963 -398.184329) (xy 432.273129 -398.167145) (xy 432.26736 -398.159986)
			(xy 432.245534 -398.134365) (xy 432.207585 -398.078775) (xy 432.176552 -398.019047) (xy 432.152881 -397.956038)
			(xy 432.13691 -397.890652) (xy 432.128868 -397.823826) (xy 431.000734 -397.823826) (xy 430.971969 -397.879041)
			(xy 430.93388 -397.934676) (xy 430.912016 -397.960342) (xy 430.906221 -397.967488) (xy 430.899705 -397.984678)
			(xy 430.899316 -397.99387) (xy 430.899316 -398.486376) (xy 430.899734 -398.495562) (xy 430.906242 -398.512747)
			(xy 430.912016 -398.519904) (xy 430.933915 -398.54554) (xy 430.972001 -398.601179) (xy 431.00315 -398.66098)
			(xy 431.026911 -398.72408) (xy 431.042944 -398.789573) (xy 431.051016 -398.856514) (xy 431.051013 -398.92394)
			(xy 431.042934 -398.990881) (xy 431.026895 -399.056371) (xy 431.003128 -399.11947) (xy 430.971974 -399.179267)
			(xy 430.933882 -399.234902) (xy 430.912016 -399.260568) (xy 430.90621 -399.267707) (xy 430.8997 -399.284902)
			(xy 430.899316 -399.294096) (xy 430.899316 -399.451576) (xy 430.898865 -399.461695) (xy 430.891128 -399.480395)
			(xy 430.876822 -399.49471) (xy 430.858127 -399.502459) (xy 430.848008 -399.502884) (xy 430.131728 -399.502884)
			(xy 430.121605 -399.502461) (xy 430.102899 -399.494719) (xy 430.088583 -399.480404) (xy 430.08084 -399.461699)
			(xy 430.08042 -399.451576) (xy 430.08042 -399.294096) (xy 430.080008 -399.284909) (xy 430.073495 -399.267725)
			(xy 430.06772 -399.260568) (xy 430.045891 -399.234874) (xy 430.0078 -399.179244) (xy 429.976646 -399.119452)
			(xy 429.952879 -399.056359) (xy 429.936841 -398.990873) (xy 429.928761 -398.923938) (xy 429.928758 -398.856516)
			(xy 429.936831 -398.78958) (xy 429.952863 -398.724093) (xy 429.976624 -398.660997) (xy 430.007772 -398.601202)
			(xy 430.045857 -398.545569) (xy 430.06772 -398.519904) (xy 430.0735 -398.512747) (xy 430.080024 -398.495565)
			(xy 430.08042 -398.486376) (xy 430.08042 -397.99387) (xy 430.08002 -397.984682) (xy 430.073499 -397.967498)
			(xy 430.06772 -397.960342) (xy 430.045865 -397.934669) (xy 430.007775 -397.879036) (xy 429.976623 -397.819241)
			(xy 429.952857 -397.756145) (xy 429.93682 -397.690657) (xy 429.928743 -397.623719) (xy 429.928742 -397.556296)
			(xy 428.800497 -397.556296) (xy 428.803109 -397.561323) (xy 428.826783 -397.624323) (xy 428.842758 -397.689702)
			(xy 428.850805 -397.756521) (xy 428.850808 -397.823822) (xy 428.842768 -397.890642) (xy 428.8268 -397.956022)
			(xy 428.803132 -398.019025) (xy 428.772104 -398.078747) (xy 428.734161 -398.134333) (xy 428.712376 -398.159986)
			(xy 428.706558 -398.167116) (xy 428.700057 -398.184318) (xy 428.699676 -398.193514) (xy 428.699676 -398.351502)
			(xy 428.699169 -398.361658) (xy 428.691396 -398.380425) (xy 428.677035 -398.394789) (xy 428.65827 -398.402566)
			(xy 428.648114 -398.403064) (xy 427.931834 -398.403064) (xy 427.921665 -398.402608) (xy 427.902871 -398.394835)
			(xy 427.888485 -398.380459) (xy 427.880699 -398.361671) (xy 427.880272 -398.351502) (xy 427.880272 -398.193514)
			(xy 427.879861 -398.184327) (xy 427.873349 -398.167142) (xy 427.867572 -398.159986) (xy 427.845746 -398.134365)
			(xy 427.807796 -398.078775) (xy 427.776762 -398.019047) (xy 427.75309 -397.956039) (xy 427.737119 -397.890652)
			(xy 427.729077 -397.823826) (xy 426.600432 -397.823826) (xy 426.571969 -397.878596) (xy 426.534017 -397.934182)
			(xy 426.512228 -397.959834) (xy 426.506426 -397.966975) (xy 426.499917 -397.984169) (xy 426.499528 -397.993362)
			(xy 426.499528 -398.486884) (xy 426.499939 -398.496071) (xy 426.506451 -398.513256) (xy 426.512228 -398.520412)
			(xy 426.534052 -398.546034) (xy 426.572002 -398.601624) (xy 426.603036 -398.661352) (xy 426.626708 -398.72436)
			(xy 426.64268 -398.789746) (xy 426.650721 -398.856573) (xy 426.650718 -398.923881) (xy 426.64267 -398.990707)
			(xy 426.626692 -399.056092) (xy 426.603014 -399.119098) (xy 426.571974 -399.178822) (xy 426.534019 -399.234408)
			(xy 426.512228 -399.26006) (xy 426.506415 -399.267193) (xy 426.499912 -399.284393) (xy 426.499528 -399.293588)
			(xy 426.499528 -399.451576) (xy 426.499059 -399.461725) (xy 426.491277 -399.480472) (xy 426.476895 -399.494795)
			(xy 426.458117 -399.502501) (xy 426.447966 -399.502884) (xy 425.731686 -399.502884) (xy 425.721561 -399.502385)
			(xy 425.702845 -399.494657) (xy 425.68849 -399.480375) (xy 425.680667 -399.461698) (xy 425.680124 -399.451576)
			(xy 425.680124 -399.293588) (xy 425.679714 -399.284401) (xy 425.6732 -399.267217) (xy 425.667424 -399.26006)
			(xy 425.645672 -399.234378) (xy 425.607723 -399.178796) (xy 425.576689 -399.119076) (xy 425.553015 -399.056076)
			(xy 425.53704 -398.990697) (xy 425.528994 -398.923878) (xy 425.52899 -398.856576) (xy 425.537031 -398.789756)
			(xy 425.552999 -398.724376) (xy 425.576667 -398.661373) (xy 425.607696 -398.601651) (xy 425.645639 -398.546065)
			(xy 425.667424 -398.520412) (xy 425.673243 -398.513283) (xy 425.679744 -398.49608) (xy 425.680124 -398.486884)
			(xy 425.680124 -397.993362) (xy 425.679727 -397.984174) (xy 425.673204 -397.96699) (xy 425.667424 -397.959834)
			(xy 425.645646 -397.934174) (xy 425.607698 -397.878588) (xy 425.576665 -397.818865) (xy 425.552993 -397.755862)
			(xy 425.53702 -397.690481) (xy 425.528975 -397.62366) (xy 425.528974 -397.556356) (xy 424.40076 -397.556356)
			(xy 424.403152 -397.560947) (xy 424.426919 -397.62404) (xy 424.442958 -397.689526) (xy 424.451037 -397.756461)
			(xy 424.451041 -397.823882) (xy 424.442968 -397.890818) (xy 424.426936 -397.956305) (xy 424.403175 -398.019401)
			(xy 424.372028 -398.079196) (xy 424.333942 -398.134829) (xy 424.31208 -398.160494) (xy 424.306301 -398.167652)
			(xy 424.299777 -398.184833) (xy 424.29938 -398.194022) (xy 424.29938 -398.351502) (xy 424.298876 -398.361626)
			(xy 424.291151 -398.380344) (xy 424.27687 -398.394699) (xy 424.258194 -398.402522) (xy 424.248072 -398.403064)
			(xy 423.531792 -398.403064) (xy 423.521633 -398.402684) (xy 423.502873 -398.394879) (xy 423.488549 -398.380469)
			(xy 423.480856 -398.361663) (xy 423.480484 -398.351502) (xy 423.480484 -398.194022) (xy 423.480067 -398.184835)
			(xy 423.473558 -398.167651) (xy 423.467784 -398.160494) (xy 423.445883 -398.134859) (xy 423.407797 -398.07922)
			(xy 423.376649 -398.019419) (xy 423.352887 -397.956319) (xy 423.336855 -397.890826) (xy 423.328782 -397.823885)
			(xy 422.200615 -397.823885) (xy 422.171883 -397.879041) (xy 422.133795 -397.934676) (xy 422.111932 -397.960342)
			(xy 422.106127 -397.967481) (xy 422.099619 -397.984676) (xy 422.099232 -397.99387) (xy 422.099232 -398.486376)
			(xy 422.099669 -398.49556) (xy 422.106166 -398.512744) (xy 422.111932 -398.519904) (xy 422.13383 -398.545541)
			(xy 422.171916 -398.60118) (xy 422.203063 -398.66098) (xy 422.226824 -398.724081) (xy 422.242856 -398.789573)
			(xy 422.250928 -398.856514) (xy 422.250925 -398.92394) (xy 422.242846 -398.99088) (xy 422.226808 -399.056371)
			(xy 422.203041 -399.119469) (xy 422.171888 -399.179266) (xy 422.133797 -399.234902) (xy 422.111932 -399.260568)
			(xy 422.106116 -399.267699) (xy 422.099615 -399.284901) (xy 422.099232 -399.294096) (xy 422.099232 -399.451576)
			(xy 422.098696 -399.461679) (xy 422.090972 -399.480351) (xy 422.076691 -399.494645) (xy 422.058027 -399.502387)
			(xy 422.047924 -399.502884) (xy 421.331644 -399.502884) (xy 421.321522 -399.502447) (xy 421.302817 -399.494711)
			(xy 421.2885 -399.4804) (xy 421.280756 -399.461697) (xy 421.280336 -399.451576) (xy 421.280336 -399.294096)
			(xy 421.27992 -399.28491) (xy 421.27341 -399.267726) (xy 421.267636 -399.260568) (xy 421.245806 -399.234874)
			(xy 421.207714 -399.179245) (xy 421.17656 -399.119453) (xy 421.152792 -399.056359) (xy 421.136753 -398.990873)
			(xy 421.128674 -398.923938) (xy 421.12867 -398.856516) (xy 421.136743 -398.78958) (xy 421.152776 -398.724092)
			(xy 421.176538 -398.660997) (xy 421.207686 -398.601202) (xy 421.245773 -398.545569) (xy 421.267636 -398.519904)
			(xy 421.273418 -398.512749) (xy 421.27994 -398.495566) (xy 421.280336 -398.486376) (xy 421.280336 -397.99387)
			(xy 421.279932 -397.984682) (xy 421.273413 -397.967498) (xy 421.267636 -397.960342) (xy 421.245781 -397.934669)
			(xy 421.207689 -397.879037) (xy 421.176536 -397.819242) (xy 421.15277 -397.756146) (xy 421.136732 -397.690657)
			(xy 421.128655 -397.623719) (xy 421.128654 -397.556296) (xy 420.00041 -397.556296) (xy 420.003023 -397.561324)
			(xy 420.026696 -397.624324) (xy 420.042671 -397.689702) (xy 420.050718 -397.756521) (xy 420.050721 -397.823822)
			(xy 420.042681 -397.890642) (xy 420.026713 -397.956021) (xy 420.003046 -398.019024) (xy 419.972019 -398.078747)
			(xy 419.934077 -398.134334) (xy 419.912292 -398.159986) (xy 419.906475 -398.167117) (xy 419.899973 -398.184318)
			(xy 419.899592 -398.193514) (xy 419.899592 -398.351502) (xy 419.899069 -398.361656) (xy 419.891299 -398.38042)
			(xy 419.876943 -398.394784) (xy 419.858184 -398.402563) (xy 419.84803 -398.403064) (xy 419.13175 -398.403064)
			(xy 419.121582 -398.402595) (xy 419.102789 -398.394827) (xy 419.088402 -398.380455) (xy 419.080615 -398.36167)
			(xy 419.080188 -398.351502) (xy 419.080188 -398.193514) (xy 419.079774 -398.184327) (xy 419.073263 -398.167143)
			(xy 419.067488 -398.159986) (xy 419.045661 -398.134365) (xy 419.007711 -398.078775) (xy 418.976676 -398.019048)
			(xy 418.953004 -397.956039) (xy 418.937032 -397.890653) (xy 418.92899 -397.823826) (xy 414.525968 -397.823826)
			(xy 414.525968 -401.723737) (xy 418.929001 -401.723737) (xy 418.929003 -401.65643) (xy 418.93705 -401.589605)
			(xy 418.953027 -401.524221) (xy 418.976704 -401.461215) (xy 419.007743 -401.401491) (xy 419.045697 -401.345906)
			(xy 419.067488 -401.320254) (xy 419.073285 -401.313109) (xy 419.0798 -401.295918) (xy 419.080188 -401.286726)
			(xy 419.080188 -400.793458) (xy 419.079801 -400.784268) (xy 419.073272 -400.767084) (xy 419.067488 -400.75993)
			(xy 419.045705 -400.734274) (xy 419.007752 -400.678689) (xy 418.976716 -400.618966) (xy 418.953041 -400.555962)
			(xy 418.937066 -400.49058) (xy 418.929021 -400.423757) (xy 418.92902 -400.356452) (xy 418.937065 -400.289629)
			(xy 418.953038 -400.224246) (xy 418.976713 -400.161242) (xy 419.007748 -400.101519) (xy 419.045699 -400.045933)
			(xy 419.067488 -400.020282) (xy 419.073273 -400.013129) (xy 419.079795 -399.995944) (xy 419.080188 -399.986754)
			(xy 419.080188 -399.828766) (xy 419.080537 -399.818586) (xy 419.088343 -399.799781) (xy 419.102752 -399.785395)
			(xy 419.121569 -399.777621) (xy 419.13175 -399.777204) (xy 419.84803 -399.777204) (xy 419.858186 -399.777708)
			(xy 419.876949 -399.785486) (xy 419.891312 -399.799848) (xy 419.899091 -399.818611) (xy 419.899592 -399.828766)
			(xy 419.899592 -399.986754) (xy 419.900026 -399.995939) (xy 419.906523 -400.013123) (xy 419.912292 -400.020282)
			(xy 419.934085 -400.04593) (xy 419.972031 -400.101518) (xy 420.003063 -400.161242) (xy 420.026734 -400.224247)
			(xy 420.042705 -400.289629) (xy 420.050749 -400.356452) (xy 420.050748 -400.423757) (xy 420.042704 -400.490579)
			(xy 420.026731 -400.555962) (xy 420.003059 -400.618966) (xy 419.972027 -400.67869) (xy 419.934079 -400.734277)
			(xy 419.912292 -400.75993) (xy 419.906499 -400.767078) (xy 419.899983 -400.784266) (xy 419.899592 -400.793458)
			(xy 419.899592 -401.286726) (xy 419.899991 -401.295914) (xy 419.906513 -401.313099) (xy 419.912292 -401.320254)
			(xy 419.934057 -401.345924) (xy 419.972005 -401.401509) (xy 420.003037 -401.46123) (xy 420.02671 -401.524232)
			(xy 420.042683 -401.589612) (xy 420.050729 -401.656432) (xy 420.050731 -401.723735) (xy 420.042689 -401.790555)
			(xy 420.02672 -401.855936) (xy 420.003051 -401.918939) (xy 419.972022 -401.978663) (xy 419.934077 -402.034249)
			(xy 419.912292 -402.059902) (xy 419.906511 -402.067058) (xy 419.899987 -402.08424) (xy 419.899592 -402.09343)
			(xy 419.899592 -402.251418) (xy 419.899082 -402.261573) (xy 419.891308 -402.280337) (xy 419.876947 -402.294701)
			(xy 419.858185 -402.30248) (xy 419.84803 -402.30298) (xy 419.13175 -402.30298) (xy 419.121584 -402.302496)
			(xy 419.102794 -402.29473) (xy 419.088408 -402.280363) (xy 419.080618 -402.261584) (xy 419.080188 -402.251418)
			(xy 419.080188 -402.09343) (xy 419.079766 -402.084244) (xy 419.073261 -402.067059) (xy 419.067488 -402.059902)
			(xy 419.045677 -402.034268) (xy 419.007726 -401.97868) (xy 418.976691 -401.918955) (xy 418.953017 -401.855948)
			(xy 418.937044 -401.790563) (xy 418.929001 -401.723737) (xy 414.525968 -401.723737) (xy 414.525968 -402.823878)
			(xy 421.128614 -402.823878) (xy 421.128619 -402.75645) (xy 421.1367 -402.689508) (xy 421.152742 -402.624016)
			(xy 421.176513 -402.560916) (xy 421.207671 -402.501119) (xy 421.245768 -402.445485) (xy 421.267636 -402.41982)
			(xy 421.273454 -402.41269) (xy 421.279955 -402.395488) (xy 421.280336 -402.386292) (xy 421.280336 -401.89404)
			(xy 421.279898 -401.884856) (xy 421.273403 -401.867672) (xy 421.267636 -401.860512) (xy 421.245751 -401.834864)
			(xy 421.207661 -401.779227) (xy 421.176509 -401.719429) (xy 421.152744 -401.65633) (xy 421.136709 -401.590839)
			(xy 421.128634 -401.523898) (xy 421.128636 -401.456472) (xy 421.136714 -401.389532) (xy 421.152753 -401.324041)
			(xy 421.176521 -401.260943) (xy 421.207676 -401.201147) (xy 421.24577 -401.145513) (xy 421.267636 -401.119848)
			(xy 421.273442 -401.112709) (xy 421.27995 -401.095514) (xy 421.280336 -401.08632) (xy 421.280336 -400.92884)
			(xy 421.28075 -400.918716) (xy 421.288491 -400.900006) (xy 421.302809 -400.885689) (xy 421.32152 -400.877949)
			(xy 421.331644 -400.877532) (xy 422.047924 -400.877532) (xy 422.058052 -400.877897) (xy 422.076762 -400.885659)
			(xy 422.091077 -400.899991) (xy 422.098816 -400.918711) (xy 422.099232 -400.92884) (xy 422.099232 -401.08632)
			(xy 422.099648 -401.095506) (xy 422.106159 -401.11269) (xy 422.111932 -401.119848) (xy 422.133775 -401.14553)
			(xy 422.171862 -401.201163) (xy 422.203012 -401.260957) (xy 422.226776 -401.324052) (xy 422.242812 -401.389538)
			(xy 422.250889 -401.456474) (xy 422.250891 -401.523896) (xy 422.242817 -401.590832) (xy 422.226785 -401.65632)
			(xy 422.203024 -401.719415) (xy 422.200742 -401.723796) (xy 423.328794 -401.723796) (xy 423.328796 -401.656371)
			(xy 423.336873 -401.589431) (xy 423.352911 -401.523941) (xy 423.376677 -401.460844) (xy 423.407829 -401.401047)
			(xy 423.445919 -401.345412) (xy 423.467784 -401.319746) (xy 423.473584 -401.312603) (xy 423.480097 -401.295411)
			(xy 423.480484 -401.286218) (xy 423.480484 -400.793966) (xy 423.480094 -400.784777) (xy 423.473566 -400.767592)
			(xy 423.467784 -400.760438) (xy 423.445926 -400.734768) (xy 423.407839 -400.679133) (xy 423.376689 -400.619338)
			(xy 423.352925 -400.556242) (xy 423.336889 -400.490753) (xy 423.328813 -400.423816) (xy 423.328813 -400.356393)
			(xy 423.336888 -400.289455) (xy 423.352922 -400.223967) (xy 423.376685 -400.16087) (xy 423.407834 -400.101074)
			(xy 423.445921 -400.045439) (xy 423.467784 -400.019774) (xy 423.473572 -400.012623) (xy 423.480092 -399.995437)
			(xy 423.480484 -399.986246) (xy 423.480484 -399.828766) (xy 423.4809 -399.818632) (xy 423.488647 -399.799901)
			(xy 423.502955 -399.785545) (xy 423.521659 -399.777735) (xy 423.531792 -399.777204) (xy 424.248072 -399.777204)
			(xy 424.258225 -399.777644) (xy 424.276977 -399.785431) (xy 424.291302 -399.799823) (xy 424.299002 -399.818611)
			(xy 424.29938 -399.828766) (xy 424.29938 -399.986246) (xy 424.299821 -399.99543) (xy 424.306314 -400.012614)
			(xy 424.31208 -400.019774) (xy 424.333951 -400.045434) (xy 424.37204 -400.101069) (xy 424.403192 -400.160866)
			(xy 424.426957 -400.223963) (xy 424.442992 -400.289453) (xy 424.451068 -400.356392) (xy 424.451068 -400.423817)
			(xy 424.442991 -400.490756) (xy 424.426954 -400.556245) (xy 424.403188 -400.619343) (xy 424.372036 -400.679139)
			(xy 424.333945 -400.734773) (xy 424.31208 -400.760438) (xy 424.306282 -400.767582) (xy 424.299769 -400.784774)
			(xy 424.29938 -400.793966) (xy 424.29938 -401.286218) (xy 424.299786 -401.295406) (xy 424.306303 -401.31259)
			(xy 424.31208 -401.319746) (xy 424.333923 -401.345429) (xy 424.372014 -401.40106) (xy 424.403167 -401.460854)
			(xy 424.426933 -401.523949) (xy 424.44297 -401.589436) (xy 424.451048 -401.656372) (xy 424.45105 -401.723795)
			(xy 424.442976 -401.790732) (xy 424.426943 -401.85622) (xy 424.40318 -401.919316) (xy 424.372031 -401.979111)
			(xy 424.333943 -402.034745) (xy 424.31208 -402.06041) (xy 424.306294 -402.067563) (xy 424.299774 -402.084748)
			(xy 424.29938 -402.093938) (xy 424.29938 -402.251418) (xy 424.298889 -402.261543) (xy 424.291159 -402.280261)
			(xy 424.276874 -402.294616) (xy 424.258195 -402.302438) (xy 424.248072 -402.30298) (xy 423.531792 -402.30298)
			(xy 423.521635 -402.302584) (xy 423.502879 -402.294782) (xy 423.488555 -402.280378) (xy 423.480859 -402.261577)
			(xy 423.480484 -402.251418) (xy 423.480484 -402.093938) (xy 423.480059 -402.084752) (xy 423.473556 -402.067568)
			(xy 423.467784 -402.06041) (xy 423.445899 -402.034762) (xy 423.407812 -401.979125) (xy 423.376663 -401.919326)
			(xy 423.352901 -401.856227) (xy 423.336867 -401.790736) (xy 423.328794 -401.723796) (xy 422.200742 -401.723796)
			(xy 422.171878 -401.779211) (xy 422.133794 -401.834846) (xy 422.111932 -401.860512) (xy 422.10614 -401.86766)
			(xy 422.099624 -401.884849) (xy 422.099232 -401.89404) (xy 422.099232 -402.386292) (xy 422.099661 -402.395477)
			(xy 422.106163 -402.412661) (xy 422.111932 -402.41982) (xy 422.133748 -402.445525) (xy 422.171836 -402.501154)
			(xy 422.202987 -402.560945) (xy 422.226752 -402.624037) (xy 422.24279 -402.689521) (xy 422.250869 -402.756454)
			(xy 422.250874 -402.823818) (xy 425.528934 -402.823818) (xy 425.528938 -402.75651) (xy 425.536987 -402.689684)
			(xy 425.552965 -402.624299) (xy 425.576642 -402.561293) (xy 425.60768 -402.501568) (xy 425.645634 -402.44598)
			(xy 425.667424 -402.420328) (xy 425.673236 -402.413194) (xy 425.679741 -402.395995) (xy 425.680124 -402.3868)
			(xy 425.680124 -401.893532) (xy 425.679693 -401.884347) (xy 425.673193 -401.867163) (xy 425.667424 -401.860004)
			(xy 425.645617 -401.834368) (xy 425.60767 -401.778779) (xy 425.576638 -401.719053) (xy 425.552967 -401.656046)
			(xy 425.536996 -401.590662) (xy 425.528954 -401.523838) (xy 425.528956 -401.456532) (xy 425.537001 -401.389708)
			(xy 425.552976 -401.324325) (xy 425.57665 -401.26132) (xy 425.607685 -401.201595) (xy 425.645635 -401.146008)
			(xy 425.667424 -401.120356) (xy 425.673225 -401.113214) (xy 425.679736 -401.096021) (xy 425.680124 -401.086828)
			(xy 425.680124 -400.92884) (xy 425.680555 -400.918686) (xy 425.688342 -400.899929) (xy 425.702736 -400.885604)
			(xy 425.72153 -400.877907) (xy 425.731686 -400.877532) (xy 426.447966 -400.877532) (xy 426.45809 -400.878054)
			(xy 426.476808 -400.88577) (xy 426.491165 -400.900045) (xy 426.498987 -400.918719) (xy 426.499528 -400.92884)
			(xy 426.499528 -401.086828) (xy 426.499918 -401.096017) (xy 426.506445 -401.113202) (xy 426.512228 -401.120356)
			(xy 426.533997 -401.146024) (xy 426.571949 -401.201607) (xy 426.602985 -401.261328) (xy 426.62666 -401.324331)
			(xy 426.642635 -401.389712) (xy 426.650681 -401.456533) (xy 426.650683 -401.523837) (xy 426.642641 -401.590659)
			(xy 426.626669 -401.65604) (xy 426.602997 -401.719044) (xy 426.600558 -401.723737) (xy 427.729089 -401.723737)
			(xy 427.729091 -401.65643) (xy 427.737138 -401.589605) (xy 427.753114 -401.524221) (xy 427.776791 -401.461216)
			(xy 427.807828 -401.401492) (xy 427.845782 -401.345906) (xy 427.867572 -401.320254) (xy 427.873379 -401.313117)
			(xy 427.879886 -401.29592) (xy 427.880272 -401.286726) (xy 427.880272 -400.793458) (xy 427.879888 -400.784268)
			(xy 427.873357 -400.767084) (xy 427.867572 -400.75993) (xy 427.845789 -400.734273) (xy 427.807838 -400.678688)
			(xy 427.776803 -400.618966) (xy 427.753128 -400.555962) (xy 427.737154 -400.49058) (xy 427.729109 -400.423757)
			(xy 427.729108 -400.356452) (xy 427.737152 -400.289629) (xy 427.753126 -400.224247) (xy 427.776799 -400.161243)
			(xy 427.807833 -400.101519) (xy 427.845784 -400.045934) (xy 427.867572 -400.020282) (xy 427.873367 -400.013136)
			(xy 427.879881 -399.995946) (xy 427.880272 -399.986754) (xy 427.880272 -399.828766) (xy 427.880706 -399.818602)
			(xy 427.888498 -399.799825) (xy 427.902883 -399.78546) (xy 427.921669 -399.777693) (xy 427.931834 -399.777204)
			(xy 428.648114 -399.777204) (xy 428.658268 -399.777721) (xy 428.677031 -399.785494) (xy 428.691395 -399.799852)
			(xy 428.699175 -399.818612) (xy 428.699676 -399.828766) (xy 428.699676 -399.986754) (xy 428.700114 -399.995938)
			(xy 428.706609 -400.013122) (xy 428.712376 -400.020282) (xy 428.734169 -400.045929) (xy 428.772117 -400.101517)
			(xy 428.803149 -400.161241) (xy 428.826821 -400.224246) (xy 428.842793 -400.289629) (xy 428.850836 -400.356452)
			(xy 428.850836 -400.423757) (xy 428.842791 -400.49058) (xy 428.826818 -400.555962) (xy 428.803145 -400.618967)
			(xy 428.772112 -400.678691) (xy 428.734164 -400.734278) (xy 428.712376 -400.75993) (xy 428.706581 -400.767076)
			(xy 428.700066 -400.784266) (xy 428.699676 -400.793458) (xy 428.699676 -401.286726) (xy 428.700079 -401.295914)
			(xy 428.706598 -401.313098) (xy 428.712376 -401.320254) (xy 428.734142 -401.345924) (xy 428.77209 -401.401508)
			(xy 428.803124 -401.46123) (xy 428.826797 -401.524232) (xy 428.842771 -401.589612) (xy 428.850817 -401.656432)
			(xy 428.850819 -401.723735) (xy 428.842777 -401.790556) (xy 428.826807 -401.855937) (xy 428.803137 -401.91894)
			(xy 428.772107 -401.978663) (xy 428.734162 -402.03425) (xy 428.712376 -402.059902) (xy 428.706593 -402.067057)
			(xy 428.700071 -402.08424) (xy 428.699676 -402.09343) (xy 428.699676 -402.251418) (xy 428.699182 -402.261575)
			(xy 428.691404 -402.280342) (xy 428.677039 -402.294706) (xy 428.658271 -402.302483) (xy 428.648114 -402.30298)
			(xy 427.931834 -402.30298) (xy 427.921667 -402.302509) (xy 427.902876 -402.294738) (xy 427.888491 -402.280367)
			(xy 427.880702 -402.261585) (xy 427.880272 -402.251418) (xy 427.880272 -402.09343) (xy 427.879854 -402.084244)
			(xy 427.873347 -402.067059) (xy 427.867572 -402.059902) (xy 427.845762 -402.034268) (xy 427.807811 -401.97868)
			(xy 427.776777 -401.918954) (xy 427.753104 -401.855947) (xy 427.737132 -401.790562) (xy 427.729089 -401.723737)
			(xy 426.600558 -401.723737) (xy 426.571964 -401.778767) (xy 426.534015 -401.834352) (xy 426.512228 -401.860004)
			(xy 426.506438 -401.867154) (xy 426.499922 -401.884341) (xy 426.499528 -401.893532) (xy 426.499528 -402.3868)
			(xy 426.499932 -402.395988) (xy 426.506449 -402.413173) (xy 426.512228 -402.420328) (xy 426.53397 -402.446019)
			(xy 426.571922 -402.501599) (xy 426.602959 -402.561317) (xy 426.626636 -402.624316) (xy 426.642613 -402.689694)
			(xy 426.650662 -402.756513) (xy 426.650666 -402.823815) (xy 426.650658 -402.823878) (xy 429.928702 -402.823878)
			(xy 429.928707 -402.75645) (xy 429.936788 -402.689508) (xy 429.952829 -402.624016) (xy 429.976599 -402.560917)
			(xy 430.007757 -402.50112) (xy 430.045852 -402.445485) (xy 430.06772 -402.41982) (xy 430.073535 -402.412688)
			(xy 430.080038 -402.395487) (xy 430.08042 -402.386292) (xy 430.08042 -401.89404) (xy 430.079986 -401.884855)
			(xy 430.073488 -401.867671) (xy 430.06772 -401.860512) (xy 430.045836 -401.834863) (xy 430.007746 -401.779227)
			(xy 429.976595 -401.719429) (xy 429.952831 -401.656329) (xy 429.936797 -401.590838) (xy 429.928722 -401.523898)
			(xy 429.928724 -401.456472) (xy 429.936802 -401.389532) (xy 429.95284 -401.324042) (xy 429.976608 -401.260944)
			(xy 430.007762 -401.201147) (xy 430.045854 -401.145513) (xy 430.06772 -401.119848) (xy 430.073523 -401.112708)
			(xy 430.080033 -401.095513) (xy 430.08042 -401.08632) (xy 430.08042 -400.92884) (xy 430.080849 -400.918718)
			(xy 430.088588 -400.900011) (xy 430.102901 -400.885695) (xy 430.121606 -400.877952) (xy 430.131728 -400.877532)
			(xy 430.848008 -400.877532) (xy 430.858135 -400.87791) (xy 430.876845 -400.885667) (xy 430.89116 -400.899996)
			(xy 430.898899 -400.918713) (xy 430.899316 -400.92884) (xy 430.899316 -401.08632) (xy 430.899713 -401.095509)
			(xy 430.906236 -401.112693) (xy 430.912016 -401.119848) (xy 430.93386 -401.14553) (xy 430.971948 -401.201162)
			(xy 431.003099 -401.260956) (xy 431.026863 -401.324051) (xy 431.0429 -401.389538) (xy 431.050977 -401.456474)
			(xy 431.050979 -401.523896) (xy 431.042905 -401.590832) (xy 431.026872 -401.65632) (xy 431.003111 -401.719416)
			(xy 431.00086 -401.723737) (xy 432.128879 -401.723737) (xy 432.128881 -401.65643) (xy 432.136928 -401.589605)
			(xy 432.152904 -401.524222) (xy 432.17658 -401.461216) (xy 432.207617 -401.401492) (xy 432.24557 -401.345906)
			(xy 432.26736 -401.320254) (xy 432.273166 -401.313116) (xy 432.279673 -401.29592) (xy 432.28006 -401.286726)
			(xy 432.28006 -400.793458) (xy 432.279657 -400.78427) (xy 432.273137 -400.767087) (xy 432.26736 -400.75993)
			(xy 432.245578 -400.734273) (xy 432.207627 -400.678688) (xy 432.176593 -400.618965) (xy 432.152919 -400.555961)
			(xy 432.136945 -400.490579) (xy 432.1289 -400.423757) (xy 432.128899 -400.356452) (xy 432.136943 -400.28963)
			(xy 432.152916 -400.224247) (xy 432.176589 -400.161243) (xy 432.207623 -400.10152) (xy 432.245572 -400.045934)
			(xy 432.26736 -400.020282) (xy 432.273154 -400.013135) (xy 432.279669 -399.995946) (xy 432.28006 -399.986754)
			(xy 432.28006 -399.828766) (xy 432.280506 -399.818603) (xy 432.288296 -399.799829) (xy 432.302676 -399.785464)
			(xy 432.321459 -399.777695) (xy 432.331622 -399.777204) (xy 433.047902 -399.777204) (xy 433.058056 -399.777731)
			(xy 433.076818 -399.7855) (xy 433.091182 -399.799855) (xy 433.098963 -399.818613) (xy 433.099464 -399.828766)
			(xy 433.099464 -399.986754) (xy 433.099905 -399.995938) (xy 433.106398 -400.013122) (xy 433.112164 -400.020282)
			(xy 433.133958 -400.045929) (xy 433.171906 -400.101516) (xy 433.202939 -400.161241) (xy 433.226611 -400.224246)
			(xy 433.242584 -400.289629) (xy 433.250627 -400.356452) (xy 433.250627 -400.423757) (xy 433.242582 -400.49058)
			(xy 433.226609 -400.555963) (xy 433.202935 -400.618968) (xy 433.171901 -400.678691) (xy 433.133952 -400.734278)
			(xy 433.112164 -400.75993) (xy 433.106368 -400.767075) (xy 433.099854 -400.784266) (xy 433.099464 -400.793458)
			(xy 433.099464 -401.286726) (xy 433.09987 -401.295913) (xy 433.106387 -401.313097) (xy 433.112164 -401.320254)
			(xy 433.13393 -401.345924) (xy 433.171879 -401.401508) (xy 433.202913 -401.461229) (xy 433.226587 -401.524231)
			(xy 433.242561 -401.589611) (xy 433.250607 -401.656432) (xy 433.250609 -401.723735) (xy 433.242567 -401.790556)
			(xy 433.226597 -401.855937) (xy 433.202927 -401.918941) (xy 433.171896 -401.978663) (xy 433.13395 -402.03425)
			(xy 433.112164 -402.059902) (xy 433.106379 -402.067056) (xy 433.099858 -402.08424) (xy 433.099464 -402.09343)
			(xy 433.099464 -402.251418) (xy 433.098982 -402.261577) (xy 433.091202 -402.280346) (xy 433.076833 -402.294711)
			(xy 433.058061 -402.302485) (xy 433.047902 -402.30298) (xy 432.331622 -402.30298) (xy 432.321454 -402.302518)
			(xy 432.302663 -402.294744) (xy 432.288278 -402.28037) (xy 432.28049 -402.261586) (xy 432.28006 -402.251418)
			(xy 432.28006 -402.09343) (xy 432.279622 -402.084246) (xy 432.273126 -402.067062) (xy 432.26736 -402.059902)
			(xy 432.24555 -402.034268) (xy 432.2076 -401.97868) (xy 432.176567 -401.918954) (xy 432.152894 -401.855947)
			(xy 432.136922 -401.790562) (xy 432.128879 -401.723737) (xy 431.00086 -401.723737) (xy 430.971963 -401.779212)
			(xy 430.933878 -401.834847) (xy 430.912016 -401.860512) (xy 430.906234 -401.867667) (xy 430.89971 -401.88485)
			(xy 430.899316 -401.89404) (xy 430.899316 -402.386292) (xy 430.899726 -402.395479) (xy 430.90624 -402.412664)
			(xy 430.912016 -402.41982) (xy 430.933832 -402.445524) (xy 430.971921 -402.501154) (xy 431.003073 -402.560945)
			(xy 431.026839 -402.624036) (xy 431.042878 -402.68952) (xy 431.050957 -402.756454) (xy 431.050962 -402.823818)
			(xy 434.329022 -402.823818) (xy 434.329026 -402.75651) (xy 434.337075 -402.689684) (xy 434.353052 -402.6243)
			(xy 434.376729 -402.561294) (xy 434.407766 -402.501568) (xy 434.445718 -402.445981) (xy 434.467508 -402.420328)
			(xy 434.473319 -402.413193) (xy 434.479825 -402.395995) (xy 434.480208 -402.3868) (xy 434.480208 -401.893532)
			(xy 434.479781 -401.884347) (xy 434.473279 -401.867162) (xy 434.467508 -401.860004) (xy 434.445702 -401.834368)
			(xy 434.407755 -401.778778) (xy 434.376725 -401.719052) (xy 434.353054 -401.656046) (xy 434.337084 -401.590662)
			(xy 434.329042 -401.523838) (xy 434.329043 -401.456532) (xy 434.337089 -401.389709) (xy 434.353063 -401.324326)
			(xy 434.376737 -401.26132) (xy 434.407771 -401.201596) (xy 434.44572 -401.146009) (xy 434.467508 -401.120356)
			(xy 434.473307 -401.113212) (xy 434.47982 -401.096021) (xy 434.480208 -401.086828) (xy 434.480208 -400.92884)
			(xy 434.480655 -400.918688) (xy 434.488438 -400.899934) (xy 434.502828 -400.885609) (xy 434.521616 -400.87791)
			(xy 434.53177 -400.877532) (xy 435.24805 -400.877532) (xy 435.258173 -400.878067) (xy 435.276891 -400.885777)
			(xy 435.291249 -400.900049) (xy 435.299071 -400.918721) (xy 435.299612 -400.92884) (xy 435.299612 -401.086828)
			(xy 435.300006 -401.096017) (xy 435.306531 -401.113201) (xy 435.312312 -401.120356) (xy 435.334082 -401.146024)
			(xy 435.372034 -401.201607) (xy 435.403071 -401.261328) (xy 435.426747 -401.32433) (xy 435.442723 -401.389711)
			(xy 435.450769 -401.456533) (xy 435.450771 -401.523837) (xy 435.442728 -401.590659) (xy 435.426756 -401.656041)
			(xy 435.403083 -401.719045) (xy 435.37205 -401.778767) (xy 435.3341 -401.834353) (xy 435.312312 -401.860004)
			(xy 435.306533 -401.867161) (xy 435.300007 -401.884343) (xy 435.299612 -401.893532) (xy 435.299612 -402.3868)
			(xy 435.30002 -402.395988) (xy 435.306535 -402.413172) (xy 435.312312 -402.420328) (xy 435.334054 -402.446018)
			(xy 435.372008 -402.501598) (xy 435.403046 -402.561316) (xy 435.426723 -402.624316) (xy 435.442701 -402.689694)
			(xy 435.45075 -402.756513) (xy 435.450754 -402.823815) (xy 435.442714 -402.890635) (xy 435.426745 -402.956015)
			(xy 435.403075 -403.019018) (xy 435.372045 -403.07874) (xy 435.334098 -403.134325) (xy 435.312312 -403.159976)
			(xy 435.306502 -403.167112) (xy 435.299995 -403.184309) (xy 435.299612 -403.193504) (xy 435.299612 -403.351492)
			(xy 435.299172 -403.361644) (xy 435.291381 -403.380394) (xy 435.27699 -403.394717) (xy 435.258204 -403.402419)
			(xy 435.24805 -403.4028) (xy 434.53177 -403.4028) (xy 434.521646 -403.402299) (xy 434.502932 -403.394569)
			(xy 434.488578 -403.380288) (xy 434.480753 -403.361613) (xy 434.480208 -403.351492) (xy 434.480208 -403.193504)
			(xy 434.479794 -403.184317) (xy 434.473283 -403.167133) (xy 434.467508 -403.159976) (xy 434.445674 -403.134362)
			(xy 434.407729 -403.07877) (xy 434.376699 -403.01904) (xy 434.353031 -402.956031) (xy 434.337062 -402.890644)
			(xy 434.329022 -402.823818) (xy 431.050962 -402.823818) (xy 431.050962 -402.823874) (xy 431.042891 -402.890808)
			(xy 431.026861 -402.956295) (xy 431.003103 -403.019389) (xy 430.971958 -403.079184) (xy 430.933877 -403.134819)
			(xy 430.912016 -403.160484) (xy 430.906203 -403.167618) (xy 430.899698 -403.184817) (xy 430.899316 -403.194012)
			(xy 430.899316 -403.351492) (xy 430.898809 -403.361598) (xy 430.891077 -403.380273) (xy 430.876787 -403.394568)
			(xy 430.858114 -403.402306) (xy 430.848008 -403.4028) (xy 430.131728 -403.4028) (xy 430.121607 -403.402361)
			(xy 430.102904 -403.394622) (xy 430.088589 -403.380313) (xy 430.080843 -403.361613) (xy 430.08042 -403.351492)
			(xy 430.08042 -403.194012) (xy 430.079999 -403.184826) (xy 430.073492 -403.167642) (xy 430.06772 -403.160484)
			(xy 430.045808 -403.134858) (xy 430.00772 -403.079218) (xy 429.97657 -403.019417) (xy 429.952807 -402.956315)
			(xy 429.936775 -402.890821) (xy 429.928702 -402.823878) (xy 426.650658 -402.823878) (xy 426.642626 -402.890635)
			(xy 426.626657 -402.956015) (xy 426.602989 -403.019017) (xy 426.571959 -403.078739) (xy 426.534014 -403.134324)
			(xy 426.512228 -403.159976) (xy 426.506408 -403.167104) (xy 426.499909 -403.184308) (xy 426.499528 -403.193504)
			(xy 426.499528 -403.351492) (xy 426.499072 -403.361642) (xy 426.491285 -403.380389) (xy 426.476899 -403.394712)
			(xy 426.458118 -403.402417) (xy 426.447966 -403.4028) (xy 425.731686 -403.4028) (xy 425.721563 -403.402286)
			(xy 425.70285 -403.394561) (xy 425.688495 -403.380284) (xy 425.68067 -403.361612) (xy 425.680124 -403.351492)
			(xy 425.680124 -403.193504) (xy 425.679707 -403.184318) (xy 425.673198 -403.167133) (xy 425.667424 -403.159976)
			(xy 425.64559 -403.134362) (xy 425.607643 -403.07877) (xy 425.576613 -403.019041) (xy 425.552943 -402.956032)
			(xy 425.536974 -402.890645) (xy 425.528934 -402.823818) (xy 422.250874 -402.823818) (xy 422.250874 -402.823874)
			(xy 422.242803 -402.890808) (xy 422.226774 -402.956294) (xy 422.203016 -403.019389) (xy 422.171873 -403.079184)
			(xy 422.133792 -403.134818) (xy 422.111932 -403.160484) (xy 422.106109 -403.16761) (xy 422.099612 -403.184816)
			(xy 422.099232 -403.194012) (xy 422.099232 -403.351492) (xy 422.098709 -403.361596) (xy 422.09098 -403.380268)
			(xy 422.076695 -403.394562) (xy 422.058028 -403.402303) (xy 422.047924 -403.4028) (xy 421.331644 -403.4028)
			(xy 421.321524 -403.402348) (xy 421.302822 -403.394614) (xy 421.288506 -403.380308) (xy 421.280759 -403.361611)
			(xy 421.280336 -403.351492) (xy 421.280336 -403.194012) (xy 421.279912 -403.184826) (xy 421.273407 -403.167642)
			(xy 421.267636 -403.160484) (xy 421.245724 -403.134858) (xy 421.207634 -403.079219) (xy 421.176483 -403.019418)
			(xy 421.15272 -402.956315) (xy 421.136687 -402.890821) (xy 421.128614 -402.823878) (xy 414.525968 -402.823878)
			(xy 414.525968 -405.623649) (xy 418.929012 -405.623649) (xy 418.929013 -405.556342) (xy 418.937058 -405.489518)
			(xy 418.953033 -405.424135) (xy 418.976709 -405.36113) (xy 419.007746 -405.301407) (xy 419.045698 -405.245822)
			(xy 419.067488 -405.22017) (xy 419.073278 -405.21302) (xy 419.079797 -405.195833) (xy 419.080188 -405.186642)
			(xy 419.080188 -404.693374) (xy 419.079793 -404.684185) (xy 419.073269 -404.667001) (xy 419.067488 -404.659846)
			(xy 419.04572 -404.634177) (xy 419.007768 -404.578594) (xy 418.976731 -404.518873) (xy 418.953055 -404.455871)
			(xy 418.937079 -404.39049) (xy 418.929032 -404.323669) (xy 418.92903 -404.256364) (xy 418.937073 -404.189542)
			(xy 418.953045 -404.124161) (xy 418.976717 -404.061157) (xy 419.007751 -404.001435) (xy 419.0457 -403.945849)
			(xy 419.067488 -403.920198) (xy 419.073267 -403.91304) (xy 419.079792 -403.895859) (xy 419.080188 -403.88667)
			(xy 419.080188 -403.728682) (xy 419.08055 -403.718503) (xy 419.088351 -403.699698) (xy 419.102756 -403.685313)
			(xy 419.12157 -403.677537) (xy 419.13175 -403.67712) (xy 419.84803 -403.67712) (xy 419.858187 -403.677608)
			(xy 419.876954 -403.685389) (xy 419.891317 -403.699756) (xy 419.899094 -403.718524) (xy 419.899592 -403.728682)
			(xy 419.899592 -403.88667) (xy 419.900018 -403.895855) (xy 419.906521 -403.91304) (xy 419.912292 -403.920198)
			(xy 419.9341 -403.945833) (xy 419.972047 -404.001422) (xy 420.003077 -404.061149) (xy 420.026747 -404.124155)
			(xy 420.042718 -404.189539) (xy 420.05076 -404.256363) (xy 420.050758 -404.32367) (xy 420.042712 -404.390493)
			(xy 420.026738 -404.455876) (xy 420.003064 -404.518882) (xy 419.97203 -404.578606) (xy 419.93408 -404.634193)
			(xy 419.912292 -404.659846) (xy 419.906492 -404.666989) (xy 419.89998 -404.684181) (xy 419.899592 -404.693374)
			(xy 419.899592 -405.186642) (xy 419.899984 -405.195831) (xy 419.90651 -405.213015) (xy 419.912292 -405.22017)
			(xy 419.934073 -405.245827) (xy 419.97202 -405.301414) (xy 420.003052 -405.361137) (xy 420.026723 -405.424141)
			(xy 420.042696 -405.489522) (xy 420.05074 -405.556343) (xy 420.050741 -405.623647) (xy 420.042698 -405.690469)
			(xy 420.026726 -405.755851) (xy 420.003055 -405.818855) (xy 419.972025 -405.878578) (xy 419.934078 -405.934165)
			(xy 419.912292 -405.959818) (xy 419.906504 -405.96697) (xy 419.899985 -405.984155) (xy 419.899592 -405.993346)
			(xy 419.899592 -406.151334) (xy 419.899095 -406.16149) (xy 419.891315 -406.180254) (xy 419.876951 -406.194617)
			(xy 419.858186 -406.202396) (xy 419.84803 -406.202896) (xy 419.13175 -406.202896) (xy 419.121586 -406.202396)
			(xy 419.102799 -406.194634) (xy 419.088413 -406.180272) (xy 419.08062 -406.161497) (xy 419.080188 -406.151334)
			(xy 419.080188 -405.993346) (xy 419.079759 -405.984161) (xy 419.073259 -405.966976) (xy 419.067488 -405.959818)
			(xy 419.045693 -405.934171) (xy 419.007741 -405.878585) (xy 418.976705 -405.818861) (xy 418.953031 -405.755856)
			(xy 418.937057 -405.690473) (xy 418.929012 -405.623649) (xy 414.525968 -405.623649) (xy 414.525968 -406.723789)
			(xy 421.128626 -406.723789) (xy 421.128629 -406.656363) (xy 421.136708 -406.589421) (xy 421.152748 -406.52393)
			(xy 421.176518 -406.460832) (xy 421.207674 -406.401035) (xy 421.245769 -406.345401) (xy 421.267636 -406.319736)
			(xy 421.273447 -406.312601) (xy 421.279952 -406.295403) (xy 421.280336 -406.286208) (xy 421.280336 -405.793956)
			(xy 421.279939 -405.784768) (xy 421.273415 -405.767584) (xy 421.267636 -405.760428) (xy 421.245767 -405.734767)
			(xy 421.207676 -405.679132) (xy 421.176523 -405.619336) (xy 421.152758 -405.556239) (xy 421.136722 -405.490749)
			(xy 421.128645 -405.423809) (xy 421.128646 -405.356385) (xy 421.136723 -405.289445) (xy 421.15276 -405.223956)
			(xy 421.176526 -405.160859) (xy 421.207679 -405.101062) (xy 421.245771 -405.045429) (xy 421.267636 -405.019764)
			(xy 421.273435 -405.012621) (xy 421.279947 -404.995429) (xy 421.280336 -404.986236) (xy 421.280336 -404.828756)
			(xy 421.28075 -404.81864) (xy 421.288509 -404.799954) (xy 421.302828 -404.785659) (xy 421.321527 -404.777933)
			(xy 421.331644 -404.777448) (xy 422.047924 -404.777448) (xy 422.058028 -404.777964) (xy 422.076697 -404.7857)
			(xy 422.090989 -404.799986) (xy 422.098732 -404.818652) (xy 422.099232 -404.828756) (xy 422.099232 -404.986236)
			(xy 422.09964 -404.995423) (xy 422.106157 -405.012607) (xy 422.111932 -405.019764) (xy 422.133791 -405.045433)
			(xy 422.171878 -405.101068) (xy 422.203027 -405.160864) (xy 422.22679 -405.22396) (xy 422.242825 -405.289448)
			(xy 422.2509 -405.356386) (xy 422.250901 -405.423808) (xy 422.242826 -405.490746) (xy 422.226792 -405.556234)
			(xy 422.203029 -405.619331) (xy 422.20075 -405.623707) (xy 423.328805 -405.623707) (xy 423.328805 -405.556284)
			(xy 423.336882 -405.489345) (xy 423.352917 -405.423856) (xy 423.376681 -405.360759) (xy 423.407832 -405.300962)
			(xy 423.44592 -405.245328) (xy 423.467784 -405.219662) (xy 423.473577 -405.212514) (xy 423.480094 -405.195326)
			(xy 423.480484 -405.186134) (xy 423.480484 -404.693882) (xy 423.480086 -404.684693) (xy 423.473564 -404.667509)
			(xy 423.467784 -404.660354) (xy 423.445942 -404.634671) (xy 423.407854 -404.579038) (xy 423.376703 -404.519245)
			(xy 423.352938 -404.45615) (xy 423.336902 -404.390663) (xy 423.328825 -404.323727) (xy 423.328823 -404.256306)
			(xy 423.336896 -404.189369) (xy 423.352929 -404.123882) (xy 423.37669 -404.060786) (xy 423.407837 -404.00099)
			(xy 423.445922 -403.945355) (xy 423.467784 -403.91969) (xy 423.473565 -403.912534) (xy 423.48009 -403.895352)
			(xy 423.480484 -403.886162) (xy 423.480484 -403.728682) (xy 423.480913 -403.718549) (xy 423.488655 -403.699819)
			(xy 423.502959 -403.685461) (xy 423.521661 -403.677651) (xy 423.531792 -403.67712) (xy 424.248072 -403.67712)
			(xy 424.258227 -403.677545) (xy 424.276983 -403.685335) (xy 424.291308 -403.699731) (xy 424.299005 -403.718525)
			(xy 424.29938 -403.728682) (xy 424.29938 -403.886162) (xy 424.299813 -403.895347) (xy 424.306311 -403.912531)
			(xy 424.31208 -403.91969) (xy 424.333966 -403.945337) (xy 424.372056 -404.000974) (xy 424.403207 -404.060772)
			(xy 424.42697 -404.123872) (xy 424.443005 -404.189363) (xy 424.451079 -404.256304) (xy 424.451077 -404.323729)
			(xy 424.442999 -404.39067) (xy 424.426961 -404.45616) (xy 424.403193 -404.519258) (xy 424.372039 -404.579055)
			(xy 424.333946 -404.634689) (xy 424.31208 -404.660354) (xy 424.306276 -404.667494) (xy 424.299766 -404.684688)
			(xy 424.29938 -404.693882) (xy 424.29938 -405.186134) (xy 424.299778 -405.195322) (xy 424.306301 -405.212506)
			(xy 424.31208 -405.219662) (xy 424.333939 -405.245332) (xy 424.372029 -405.300965) (xy 424.403181 -405.360761)
			(xy 424.426946 -405.423857) (xy 424.442983 -405.489346) (xy 424.45106 -405.556284) (xy 424.45106 -405.623707)
			(xy 424.442985 -405.690646) (xy 424.426949 -405.756134) (xy 424.403185 -405.819231) (xy 424.372034 -405.879027)
			(xy 424.333944 -405.934661) (xy 424.31208 -405.960326) (xy 424.306288 -405.967474) (xy 424.299771 -405.984662)
			(xy 424.29938 -405.993854) (xy 424.29938 -406.151334) (xy 424.298902 -406.16146) (xy 424.291167 -406.180179)
			(xy 424.276878 -406.194533) (xy 424.258196 -406.202355) (xy 424.248072 -406.202896) (xy 423.531792 -406.202896)
			(xy 423.521637 -406.202485) (xy 423.502884 -406.194686) (xy 423.48856 -406.180286) (xy 423.480862 -406.161491)
			(xy 423.480484 -406.151334) (xy 423.480484 -405.993854) (xy 423.480051 -405.984669) (xy 423.473553 -405.967484)
			(xy 423.467784 -405.960326) (xy 423.445915 -405.934665) (xy 423.407827 -405.87903) (xy 423.376678 -405.819233)
			(xy 423.352915 -405.756135) (xy 423.33688 -405.690646) (xy 423.328805 -405.623707) (xy 422.20075 -405.623707)
			(xy 422.171881 -405.679127) (xy 422.133795 -405.734762) (xy 422.111932 -405.760428) (xy 422.106133 -405.767571)
			(xy 422.099622 -405.784763) (xy 422.099232 -405.793956) (xy 422.099232 -406.286208) (xy 422.099654 -406.295394)
			(xy 422.106161 -406.312577) (xy 422.111932 -406.319736) (xy 422.133763 -406.345428) (xy 422.171851 -406.401059)
			(xy 422.203001 -406.460852) (xy 422.226766 -406.523945) (xy 422.242803 -406.589431) (xy 422.250881 -406.656366)
			(xy 422.250883 -406.72373) (xy 425.528945 -406.72373) (xy 425.528948 -406.656422) (xy 425.536995 -406.589598)
			(xy 425.552971 -406.524214) (xy 425.576647 -406.461208) (xy 425.607683 -406.401484) (xy 425.645635 -406.345896)
			(xy 425.667424 -406.320244) (xy 425.67323 -406.313105) (xy 425.679738 -406.29591) (xy 425.680124 -406.286716)
			(xy 425.680124 -405.793448) (xy 425.679685 -405.784264) (xy 425.673191 -405.76708) (xy 425.667424 -405.75992)
			(xy 425.645633 -405.734271) (xy 425.607685 -405.678684) (xy 425.576653 -405.61896) (xy 425.552981 -405.555955)
			(xy 425.537009 -405.490572) (xy 425.528965 -405.42375) (xy 425.528965 -405.356444) (xy 425.53701 -405.289622)
			(xy 425.552983 -405.22424) (xy 425.576655 -405.161235) (xy 425.607688 -405.101511) (xy 425.645636 -405.045924)
			(xy 425.667424 -405.020272) (xy 425.673218 -405.013125) (xy 425.679733 -404.995936) (xy 425.680124 -404.986744)
			(xy 425.680124 -404.828756) (xy 425.680486 -404.818596) (xy 425.688301 -404.799838) (xy 425.702716 -404.785515)
			(xy 425.721523 -404.777822) (xy 425.731686 -404.777448) (xy 426.447966 -404.777448) (xy 426.458091 -404.777955)
			(xy 426.476813 -404.785673) (xy 426.491171 -404.799953) (xy 426.49899 -404.818633) (xy 426.499528 -404.828756)
			(xy 426.499528 -404.986744) (xy 426.499911 -404.995934) (xy 426.506443 -405.013119) (xy 426.512228 -405.020272)
			(xy 426.534013 -405.045927) (xy 426.571964 -405.101512) (xy 426.602999 -405.161235) (xy 426.626674 -405.224239)
			(xy 426.642648 -405.289622) (xy 426.650693 -405.356444) (xy 426.650693 -405.42375) (xy 426.642649 -405.490573)
			(xy 426.626675 -405.555955) (xy 426.603002 -405.618959) (xy 426.600565 -405.623649) (xy 427.7291 -405.623649)
			(xy 427.729101 -405.556342) (xy 427.737146 -405.489519) (xy 427.753121 -405.424136) (xy 427.776796 -405.361131)
			(xy 427.807831 -405.301408) (xy 427.845783 -405.245822) (xy 427.867572 -405.22017) (xy 427.873373 -405.213028)
			(xy 427.879883 -405.195835) (xy 427.880272 -405.186642) (xy 427.880272 -404.693374) (xy 427.879881 -404.684185)
			(xy 427.873355 -404.667) (xy 427.867572 -404.659846) (xy 427.845805 -404.634176) (xy 427.807853 -404.578593)
			(xy 427.776817 -404.518872) (xy 427.753142 -404.45587) (xy 427.737166 -404.39049) (xy 427.72912 -404.323668)
			(xy 427.729118 -404.256365) (xy 427.73716 -404.189543) (xy 427.753132 -404.124162) (xy 427.776804 -404.061158)
			(xy 427.807836 -404.001435) (xy 427.845785 -403.94585) (xy 427.867572 -403.920198) (xy 427.873361 -403.913048)
			(xy 427.879878 -403.895861) (xy 427.880272 -403.88667) (xy 427.880272 -403.728682) (xy 427.88065 -403.718505)
			(xy 427.888447 -403.699703) (xy 427.902847 -403.685318) (xy 427.921657 -403.67754) (xy 427.931834 -403.67712)
			(xy 428.648114 -403.67712) (xy 428.65827 -403.677622) (xy 428.677036 -403.685397) (xy 428.6914 -403.69976)
			(xy 428.699178 -403.718526) (xy 428.699676 -403.728682) (xy 428.699676 -403.88667) (xy 428.700106 -403.895855)
			(xy 428.706607 -403.913039) (xy 428.712376 -403.920198) (xy 428.734185 -403.945833) (xy 428.772132 -404.001422)
			(xy 428.803164 -404.061148) (xy 428.826835 -404.124155) (xy 428.842806 -404.189539) (xy 428.850848 -404.256363)
			(xy 428.850846 -404.32367) (xy 428.8428 -404.390494) (xy 428.826825 -404.455877) (xy 428.80315 -404.518882)
			(xy 428.772115 -404.578607) (xy 428.734165 -404.634194) (xy 428.712376 -404.659846) (xy 428.706575 -404.666988)
			(xy 428.700064 -404.684181) (xy 428.699676 -404.693374) (xy 428.699676 -405.186642) (xy 428.700071 -405.195831)
			(xy 428.706596 -405.213015) (xy 428.712376 -405.22017) (xy 428.734157 -405.245827) (xy 428.772106 -405.301413)
			(xy 428.803138 -405.361136) (xy 428.826811 -405.42414) (xy 428.842784 -405.489522) (xy 428.850828 -405.556343)
			(xy 428.850829 -405.623648) (xy 428.842785 -405.69047) (xy 428.826813 -405.755851) (xy 428.803142 -405.818856)
			(xy 428.77211 -405.878579) (xy 428.734163 -405.934166) (xy 428.712376 -405.959818) (xy 428.706587 -405.966968)
			(xy 428.700068 -405.984155) (xy 428.699676 -405.993346) (xy 428.699676 -406.151334) (xy 428.699195 -406.161492)
			(xy 428.691412 -406.180259) (xy 428.677043 -406.194623) (xy 428.658272 -406.202399) (xy 428.648114 -406.202896)
			(xy 427.931834 -406.202896) (xy 427.921683 -406.202339) (xy 427.902921 -406.194583) (xy 427.888556 -406.180236)
			(xy 427.880774 -406.161485) (xy 427.880272 -406.151334) (xy 427.880272 -405.993346) (xy 427.879846 -405.98416)
			(xy 427.873344 -405.966976) (xy 427.867572 -405.959818) (xy 427.845777 -405.934171) (xy 427.807827 -405.878585)
			(xy 427.776792 -405.818861) (xy 427.753118 -405.755855) (xy 427.737144 -405.690472) (xy 427.7291 -405.623649)
			(xy 426.600565 -405.623649) (xy 426.571967 -405.678683) (xy 426.534016 -405.734268) (xy 426.512228 -405.75992)
			(xy 426.506432 -405.767065) (xy 426.499919 -405.784256) (xy 426.499528 -405.793448) (xy 426.499528 -406.286716)
			(xy 426.499924 -406.295905) (xy 426.506447 -406.313089) (xy 426.512228 -406.320244) (xy 426.533985 -406.345922)
			(xy 426.571937 -406.401504) (xy 426.602974 -406.461223) (xy 426.62665 -406.524225) (xy 426.642626 -406.589604)
			(xy 426.650673 -406.656424) (xy 426.650676 -406.723728) (xy 426.650669 -406.723789) (xy 429.928714 -406.723789)
			(xy 429.928717 -406.656363) (xy 429.936796 -406.589422) (xy 429.952835 -406.523931) (xy 429.976604 -406.460832)
			(xy 430.00776 -406.401036) (xy 430.045853 -406.345401) (xy 430.06772 -406.319736) (xy 430.073529 -406.312599)
			(xy 430.080035 -406.295402) (xy 430.08042 -406.286208) (xy 430.08042 -405.793956) (xy 430.080027 -405.784767)
			(xy 430.073501 -405.767583) (xy 430.06772 -405.760428) (xy 430.045851 -405.734766) (xy 430.007761 -405.679132)
			(xy 429.97661 -405.619335) (xy 429.952845 -405.556238) (xy 429.936809 -405.490748) (xy 429.928733 -405.423809)
			(xy 429.928734 -405.356385) (xy 429.93681 -405.289446) (xy 429.952847 -405.223956) (xy 429.976612 -405.160859)
			(xy 430.007765 -405.101063) (xy 430.045855 -405.045429) (xy 430.06772 -405.019764) (xy 430.073517 -405.012619)
			(xy 430.080031 -404.995428) (xy 430.08042 -404.986236) (xy 430.08042 -404.828756) (xy 430.08085 -404.818642)
			(xy 430.088605 -404.799959) (xy 430.102919 -404.785665) (xy 430.121613 -404.777935) (xy 430.131728 -404.777448)
			(xy 430.848008 -404.777448) (xy 430.858111 -404.777977) (xy 430.876779 -404.785708) (xy 430.891072 -404.799991)
			(xy 430.898815 -404.818654) (xy 430.899316 -404.828756) (xy 430.899316 -404.986236) (xy 430.899705 -404.995425)
			(xy 430.906233 -405.01261) (xy 430.912016 -405.019764) (xy 430.933875 -405.045433) (xy 430.971963 -405.101067)
			(xy 431.003113 -405.160863) (xy 431.026877 -405.223959) (xy 431.042912 -405.289448) (xy 431.050988 -405.356385)
			(xy 431.050989 -405.423809) (xy 431.042913 -405.490746) (xy 431.026879 -405.556235) (xy 431.003116 -405.619331)
			(xy 431.000867 -405.623648) (xy 432.128891 -405.623648) (xy 432.128892 -405.556343) (xy 432.136937 -405.489519)
			(xy 432.152911 -405.424136) (xy 432.176585 -405.361132) (xy 432.207621 -405.301408) (xy 432.245571 -405.245822)
			(xy 432.26736 -405.22017) (xy 432.273159 -405.213027) (xy 432.279671 -405.195835) (xy 432.28006 -405.186642)
			(xy 432.28006 -404.693374) (xy 432.279649 -404.684187) (xy 432.273134 -404.667004) (xy 432.26736 -404.659846)
			(xy 432.245593 -404.634176) (xy 432.207643 -404.578593) (xy 432.176607 -404.518872) (xy 432.152932 -404.45587)
			(xy 432.136957 -404.390489) (xy 432.128911 -404.323668) (xy 432.128909 -404.256365) (xy 432.136951 -404.189543)
			(xy 432.152922 -404.124162) (xy 432.176594 -404.061158) (xy 432.207626 -404.001436) (xy 432.245573 -403.94585)
			(xy 432.26736 -403.920198) (xy 432.273147 -403.913047) (xy 432.279666 -403.895861) (xy 432.28006 -403.88667)
			(xy 432.28006 -403.728682) (xy 432.28045 -403.718507) (xy 432.288245 -403.699707) (xy 432.302641 -403.685322)
			(xy 432.321446 -403.677542) (xy 432.331622 -403.67712) (xy 433.047902 -403.67712) (xy 433.058058 -403.677631)
			(xy 433.076823 -403.685403) (xy 433.091188 -403.699763) (xy 433.098965 -403.718526) (xy 433.099464 -403.728682)
			(xy 433.099464 -403.88667) (xy 433.099897 -403.895855) (xy 433.106396 -403.913039) (xy 433.112164 -403.920198)
			(xy 433.133973 -403.945832) (xy 433.171921 -404.001421) (xy 433.202954 -404.061147) (xy 433.226625 -404.124154)
			(xy 433.242596 -404.189539) (xy 433.250639 -404.256363) (xy 433.250637 -404.32367) (xy 433.24259 -404.390494)
			(xy 433.226615 -404.455877) (xy 433.20294 -404.518883) (xy 433.171904 -404.578607) (xy 433.133953 -404.634194)
			(xy 433.112164 -404.659846) (xy 433.106361 -404.666986) (xy 433.099851 -404.684181) (xy 433.099464 -404.693374)
			(xy 433.099464 -405.186642) (xy 433.099862 -405.19583) (xy 433.106385 -405.213014) (xy 433.112164 -405.22017)
			(xy 433.133946 -405.245827) (xy 433.171895 -405.301413) (xy 433.202928 -405.361136) (xy 433.226601 -405.42414)
			(xy 433.242574 -405.489521) (xy 433.250619 -405.556343) (xy 433.250619 -405.623648) (xy 433.242576 -405.69047)
			(xy 433.226604 -405.755852) (xy 433.202932 -405.818856) (xy 433.171899 -405.878579) (xy 433.133951 -405.934166)
			(xy 433.112164 -405.959818) (xy 433.106373 -405.966967) (xy 433.099856 -405.984155) (xy 433.099464 -405.993346)
			(xy 433.099464 -406.151334) (xy 433.098995 -406.161494) (xy 433.091209 -406.180263) (xy 433.076836 -406.194627)
			(xy 433.058062 -406.202401) (xy 433.047902 -406.202896) (xy 432.331622 -406.202896) (xy 432.32147 -406.20235)
			(xy 432.302708 -406.194589) (xy 432.288343 -406.180239) (xy 432.280561 -406.161486) (xy 432.28006 -406.151334)
			(xy 432.28006 -405.993346) (xy 432.279614 -405.984163) (xy 432.273124 -405.966979) (xy 432.26736 -405.959818)
			(xy 432.245566 -405.934171) (xy 432.207616 -405.878584) (xy 432.176582 -405.81886) (xy 432.152908 -405.755855)
			(xy 432.136935 -405.690472) (xy 432.128891 -405.623648) (xy 431.000867 -405.623648) (xy 430.971966 -405.679128)
			(xy 430.933879 -405.734762) (xy 430.912016 -405.760428) (xy 430.906227 -405.767579) (xy 430.899707 -405.784765)
			(xy 430.899316 -405.793956) (xy 430.899316 -406.286208) (xy 430.899719 -406.295396) (xy 430.906237 -406.31258)
			(xy 430.912016 -406.319736) (xy 430.933848 -406.345427) (xy 430.971937 -406.401059) (xy 431.003088 -406.460851)
			(xy 431.026853 -406.523945) (xy 431.04289 -406.58943) (xy 431.050968 -406.656366) (xy 431.050971 -406.723729)
			(xy 434.329033 -406.723729) (xy 434.329036 -406.656422) (xy 434.337083 -406.589598) (xy 434.353058 -406.524215)
			(xy 434.376733 -406.461209) (xy 434.407769 -406.401484) (xy 434.445719 -406.345897) (xy 434.467508 -406.320244)
			(xy 434.473312 -406.313104) (xy 434.479822 -406.295909) (xy 434.480208 -406.286716) (xy 434.480208 -405.793448)
			(xy 434.479773 -405.784263) (xy 434.473276 -405.767079) (xy 434.467508 -405.75992) (xy 434.445717 -405.734271)
			(xy 434.407771 -405.678683) (xy 434.376739 -405.618959) (xy 434.353068 -405.555954) (xy 434.337096 -405.490572)
			(xy 434.329053 -405.423749) (xy 434.329053 -405.356445) (xy 434.337097 -405.289622) (xy 434.35307 -405.22424)
			(xy 434.376742 -405.161236) (xy 434.407774 -405.101512) (xy 434.445721 -405.045925) (xy 434.467508 -405.020272)
			(xy 434.4733 -405.013124) (xy 434.479817 -404.995935) (xy 434.480208 -404.986744) (xy 434.480208 -404.828756)
			(xy 434.480586 -404.818598) (xy 434.488397 -404.799843) (xy 434.502807 -404.785521) (xy 434.52161 -404.777824)
			(xy 434.53177 -404.777448) (xy 435.24805 -404.777448) (xy 435.258175 -404.777968) (xy 435.276896 -404.785681)
			(xy 435.291254 -404.799957) (xy 435.299074 -404.818634) (xy 435.299612 -404.828756) (xy 435.299612 -404.986744)
			(xy 435.299998 -404.995934) (xy 435.306528 -405.013118) (xy 435.312312 -405.020272) (xy 435.334097 -405.045927)
			(xy 435.372049 -405.101512) (xy 435.403086 -405.161234) (xy 435.426761 -405.224239) (xy 435.442735 -405.289621)
			(xy 435.450781 -405.356444) (xy 435.450781 -405.42375) (xy 435.442736 -405.490573) (xy 435.426762 -405.555956)
			(xy 435.403088 -405.61896) (xy 435.372052 -405.678683) (xy 435.334101 -405.734269) (xy 435.312312 -405.75992)
			(xy 435.306526 -405.767073) (xy 435.300005 -405.784257) (xy 435.299612 -405.793448) (xy 435.299612 -406.286716)
			(xy 435.300012 -406.295904) (xy 435.306532 -406.313089) (xy 435.312312 -406.320244) (xy 435.33407 -406.345921)
			(xy 435.372023 -406.401503) (xy 435.40306 -406.461223) (xy 435.426737 -406.524224) (xy 435.442713 -406.589604)
			(xy 435.450761 -406.656424) (xy 435.450764 -406.723728) (xy 435.442722 -406.790549) (xy 435.426751 -406.85593)
			(xy 435.40308 -406.918933) (xy 435.372048 -406.978656) (xy 435.334099 -407.034241) (xy 435.312312 -407.059892)
			(xy 435.306538 -407.067053) (xy 435.300009 -407.084231) (xy 435.299612 -407.09342) (xy 435.299612 -407.251408)
			(xy 435.299185 -407.261561) (xy 435.291389 -407.280311) (xy 435.276994 -407.294634) (xy 435.258205 -407.302335)
			(xy 435.24805 -407.302716) (xy 434.53177 -407.302716) (xy 434.521636 -407.302297) (xy 434.502906 -407.294551)
			(xy 434.488549 -407.280244) (xy 434.480739 -407.26154) (xy 434.480208 -407.251408) (xy 434.480208 -407.09342)
			(xy 434.479786 -407.084234) (xy 434.47328 -407.06705) (xy 434.467508 -407.059892) (xy 434.44569 -407.034265)
			(xy 434.407744 -406.978674) (xy 434.376714 -406.918947) (xy 434.353044 -406.855939) (xy 434.337074 -406.790554)
			(xy 434.329033 -406.723729) (xy 431.050971 -406.723729) (xy 431.050971 -406.723786) (xy 431.042899 -406.790722)
			(xy 431.026867 -406.856209) (xy 431.003107 -406.919305) (xy 430.971961 -406.9791) (xy 430.933877 -407.034735)
			(xy 430.912016 -407.0604) (xy 430.906239 -407.067559) (xy 430.899712 -407.084739) (xy 430.899316 -407.093928)
			(xy 430.899316 -407.251408) (xy 430.898822 -407.261515) (xy 430.891084 -407.28019) (xy 430.87679 -407.294484)
			(xy 430.858115 -407.302222) (xy 430.848008 -407.302716) (xy 430.131728 -407.302716) (xy 430.121609 -407.302262)
			(xy 430.102909 -407.294526) (xy 430.088595 -407.280221) (xy 430.080845 -407.261526) (xy 430.08042 -407.251408)
			(xy 430.08042 -407.093928) (xy 430.079992 -407.084743) (xy 430.07349 -407.067559) (xy 430.06772 -407.0604)
			(xy 430.045824 -407.034761) (xy 430.007735 -406.979123) (xy 429.976584 -406.919324) (xy 429.952821 -406.856223)
			(xy 429.936787 -406.790731) (xy 429.928714 -406.723789) (xy 426.650669 -406.723789) (xy 426.642634 -406.790548)
			(xy 426.626664 -406.855929) (xy 426.602993 -406.918933) (xy 426.571962 -406.978655) (xy 426.534015 -407.03424)
			(xy 426.512228 -407.059892) (xy 426.506444 -407.067045) (xy 426.499924 -407.08423) (xy 426.499528 -407.09342)
			(xy 426.499528 -407.251408) (xy 426.499085 -407.261559) (xy 426.491292 -407.280306) (xy 426.476903 -407.294628)
			(xy 426.458119 -407.302333) (xy 426.447966 -407.302716) (xy 425.731686 -407.302716) (xy 425.721553 -407.302283)
			(xy 425.702823 -407.294543) (xy 425.688466 -407.28024) (xy 425.680655 -407.261539) (xy 425.680124 -407.251408)
			(xy 425.680124 -407.09342) (xy 425.679699 -407.084235) (xy 425.673195 -407.06705) (xy 425.667424 -407.059892)
			(xy 425.645605 -407.034266) (xy 425.607658 -406.978675) (xy 425.576627 -406.918948) (xy 425.552957 -406.85594)
			(xy 425.536987 -406.790555) (xy 425.528945 -406.72373) (xy 422.250883 -406.72373) (xy 422.250883 -406.723786)
			(xy 422.242811 -406.790722) (xy 422.22678 -406.856209) (xy 422.203021 -406.919304) (xy 422.171876 -406.9791)
			(xy 422.133793 -407.034734) (xy 422.111932 -407.0604) (xy 422.106145 -407.067551) (xy 422.099626 -407.084737)
			(xy 422.099232 -407.093928) (xy 422.099232 -407.251408) (xy 422.098722 -407.261513) (xy 422.090988 -407.280185)
			(xy 422.076699 -407.294479) (xy 422.058029 -407.302219) (xy 422.047924 -407.302716) (xy 421.331644 -407.302716)
			(xy 421.321526 -407.302248) (xy 421.302827 -407.294518) (xy 421.288512 -407.280217) (xy 421.280762 -407.261525)
			(xy 421.280336 -407.251408) (xy 421.280336 -407.093928) (xy 421.279904 -407.084743) (xy 421.273405 -407.067559)
			(xy 421.267636 -407.0604) (xy 421.245739 -407.034761) (xy 421.207649 -406.979124) (xy 421.176498 -406.919324)
			(xy 421.152734 -406.856224) (xy 421.1367 -406.790731) (xy 421.128626 -406.723789) (xy 414.525968 -406.723789)
			(xy 414.525968 -409.523827) (xy 418.928991 -409.523827) (xy 418.928995 -409.456519) (xy 418.937043 -409.389693)
			(xy 418.953021 -409.324308) (xy 418.9767 -409.261302) (xy 419.00774 -409.201577) (xy 419.045697 -409.145992)
			(xy 419.067488 -409.12034) (xy 419.073291 -409.113199) (xy 419.079802 -409.096005) (xy 419.080188 -409.086812)
			(xy 419.080188 -408.593544) (xy 419.079759 -408.584359) (xy 419.073259 -408.567174) (xy 419.067488 -408.560016)
			(xy 419.045691 -408.534371) (xy 419.007739 -408.478785) (xy 418.976704 -408.419061) (xy 418.953029 -408.356055)
			(xy 418.937055 -408.290671) (xy 418.929011 -408.223847) (xy 418.929012 -408.156541) (xy 418.937057 -408.089717)
			(xy 418.953033 -408.024333) (xy 418.976708 -407.961328) (xy 419.007745 -407.901605) (xy 419.045698 -407.84602)
			(xy 419.067488 -407.820368) (xy 419.073279 -407.813219) (xy 419.079797 -407.796031) (xy 419.080188 -407.78684)
			(xy 419.080188 -407.628852) (xy 419.080582 -407.618696) (xy 419.088391 -407.599945) (xy 419.102796 -407.585624)
			(xy 419.121592 -407.577924) (xy 419.13175 -407.577544) (xy 419.84803 -407.577544) (xy 419.858159 -407.578002)
			(xy 419.876882 -407.58574) (xy 419.891237 -407.600035) (xy 419.899055 -407.618725) (xy 419.899592 -407.628852)
			(xy 419.899592 -407.78684) (xy 419.899985 -407.796029) (xy 419.906511 -407.813213) (xy 419.912292 -407.820368)
			(xy 419.934071 -407.846027) (xy 419.972018 -407.901613) (xy 420.00305 -407.961336) (xy 420.026722 -408.02434)
			(xy 420.042694 -408.089721) (xy 420.050739 -408.156542) (xy 420.050739 -408.223846) (xy 420.042697 -408.290667)
			(xy 420.026725 -408.356049) (xy 420.003055 -408.419053) (xy 419.972024 -408.478776) (xy 419.934078 -408.534363)
			(xy 419.912292 -408.560016) (xy 419.906505 -408.567168) (xy 419.899985 -408.584353) (xy 419.899592 -408.593544)
			(xy 419.899592 -409.086812) (xy 419.899998 -409.096) (xy 419.906515 -409.113184) (xy 419.912292 -409.12034)
			(xy 419.934043 -409.146022) (xy 419.971991 -409.201605) (xy 420.003024 -409.261324) (xy 420.026698 -409.324325)
			(xy 420.042672 -409.389703) (xy 420.050719 -409.456522) (xy 420.050722 -409.523824) (xy 420.042682 -409.590643)
			(xy 420.026714 -409.656023) (xy 420.003047 -409.719026) (xy 419.972019 -409.778749) (xy 419.934077 -409.834336)
			(xy 419.912292 -409.859988) (xy 419.906475 -409.867118) (xy 419.899973 -409.88432) (xy 419.899592 -409.893516)
			(xy 419.899592 -410.051504) (xy 419.899181 -410.061659) (xy 419.891383 -410.080413) (xy 419.876983 -410.094737)
			(xy 419.858187 -410.102435) (xy 419.84803 -410.102812) (xy 419.13175 -410.102812) (xy 419.121633 -410.102234)
			(xy 419.102923 -410.094532) (xy 419.088567 -410.080274) (xy 419.080736 -410.061618) (xy 419.080188 -410.051504)
			(xy 419.080188 -409.893516) (xy 419.079773 -409.884329) (xy 419.073263 -409.867145) (xy 419.067488 -409.859988)
			(xy 419.045663 -409.834366) (xy 419.007713 -409.778776) (xy 418.976678 -409.719049) (xy 418.953005 -409.65604)
			(xy 418.937033 -409.590654) (xy 418.928991 -409.523827) (xy 414.525968 -409.523827) (xy 414.525968 -410.623701)
			(xy 421.128637 -410.623701) (xy 421.128638 -410.556275) (xy 421.136716 -410.489335) (xy 421.152755 -410.423845)
			(xy 421.176522 -410.360747) (xy 421.207677 -410.300951) (xy 421.24577 -410.245317) (xy 421.267636 -410.219652)
			(xy 421.27344 -410.212512) (xy 421.279949 -410.195317) (xy 421.280336 -410.186124) (xy 421.280336 -409.693872)
			(xy 421.279931 -409.684684) (xy 421.273413 -409.667501) (xy 421.267636 -409.660344) (xy 421.245783 -409.63467)
			(xy 421.207691 -409.579037) (xy 421.176538 -409.519243) (xy 421.152771 -409.456147) (xy 421.136734 -409.390659)
			(xy 421.128657 -409.323721) (xy 421.128656 -409.256297) (xy 421.136731 -409.189359) (xy 421.152766 -409.12387)
			(xy 421.176531 -409.060774) (xy 421.207682 -409.000978) (xy 421.245771 -408.945345) (xy 421.267636 -408.91968)
			(xy 421.273428 -408.912532) (xy 421.279945 -408.895343) (xy 421.280336 -408.886152) (xy 421.280336 -408.728672)
			(xy 421.280694 -408.718543) (xy 421.288458 -408.699832) (xy 421.302793 -408.685517) (xy 421.321515 -408.67778)
			(xy 421.331644 -408.677364) (xy 422.047924 -408.677364) (xy 422.05803 -408.677864) (xy 422.076702 -408.685603)
			(xy 422.090994 -408.699895) (xy 422.098735 -408.718566) (xy 422.099232 -408.728672) (xy 422.099232 -408.886152)
			(xy 422.09968 -408.895335) (xy 422.106169 -408.912519) (xy 422.111932 -408.91968) (xy 422.133807 -408.945336)
			(xy 422.171893 -409.000973) (xy 422.203041 -409.06077) (xy 422.226803 -409.123868) (xy 422.242837 -409.189358)
			(xy 422.250911 -409.256297) (xy 422.25091 -409.323721) (xy 422.242834 -409.39066) (xy 422.226798 -409.456149)
			(xy 422.203034 -409.519246) (xy 422.200617 -409.523886) (xy 423.328784 -409.523886) (xy 423.328787 -409.45646)
			(xy 423.336866 -409.389519) (xy 423.352905 -409.324029) (xy 423.376672 -409.26093) (xy 423.407826 -409.201133)
			(xy 423.445918 -409.145498) (xy 423.467784 -409.119832) (xy 423.47359 -409.112693) (xy 423.4801 -409.095498)
			(xy 423.480484 -409.086304) (xy 423.480484 -408.594052) (xy 423.480052 -408.584867) (xy 423.473554 -408.567682)
			(xy 423.467784 -408.560524) (xy 423.445913 -408.534865) (xy 423.407825 -408.479229) (xy 423.376676 -408.419432)
			(xy 423.352913 -408.356334) (xy 423.336878 -408.290845) (xy 423.328803 -408.223906) (xy 423.328804 -408.156482)
			(xy 423.336881 -408.089543) (xy 423.352916 -408.024054) (xy 423.376681 -407.960957) (xy 423.407832 -407.901161)
			(xy 423.44592 -407.845526) (xy 423.467784 -407.81986) (xy 423.473578 -407.812713) (xy 423.480095 -407.795524)
			(xy 423.480484 -407.786332) (xy 423.480484 -407.628852) (xy 423.480946 -407.618742) (xy 423.488696 -407.600066)
			(xy 423.503 -407.585774) (xy 423.521682 -407.578038) (xy 423.531792 -407.577544) (xy 424.248072 -407.577544)
			(xy 424.258172 -407.578106) (xy 424.276839 -407.585825) (xy 424.291133 -407.600097) (xy 424.298879 -407.618753)
			(xy 424.29938 -407.628852) (xy 424.29938 -407.786332) (xy 424.299779 -407.79552) (xy 424.306301 -407.812704)
			(xy 424.31208 -407.81986) (xy 424.333937 -407.845531) (xy 424.372027 -407.901165) (xy 424.403179 -407.96096)
			(xy 424.426945 -408.024056) (xy 424.442981 -408.089544) (xy 424.451058 -408.156482) (xy 424.451059 -408.223906)
			(xy 424.442984 -408.290844) (xy 424.426948 -408.356333) (xy 424.403184 -408.419429) (xy 424.372033 -408.479225)
			(xy 424.333944 -408.534859) (xy 424.31208 -408.560524) (xy 424.306288 -408.567673) (xy 424.299771 -408.584861)
			(xy 424.29938 -408.594052) (xy 424.29938 -409.086304) (xy 424.299792 -409.095491) (xy 424.306305 -409.112675)
			(xy 424.31208 -409.119832) (xy 424.333909 -409.145526) (xy 424.372 -409.201156) (xy 424.403154 -409.260948)
			(xy 424.426921 -409.324041) (xy 424.442959 -409.389527) (xy 424.451039 -409.456462) (xy 424.451042 -409.523884)
			(xy 424.442969 -409.59082) (xy 424.426937 -409.656307) (xy 424.403176 -409.719403) (xy 424.372028 -409.779198)
			(xy 424.333943 -409.834831) (xy 424.31208 -409.860496) (xy 424.3063 -409.867653) (xy 424.299776 -409.884835)
			(xy 424.29938 -409.894024) (xy 424.29938 -410.051504) (xy 424.298987 -410.061629) (xy 424.291234 -410.080337)
			(xy 424.27691 -410.094651) (xy 424.258197 -410.102393) (xy 424.248072 -410.102812) (xy 423.531792 -410.102812)
			(xy 423.521684 -410.102322) (xy 423.503008 -410.094584) (xy 423.488714 -410.080288) (xy 423.480978 -410.061612)
			(xy 423.480484 -410.051504) (xy 423.480484 -409.894024) (xy 423.480066 -409.884838) (xy 423.473558 -409.867653)
			(xy 423.467784 -409.860496) (xy 423.445885 -409.83486) (xy 423.407799 -409.779221) (xy 423.37665 -409.71942)
			(xy 423.352889 -409.65632) (xy 423.336856 -409.590827) (xy 423.328784 -409.523886) (xy 422.200617 -409.523886)
			(xy 422.171884 -409.579043) (xy 422.133796 -409.634678) (xy 422.111932 -409.660344) (xy 422.106126 -409.667482)
			(xy 422.099619 -409.684678) (xy 422.099232 -409.693872) (xy 422.099232 -410.186124) (xy 422.099646 -410.19531)
			(xy 422.106159 -410.212494) (xy 422.111932 -410.219652) (xy 422.133779 -410.245331) (xy 422.171866 -410.300964)
			(xy 422.203016 -410.360759) (xy 422.22678 -410.423854) (xy 422.242815 -410.489341) (xy 422.250892 -410.556277)
			(xy 422.250893 -410.623641) (xy 425.528957 -410.623641) (xy 425.528958 -410.556335) (xy 425.537003 -410.489512)
			(xy 425.552978 -410.424129) (xy 425.576652 -410.361123) (xy 425.607686 -410.301399) (xy 425.645636 -410.245812)
			(xy 425.667424 -410.22016) (xy 425.673223 -410.213017) (xy 425.679735 -410.195825) (xy 425.680124 -410.186632)
			(xy 425.680124 -409.693364) (xy 425.679726 -409.684176) (xy 425.673203 -409.666992) (xy 425.667424 -409.659836)
			(xy 425.645648 -409.634174) (xy 425.6077 -409.578589) (xy 425.576667 -409.518866) (xy 425.552994 -409.455863)
			(xy 425.537021 -409.390482) (xy 425.528976 -409.323661) (xy 425.528975 -409.256357) (xy 425.537018 -409.189536)
			(xy 425.552989 -409.124154) (xy 425.57666 -409.06115) (xy 425.607691 -409.001427) (xy 425.645637 -408.94584)
			(xy 425.667424 -408.920188) (xy 425.673211 -408.913036) (xy 425.679731 -408.895851) (xy 425.680124 -408.88666)
			(xy 425.680124 -408.728672) (xy 425.680499 -408.718513) (xy 425.688308 -408.699755) (xy 425.70272 -408.685432)
			(xy 425.721525 -408.677738) (xy 425.731686 -408.677364) (xy 426.447966 -408.677364) (xy 426.458093 -408.677855)
			(xy 426.476818 -408.685576) (xy 426.491177 -408.699862) (xy 426.498993 -408.718547) (xy 426.499528 -408.728672)
			(xy 426.499528 -408.88666) (xy 426.499951 -408.895846) (xy 426.506455 -408.913031) (xy 426.512228 -408.920188)
			(xy 426.534028 -408.94583) (xy 426.571979 -409.001417) (xy 426.603014 -409.061142) (xy 426.626687 -409.124148)
			(xy 426.64266 -409.189532) (xy 426.650704 -409.256356) (xy 426.650703 -409.323662) (xy 426.642657 -409.390486)
			(xy 426.626682 -409.45587) (xy 426.603006 -409.518875) (xy 426.600433 -409.523827) (xy 427.729079 -409.523827)
			(xy 427.729082 -409.456519) (xy 427.73713 -409.389693) (xy 427.753108 -409.324308) (xy 427.776786 -409.261302)
			(xy 427.807826 -409.201578) (xy 427.845781 -409.145992) (xy 427.867572 -409.12034) (xy 427.873385 -409.113207)
			(xy 427.879888 -409.096007) (xy 427.880272 -409.086812) (xy 427.880272 -408.593544) (xy 427.879847 -408.584358)
			(xy 427.873344 -408.567174) (xy 427.867572 -408.560016) (xy 427.845776 -408.534371) (xy 427.807825 -408.478784)
			(xy 427.77679 -408.41906) (xy 427.753116 -408.356054) (xy 427.737143 -408.290671) (xy 427.729099 -408.223847)
			(xy 427.7291 -408.156541) (xy 427.737145 -408.089717) (xy 427.75312 -408.024334) (xy 427.776795 -407.961329)
			(xy 427.807831 -407.901606) (xy 427.845783 -407.84602) (xy 427.867572 -407.820368) (xy 427.873373 -407.813227)
			(xy 427.879883 -407.796033) (xy 427.880272 -407.78684) (xy 427.880272 -407.628852) (xy 427.880682 -407.618698)
			(xy 427.888488 -407.59995) (xy 427.902887 -407.58563) (xy 427.921678 -407.577927) (xy 427.931834 -407.577544)
			(xy 428.648114 -407.577544) (xy 428.658242 -407.578015) (xy 428.676964 -407.585749) (xy 428.69132 -407.600039)
			(xy 428.699138 -407.618726) (xy 428.699676 -407.628852) (xy 428.699676 -407.78684) (xy 428.700072 -407.796029)
			(xy 428.706596 -407.813212) (xy 428.712376 -407.820368) (xy 428.734155 -407.846027) (xy 428.772104 -407.901613)
			(xy 428.803136 -407.961335) (xy 428.826809 -408.024339) (xy 428.842782 -408.08972) (xy 428.850827 -408.156542)
			(xy 428.850827 -408.223846) (xy 428.842784 -408.290668) (xy 428.826813 -408.356049) (xy 428.803141 -408.419054)
			(xy 428.77211 -408.478777) (xy 428.734163 -408.534364) (xy 428.712376 -408.560016) (xy 428.706587 -408.567167)
			(xy 428.700069 -408.584353) (xy 428.699676 -408.593544) (xy 428.699676 -409.086812) (xy 428.700086 -409.095999)
			(xy 428.7066 -409.113183) (xy 428.712376 -409.12034) (xy 428.734128 -409.146022) (xy 428.772077 -409.201604)
			(xy 428.803111 -409.261324) (xy 428.826785 -409.324324) (xy 428.84276 -409.389703) (xy 428.850806 -409.456522)
			(xy 428.85081 -409.523824) (xy 428.842769 -409.590644) (xy 428.826801 -409.656024) (xy 428.803133 -409.719027)
			(xy 428.772104 -409.778749) (xy 428.734161 -409.834335) (xy 428.712376 -409.859988) (xy 428.706557 -409.867117)
			(xy 428.700056 -409.88432) (xy 428.699676 -409.893516) (xy 428.699676 -410.051504) (xy 428.699281 -410.061661)
			(xy 428.69148 -410.080418) (xy 428.677074 -410.094742) (xy 428.658274 -410.102438) (xy 428.648114 -410.102812)
			(xy 427.931834 -410.102812) (xy 427.921716 -410.102247) (xy 427.903005 -410.09454) (xy 427.88865 -410.080278)
			(xy 427.88082 -410.061619) (xy 427.880272 -410.051504) (xy 427.880272 -409.893516) (xy 427.879861 -409.884329)
			(xy 427.873349 -409.867144) (xy 427.867572 -409.859988) (xy 427.845748 -409.834366) (xy 427.807798 -409.778776)
			(xy 427.776764 -409.719048) (xy 427.753092 -409.65604) (xy 427.73712 -409.590654) (xy 427.729079 -409.523827)
			(xy 426.600433 -409.523827) (xy 426.57197 -409.578598) (xy 426.534017 -409.634184) (xy 426.512228 -409.659836)
			(xy 426.506425 -409.666976) (xy 426.499916 -409.684171) (xy 426.499528 -409.693364) (xy 426.499528 -410.186632)
			(xy 426.499917 -410.195822) (xy 426.506445 -410.213006) (xy 426.512228 -410.22016) (xy 426.534001 -410.245825)
			(xy 426.571952 -410.301409) (xy 426.602988 -410.36113) (xy 426.626663 -410.424133) (xy 426.642638 -410.489514)
			(xy 426.650684 -410.556336) (xy 426.650686 -410.62364) (xy 426.650679 -410.623701) (xy 429.928725 -410.623701)
			(xy 429.928726 -410.556275) (xy 429.936804 -410.489336) (xy 429.952842 -410.423845) (xy 429.976609 -410.360748)
			(xy 430.007762 -410.300951) (xy 430.045854 -410.245317) (xy 430.06772 -410.219652) (xy 430.073522 -410.212511)
			(xy 430.080033 -410.195317) (xy 430.08042 -410.186124) (xy 430.08042 -409.693872) (xy 430.080019 -409.684684)
			(xy 430.073498 -409.6675) (xy 430.06772 -409.660344) (xy 430.045867 -409.634669) (xy 430.007777 -409.579037)
			(xy 429.976624 -409.519242) (xy 429.952859 -409.456146) (xy 429.936822 -409.390658) (xy 429.928745 -409.323721)
			(xy 429.928744 -409.256297) (xy 429.936819 -409.18936) (xy 429.952853 -409.123871) (xy 429.976617 -409.060775)
			(xy 430.007767 -409.000979) (xy 430.045856 -408.945345) (xy 430.06772 -408.91968) (xy 430.07351 -408.91253)
			(xy 430.080028 -408.895343) (xy 430.08042 -408.886152) (xy 430.08042 -408.728672) (xy 430.080863 -408.718559)
			(xy 430.088613 -408.699876) (xy 430.102923 -408.685582) (xy 430.121614 -408.677852) (xy 430.131728 -408.677364)
			(xy 430.848008 -408.677364) (xy 430.858113 -408.677878) (xy 430.876784 -408.685611) (xy 430.891077 -408.699899)
			(xy 430.898818 -408.718567) (xy 430.899316 -408.728672) (xy 430.899316 -408.886152) (xy 430.899745 -408.895337)
			(xy 430.906245 -408.912522) (xy 430.912016 -408.91968) (xy 430.933891 -408.945336) (xy 430.971979 -409.000972)
			(xy 431.003128 -409.06077) (xy 431.026891 -409.123868) (xy 431.042925 -409.189358) (xy 431.050999 -409.256297)
			(xy 431.050998 -409.323721) (xy 431.042922 -409.39066) (xy 431.026885 -409.456149) (xy 431.00312 -409.519247)
			(xy 431.000734 -409.523827) (xy 432.12887 -409.523827) (xy 432.128873 -409.456519) (xy 432.136921 -409.389693)
			(xy 432.152898 -409.324309) (xy 432.176576 -409.261303) (xy 432.207615 -409.201578) (xy 432.245569 -409.145992)
			(xy 432.26736 -409.12034) (xy 432.273172 -409.113206) (xy 432.279676 -409.096007) (xy 432.28006 -409.086812)
			(xy 432.28006 -408.593544) (xy 432.279615 -408.584361) (xy 432.273124 -408.567177) (xy 432.26736 -408.560016)
			(xy 432.245564 -408.53437) (xy 432.207614 -408.478784) (xy 432.17658 -408.419059) (xy 432.152907 -408.356054)
			(xy 432.136934 -408.290671) (xy 432.12889 -408.223847) (xy 432.128891 -408.156541) (xy 432.136936 -408.089717)
			(xy 432.15291 -408.024335) (xy 432.176585 -407.96133) (xy 432.20762 -407.901606) (xy 432.245571 -407.84602)
			(xy 432.26736 -407.820368) (xy 432.27316 -407.813226) (xy 432.279671 -407.796033) (xy 432.28006 -407.78684)
			(xy 432.28006 -407.628852) (xy 432.280482 -407.6187) (xy 432.288286 -407.599954) (xy 432.302681 -407.585634)
			(xy 432.321468 -407.577929) (xy 432.331622 -407.577544) (xy 433.047902 -407.577544) (xy 433.058029 -407.578025)
			(xy 433.076751 -407.585754) (xy 433.091108 -407.600042) (xy 433.098926 -407.618727) (xy 433.099464 -407.628852)
			(xy 433.099464 -407.78684) (xy 433.099863 -407.796028) (xy 433.106385 -407.813212) (xy 433.112164 -407.820368)
			(xy 433.133944 -407.846027) (xy 433.171893 -407.901612) (xy 433.202926 -407.961335) (xy 433.226599 -408.024339)
			(xy 433.242573 -408.08972) (xy 433.250618 -408.156542) (xy 433.250618 -408.223846) (xy 433.242575 -408.290668)
			(xy 433.226603 -408.35605) (xy 433.202931 -408.419054) (xy 433.171899 -408.478778) (xy 433.133951 -408.534364)
			(xy 433.112164 -408.560016) (xy 433.106374 -408.567165) (xy 433.099856 -408.584353) (xy 433.099464 -408.593544)
			(xy 433.099464 -409.086812) (xy 433.099876 -409.095999) (xy 433.106389 -409.113183) (xy 433.112164 -409.12034)
			(xy 433.133916 -409.146021) (xy 433.171866 -409.201604) (xy 433.2029 -409.261323) (xy 433.226575 -409.324324)
			(xy 433.24255 -409.389703) (xy 433.250597 -409.456522) (xy 433.250601 -409.523824) (xy 433.24256 -409.590644)
			(xy 433.226591 -409.656024) (xy 433.202922 -409.719027) (xy 433.171894 -409.77875) (xy 433.133949 -409.834336)
			(xy 433.112164 -409.859988) (xy 433.106343 -409.867116) (xy 433.099844 -409.88432) (xy 433.099464 -409.893516)
			(xy 433.099464 -410.051504) (xy 433.099081 -410.061663) (xy 433.091277 -410.080422) (xy 433.076868 -410.094747)
			(xy 433.058063 -410.10244) (xy 433.047902 -410.102812) (xy 432.331622 -410.102812) (xy 432.321503 -410.102257)
			(xy 432.302792 -410.094546) (xy 432.288437 -410.080281) (xy 432.280608 -410.06162) (xy 432.28006 -410.051504)
			(xy 432.28006 -409.893516) (xy 432.279629 -409.884331) (xy 432.273128 -409.867147) (xy 432.26736 -409.859988)
			(xy 432.245536 -409.834365) (xy 432.207587 -409.778775) (xy 432.176554 -409.719048) (xy 432.152882 -409.656039)
			(xy 432.136911 -409.590653) (xy 432.12887 -409.523827) (xy 431.000734 -409.523827) (xy 430.971969 -409.579043)
			(xy 430.93388 -409.634678) (xy 430.912016 -409.660344) (xy 430.90622 -409.66749) (xy 430.899705 -409.68468)
			(xy 430.899316 -409.693872) (xy 430.899316 -410.186124) (xy 430.899711 -410.195313) (xy 430.906235 -410.212497)
			(xy 430.912016 -410.219652) (xy 430.933864 -410.24533) (xy 430.971952 -410.300963) (xy 431.003102 -410.360758)
			(xy 431.026867 -410.423853) (xy 431.042903 -410.48934) (xy 431.05098 -410.556277) (xy 431.050981 -410.623641)
			(xy 434.329044 -410.623641) (xy 434.329046 -410.556335) (xy 434.337091 -410.489512) (xy 434.353065 -410.424129)
			(xy 434.376738 -410.361124) (xy 434.407772 -410.3014) (xy 434.44572 -410.245813) (xy 434.467508 -410.22016)
			(xy 434.473305 -410.213015) (xy 434.479819 -410.195824) (xy 434.480208 -410.186632) (xy 434.480208 -409.693364)
			(xy 434.479814 -409.684175) (xy 434.473289 -409.666991) (xy 434.467508 -409.659836) (xy 434.445733 -409.634174)
			(xy 434.407786 -409.578588) (xy 434.376754 -409.518866) (xy 434.353082 -409.455862) (xy 434.337109 -409.390482)
			(xy 434.329064 -409.323661) (xy 434.329063 -409.256357) (xy 434.337106 -409.189536) (xy 434.353076 -409.124155)
			(xy 434.376746 -409.061151) (xy 434.407777 -409.001427) (xy 434.445722 -408.945841) (xy 434.467508 -408.920188)
			(xy 434.473293 -408.913035) (xy 434.479814 -408.89585) (xy 434.480208 -408.88666) (xy 434.480208 -408.728672)
			(xy 434.480599 -408.718515) (xy 434.488405 -408.69976) (xy 434.502811 -408.685438) (xy 434.521611 -408.67774)
			(xy 434.53177 -408.677364) (xy 435.24805 -408.677364) (xy 435.258176 -408.677868) (xy 435.276901 -408.685584)
			(xy 435.29126 -408.699866) (xy 435.299077 -408.718548) (xy 435.299612 -408.728672) (xy 435.299612 -408.88666)
			(xy 435.300039 -408.895846) (xy 435.30654 -408.91303) (xy 435.312312 -408.920188) (xy 435.334113 -408.94583)
			(xy 435.372065 -409.001417) (xy 435.4031 -409.061141) (xy 435.426774 -409.124147) (xy 435.442748 -409.189531)
			(xy 435.450792 -409.256356) (xy 435.450791 -409.323662) (xy 435.442745 -409.390487) (xy 435.426769 -409.45587)
			(xy 435.403093 -409.518875) (xy 435.372055 -409.578599) (xy 435.334102 -409.634184) (xy 435.312312 -409.659836)
			(xy 435.306519 -409.666984) (xy 435.300002 -409.684172) (xy 435.299612 -409.693364) (xy 435.299612 -410.186632)
			(xy 435.300004 -410.195821) (xy 435.30653 -410.213006) (xy 435.312312 -410.22016) (xy 435.334085 -410.245824)
			(xy 435.372038 -410.301408) (xy 435.403075 -410.361129) (xy 435.42675 -410.424132) (xy 435.442726 -410.489514)
			(xy 435.450772 -410.556336) (xy 435.450774 -410.62364) (xy 435.44273 -410.690463) (xy 435.426758 -410.755845)
			(xy 435.403084 -410.818849) (xy 435.37205 -410.878571) (xy 435.3341 -410.934157) (xy 435.312312 -410.959808)
			(xy 435.306531 -410.966964) (xy 435.300007 -410.984146) (xy 435.299612 -410.993336) (xy 435.299612 -411.151324)
			(xy 435.299198 -411.161478) (xy 435.291397 -411.180229) (xy 435.276998 -411.194551) (xy 435.258206 -411.202252)
			(xy 435.24805 -411.202632) (xy 434.53177 -411.202632) (xy 434.521638 -411.202197) (xy 434.502911 -411.194454)
			(xy 434.488554 -411.180152) (xy 434.480741 -411.161454) (xy 434.480208 -411.151324) (xy 434.480208 -410.993336)
			(xy 434.479779 -410.984151) (xy 434.473278 -410.966966) (xy 434.467508 -410.959808) (xy 434.445706 -410.934168)
			(xy 434.407759 -410.878579) (xy 434.376728 -410.818854) (xy 434.353058 -410.755848) (xy 434.337087 -410.690464)
			(xy 434.329044 -410.623641) (xy 431.050981 -410.623641) (xy 431.050981 -410.623699) (xy 431.042907 -410.690636)
			(xy 431.026874 -410.756124) (xy 431.003112 -410.81922) (xy 430.971964 -410.879016) (xy 430.933878 -410.934651)
			(xy 430.912016 -410.960316) (xy 430.906232 -410.96747) (xy 430.899709 -410.984654) (xy 430.899316 -410.993844)
			(xy 430.899316 -411.151324) (xy 430.898835 -411.161432) (xy 430.891092 -411.180108) (xy 430.876795 -411.194401)
			(xy 430.858116 -411.202138) (xy 430.848008 -411.202632) (xy 430.131728 -411.202632) (xy 430.121611 -411.202162)
			(xy 430.102914 -411.194429) (xy 430.0886 -411.180129) (xy 430.080848 -411.16144) (xy 430.08042 -411.151324)
			(xy 430.08042 -410.993844) (xy 430.079984 -410.98466) (xy 430.073488 -410.967475) (xy 430.06772 -410.960316)
			(xy 430.04584 -410.934664) (xy 430.00775 -410.879028) (xy 429.976599 -410.81923) (xy 429.952835 -410.756132)
			(xy 429.9368 -410.690641) (xy 429.928725 -410.623701) (xy 426.650679 -410.623701) (xy 426.642643 -410.690462)
			(xy 426.62667 -410.755844) (xy 426.602998 -410.818848) (xy 426.571965 -410.878571) (xy 426.534016 -410.934156)
			(xy 426.512228 -410.959808) (xy 426.506437 -410.966957) (xy 426.499921 -410.984145) (xy 426.499528 -410.993336)
			(xy 426.499528 -411.151324) (xy 426.499099 -411.161476) (xy 426.4913 -411.180224) (xy 426.476907 -411.194545)
			(xy 426.45812 -411.202249) (xy 426.447966 -411.202632) (xy 425.731686 -411.202632) (xy 425.721555 -411.202184)
			(xy 425.702828 -411.194446) (xy 425.688472 -411.180148) (xy 425.680658 -411.161453) (xy 425.680124 -411.151324)
			(xy 425.680124 -410.993336) (xy 425.679691 -410.984151) (xy 425.673193 -410.966967) (xy 425.667424 -410.959808)
			(xy 425.645621 -410.934169) (xy 425.607674 -410.87858) (xy 425.576642 -410.818855) (xy 425.552971 -410.755848)
			(xy 425.536999 -410.690465) (xy 425.528957 -410.623641) (xy 422.250893 -410.623641) (xy 422.250893 -410.623699)
			(xy 422.242819 -410.690635) (xy 422.226787 -410.756123) (xy 422.203026 -410.819219) (xy 422.171879 -410.879015)
			(xy 422.133794 -410.93465) (xy 422.111932 -410.960316) (xy 422.106138 -410.967463) (xy 422.099624 -410.984652)
			(xy 422.099232 -410.993844) (xy 422.099232 -411.151324) (xy 422.098735 -411.16143) (xy 422.090996 -411.180103)
			(xy 422.076703 -411.194396) (xy 422.05803 -411.202135) (xy 422.047924 -411.202632) (xy 421.331644 -411.202632)
			(xy 421.321528 -411.202149) (xy 421.302832 -411.194421) (xy 421.288517 -411.180125) (xy 421.280765 -411.161439)
			(xy 421.280336 -411.151324) (xy 421.280336 -410.993844) (xy 421.279896 -410.98466) (xy 421.273402 -410.967476)
			(xy 421.267636 -410.960316) (xy 421.245755 -410.934664) (xy 421.207664 -410.879029) (xy 421.176512 -410.819231)
			(xy 421.152748 -410.756132) (xy 421.136712 -410.690641) (xy 421.128637 -410.623701) (xy 414.525968 -410.623701)
			(xy 414.525968 -417.366196) (xy 414.52546 -417.366196) (xy 414.52546 -417.533836) (xy 414.525117 -417.545925)
			(xy 414.517634 -417.568917) (xy 414.503411 -417.588471) (xy 414.483842 -417.602672) (xy 414.460842 -417.61013)
			(xy 414.448752 -417.610544) (xy 401.15109 -417.610544) (xy 401.138998 -417.610101) (xy 401.115995 -417.602639)
			(xy 401.096414 -417.588447) (xy 401.082164 -417.568908) (xy 401.074635 -417.545926) (xy 401.074128 -417.533836)
			(xy 326.525636 -417.533836) (xy 326.525172 -417.545885) (xy 326.517733 -417.568805) (xy 326.503592 -417.588317)
			(xy 326.484126 -417.602521) (xy 326.461229 -417.610032) (xy 326.449182 -417.610544) (xy 313.151012 -417.610544)
			(xy 313.138942 -417.610026) (xy 313.115981 -417.602571) (xy 313.096447 -417.588387) (xy 313.082251 -417.568862)
			(xy 313.074781 -417.545906) (xy 313.074304 -417.533836) (xy 313.074304 -417.379404) (xy 313.073796 -417.379404)
			(xy 273.434939 -417.379404) (xy 273.506495 -417.442585) (xy 273.605798 -417.540617) (xy 273.652996 -417.592002)
			(xy 273.691387 -417.633573) (xy 273.773525 -417.71142) (xy 273.861325 -417.782821) (xy 273.954282 -417.847364)
			(xy 274.051862 -417.90468) (xy 274.153504 -417.954438) (xy 274.258623 -417.996352) (xy 274.366616 -418.030181)
			(xy 274.476862 -418.055732) (xy 274.588726 -418.072856) (xy 274.701566 -418.081457) (xy 274.75815 -418.081968)
			(xy 465.600034 -418.081968) (xy 465.65584 -418.081445) (xy 465.767139 -418.073102) (xy 465.877504 -418.056464)
			(xy 465.986317 -418.031626) (xy 466.092969 -417.998726) (xy 466.196865 -417.957947) (xy 466.297422 -417.909518)
			(xy 466.39408 -417.85371) (xy 466.486296 -417.790835) (xy 466.573556 -417.721245) (xy 466.655372 -417.645328)
			(xy 466.731285 -417.563509) (xy 466.800872 -417.476246) (xy 466.863743 -417.384027) (xy 466.919547 -417.287367)
			(xy 466.967972 -417.186808) (xy 467.008746 -417.082911) (xy 467.041642 -416.976257) (xy 467.066476 -416.867443)
			(xy 467.083109 -416.757078) (xy 467.091447 -416.645778) (xy 467.09203 -416.589972) (xy 467.09203 -246.48795)
			(xy 467.091546 -246.4347) (xy 467.083933 -246.328473) (xy 467.068764 -246.223059) (xy 467.046116 -246.118995)
			(xy 467.016104 -246.016811) (xy 466.978881 -245.917028) (xy 466.934637 -245.820154) (xy 466.883597 -245.726681)
			(xy 466.82602 -245.637087) (xy 466.762201 -245.551827) (xy 466.692464 -245.471335) (xy 466.65515 -245.433342)
			(xy 464.026504 -242.80495) (xy 463.9771 -242.754859) (xy 463.883341 -242.649941) (xy 463.795613 -242.53993)
			(xy 463.714192 -242.425173) (xy 463.639333 -242.306031) (xy 463.571273 -242.182879) (xy 463.510225 -242.056105)
			(xy 463.456381 -241.926107) (xy 463.409911 -241.793295) (xy 463.370962 -241.658086) (xy 463.339655 -241.520905)
			(xy 463.31609 -241.382185) (xy 463.300339 -241.242362) (xy 463.292454 -241.101876) (xy 463.291936 -241.031522)
			(xy 463.291936 -87.588344) (xy 463.292417 -87.517998) (xy 463.3003 -87.377526) (xy 463.316048 -87.237717)
			(xy 463.339614 -87.099011) (xy 463.370921 -86.961846) (xy 463.409872 -86.826652) (xy 463.456344 -86.693856)
			(xy 463.510191 -86.563875) (xy 463.571243 -86.437119) (xy 463.639308 -86.313987) (xy 463.714172 -86.194865)
			(xy 463.7956 -86.08013) (xy 463.883333 -85.970143) (xy 463.977098 -85.865249) (xy 464.026504 -85.81517)
			(xy 466.65515 -83.186524) (xy 466.692477 -83.148543) (xy 466.762224 -83.068056) (xy 466.826051 -82.982799)
			(xy 466.883632 -82.893206) (xy 466.934676 -82.799733) (xy 466.978921 -82.702856) (xy 467.016141 -82.60307)
			(xy 467.046149 -82.500883) (xy 467.068789 -82.396815) (xy 467.083947 -82.291397) (xy 467.091547 -82.185167)
			(xy 467.09203 -82.131916) (xy 467.09203 -1.999996) (xy 467.091508 -1.944189) (xy 467.083167 -1.832886)
			(xy 467.066532 -1.722518) (xy 467.041695 -1.613701) (xy 467.008796 -1.507045) (xy 466.968019 -1.403146)
			(xy 466.919592 -1.302584) (xy 466.863785 -1.205923) (xy 466.800911 -1.113702) (xy 466.731321 -1.026437)
			(xy 466.655404 -0.944617) (xy 466.573586 -0.868699) (xy 466.486322 -0.799107) (xy 466.394103 -0.736231)
			(xy 466.297442 -0.680422) (xy 466.196882 -0.631993) (xy 466.092983 -0.591214) (xy 465.986328 -0.558313)
			(xy 465.877512 -0.533474) (xy 465.767144 -0.516836) (xy 465.655841 -0.508493) (xy 465.600034 -0.508)
			(xy 446.265046 -0.508) (xy 446.209237 -0.508508) (xy 446.097932 -0.516845) (xy 445.987561 -0.533478)
			(xy 445.878741 -0.558312) (xy 445.772082 -0.591209) (xy 445.668179 -0.631985) (xy 445.567615 -0.680412)
			(xy 445.47095 -0.736218) (xy 445.378726 -0.799093) (xy 445.291459 -0.868683) (xy 445.209636 -0.944601)
			(xy 445.133716 -1.026421) (xy 445.064123 -1.113686) (xy 445.001245 -1.205908) (xy 444.945435 -1.30257)
			(xy 444.897005 -1.403134) (xy 444.856226 -1.507035) (xy 444.823325 -1.613693) (xy 444.798487 -1.722512)
			(xy 444.781851 -1.832882) (xy 444.773509 -1.944187) (xy 444.77305 -1.999996) (xy 444.77305 -11.850116)
			(xy 444.77258 -11.903957) (xy 444.764897 -12.011363) (xy 444.749571 -12.117948) (xy 444.726681 -12.223168)
			(xy 444.696342 -12.326487) (xy 444.65871 -12.427378) (xy 444.613976 -12.525327) (xy 444.562368 -12.619836)
			(xy 444.504149 -12.710422) (xy 444.439617 -12.796624) (xy 444.369099 -12.878002) (xy 444.292955 -12.954143)
			(xy 444.211574 -13.024657) (xy 444.125369 -13.089186) (xy 444.034781 -13.147401) (xy 443.94027 -13.199004)
			(xy 443.842319 -13.243734) (xy 443.741426 -13.281362) (xy 443.638106 -13.311696) (xy 443.532885 -13.334583)
			(xy 443.4263 -13.349904) (xy 443.318893 -13.357583) (xy 443.265052 -13.358114) (xy 435.265068 -13.358114)
			(xy 435.211227 -13.357632) (xy 435.103821 -13.349948) (xy 434.997236 -13.334622) (xy 434.892016 -13.311731)
			(xy 434.788697 -13.281392) (xy 434.687806 -13.24376) (xy 434.589856 -13.199026) (xy 434.495347 -13.147419)
			(xy 434.40476 -13.089201) (xy 434.318558 -13.024669) (xy 434.237178 -12.954153) (xy 434.161036 -12.87801)
			(xy 434.090521 -12.79663) (xy 434.02599 -12.710426) (xy 433.967773 -12.619839) (xy 433.916167 -12.52533)
			(xy 433.871434 -12.42738) (xy 433.833803 -12.326488) (xy 433.803465 -12.223169) (xy 433.780576 -12.117948)
			(xy 433.76525 -12.011363) (xy 433.757567 -11.903957) (xy 433.75707 -11.850116) (xy 433.75707 -1.999996)
			(xy 433.756561 -1.944189) (xy 433.748219 -1.832887) (xy 433.731584 -1.72252) (xy 433.706747 -1.613704)
			(xy 433.673847 -1.507049) (xy 433.633069 -1.40315) (xy 433.584641 -1.30259) (xy 433.528833 -1.20593)
			(xy 433.465958 -1.11371) (xy 433.396367 -1.026448) (xy 433.320449 -0.944629) (xy 433.23863 -0.868713)
			(xy 433.151366 -0.799124) (xy 433.059145 -0.736251) (xy 432.962484 -0.680445) (xy 432.861922 -0.632019)
			(xy 432.758023 -0.591243) (xy 432.651367 -0.558346) (xy 432.542551 -0.533511) (xy 432.432183 -0.516877)
			(xy 432.320881 -0.508538) (xy 432.265074 -0.508) (xy 420.265098 -0.508) (xy 420.209291 -0.508522)
			(xy 420.097989 -0.516863) (xy 419.987622 -0.533498) (xy 419.878806 -0.558335) (xy 419.772151 -0.591234)
			(xy 419.668252 -0.632011) (xy 419.567691 -0.680438) (xy 419.471031 -0.736245) (xy 419.378811 -0.79912)
			(xy 419.291547 -0.86871) (xy 419.209728 -0.944627) (xy 419.133811 -1.026446) (xy 419.064221 -1.113709)
			(xy 419.001346 -1.205929) (xy 418.945539 -1.302589) (xy 418.897112 -1.40315) (xy 418.856334 -1.507049)
			(xy 418.823435 -1.613704) (xy 418.798599 -1.72252) (xy 418.781963 -1.832887) (xy 418.773622 -1.944189)
			(xy 418.773102 -1.999996) (xy 418.773102 -11.850116) (xy 418.772621 -11.903957) (xy 418.764938 -12.011364)
			(xy 418.749612 -12.117949) (xy 418.726722 -12.22317) (xy 418.696384 -12.326489) (xy 418.658752 -12.427381)
			(xy 418.614019 -12.525332) (xy 418.562412 -12.619841) (xy 418.504194 -12.710429) (xy 418.439663 -12.796632)
			(xy 418.369146 -12.878012) (xy 418.293003 -12.954154) (xy 418.211622 -13.02467) (xy 418.125419 -13.089201)
			(xy 418.034831 -13.147418) (xy 417.940321 -13.199024) (xy 417.84237 -13.243756) (xy 417.741478 -13.281387)
			(xy 417.638158 -13.311725) (xy 417.532938 -13.334614) (xy 417.426352 -13.349939) (xy 417.318945 -13.357621)
			(xy 417.265104 -13.358114) (xy 409.26512 -13.358114) (xy 409.211278 -13.357646) (xy 409.103868 -13.349965)
			(xy 408.997279 -13.334641) (xy 408.892055 -13.311753) (xy 408.788733 -13.281416) (xy 408.687837 -13.243785)
			(xy 408.589884 -13.199053) (xy 408.495371 -13.147446) (xy 408.40478 -13.089229) (xy 408.318573 -13.024697)
			(xy 408.23719 -12.95418) (xy 408.161045 -12.878036) (xy 408.090526 -12.796655) (xy 408.025992 -12.71045)
			(xy 407.967772 -12.61986) (xy 407.916164 -12.525349) (xy 407.871429 -12.427396) (xy 407.833796 -12.326502)
			(xy 407.803456 -12.223179) (xy 407.780565 -12.117956) (xy 407.765239 -12.011368) (xy 407.757556 -11.903958)
			(xy 407.757122 -11.850116) (xy 407.757122 -1.999996) (xy 407.7566 -1.944189) (xy 407.748259 -1.832886)
			(xy 407.731624 -1.722518) (xy 407.706787 -1.613702) (xy 407.673888 -1.507046) (xy 407.633111 -1.403147)
			(xy 407.584684 -1.302586) (xy 407.528877 -1.205924) (xy 407.466002 -1.113704) (xy 407.396412 -1.02644)
			(xy 407.320496 -0.94462) (xy 407.238677 -0.868702) (xy 407.151414 -0.799111) (xy 407.059194 -0.736235)
			(xy 406.962534 -0.680427) (xy 406.861973 -0.631998) (xy 406.758075 -0.591219) (xy 406.651419 -0.558319)
			(xy 406.542603 -0.53348) (xy 406.432236 -0.516843) (xy 406.320933 -0.508501) (xy 406.265126 -0.508)
			(xy 394.264896 -0.508) (xy 394.209089 -0.508522) (xy 394.097787 -0.516863) (xy 393.98742 -0.533498)
			(xy 393.878604 -0.558335) (xy 393.771949 -0.591234) (xy 393.668051 -0.632011) (xy 393.56749 -0.680439)
			(xy 393.470829 -0.736246) (xy 393.37861 -0.799121) (xy 393.291346 -0.868711) (xy 393.209528 -0.944628)
			(xy 393.133611 -1.026446) (xy 393.064021 -1.11371) (xy 393.001146 -1.205929) (xy 392.945339 -1.30259)
			(xy 392.896911 -1.403151) (xy 392.856134 -1.507049) (xy 392.823235 -1.613704) (xy 392.798398 -1.72252)
			(xy 392.781763 -1.832887) (xy 392.773422 -1.944189) (xy 392.7729 -1.999996) (xy 392.7729 -11.850116)
			(xy 392.772419 -11.903957) (xy 392.764736 -12.011364) (xy 392.74941 -12.117949) (xy 392.72652 -12.22317)
			(xy 392.696182 -12.326489) (xy 392.65855 -12.427381) (xy 392.613817 -12.525331) (xy 392.56221 -12.619841)
			(xy 392.503992 -12.710428) (xy 392.43946 -12.796631) (xy 392.368944 -12.878011) (xy 392.292801 -12.954153)
			(xy 392.21142 -13.024669) (xy 392.125217 -13.0892) (xy 392.034629 -13.147417) (xy 391.940119 -13.199023)
			(xy 391.842168 -13.243755) (xy 391.741276 -13.281386) (xy 391.637956 -13.311723) (xy 391.532735 -13.334613)
			(xy 391.42615 -13.349937) (xy 391.318743 -13.357619) (xy 391.264902 -13.358114) (xy 383.264918 -13.358114)
			(xy 383.211076 -13.357645) (xy 383.103666 -13.349965) (xy 382.997077 -13.334641) (xy 382.891854 -13.311752)
			(xy 382.788531 -13.281415) (xy 382.687636 -13.243785) (xy 382.589682 -13.199052) (xy 382.495169 -13.147445)
			(xy 382.404579 -13.089228) (xy 382.318373 -13.024696) (xy 382.236989 -12.954179) (xy 382.160844 -12.878035)
			(xy 382.090325 -12.796654) (xy 382.025791 -12.710449) (xy 381.967572 -12.61986) (xy 381.915963 -12.525348)
			(xy 381.871228 -12.427396) (xy 381.833596 -12.326501) (xy 381.803256 -12.223179) (xy 381.780365 -12.117956)
			(xy 381.765039 -12.011368) (xy 381.757356 -11.903958) (xy 381.75692 -11.850116) (xy 381.75692 -1.999996)
			(xy 381.756398 -1.944189) (xy 381.748057 -1.832886) (xy 381.731422 -1.722518) (xy 381.706585 -1.613702)
			(xy 381.673686 -1.507047) (xy 381.632909 -1.403147) (xy 381.584482 -1.302586) (xy 381.528675 -1.205925)
			(xy 381.4658 -1.113704) (xy 381.39621 -1.02644) (xy 381.320294 -0.944621) (xy 381.238475 -0.868703)
			(xy 381.151212 -0.799112) (xy 381.058992 -0.736236) (xy 380.962332 -0.680428) (xy 380.861771 -0.631999)
			(xy 380.757872 -0.59122) (xy 380.651217 -0.55832) (xy 380.542401 -0.533482) (xy 380.432034 -0.516845)
			(xy 380.320731 -0.508503) (xy 380.264924 -0.508) (xy 368.264948 -0.508) (xy 368.209139 -0.508507)
			(xy 368.097834 -0.516845) (xy 367.987463 -0.533478) (xy 367.878643 -0.558312) (xy 367.771984 -0.591209)
			(xy 367.668081 -0.631985) (xy 367.567516 -0.680411) (xy 367.470851 -0.736218) (xy 367.378627 -0.799092)
			(xy 367.29136 -0.868683) (xy 367.209537 -0.9446) (xy 367.133617 -1.02642) (xy 367.064023 -1.113685)
			(xy 367.001145 -1.205907) (xy 366.945336 -1.30257) (xy 366.896905 -1.403133) (xy 366.856126 -1.507034)
			(xy 366.823225 -1.613693) (xy 366.798387 -1.722511) (xy 366.781751 -1.832882) (xy 366.773409 -1.944187)
			(xy 366.772952 -1.999996) (xy 366.772952 -11.850116) (xy 366.772482 -11.903957) (xy 366.764799 -12.011363)
			(xy 366.749473 -12.117948) (xy 366.726583 -12.223168) (xy 366.696244 -12.326487) (xy 366.658612 -12.427378)
			(xy 366.613878 -12.525328) (xy 366.56227 -12.619836) (xy 366.504051 -12.710422) (xy 366.439519 -12.796624)
			(xy 366.369001 -12.878003) (xy 366.292858 -12.954143) (xy 366.211476 -13.024658) (xy 366.125271 -13.089187)
			(xy 366.034683 -13.147402) (xy 365.940172 -13.199005) (xy 365.842221 -13.243735) (xy 365.741328 -13.281363)
			(xy 365.638008 -13.311698) (xy 365.532787 -13.334584) (xy 365.426202 -13.349906) (xy 365.318795 -13.357584)
			(xy 365.264954 -13.358114) (xy 357.26497 -13.358114) (xy 357.211129 -13.357632) (xy 357.103723 -13.349948)
			(xy 356.997138 -13.334622) (xy 356.891918 -13.311731) (xy 356.788599 -13.281392) (xy 356.687707 -13.24376)
			(xy 356.589757 -13.199027) (xy 356.495248 -13.147419) (xy 356.404661 -13.089202) (xy 356.318459 -13.02467)
			(xy 356.237079 -12.954153) (xy 356.160937 -12.878011) (xy 356.090421 -12.796631) (xy 356.02589 -12.710427)
			(xy 355.967673 -12.61984) (xy 355.916067 -12.52533) (xy 355.871335 -12.42738) (xy 355.833703 -12.326488)
			(xy 355.803366 -12.223169) (xy 355.780476 -12.117949) (xy 355.76515 -12.011363) (xy 355.757467 -11.903957)
			(xy 355.756972 -11.850116) (xy 355.756972 -1.999996) (xy 355.756463 -1.944189) (xy 355.748121 -1.832887)
			(xy 355.731486 -1.722519) (xy 355.706649 -1.613704) (xy 355.673749 -1.507049) (xy 355.632971 -1.40315)
			(xy 355.584543 -1.30259) (xy 355.528735 -1.205929) (xy 355.46586 -1.11371) (xy 355.396269 -1.026447)
			(xy 355.320352 -0.944629) (xy 355.238532 -0.868713) (xy 355.151268 -0.799123) (xy 355.059047 -0.73625)
			(xy 354.962386 -0.680444) (xy 354.861824 -0.632017) (xy 354.757925 -0.591241) (xy 354.651269 -0.558344)
			(xy 354.542453 -0.533509) (xy 354.432085 -0.516876) (xy 354.320783 -0.508536) (xy 354.264976 -0.508)
			(xy 330.164948 -0.508) (xy 330.109139 -0.508507) (xy 329.997834 -0.516845) (xy 329.887463 -0.533478)
			(xy 329.778643 -0.558312) (xy 329.671984 -0.591209) (xy 329.568081 -0.631985) (xy 329.467516 -0.680411)
			(xy 329.370851 -0.736218) (xy 329.278627 -0.799092) (xy 329.19136 -0.868683) (xy 329.109537 -0.9446)
			(xy 329.033617 -1.02642) (xy 328.964023 -1.113685) (xy 328.901145 -1.205907) (xy 328.845336 -1.30257)
			(xy 328.796905 -1.403133) (xy 328.756126 -1.507034) (xy 328.723225 -1.613693) (xy 328.698387 -1.722511)
			(xy 328.681751 -1.832882) (xy 328.673409 -1.944187) (xy 328.672952 -1.999996) (xy 328.672952 -11.850116)
			(xy 328.672482 -11.903957) (xy 328.664799 -12.011363) (xy 328.649473 -12.117948) (xy 328.626583 -12.223168)
			(xy 328.596244 -12.326487) (xy 328.558612 -12.427378) (xy 328.513878 -12.525328) (xy 328.46227 -12.619836)
			(xy 328.404051 -12.710422) (xy 328.339519 -12.796624) (xy 328.269001 -12.878003) (xy 328.192858 -12.954143)
			(xy 328.111476 -13.024658) (xy 328.025271 -13.089187) (xy 327.934683 -13.147402) (xy 327.840172 -13.199005)
			(xy 327.742221 -13.243735) (xy 327.641328 -13.281363) (xy 327.538008 -13.311698) (xy 327.432787 -13.334584)
			(xy 327.326202 -13.349906) (xy 327.218795 -13.357584) (xy 327.164954 -13.358114) (xy 319.16497 -13.358114)
			(xy 319.111129 -13.357632) (xy 319.003723 -13.349948) (xy 318.897138 -13.334622) (xy 318.791918 -13.311731)
			(xy 318.688599 -13.281392) (xy 318.587707 -13.24376) (xy 318.489757 -13.199027) (xy 318.395248 -13.147419)
			(xy 318.304661 -13.089202) (xy 318.218459 -13.02467) (xy 318.137079 -12.954153) (xy 318.060937 -12.878011)
			(xy 317.990421 -12.796631) (xy 317.92589 -12.710427) (xy 317.867673 -12.61984) (xy 317.816067 -12.52533)
			(xy 317.771335 -12.42738) (xy 317.733703 -12.326488) (xy 317.703366 -12.223169) (xy 317.680476 -12.117949)
			(xy 317.66515 -12.011363) (xy 317.657467 -11.903957) (xy 317.656972 -11.850116) (xy 317.656972 -1.999996)
			(xy 317.656463 -1.944189) (xy 317.648121 -1.832887) (xy 317.631486 -1.722519) (xy 317.606649 -1.613704)
			(xy 317.573749 -1.507049) (xy 317.532971 -1.40315) (xy 317.484543 -1.30259) (xy 317.428735 -1.205929)
			(xy 317.36586 -1.11371) (xy 317.296269 -1.026447) (xy 317.220352 -0.944629) (xy 317.138532 -0.868713)
			(xy 317.051268 -0.799123) (xy 316.959047 -0.73625) (xy 316.862386 -0.680444) (xy 316.761824 -0.632017)
			(xy 316.657925 -0.591241) (xy 316.551269 -0.558344) (xy 316.442453 -0.533509) (xy 316.332085 -0.516876)
			(xy 316.220783 -0.508536) (xy 316.164976 -0.508) (xy 304.165 -0.508) (xy 304.109193 -0.508522) (xy 303.997891 -0.516863)
			(xy 303.887523 -0.533498) (xy 303.778708 -0.558334) (xy 303.672052 -0.591233) (xy 303.568153 -0.63201)
			(xy 303.467592 -0.680438) (xy 303.370932 -0.736245) (xy 303.278712 -0.799119) (xy 303.191448 -0.868709)
			(xy 303.109629 -0.944626) (xy 303.033712 -1.026445) (xy 302.964122 -1.113708) (xy 302.901247 -1.205928)
			(xy 302.84544 -1.302589) (xy 302.797012 -1.40315) (xy 302.756234 -1.507048) (xy 302.723335 -1.613704)
			(xy 302.698499 -1.722519) (xy 302.681863 -1.832887) (xy 302.673522 -1.944189) (xy 302.673004 -1.999996)
			(xy 302.673004 -11.850116) (xy 302.672523 -11.903957) (xy 302.66484 -12.011364) (xy 302.649514 -12.11795)
			(xy 302.626624 -12.22317) (xy 302.596286 -12.32649) (xy 302.558654 -12.427382) (xy 302.513921 -12.525332)
			(xy 302.462314 -12.619842) (xy 302.404096 -12.710429) (xy 302.339565 -12.796632) (xy 302.269048 -12.878012)
			(xy 302.192905 -12.954155) (xy 302.111525 -13.024671) (xy 302.025321 -13.089202) (xy 301.934733 -13.147419)
			(xy 301.840223 -13.199025) (xy 301.742272 -13.243758) (xy 301.64138 -13.281389) (xy 301.53806 -13.311726)
			(xy 301.43284 -13.334616) (xy 301.326254 -13.349941) (xy 301.218847 -13.357623) (xy 301.165006 -13.358114)
			(xy 293.165022 -13.358114) (xy 293.11118 -13.357646) (xy 293.00377 -13.349965) (xy 292.897181 -13.334641)
			(xy 292.791957 -13.311753) (xy 292.688634 -13.281416) (xy 292.587739 -13.243786) (xy 292.489785 -13.199053)
			(xy 292.395272 -13.147447) (xy 292.304681 -13.089229) (xy 292.218474 -13.024698) (xy 292.137091 -12.95418)
			(xy 292.060946 -12.878037) (xy 291.990426 -12.796655) (xy 291.925892 -12.71045) (xy 291.867673 -12.619861)
			(xy 291.816064 -12.525349) (xy 291.771329 -12.427396) (xy 291.733696 -12.326502) (xy 291.703356 -12.22318)
			(xy 291.680465 -12.117956) (xy 291.665139 -12.011368) (xy 291.657456 -11.903958) (xy 291.657024 -11.850116)
			(xy 291.657024 -1.999996) (xy 291.656502 -1.944189) (xy 291.648161 -1.832886) (xy 291.631526 -1.722518)
			(xy 291.606689 -1.613702) (xy 291.57379 -1.507046) (xy 291.533013 -1.403147) (xy 291.484586 -1.302585)
			(xy 291.428779 -1.205924) (xy 291.365905 -1.113703) (xy 291.296314 -1.026439) (xy 291.220398 -0.944619)
			(xy 291.138579 -0.868701) (xy 291.051316 -0.79911) (xy 290.959096 -0.736234) (xy 290.862436 -0.680426)
			(xy 290.761875 -0.631997) (xy 290.657977 -0.591218) (xy 290.551321 -0.558317) (xy 290.442505 -0.533479)
			(xy 290.332138 -0.516842) (xy 290.220835 -0.508499) (xy 290.165028 -0.508) (xy 278.165052 -0.508)
			(xy 278.109246 -0.508523) (xy 277.997947 -0.516868) (xy 277.887582 -0.533506) (xy 277.778769 -0.558345)
			(xy 277.672116 -0.591246) (xy 277.568221 -0.632024) (xy 277.467663 -0.680453) (xy 277.371005 -0.736261)
			(xy 277.278789 -0.799136) (xy 277.191528 -0.868726) (xy 277.109712 -0.944643) (xy 277.033798 -1.026461)
			(xy 276.96421 -1.113724) (xy 276.901338 -1.205943) (xy 276.845533 -1.302602) (xy 276.797107 -1.403161)
			(xy 276.756331 -1.507058) (xy 276.723433 -1.613711) (xy 276.698598 -1.722525) (xy 276.681963 -1.83289)
			(xy 276.673622 -1.94419) (xy 276.673056 -1.999996) (xy 276.673056 -11.850116) (xy 276.672586 -11.903957)
			(xy 276.664903 -12.011363) (xy 276.649577 -12.117948) (xy 276.626687 -12.223169) (xy 276.596348 -12.326487)
			(xy 276.558716 -12.427379) (xy 276.513982 -12.525328) (xy 276.462374 -12.619837) (xy 276.404156 -12.710423)
			(xy 276.339623 -12.796626) (xy 276.269105 -12.878004) (xy 276.192962 -12.954145) (xy 276.11158 -13.02466)
			(xy 276.025376 -13.089189) (xy 275.934787 -13.147404) (xy 275.840277 -13.199008) (xy 275.742325 -13.243738)
			(xy 275.641432 -13.281366) (xy 275.538112 -13.311701) (xy 275.432891 -13.334588) (xy 275.326306 -13.349909)
			(xy 275.218899 -13.357588) (xy 275.165058 -13.358114) (xy 267.165074 -13.358114) (xy 267.111233 -13.357632)
			(xy 267.003826 -13.349949) (xy 266.897241 -13.334623) (xy 266.792021 -13.311732) (xy 266.688702 -13.281393)
			(xy 266.58781 -13.243761) (xy 266.48986 -13.199028) (xy 266.39535 -13.147421) (xy 266.304763 -13.089203)
			(xy 266.21856 -13.024672) (xy 266.13718 -12.954155) (xy 266.061038 -12.878012) (xy 265.990522 -12.796632)
			(xy 265.925991 -12.710428) (xy 265.867774 -12.619841) (xy 265.816168 -12.525331) (xy 265.771435 -12.427381)
			(xy 265.733804 -12.326489) (xy 265.703466 -12.22317) (xy 265.680576 -12.117949) (xy 265.66525 -12.011364)
			(xy 265.657567 -11.903957) (xy 265.657076 -11.850116) (xy 265.657076 -1.999996) (xy 265.656567 -1.944189)
			(xy 265.648225 -1.832887) (xy 265.63159 -1.722519) (xy 265.606753 -1.613703) (xy 265.573853 -1.507048)
			(xy 265.533076 -1.403149) (xy 265.484647 -1.302589) (xy 265.42884 -1.205928) (xy 265.365964 -1.113709)
			(xy 265.296373 -1.026446) (xy 265.220456 -0.944627) (xy 265.138636 -0.868711) (xy 265.051372 -0.799121)
			(xy 264.959151 -0.736248) (xy 264.86249 -0.680441) (xy 264.761929 -0.632015) (xy 264.658029 -0.591239)
			(xy 264.551373 -0.558341) (xy 264.442557 -0.533506) (xy 264.332189 -0.516872) (xy 264.220887 -0.508532)
			(xy 264.16508 -0.508) (xy 252.165104 -0.508) (xy 252.109297 -0.508522) (xy 251.997995 -0.516862)
			(xy 251.887627 -0.533497) (xy 251.778811 -0.558333) (xy 251.672155 -0.591232) (xy 251.568256 -0.632009)
			(xy 251.467695 -0.680436) (xy 251.371034 -0.736243) (xy 251.278814 -0.799118) (xy 251.19155 -0.868708)
			(xy 251.10973 -0.944625) (xy 251.033813 -1.026444) (xy 250.964222 -1.113707) (xy 250.901348 -1.205927)
			(xy 250.84554 -1.302588) (xy 250.797112 -1.403149) (xy 250.756335 -1.507047) (xy 250.723435 -1.613703)
			(xy 250.698599 -1.722519) (xy 250.681963 -1.832887) (xy 250.673622 -1.944189) (xy 250.673108 -1.999996)
			(xy 250.673108 -11.850116) (xy 250.672627 -11.903957) (xy 250.664944 -12.011364) (xy 250.649618 -12.11795)
			(xy 250.626728 -12.223171) (xy 250.59639 -12.32649) (xy 250.558758 -12.427382) (xy 250.514025 -12.525333)
			(xy 250.462418 -12.619843) (xy 250.4042 -12.71043) (xy 250.339669 -12.796633) (xy 250.269152 -12.878014)
			(xy 250.193009 -12.954156) (xy 250.111629 -13.024673) (xy 250.025425 -13.089204) (xy 249.934837 -13.147421)
			(xy 249.840327 -13.199027) (xy 249.742377 -13.24376) (xy 249.641484 -13.281392) (xy 249.538165 -13.311729)
			(xy 249.432944 -13.334619) (xy 249.326358 -13.349944) (xy 249.218951 -13.357627) (xy 249.16511 -13.358114)
			(xy 241.164872 -13.358114) (xy 241.111035 -13.357619) (xy 241.003638 -13.34991) (xy 240.897064 -13.334562)
			(xy 240.791856 -13.311652) (xy 240.688549 -13.281298) (xy 240.58767 -13.243654) (xy 240.489733 -13.198912)
			(xy 240.395235 -13.1473) (xy 240.304659 -13.08908) (xy 240.218466 -13.024548) (xy 240.137093 -12.954035)
			(xy 240.060957 -12.877898) (xy 239.990444 -12.796525) (xy 239.925914 -12.710331) (xy 239.867694 -12.619754)
			(xy 239.816083 -12.525256) (xy 239.771341 -12.427319) (xy 239.733698 -12.326439) (xy 239.703345 -12.223133)
			(xy 239.680436 -12.117924) (xy 239.665089 -12.01135) (xy 239.657381 -11.903953) (xy 239.656874 -11.850116)
			(xy 239.656874 -1.999996) (xy 239.656365 -1.944189) (xy 239.648023 -1.832887) (xy 239.631388 -1.722519)
			(xy 239.606551 -1.613704) (xy 239.573651 -1.507048) (xy 239.532873 -1.40315) (xy 239.484445 -1.302589)
			(xy 239.428638 -1.205929) (xy 239.365762 -1.113709) (xy 239.296171 -1.026446) (xy 239.220254 -0.944628)
			(xy 239.138434 -0.868712) (xy 239.05117 -0.799122) (xy 238.958949 -0.736249) (xy 238.862288 -0.680443)
			(xy 238.761726 -0.632016) (xy 238.657827 -0.59124) (xy 238.551171 -0.558343) (xy 238.442355 -0.533507)
			(xy 238.331987 -0.516874) (xy 238.220685 -0.508534) (xy 238.164878 -0.508) (xy 214.065104 -0.508)
			(xy 214.009297 -0.508522) (xy 213.897995 -0.516862) (xy 213.787627 -0.533497) (xy 213.678811 -0.558333)
			(xy 213.572155 -0.591232) (xy 213.468256 -0.632009) (xy 213.367695 -0.680436) (xy 213.271034 -0.736243)
			(xy 213.178814 -0.799118) (xy 213.09155 -0.868708) (xy 213.00973 -0.944625) (xy 212.933813 -1.026444)
			(xy 212.864222 -1.113707) (xy 212.801348 -1.205927) (xy 212.74554 -1.302588) (xy 212.697112 -1.403149)
			(xy 212.656335 -1.507047) (xy 212.623435 -1.613703) (xy 212.598599 -1.722519) (xy 212.581963 -1.832887)
			(xy 212.573622 -1.944189) (xy 212.573108 -1.999996) (xy 212.573108 -11.850116) (xy 212.572627 -11.903957)
			(xy 212.564944 -12.011364) (xy 212.549618 -12.11795) (xy 212.526728 -12.223171) (xy 212.49639 -12.32649)
			(xy 212.458758 -12.427382) (xy 212.414025 -12.525333) (xy 212.362418 -12.619843) (xy 212.3042 -12.71043)
			(xy 212.239669 -12.796633) (xy 212.169152 -12.878014) (xy 212.093009 -12.954156) (xy 212.011629 -13.024673)
			(xy 211.925425 -13.089204) (xy 211.834837 -13.147421) (xy 211.740327 -13.199027) (xy 211.642377 -13.24376)
			(xy 211.541484 -13.281392) (xy 211.438165 -13.311729) (xy 211.332944 -13.334619) (xy 211.226358 -13.349944)
			(xy 211.118951 -13.357627) (xy 211.06511 -13.358114) (xy 203.064872 -13.358114) (xy 203.011035 -13.357619)
			(xy 202.903638 -13.34991) (xy 202.797064 -13.334562) (xy 202.691856 -13.311652) (xy 202.588549 -13.281298)
			(xy 202.48767 -13.243654) (xy 202.389733 -13.198912) (xy 202.295235 -13.1473) (xy 202.204659 -13.08908)
			(xy 202.118466 -13.024548) (xy 202.037093 -12.954035) (xy 201.960957 -12.877898) (xy 201.890444 -12.796525)
			(xy 201.825914 -12.710331) (xy 201.767694 -12.619754) (xy 201.716083 -12.525256) (xy 201.671341 -12.427319)
			(xy 201.633698 -12.326439) (xy 201.603345 -12.223133) (xy 201.580436 -12.117924) (xy 201.565089 -12.01135)
			(xy 201.557381 -11.903953) (xy 201.556874 -11.850116) (xy 201.556874 -1.999996) (xy 201.556365 -1.944189)
			(xy 201.548023 -1.832887) (xy 201.531388 -1.722519) (xy 201.506551 -1.613704) (xy 201.473651 -1.507048)
			(xy 201.432873 -1.40315) (xy 201.384445 -1.302589) (xy 201.328638 -1.205929) (xy 201.265762 -1.113709)
			(xy 201.196171 -1.026446) (xy 201.120254 -0.944628) (xy 201.038434 -0.868712) (xy 200.95117 -0.799122)
			(xy 200.858949 -0.736249) (xy 200.762288 -0.680443) (xy 200.661726 -0.632016) (xy 200.557827 -0.59124)
			(xy 200.451171 -0.558343) (xy 200.342355 -0.533507) (xy 200.231987 -0.516874) (xy 200.120685 -0.508534)
			(xy 200.064878 -0.508) (xy 188.064902 -0.508) (xy 188.009095 -0.508522) (xy 187.897793 -0.516862)
			(xy 187.787425 -0.533498) (xy 187.678609 -0.558334) (xy 187.571954 -0.591233) (xy 187.468055 -0.63201)
			(xy 187.367494 -0.680437) (xy 187.270833 -0.736244) (xy 187.178613 -0.799118) (xy 187.091349 -0.868709)
			(xy 187.00953 -0.944625) (xy 186.933613 -1.026444) (xy 186.864022 -1.113708) (xy 186.801147 -1.205928)
			(xy 186.74534 -1.302588) (xy 186.696912 -1.403149) (xy 186.656135 -1.507048) (xy 186.623235 -1.613703)
			(xy 186.598399 -1.722519) (xy 186.581763 -1.832887) (xy 186.573422 -1.944189) (xy 186.572906 -1.999996)
			(xy 186.572906 -11.850116) (xy 186.572425 -11.903957) (xy 186.564742 -12.011364) (xy 186.549416 -12.11795)
			(xy 186.526526 -12.22317) (xy 186.496188 -12.32649) (xy 186.458556 -12.427382) (xy 186.413823 -12.525332)
			(xy 186.362216 -12.619842) (xy 186.303998 -12.71043) (xy 186.239467 -12.796633) (xy 186.16895 -12.878013)
			(xy 186.092807 -12.954155) (xy 186.011427 -13.024672) (xy 185.925223 -13.089203) (xy 185.834635 -13.14742)
			(xy 185.740125 -13.199026) (xy 185.642175 -13.243759) (xy 185.541282 -13.28139) (xy 185.437963 -13.311728)
			(xy 185.332742 -13.334618) (xy 185.226156 -13.349943) (xy 185.118749 -13.357625) (xy 185.064908 -13.358114)
			(xy 177.064924 -13.358114) (xy 177.011082 -13.357646) (xy 176.903671 -13.349965) (xy 176.797083 -13.334642)
			(xy 176.691859 -13.311753) (xy 176.588536 -13.281417) (xy 176.48764 -13.243786) (xy 176.389686 -13.199054)
			(xy 176.295173 -13.147447) (xy 176.204582 -13.08923) (xy 176.118375 -13.024698) (xy 176.036992 -12.954181)
			(xy 175.960846 -12.878038) (xy 175.890327 -12.796656) (xy 175.825793 -12.710451) (xy 175.767573 -12.619862)
			(xy 175.715964 -12.52535) (xy 175.671229 -12.427397) (xy 175.633596 -12.326502) (xy 175.603257 -12.22318)
			(xy 175.580365 -12.117957) (xy 175.565039 -12.011368) (xy 175.557356 -11.903958) (xy 175.556926 -11.850116)
			(xy 175.556926 -1.999996) (xy 175.556404 -1.944189) (xy 175.548063 -1.832886) (xy 175.531428 -1.722518)
			(xy 175.506591 -1.613702) (xy 175.473692 -1.507046) (xy 175.432915 -1.403146) (xy 175.384488 -1.302585)
			(xy 175.328681 -1.205923) (xy 175.265807 -1.113703) (xy 175.196217 -1.026438) (xy 175.1203 -0.944618)
			(xy 175.038481 -0.8687) (xy 174.951218 -0.799109) (xy 174.858999 -0.736233) (xy 174.762338 -0.680424)
			(xy 174.661777 -0.631995) (xy 174.557879 -0.591216) (xy 174.451223 -0.558316) (xy 174.342408 -0.533477)
			(xy 174.23204 -0.51684) (xy 174.120737 -0.508497) (xy 174.06493 -0.508) (xy 162.064954 -0.508) (xy 162.009148 -0.508523)
			(xy 161.897848 -0.516867) (xy 161.787483 -0.533505) (xy 161.67867 -0.558344) (xy 161.572018 -0.591245)
			(xy 161.468122 -0.632024) (xy 161.367564 -0.680453) (xy 161.270907 -0.73626) (xy 161.17869 -0.799135)
			(xy 161.091429 -0.868726) (xy 161.009613 -0.944642) (xy 160.933698 -1.026461) (xy 160.86411 -1.113723)
			(xy 160.801238 -1.205942) (xy 160.745433 -1.302601) (xy 160.697007 -1.403161) (xy 160.656231 -1.507058)
			(xy 160.623333 -1.613711) (xy 160.598498 -1.722525) (xy 160.581863 -1.83289) (xy 160.573522 -1.94419)
			(xy 160.572958 -1.999996) (xy 160.572958 -11.850116) (xy 160.572488 -11.903957) (xy 160.564805 -12.011363)
			(xy 160.549479 -12.117949) (xy 160.526589 -12.223169) (xy 160.49625 -12.326488) (xy 160.458618 -12.427379)
			(xy 160.413884 -12.525329) (xy 160.362276 -12.619838) (xy 160.304058 -12.710424) (xy 160.239525 -12.796626)
			(xy 160.169008 -12.878005) (xy 160.092864 -12.954146) (xy 160.011483 -13.02466) (xy 159.925278 -13.08919)
			(xy 159.834689 -13.147405) (xy 159.740179 -13.199009) (xy 159.642227 -13.243739) (xy 159.541335 -13.281368)
			(xy 159.438014 -13.311702) (xy 159.332793 -13.334589) (xy 159.226208 -13.349911) (xy 159.118801 -13.35759)
			(xy 159.06496 -13.358114) (xy 151.064976 -13.358114) (xy 151.011135 -13.357633) (xy 150.903728 -13.349949)
			(xy 150.797143 -13.334623) (xy 150.691922 -13.311732) (xy 150.588603 -13.281394) (xy 150.487711 -13.243762)
			(xy 150.389761 -13.199028) (xy 150.295252 -13.147421) (xy 150.204664 -13.089204) (xy 150.118461 -13.024672)
			(xy 150.037081 -12.954156) (xy 149.960939 -12.878013) (xy 149.890423 -12.796633) (xy 149.825892 -12.710429)
			(xy 149.767674 -12.619842) (xy 149.716068 -12.525332) (xy 149.671335 -12.427381) (xy 149.633704 -12.326489)
			(xy 149.603366 -12.22317) (xy 149.580476 -12.117949) (xy 149.56515 -12.011364) (xy 149.557467 -11.903957)
			(xy 149.556978 -11.850116) (xy 149.556978 -1.999996) (xy 149.556469 -1.944189) (xy 149.548127 -1.832887)
			(xy 149.531492 -1.722519) (xy 149.506655 -1.613703) (xy 149.473755 -1.507048) (xy 149.432978 -1.403149)
			(xy 149.384549 -1.302588) (xy 149.328742 -1.205928) (xy 149.265867 -1.113708) (xy 149.196276 -1.026445)
			(xy 149.120358 -0.944627) (xy 149.038538 -0.86871) (xy 148.951274 -0.79912) (xy 148.859054 -0.736247)
			(xy 148.762392 -0.68044) (xy 148.661831 -0.632014) (xy 148.557931 -0.591237) (xy 148.451276 -0.55834)
			(xy 148.342459 -0.533504) (xy 148.232091 -0.51687) (xy 148.120789 -0.508531) (xy 148.064982 -0.508)
			(xy 136.065006 -0.508) (xy 136.009198 -0.508509) (xy 135.897895 -0.51685) (xy 135.787526 -0.533485)
			(xy 135.678709 -0.558321) (xy 135.572052 -0.59122) (xy 135.468152 -0.631997) (xy 135.36759 -0.680425)
			(xy 135.270928 -0.736232) (xy 135.178707 -0.799107) (xy 135.091442 -0.868698) (xy 135.009622 -0.944615)
			(xy 134.933704 -1.026435) (xy 134.864113 -1.113699) (xy 134.801237 -1.20592) (xy 134.745429 -1.302581)
			(xy 134.697001 -1.403143) (xy 134.656223 -1.507043) (xy 134.623324 -1.613699) (xy 134.598486 -1.722516)
			(xy 134.581851 -1.832885) (xy 134.573509 -1.944188) (xy 134.57301 -1.999996) (xy 134.57301 -11.850116)
			(xy 134.572529 -11.903957) (xy 134.564846 -12.011364) (xy 134.54952 -12.11795) (xy 134.52663 -12.223171)
			(xy 134.496292 -12.32649) (xy 134.45866 -12.427383) (xy 134.413927 -12.525333) (xy 134.36232 -12.619843)
			(xy 134.304102 -12.710431) (xy 134.239571 -12.796634) (xy 134.169054 -12.878014) (xy 134.092911 -12.954157)
			(xy 134.011531 -13.024673) (xy 133.925327 -13.089205) (xy 133.83474 -13.147422) (xy 133.74023 -13.199029)
			(xy 133.642279 -13.243762) (xy 133.541387 -13.281393) (xy 133.438067 -13.311731) (xy 133.332846 -13.334621)
			(xy 133.22626 -13.349946) (xy 133.118853 -13.357629) (xy 133.065012 -13.358114) (xy 125.065028 -13.358114)
			(xy 125.011186 -13.357646) (xy 124.903775 -13.349966) (xy 124.797186 -13.334642) (xy 124.691962 -13.311754)
			(xy 124.588639 -13.281418) (xy 124.487743 -13.243787) (xy 124.389789 -13.199055) (xy 124.295275 -13.147449)
			(xy 124.204684 -13.089231) (xy 124.118477 -13.0247) (xy 124.037093 -12.954182) (xy 123.960948 -12.878039)
			(xy 123.890428 -12.796657) (xy 123.825894 -12.710452) (xy 123.767674 -12.619863) (xy 123.716065 -12.525351)
			(xy 123.671329 -12.427398) (xy 123.633696 -12.326503) (xy 123.603357 -12.223181) (xy 123.580465 -12.117957)
			(xy 123.565139 -12.011369) (xy 123.557456 -11.903958) (xy 123.55703 -11.850116) (xy 123.55703 -1.999996)
			(xy 123.556508 -1.944189) (xy 123.548167 -1.832886) (xy 123.531532 -1.722518) (xy 123.506695 -1.613701)
			(xy 123.473796 -1.507045) (xy 123.433019 -1.403146) (xy 123.384592 -1.302584) (xy 123.328785 -1.205923)
			(xy 123.265911 -1.113702) (xy 123.196321 -1.026437) (xy 123.120404 -0.944617) (xy 123.038586 -0.868699)
			(xy 122.951322 -0.799107) (xy 122.859103 -0.736231) (xy 122.762442 -0.680422) (xy 122.661882 -0.631993)
			(xy 122.557983 -0.591214) (xy 122.451328 -0.558313) (xy 122.342512 -0.533474) (xy 122.232144 -0.516836)
			(xy 122.120841 -0.508493) (xy 122.065034 -0.508) (xy 97.965006 -0.508) (xy 97.909198 -0.508509) (xy 97.797895 -0.51685)
			(xy 97.687526 -0.533485) (xy 97.578709 -0.558321) (xy 97.472052 -0.59122) (xy 97.368152 -0.631997)
			(xy 97.26759 -0.680425) (xy 97.170928 -0.736232) (xy 97.078707 -0.799107) (xy 96.991442 -0.868698)
			(xy 96.909622 -0.944615) (xy 96.833704 -1.026435) (xy 96.764113 -1.113699) (xy 96.701237 -1.20592)
			(xy 96.645429 -1.302581) (xy 96.597001 -1.403143) (xy 96.556223 -1.507043) (xy 96.523324 -1.613699)
			(xy 96.498486 -1.722516) (xy 96.481851 -1.832885) (xy 96.473509 -1.944188) (xy 96.47301 -1.999996)
			(xy 96.47301 -11.850116) (xy 96.472529 -11.903957) (xy 96.464846 -12.011364) (xy 96.44952 -12.11795)
			(xy 96.42663 -12.223171) (xy 96.396292 -12.32649) (xy 96.35866 -12.427383) (xy 96.313927 -12.525333)
			(xy 96.26232 -12.619843) (xy 96.204102 -12.710431) (xy 96.139571 -12.796634) (xy 96.069054 -12.878014)
			(xy 95.992911 -12.954157) (xy 95.911531 -13.024673) (xy 95.825327 -13.089205) (xy 95.73474 -13.147422)
			(xy 95.64023 -13.199029) (xy 95.542279 -13.243762) (xy 95.441387 -13.281393) (xy 95.338067 -13.311731)
			(xy 95.232846 -13.334621) (xy 95.12626 -13.349946) (xy 95.018853 -13.357629) (xy 94.965012 -13.358114)
			(xy 86.965028 -13.358114) (xy 86.911186 -13.357646) (xy 86.803775 -13.349966) (xy 86.697186 -13.334642)
			(xy 86.591962 -13.311754) (xy 86.488639 -13.281418) (xy 86.387743 -13.243787) (xy 86.289789 -13.199055)
			(xy 86.195275 -13.147449) (xy 86.104684 -13.089231) (xy 86.018477 -13.0247) (xy 85.937093 -12.954182)
			(xy 85.860948 -12.878039) (xy 85.790428 -12.796657) (xy 85.725894 -12.710452) (xy 85.667674 -12.619863)
			(xy 85.616065 -12.525351) (xy 85.571329 -12.427398) (xy 85.533696 -12.326503) (xy 85.503357 -12.223181)
			(xy 85.480465 -12.117957) (xy 85.465139 -12.011369) (xy 85.457456 -11.903958) (xy 85.45703 -11.850116)
			(xy 85.45703 -1.999996) (xy 85.456508 -1.944189) (xy 85.448167 -1.832886) (xy 85.431532 -1.722518)
			(xy 85.406695 -1.613701) (xy 85.373796 -1.507045) (xy 85.333019 -1.403146) (xy 85.284592 -1.302584)
			(xy 85.228785 -1.205923) (xy 85.165911 -1.113702) (xy 85.096321 -1.026437) (xy 85.020404 -0.944617)
			(xy 84.938586 -0.868699) (xy 84.851322 -0.799107) (xy 84.759103 -0.736231) (xy 84.662442 -0.680422)
			(xy 84.561882 -0.631993) (xy 84.457983 -0.591214) (xy 84.351328 -0.558313) (xy 84.242512 -0.533474)
			(xy 84.132144 -0.516836) (xy 84.020841 -0.508493) (xy 83.965034 -0.508) (xy 71.965058 -0.508) (xy 71.909252 -0.508523)
			(xy 71.797952 -0.516867) (xy 71.687587 -0.533505) (xy 71.578774 -0.558343) (xy 71.472121 -0.591244)
			(xy 71.368225 -0.632023) (xy 71.267667 -0.680451) (xy 71.171009 -0.736259) (xy 71.078791 -0.799134)
			(xy 70.991531 -0.868724) (xy 70.909714 -0.944641) (xy 70.8338 -1.026459) (xy 70.764211 -1.113722)
			(xy 70.701339 -1.205941) (xy 70.645534 -1.3026) (xy 70.597107 -1.40316) (xy 70.556331 -1.507057)
			(xy 70.523434 -1.61371) (xy 70.498598 -1.722524) (xy 70.481963 -1.83289) (xy 70.473622 -1.94419)
			(xy 70.473062 -1.999996) (xy 70.473062 -11.850116) (xy 70.472592 -11.903957) (xy 70.464909 -12.011364)
			(xy 70.449583 -12.117949) (xy 70.426693 -12.223169) (xy 70.396354 -12.326488) (xy 70.358722 -12.42738)
			(xy 70.313988 -12.52533) (xy 70.26238 -12.619839) (xy 70.204162 -12.710425) (xy 70.139629 -12.796627)
			(xy 70.069112 -12.878006) (xy 69.992968 -12.954147) (xy 69.911587 -13.024662) (xy 69.825382 -13.089192)
			(xy 69.734794 -13.147407) (xy 69.640283 -13.199011) (xy 69.542332 -13.243742) (xy 69.441439 -13.28137)
			(xy 69.338119 -13.311705) (xy 69.232898 -13.334592) (xy 69.126312 -13.349915) (xy 69.018905 -13.357594)
			(xy 68.965064 -13.358114) (xy 60.96508 -13.358114) (xy 60.911239 -13.357633) (xy 60.803832 -13.349949)
			(xy 60.697246 -13.334624) (xy 60.592026 -13.311733) (xy 60.488706 -13.281395) (xy 60.387814 -13.243763)
			(xy 60.289864 -13.19903) (xy 60.195354 -13.147423) (xy 60.104766 -13.089205) (xy 60.018563 -13.024674)
			(xy 59.937183 -12.954157) (xy 59.86104 -12.878014) (xy 59.790524 -12.796634) (xy 59.725992 -12.71043)
			(xy 59.667775 -12.619843) (xy 59.616169 -12.525333) (xy 59.571435 -12.427382) (xy 59.533804 -12.32649)
			(xy 59.503466 -12.22317) (xy 59.480576 -12.11795) (xy 59.46525 -12.011364) (xy 59.457567 -11.903957)
			(xy 59.457082 -11.850116) (xy 59.457082 -1.999996) (xy 59.456573 -1.944189) (xy 59.448231 -1.832886)
			(xy 59.431596 -1.722519) (xy 59.406759 -1.613703) (xy 59.373859 -1.507047) (xy 59.333082 -1.403148)
			(xy 59.284653 -1.302588) (xy 59.228846 -1.205927) (xy 59.165971 -1.113707) (xy 59.09638 -1.026444)
			(xy 59.020462 -0.944625) (xy 58.938643 -0.868709) (xy 58.851378 -0.799119) (xy 58.759158 -0.736245)
			(xy 58.662496 -0.680438) (xy 58.561935 -0.632011) (xy 58.458036 -0.591235) (xy 58.35138 -0.558337)
			(xy 58.242564 -0.533501) (xy 58.132196 -0.516867) (xy 58.020893 -0.508527) (xy 57.965086 -0.508)
			(xy 45.96511 -0.508) (xy 45.909302 -0.508509) (xy 45.797999 -0.516849) (xy 45.68763 -0.533484) (xy 45.578812 -0.55832)
			(xy 45.472155 -0.591219) (xy 45.368255 -0.631996) (xy 45.267693 -0.680423) (xy 45.17103 -0.736231)
			(xy 45.078809 -0.799106) (xy 44.991544 -0.868696) (xy 44.909724 -0.944614) (xy 44.833805 -1.026433)
			(xy 44.764214 -1.113698) (xy 44.701338 -1.205919) (xy 44.64553 -1.30258) (xy 44.597101 -1.403142)
			(xy 44.556323 -1.507042) (xy 44.523424 -1.613699) (xy 44.498587 -1.722516) (xy 44.481951 -1.832885)
			(xy 44.473609 -1.944188) (xy 44.473114 -1.999996) (xy 44.473114 -11.850116) (xy 44.472633 -11.903957)
			(xy 44.46495 -12.011364) (xy 44.449624 -12.11795) (xy 44.426734 -12.223171) (xy 44.396396 -12.326491)
			(xy 44.358764 -12.427383) (xy 44.314031 -12.525334) (xy 44.262424 -12.619844) (xy 44.204207 -12.710432)
			(xy 44.139675 -12.796635) (xy 44.069158 -12.878016) (xy 43.993016 -12.954158) (xy 43.911635 -13.024675)
			(xy 43.825432 -13.089207) (xy 43.734844 -13.147424) (xy 43.640334 -13.199031) (xy 43.542383 -13.243764)
			(xy 43.441491 -13.281396) (xy 43.338171 -13.311734) (xy 43.23295 -13.334624) (xy 43.126364 -13.34995)
			(xy 43.018957 -13.357633) (xy 42.965116 -13.358114) (xy 34.964878 -13.358114) (xy 34.911037 -13.357633)
			(xy 34.80363 -13.349949) (xy 34.697045 -13.334623) (xy 34.591824 -13.311733) (xy 34.488505 -13.281394)
			(xy 34.387613 -13.243762) (xy 34.289662 -13.199029) (xy 34.195153 -13.147422) (xy 34.104565 -13.089205)
			(xy 34.018362 -13.024673) (xy 33.936982 -12.954156) (xy 33.86084 -12.878014) (xy 33.790323 -12.796633)
			(xy 33.725792 -12.71043) (xy 33.667575 -12.619842) (xy 33.615968 -12.525332) (xy 33.571235 -12.427382)
			(xy 33.533604 -12.32649) (xy 33.503266 -12.22317) (xy 33.480376 -12.11795) (xy 33.46505 -12.011364)
			(xy 33.457367 -11.903957) (xy 33.45688 -11.850116) (xy 33.45688 -1.999996) (xy 33.456371 -1.944189)
			(xy 33.448029 -1.832887) (xy 33.431394 -1.722519) (xy 33.406557 -1.613703) (xy 33.373657 -1.507048)
			(xy 33.33288 -1.403149) (xy 33.284451 -1.302588) (xy 33.228644 -1.205927) (xy 33.165769 -1.113708)
			(xy 33.096178 -1.026444) (xy 33.02026 -0.944626) (xy 32.93844 -0.868709) (xy 32.851176 -0.79912)
			(xy 32.758956 -0.736246) (xy 32.662294 -0.680439) (xy 32.561733 -0.632012) (xy 32.457834 -0.591236)
			(xy 32.351178 -0.558338) (xy 32.242361 -0.533503) (xy 32.131994 -0.516868) (xy 32.020691 -0.508529)
			(xy 31.964884 -0.508) (xy 19.964908 -0.508) (xy 19.9091 -0.508509) (xy 19.797797 -0.516849) (xy 19.687428 -0.533484)
			(xy 19.578611 -0.55832) (xy 19.471954 -0.591219) (xy 19.368054 -0.631996) (xy 19.267491 -0.680424)
			(xy 19.170829 -0.736231) (xy 19.078608 -0.799106) (xy 18.991343 -0.868697) (xy 18.909523 -0.944614)
			(xy 18.833605 -1.026434) (xy 18.764013 -1.113698) (xy 18.701138 -1.205919) (xy 18.64533 -1.302581)
			(xy 18.596901 -1.403143) (xy 18.556123 -1.507043) (xy 18.523224 -1.613699) (xy 18.498386 -1.722516)
			(xy 18.481751 -1.832885) (xy 18.473409 -1.944188) (xy 18.472912 -1.999996) (xy 18.472912 -11.850116)
			(xy 18.472443 -11.903958) (xy 18.464761 -12.011366) (xy 18.449437 -12.117953) (xy 18.426547 -12.223176)
			(xy 18.396209 -12.326497) (xy 18.358578 -12.42739) (xy 18.313845 -12.525342) (xy 18.262238 -12.619854)
			(xy 18.20402 -12.710442) (xy 18.139488 -12.796647) (xy 18.068971 -12.878029) (xy 17.992827 -12.954172)
			(xy 17.911446 -13.024689) (xy 17.825241 -13.089221) (xy 17.734652 -13.147439) (xy 17.640141 -13.199046)
			(xy 17.542189 -13.243779) (xy 17.441295 -13.28141) (xy 17.337974 -13.311748) (xy 17.232751 -13.334637)
			(xy 17.126164 -13.349961) (xy 17.018756 -13.357643) (xy 16.964914 -13.358114) (xy 8.96493 -13.358114)
			(xy 8.911089 -13.357645) (xy 8.80368 -13.349963) (xy 8.697093 -13.334638) (xy 8.591871 -13.311748)
			(xy 8.48855 -13.28141) (xy 8.387656 -13.243779) (xy 8.289705 -13.199046) (xy 8.195194 -13.147439)
			(xy 8.104605 -13.089221) (xy 8.0184 -13.024689) (xy 7.937019 -12.954171) (xy 7.860876 -12.878028)
			(xy 7.790359 -12.796646) (xy 7.725827 -12.710442) (xy 7.667609 -12.619853) (xy 7.616002 -12.525342)
			(xy 7.57127 -12.42739) (xy 7.533638 -12.326496) (xy 7.503301 -12.223175) (xy 7.480411 -12.117953)
			(xy 7.465087 -12.011366) (xy 7.457405 -11.903957) (xy 7.456932 -11.850116) (xy 7.456932 -1.999996)
			(xy 7.45641 -1.944189) (xy 7.448069 -1.832887) (xy 7.431434 -1.72252) (xy 7.406597 -1.613704) (xy 7.373698 -1.507049)
			(xy 7.332921 -1.40315) (xy 7.284493 -1.30259) (xy 7.228686 -1.205929) (xy 7.165812 -1.113709) (xy 7.096221 -1.026446)
			(xy 7.020305 -0.944627) (xy 6.938486 -0.86871) (xy 6.851222 -0.79912) (xy 6.759003 -0.736245) (xy 6.662342 -0.680438)
			(xy 6.561782 -0.63201) (xy 6.457883 -0.591233) (xy 6.351228 -0.558334) (xy 6.242412 -0.533497) (xy 6.132045 -0.516861)
			(xy 6.020743 -0.50852) (xy 5.964936 -0.508) (xy 1.999996 -0.508) (xy 1.944189 -0.508522) (xy 1.832887 -0.516863)
			(xy 1.72252 -0.533498) (xy 1.613704 -0.558335) (xy 1.507049 -0.591234) (xy 1.403151 -0.632011) (xy 1.30259 -0.680439)
			(xy 1.205929 -0.736246) (xy 1.11371 -0.799121) (xy 1.026446 -0.868711) (xy 0.944628 -0.944628) (xy 0.868711 -1.026446)
			(xy 0.799121 -1.11371) (xy 0.736246 -1.205929) (xy 0.680439 -1.30259) (xy 0.632011 -1.403151) (xy 0.591234 -1.507049)
			(xy 0.558335 -1.613704) (xy 0.533498 -1.72252) (xy 0.516863 -1.832887) (xy 0.508522 -1.944189) (xy 0.508 -1.999996)
			(xy 0.508 -15.200122) (xy 459.541372 -15.200122) (xy 459.541372 -13.599922) (xy 459.54188 -13.535242)
			(xy 459.550003 -13.406136) (xy 459.566216 -13.277796) (xy 459.590456 -13.150726) (xy 459.622626 -13.02543)
			(xy 459.662601 -12.9024) (xy 459.710222 -12.782124) (xy 459.765301 -12.665075) (xy 459.827621 -12.551715)
			(xy 459.896936 -12.442492) (xy 459.972972 -12.337837) (xy 460.05543 -12.238163) (xy 460.143983 -12.143863)
			(xy 460.238283 -12.05531) (xy 460.337957 -11.972852) (xy 460.442612 -11.896816) (xy 460.551835 -11.827501)
			(xy 460.665195 -11.765181) (xy 460.782244 -11.710102) (xy 460.90252 -11.662481) (xy 461.02555 -11.622506)
			(xy 461.150846 -11.590336) (xy 461.277916 -11.566096) (xy 461.406256 -11.549883) (xy 461.535362 -11.54176)
			(xy 461.664722 -11.54176) (xy 461.793828 -11.549883) (xy 461.922168 -11.566096) (xy 462.049238 -11.590336)
			(xy 462.174534 -11.622506) (xy 462.297564 -11.662481) (xy 462.41784 -11.710102) (xy 462.534889 -11.765181)
			(xy 462.648249 -11.827501) (xy 462.757472 -11.896816) (xy 462.862127 -11.972852) (xy 462.961801 -12.05531)
			(xy 463.056101 -12.143863) (xy 463.144654 -12.238163) (xy 463.227112 -12.337837) (xy 463.303148 -12.442492)
			(xy 463.372463 -12.551715) (xy 463.434783 -12.665075) (xy 463.489862 -12.782124) (xy 463.537483 -12.9024)
			(xy 463.577458 -13.02543) (xy 463.609628 -13.150726) (xy 463.633868 -13.277796) (xy 463.650081 -13.406136)
			(xy 463.658204 -13.535242) (xy 463.658712 -13.599922) (xy 463.658712 -15.200122) (xy 463.658204 -15.264802)
			(xy 463.650081 -15.393908) (xy 463.633868 -15.522248) (xy 463.609628 -15.649318) (xy 463.577458 -15.774614)
			(xy 463.537483 -15.897644) (xy 463.489862 -16.01792) (xy 463.434783 -16.134969) (xy 463.372463 -16.248329)
			(xy 463.303148 -16.357552) (xy 463.227112 -16.462207) (xy 463.144654 -16.561881) (xy 463.056101 -16.656181)
			(xy 462.961801 -16.744734) (xy 462.862127 -16.827192) (xy 462.757472 -16.903228) (xy 462.648249 -16.972543)
			(xy 462.534889 -17.034863) (xy 462.41784 -17.089942) (xy 462.297564 -17.137563) (xy 462.174534 -17.177538)
			(xy 462.049238 -17.209708) (xy 461.922168 -17.233948) (xy 461.793828 -17.250161) (xy 461.664722 -17.258284)
			(xy 461.535362 -17.258284) (xy 461.406256 -17.250161) (xy 461.277916 -17.233948) (xy 461.150846 -17.209708)
			(xy 461.02555 -17.177538) (xy 460.90252 -17.137563) (xy 460.782244 -17.089942) (xy 460.665195 -17.034863)
			(xy 460.551835 -16.972543) (xy 460.442612 -16.903228) (xy 460.337957 -16.827192) (xy 460.238283 -16.744734)
			(xy 460.143983 -16.656181) (xy 460.05543 -16.561881) (xy 459.972972 -16.462207) (xy 459.896936 -16.357552)
			(xy 459.827621 -16.248329) (xy 459.765301 -16.134969) (xy 459.710222 -16.01792) (xy 459.662601 -15.897644)
			(xy 459.622626 -15.774614) (xy 459.590456 -15.649318) (xy 459.566216 -15.522248) (xy 459.550003 -15.393908)
			(xy 459.54188 -15.264802) (xy 459.541372 -15.200122) (xy 0.508 -15.200122) (xy 0.508 -16.969994)
			(xy 13.748265 -16.969994) (xy 13.75227 -16.882086) (xy 13.764253 -16.794906) (xy 13.784113 -16.709177)
			(xy 13.811688 -16.625609) (xy 13.846747 -16.544895) (xy 13.889 -16.467703) (xy 13.938098 -16.394674)
			(xy 13.993634 -16.326412) (xy 14.055146 -16.263482) (xy 14.122127 -16.206408) (xy 14.19402 -16.15566)
			(xy 14.270229 -16.11166) (xy 14.350124 -16.074773) (xy 14.433043 -16.045304) (xy 14.518298 -16.023497)
			(xy 14.605182 -16.009533) (xy 14.692976 -16.003527) (xy 14.780953 -16.005531) (xy 14.868383 -16.015526)
			(xy 14.954542 -16.03343) (xy 15.038716 -16.059094) (xy 15.120207 -16.092307) (xy 15.198341 -16.132793)
			(xy 15.272469 -16.180215) (xy 15.341977 -16.234182) (xy 15.406291 -16.294247) (xy 15.464875 -16.359911)
			(xy 15.517246 -16.43063) (xy 15.562969 -16.505818) (xy 15.601666 -16.584853) (xy 15.633015 -16.667079)
			(xy 15.656757 -16.751815) (xy 15.672695 -16.838359) (xy 15.680697 -16.925994) (xy 15.681198 -16.969994)
			(xy 39.748213 -16.969994) (xy 39.752218 -16.882086) (xy 39.764201 -16.794906) (xy 39.784061 -16.709177)
			(xy 39.811636 -16.625609) (xy 39.846695 -16.544895) (xy 39.888948 -16.467703) (xy 39.938046 -16.394674)
			(xy 39.993582 -16.326412) (xy 40.055094 -16.263482) (xy 40.122075 -16.206408) (xy 40.193968 -16.15566)
			(xy 40.270177 -16.11166) (xy 40.350072 -16.074773) (xy 40.432991 -16.045304) (xy 40.518246 -16.023497)
			(xy 40.60513 -16.009533) (xy 40.692924 -16.003527) (xy 40.780901 -16.005531) (xy 40.868331 -16.015526)
			(xy 40.95449 -16.03343) (xy 41.038664 -16.059094) (xy 41.120155 -16.092307) (xy 41.198289 -16.132793)
			(xy 41.272417 -16.180215) (xy 41.341925 -16.234182) (xy 41.406239 -16.294247) (xy 41.464823 -16.359911)
			(xy 41.517194 -16.43063) (xy 41.562917 -16.505818) (xy 41.601614 -16.584853) (xy 41.632963 -16.667079)
			(xy 41.656705 -16.751815) (xy 41.672643 -16.838359) (xy 41.680645 -16.925994) (xy 41.681146 -16.969994)
			(xy 65.748161 -16.969994) (xy 65.752166 -16.882086) (xy 65.764149 -16.794906) (xy 65.784009 -16.709177)
			(xy 65.811584 -16.625609) (xy 65.846643 -16.544895) (xy 65.888896 -16.467703) (xy 65.937994 -16.394674)
			(xy 65.99353 -16.326412) (xy 66.055042 -16.263482) (xy 66.122023 -16.206408) (xy 66.193916 -16.15566)
			(xy 66.270125 -16.11166) (xy 66.35002 -16.074773) (xy 66.432939 -16.045304) (xy 66.518194 -16.023497)
			(xy 66.605078 -16.009533) (xy 66.692872 -16.003527) (xy 66.780849 -16.005531) (xy 66.868279 -16.015526)
			(xy 66.954438 -16.03343) (xy 67.038612 -16.059094) (xy 67.120103 -16.092307) (xy 67.198237 -16.132793)
			(xy 67.272365 -16.180215) (xy 67.341873 -16.234182) (xy 67.406187 -16.294247) (xy 67.464771 -16.359911)
			(xy 67.517142 -16.43063) (xy 67.562865 -16.505818) (xy 67.601562 -16.584853) (xy 67.632911 -16.667079)
			(xy 67.656653 -16.751815) (xy 67.672591 -16.838359) (xy 67.680593 -16.925994) (xy 67.681094 -16.969994)
			(xy 91.748109 -16.969994) (xy 91.752114 -16.882086) (xy 91.764097 -16.794906) (xy 91.783957 -16.709177)
			(xy 91.811532 -16.625609) (xy 91.846591 -16.544895) (xy 91.888844 -16.467703) (xy 91.937942 -16.394674)
			(xy 91.993478 -16.326412) (xy 92.05499 -16.263482) (xy 92.121971 -16.206408) (xy 92.193864 -16.15566)
			(xy 92.270073 -16.11166) (xy 92.349968 -16.074773) (xy 92.432887 -16.045304) (xy 92.518142 -16.023497)
			(xy 92.605026 -16.009533) (xy 92.69282 -16.003527) (xy 92.780797 -16.005531) (xy 92.868227 -16.015526)
			(xy 92.954386 -16.03343) (xy 93.03856 -16.059094) (xy 93.120051 -16.092307) (xy 93.198185 -16.132793)
			(xy 93.272313 -16.180215) (xy 93.341821 -16.234182) (xy 93.406135 -16.294247) (xy 93.464719 -16.359911)
			(xy 93.51709 -16.43063) (xy 93.562813 -16.505818) (xy 93.60151 -16.584853) (xy 93.632859 -16.667079)
			(xy 93.656601 -16.751815) (xy 93.672539 -16.838359) (xy 93.680541 -16.925994) (xy 93.681042 -16.969994)
			(xy 129.848363 -16.969994) (xy 129.852368 -16.882086) (xy 129.864351 -16.794906) (xy 129.884211 -16.709177)
			(xy 129.911786 -16.625609) (xy 129.946845 -16.544895) (xy 129.989098 -16.467703) (xy 130.038196 -16.394674)
			(xy 130.093732 -16.326412) (xy 130.155244 -16.263482) (xy 130.222225 -16.206408) (xy 130.294118 -16.15566)
			(xy 130.370327 -16.11166) (xy 130.450222 -16.074773) (xy 130.533141 -16.045304) (xy 130.618396 -16.023497)
			(xy 130.70528 -16.009533) (xy 130.793074 -16.003527) (xy 130.881051 -16.005531) (xy 130.968481 -16.015526)
			(xy 131.05464 -16.03343) (xy 131.138814 -16.059094) (xy 131.220305 -16.092307) (xy 131.298439 -16.132793)
			(xy 131.372567 -16.180215) (xy 131.442075 -16.234182) (xy 131.506389 -16.294247) (xy 131.564973 -16.359911)
			(xy 131.617344 -16.43063) (xy 131.663067 -16.505818) (xy 131.701764 -16.584853) (xy 131.733113 -16.667079)
			(xy 131.756855 -16.751815) (xy 131.772793 -16.838359) (xy 131.780795 -16.925994) (xy 131.781296 -16.969994)
			(xy 155.848311 -16.969994) (xy 155.852316 -16.882086) (xy 155.864299 -16.794906) (xy 155.884159 -16.709177)
			(xy 155.911734 -16.625609) (xy 155.946793 -16.544895) (xy 155.989046 -16.467703) (xy 156.038144 -16.394674)
			(xy 156.09368 -16.326412) (xy 156.155192 -16.263482) (xy 156.222173 -16.206408) (xy 156.294066 -16.15566)
			(xy 156.370275 -16.11166) (xy 156.45017 -16.074773) (xy 156.533089 -16.045304) (xy 156.618344 -16.023497)
			(xy 156.705228 -16.009533) (xy 156.793022 -16.003527) (xy 156.880999 -16.005531) (xy 156.968429 -16.015526)
			(xy 157.054588 -16.03343) (xy 157.138762 -16.059094) (xy 157.220253 -16.092307) (xy 157.298387 -16.132793)
			(xy 157.372515 -16.180215) (xy 157.442023 -16.234182) (xy 157.506337 -16.294247) (xy 157.564921 -16.359911)
			(xy 157.617292 -16.43063) (xy 157.663015 -16.505818) (xy 157.701712 -16.584853) (xy 157.733061 -16.667079)
			(xy 157.756803 -16.751815) (xy 157.772741 -16.838359) (xy 157.780743 -16.925994) (xy 157.781244 -16.969994)
			(xy 181.848259 -16.969994) (xy 181.852264 -16.882086) (xy 181.864247 -16.794906) (xy 181.884107 -16.709177)
			(xy 181.911682 -16.625609) (xy 181.946741 -16.544895) (xy 181.988994 -16.467703) (xy 182.038092 -16.394674)
			(xy 182.093628 -16.326412) (xy 182.15514 -16.263482) (xy 182.222121 -16.206408) (xy 182.294014 -16.15566)
			(xy 182.370223 -16.11166) (xy 182.450118 -16.074773) (xy 182.533037 -16.045304) (xy 182.618292 -16.023497)
			(xy 182.705176 -16.009533) (xy 182.79297 -16.003527) (xy 182.880947 -16.005531) (xy 182.968377 -16.015526)
			(xy 183.054536 -16.03343) (xy 183.13871 -16.059094) (xy 183.220201 -16.092307) (xy 183.298335 -16.132793)
			(xy 183.372463 -16.180215) (xy 183.441971 -16.234182) (xy 183.506285 -16.294247) (xy 183.564869 -16.359911)
			(xy 183.61724 -16.43063) (xy 183.662963 -16.505818) (xy 183.70166 -16.584853) (xy 183.733009 -16.667079)
			(xy 183.756751 -16.751815) (xy 183.772689 -16.838359) (xy 183.780691 -16.925994) (xy 183.781192 -16.969994)
			(xy 207.848207 -16.969994) (xy 207.852212 -16.882086) (xy 207.864195 -16.794906) (xy 207.884055 -16.709177)
			(xy 207.91163 -16.625609) (xy 207.946689 -16.544895) (xy 207.988942 -16.467703) (xy 208.03804 -16.394674)
			(xy 208.093576 -16.326412) (xy 208.155088 -16.263482) (xy 208.222069 -16.206408) (xy 208.293962 -16.15566)
			(xy 208.370171 -16.11166) (xy 208.450066 -16.074773) (xy 208.532985 -16.045304) (xy 208.61824 -16.023497)
			(xy 208.705124 -16.009533) (xy 208.792918 -16.003527) (xy 208.880895 -16.005531) (xy 208.968325 -16.015526)
			(xy 209.054484 -16.03343) (xy 209.138658 -16.059094) (xy 209.220149 -16.092307) (xy 209.298283 -16.132793)
			(xy 209.372411 -16.180215) (xy 209.441919 -16.234182) (xy 209.506233 -16.294247) (xy 209.564817 -16.359911)
			(xy 209.617188 -16.43063) (xy 209.662911 -16.505818) (xy 209.701608 -16.584853) (xy 209.732957 -16.667079)
			(xy 209.756699 -16.751815) (xy 209.772637 -16.838359) (xy 209.780639 -16.925994) (xy 209.78114 -16.969994)
			(xy 245.948207 -16.969994) (xy 245.952212 -16.882086) (xy 245.964195 -16.794906) (xy 245.984055 -16.709177)
			(xy 246.01163 -16.625609) (xy 246.046689 -16.544895) (xy 246.088942 -16.467703) (xy 246.13804 -16.394674)
			(xy 246.193576 -16.326412) (xy 246.255088 -16.263482) (xy 246.322069 -16.206408) (xy 246.393962 -16.15566)
			(xy 246.470171 -16.11166) (xy 246.550066 -16.074773) (xy 246.632985 -16.045304) (xy 246.71824 -16.023497)
			(xy 246.805124 -16.009533) (xy 246.892918 -16.003527) (xy 246.980895 -16.005531) (xy 247.068325 -16.015526)
			(xy 247.154484 -16.03343) (xy 247.238658 -16.059094) (xy 247.320149 -16.092307) (xy 247.398283 -16.132793)
			(xy 247.472411 -16.180215) (xy 247.541919 -16.234182) (xy 247.606233 -16.294247) (xy 247.664817 -16.359911)
			(xy 247.717188 -16.43063) (xy 247.762911 -16.505818) (xy 247.801608 -16.584853) (xy 247.832957 -16.667079)
			(xy 247.856699 -16.751815) (xy 247.872637 -16.838359) (xy 247.880639 -16.925994) (xy 247.88114 -16.969994)
			(xy 271.948155 -16.969994) (xy 271.95216 -16.882086) (xy 271.964143 -16.794906) (xy 271.984003 -16.709177)
			(xy 272.011578 -16.625609) (xy 272.046637 -16.544895) (xy 272.08889 -16.467703) (xy 272.137988 -16.394674)
			(xy 272.193524 -16.326412) (xy 272.255036 -16.263482) (xy 272.322017 -16.206408) (xy 272.39391 -16.15566)
			(xy 272.470119 -16.11166) (xy 272.550014 -16.074773) (xy 272.632933 -16.045304) (xy 272.718188 -16.023497)
			(xy 272.805072 -16.009533) (xy 272.892866 -16.003527) (xy 272.980843 -16.005531) (xy 273.068273 -16.015526)
			(xy 273.154432 -16.03343) (xy 273.238606 -16.059094) (xy 273.320097 -16.092307) (xy 273.398231 -16.132793)
			(xy 273.472359 -16.180215) (xy 273.541867 -16.234182) (xy 273.606181 -16.294247) (xy 273.664765 -16.359911)
			(xy 273.717136 -16.43063) (xy 273.762859 -16.505818) (xy 273.801556 -16.584853) (xy 273.832905 -16.667079)
			(xy 273.856647 -16.751815) (xy 273.872585 -16.838359) (xy 273.880587 -16.925994) (xy 273.881088 -16.969994)
			(xy 297.948103 -16.969994) (xy 297.952108 -16.882086) (xy 297.964091 -16.794906) (xy 297.983951 -16.709177)
			(xy 298.011526 -16.625609) (xy 298.046585 -16.544895) (xy 298.088838 -16.467703) (xy 298.137936 -16.394674)
			(xy 298.193472 -16.326412) (xy 298.254984 -16.263482) (xy 298.321965 -16.206408) (xy 298.393858 -16.15566)
			(xy 298.470067 -16.11166) (xy 298.549962 -16.074773) (xy 298.632881 -16.045304) (xy 298.718136 -16.023497)
			(xy 298.80502 -16.009533) (xy 298.892814 -16.003527) (xy 298.980791 -16.005531) (xy 299.068221 -16.015526)
			(xy 299.15438 -16.03343) (xy 299.238554 -16.059094) (xy 299.320045 -16.092307) (xy 299.398179 -16.132793)
			(xy 299.472307 -16.180215) (xy 299.541815 -16.234182) (xy 299.606129 -16.294247) (xy 299.664713 -16.359911)
			(xy 299.717084 -16.43063) (xy 299.762807 -16.505818) (xy 299.801504 -16.584853) (xy 299.832853 -16.667079)
			(xy 299.856595 -16.751815) (xy 299.872533 -16.838359) (xy 299.880535 -16.925994) (xy 299.881036 -16.969994)
			(xy 323.948051 -16.969994) (xy 323.952056 -16.882086) (xy 323.964039 -16.794906) (xy 323.983899 -16.709177)
			(xy 324.011474 -16.625609) (xy 324.046533 -16.544895) (xy 324.088786 -16.467703) (xy 324.137884 -16.394674)
			(xy 324.19342 -16.326412) (xy 324.254932 -16.263482) (xy 324.321913 -16.206408) (xy 324.393806 -16.15566)
			(xy 324.470015 -16.11166) (xy 324.54991 -16.074773) (xy 324.632829 -16.045304) (xy 324.718084 -16.023497)
			(xy 324.804968 -16.009533) (xy 324.892762 -16.003527) (xy 324.980739 -16.005531) (xy 325.068169 -16.015526)
			(xy 325.154328 -16.03343) (xy 325.238502 -16.059094) (xy 325.319993 -16.092307) (xy 325.398127 -16.132793)
			(xy 325.472255 -16.180215) (xy 325.541763 -16.234182) (xy 325.606077 -16.294247) (xy 325.664661 -16.359911)
			(xy 325.717032 -16.43063) (xy 325.762755 -16.505818) (xy 325.801452 -16.584853) (xy 325.832801 -16.667079)
			(xy 325.856543 -16.751815) (xy 325.872481 -16.838359) (xy 325.880483 -16.925994) (xy 325.880984 -16.969994)
			(xy 362.048305 -16.969994) (xy 362.05231 -16.882086) (xy 362.064293 -16.794906) (xy 362.084153 -16.709177)
			(xy 362.111728 -16.625609) (xy 362.146787 -16.544895) (xy 362.18904 -16.467703) (xy 362.238138 -16.394674)
			(xy 362.293674 -16.326412) (xy 362.355186 -16.263482) (xy 362.422167 -16.206408) (xy 362.49406 -16.15566)
			(xy 362.570269 -16.11166) (xy 362.650164 -16.074773) (xy 362.733083 -16.045304) (xy 362.818338 -16.023497)
			(xy 362.905222 -16.009533) (xy 362.993016 -16.003527) (xy 363.080993 -16.005531) (xy 363.168423 -16.015526)
			(xy 363.254582 -16.03343) (xy 363.338756 -16.059094) (xy 363.420247 -16.092307) (xy 363.498381 -16.132793)
			(xy 363.572509 -16.180215) (xy 363.642017 -16.234182) (xy 363.706331 -16.294247) (xy 363.764915 -16.359911)
			(xy 363.817286 -16.43063) (xy 363.863009 -16.505818) (xy 363.901706 -16.584853) (xy 363.933055 -16.667079)
			(xy 363.956797 -16.751815) (xy 363.972735 -16.838359) (xy 363.980737 -16.925994) (xy 363.981238 -16.969994)
			(xy 388.048253 -16.969994) (xy 388.052258 -16.882086) (xy 388.064241 -16.794906) (xy 388.084101 -16.709177)
			(xy 388.111676 -16.625609) (xy 388.146735 -16.544895) (xy 388.188988 -16.467703) (xy 388.238086 -16.394674)
			(xy 388.293622 -16.326412) (xy 388.355134 -16.263482) (xy 388.422115 -16.206408) (xy 388.494008 -16.15566)
			(xy 388.570217 -16.11166) (xy 388.650112 -16.074773) (xy 388.733031 -16.045304) (xy 388.818286 -16.023497)
			(xy 388.90517 -16.009533) (xy 388.992964 -16.003527) (xy 389.080941 -16.005531) (xy 389.168371 -16.015526)
			(xy 389.25453 -16.03343) (xy 389.338704 -16.059094) (xy 389.420195 -16.092307) (xy 389.498329 -16.132793)
			(xy 389.572457 -16.180215) (xy 389.641965 -16.234182) (xy 389.706279 -16.294247) (xy 389.764863 -16.359911)
			(xy 389.817234 -16.43063) (xy 389.862957 -16.505818) (xy 389.901654 -16.584853) (xy 389.933003 -16.667079)
			(xy 389.956745 -16.751815) (xy 389.972683 -16.838359) (xy 389.980685 -16.925994) (xy 389.981186 -16.969994)
			(xy 414.048201 -16.969994) (xy 414.052206 -16.882086) (xy 414.064189 -16.794906) (xy 414.084049 -16.709177)
			(xy 414.111624 -16.625609) (xy 414.146683 -16.544895) (xy 414.188936 -16.467703) (xy 414.238034 -16.394674)
			(xy 414.29357 -16.326412) (xy 414.355082 -16.263482) (xy 414.422063 -16.206408) (xy 414.493956 -16.15566)
			(xy 414.570165 -16.11166) (xy 414.65006 -16.074773) (xy 414.732979 -16.045304) (xy 414.818234 -16.023497)
			(xy 414.905118 -16.009533) (xy 414.992912 -16.003527) (xy 415.080889 -16.005531) (xy 415.168319 -16.015526)
			(xy 415.254478 -16.03343) (xy 415.338652 -16.059094) (xy 415.420143 -16.092307) (xy 415.498277 -16.132793)
			(xy 415.572405 -16.180215) (xy 415.641913 -16.234182) (xy 415.706227 -16.294247) (xy 415.764811 -16.359911)
			(xy 415.817182 -16.43063) (xy 415.862905 -16.505818) (xy 415.901602 -16.584853) (xy 415.932951 -16.667079)
			(xy 415.956693 -16.751815) (xy 415.972631 -16.838359) (xy 415.980633 -16.925994) (xy 415.981134 -16.969994)
			(xy 440.048149 -16.969994) (xy 440.052154 -16.882086) (xy 440.064137 -16.794906) (xy 440.083997 -16.709177)
			(xy 440.111572 -16.625609) (xy 440.146631 -16.544895) (xy 440.188884 -16.467703) (xy 440.237982 -16.394674)
			(xy 440.293518 -16.326412) (xy 440.35503 -16.263482) (xy 440.422011 -16.206408) (xy 440.493904 -16.15566)
			(xy 440.570113 -16.11166) (xy 440.650008 -16.074773) (xy 440.732927 -16.045304) (xy 440.818182 -16.023497)
			(xy 440.905066 -16.009533) (xy 440.99286 -16.003527) (xy 441.080837 -16.005531) (xy 441.168267 -16.015526)
			(xy 441.254426 -16.03343) (xy 441.3386 -16.059094) (xy 441.420091 -16.092307) (xy 441.498225 -16.132793)
			(xy 441.572353 -16.180215) (xy 441.641861 -16.234182) (xy 441.706175 -16.294247) (xy 441.764759 -16.359911)
			(xy 441.81713 -16.43063) (xy 441.862853 -16.505818) (xy 441.90155 -16.584853) (xy 441.932899 -16.667079)
			(xy 441.956641 -16.751815) (xy 441.972579 -16.838359) (xy 441.980581 -16.925994) (xy 441.981082 -16.969994)
			(xy 441.980581 -17.013994) (xy 441.972579 -17.101629) (xy 441.956641 -17.188173) (xy 441.932899 -17.272909)
			(xy 441.90155 -17.355135) (xy 441.862853 -17.43417) (xy 441.81713 -17.509358) (xy 441.764759 -17.580077)
			(xy 441.706175 -17.645741) (xy 441.641861 -17.705806) (xy 441.572353 -17.759773) (xy 441.498225 -17.807195)
			(xy 441.420091 -17.847681) (xy 441.3386 -17.880894) (xy 441.254426 -17.906558) (xy 441.168267 -17.924462)
			(xy 441.080837 -17.934457) (xy 440.99286 -17.936461) (xy 440.905066 -17.930455) (xy 440.818182 -17.916491)
			(xy 440.732927 -17.894684) (xy 440.650008 -17.865215) (xy 440.570113 -17.828328) (xy 440.493904 -17.784328)
			(xy 440.422011 -17.73358) (xy 440.35503 -17.676506) (xy 440.293518 -17.613576) (xy 440.237982 -17.545314)
			(xy 440.188884 -17.472285) (xy 440.146631 -17.395093) (xy 440.111572 -17.314379) (xy 440.083997 -17.230811)
			(xy 440.064137 -17.145082) (xy 440.052154 -17.057902) (xy 440.048149 -16.969994) (xy 415.981134 -16.969994)
			(xy 415.980633 -17.013994) (xy 415.972631 -17.101629) (xy 415.956693 -17.188173) (xy 415.932951 -17.272909)
			(xy 415.901602 -17.355135) (xy 415.862905 -17.43417) (xy 415.817182 -17.509358) (xy 415.764811 -17.580077)
			(xy 415.706227 -17.645741) (xy 415.641913 -17.705806) (xy 415.572405 -17.759773) (xy 415.498277 -17.807195)
			(xy 415.420143 -17.847681) (xy 415.338652 -17.880894) (xy 415.254478 -17.906558) (xy 415.168319 -17.924462)
			(xy 415.080889 -17.934457) (xy 414.992912 -17.936461) (xy 414.905118 -17.930455) (xy 414.818234 -17.916491)
			(xy 414.732979 -17.894684) (xy 414.65006 -17.865215) (xy 414.570165 -17.828328) (xy 414.493956 -17.784328)
			(xy 414.422063 -17.73358) (xy 414.355082 -17.676506) (xy 414.29357 -17.613576) (xy 414.238034 -17.545314)
			(xy 414.188936 -17.472285) (xy 414.146683 -17.395093) (xy 414.111624 -17.314379) (xy 414.084049 -17.230811)
			(xy 414.064189 -17.145082) (xy 414.052206 -17.057902) (xy 414.048201 -16.969994) (xy 389.981186 -16.969994)
			(xy 389.980685 -17.013994) (xy 389.972683 -17.101629) (xy 389.956745 -17.188173) (xy 389.933003 -17.272909)
			(xy 389.901654 -17.355135) (xy 389.862957 -17.43417) (xy 389.817234 -17.509358) (xy 389.764863 -17.580077)
			(xy 389.706279 -17.645741) (xy 389.641965 -17.705806) (xy 389.572457 -17.759773) (xy 389.498329 -17.807195)
			(xy 389.420195 -17.847681) (xy 389.338704 -17.880894) (xy 389.25453 -17.906558) (xy 389.168371 -17.924462)
			(xy 389.080941 -17.934457) (xy 388.992964 -17.936461) (xy 388.90517 -17.930455) (xy 388.818286 -17.916491)
			(xy 388.733031 -17.894684) (xy 388.650112 -17.865215) (xy 388.570217 -17.828328) (xy 388.494008 -17.784328)
			(xy 388.422115 -17.73358) (xy 388.355134 -17.676506) (xy 388.293622 -17.613576) (xy 388.238086 -17.545314)
			(xy 388.188988 -17.472285) (xy 388.146735 -17.395093) (xy 388.111676 -17.314379) (xy 388.084101 -17.230811)
			(xy 388.064241 -17.145082) (xy 388.052258 -17.057902) (xy 388.048253 -16.969994) (xy 363.981238 -16.969994)
			(xy 363.980737 -17.013994) (xy 363.972735 -17.101629) (xy 363.956797 -17.188173) (xy 363.933055 -17.272909)
			(xy 363.901706 -17.355135) (xy 363.863009 -17.43417) (xy 363.817286 -17.509358) (xy 363.764915 -17.580077)
			(xy 363.706331 -17.645741) (xy 363.642017 -17.705806) (xy 363.572509 -17.759773) (xy 363.498381 -17.807195)
			(xy 363.420247 -17.847681) (xy 363.338756 -17.880894) (xy 363.254582 -17.906558) (xy 363.168423 -17.924462)
			(xy 363.080993 -17.934457) (xy 362.993016 -17.936461) (xy 362.905222 -17.930455) (xy 362.818338 -17.916491)
			(xy 362.733083 -17.894684) (xy 362.650164 -17.865215) (xy 362.570269 -17.828328) (xy 362.49406 -17.784328)
			(xy 362.422167 -17.73358) (xy 362.355186 -17.676506) (xy 362.293674 -17.613576) (xy 362.238138 -17.545314)
			(xy 362.18904 -17.472285) (xy 362.146787 -17.395093) (xy 362.111728 -17.314379) (xy 362.084153 -17.230811)
			(xy 362.064293 -17.145082) (xy 362.05231 -17.057902) (xy 362.048305 -16.969994) (xy 325.880984 -16.969994)
			(xy 325.880483 -17.013994) (xy 325.872481 -17.101629) (xy 325.856543 -17.188173) (xy 325.832801 -17.272909)
			(xy 325.801452 -17.355135) (xy 325.762755 -17.43417) (xy 325.717032 -17.509358) (xy 325.664661 -17.580077)
			(xy 325.606077 -17.645741) (xy 325.541763 -17.705806) (xy 325.472255 -17.759773) (xy 325.398127 -17.807195)
			(xy 325.319993 -17.847681) (xy 325.238502 -17.880894) (xy 325.154328 -17.906558) (xy 325.068169 -17.924462)
			(xy 324.980739 -17.934457) (xy 324.892762 -17.936461) (xy 324.804968 -17.930455) (xy 324.718084 -17.916491)
			(xy 324.632829 -17.894684) (xy 324.54991 -17.865215) (xy 324.470015 -17.828328) (xy 324.393806 -17.784328)
			(xy 324.321913 -17.73358) (xy 324.254932 -17.676506) (xy 324.19342 -17.613576) (xy 324.137884 -17.545314)
			(xy 324.088786 -17.472285) (xy 324.046533 -17.395093) (xy 324.011474 -17.314379) (xy 323.983899 -17.230811)
			(xy 323.964039 -17.145082) (xy 323.952056 -17.057902) (xy 323.948051 -16.969994) (xy 299.881036 -16.969994)
			(xy 299.880535 -17.013994) (xy 299.872533 -17.101629) (xy 299.856595 -17.188173) (xy 299.832853 -17.272909)
			(xy 299.801504 -17.355135) (xy 299.762807 -17.43417) (xy 299.717084 -17.509358) (xy 299.664713 -17.580077)
			(xy 299.606129 -17.645741) (xy 299.541815 -17.705806) (xy 299.472307 -17.759773) (xy 299.398179 -17.807195)
			(xy 299.320045 -17.847681) (xy 299.238554 -17.880894) (xy 299.15438 -17.906558) (xy 299.068221 -17.924462)
			(xy 298.980791 -17.934457) (xy 298.892814 -17.936461) (xy 298.80502 -17.930455) (xy 298.718136 -17.916491)
			(xy 298.632881 -17.894684) (xy 298.549962 -17.865215) (xy 298.470067 -17.828328) (xy 298.393858 -17.784328)
			(xy 298.321965 -17.73358) (xy 298.254984 -17.676506) (xy 298.193472 -17.613576) (xy 298.137936 -17.545314)
			(xy 298.088838 -17.472285) (xy 298.046585 -17.395093) (xy 298.011526 -17.314379) (xy 297.983951 -17.230811)
			(xy 297.964091 -17.145082) (xy 297.952108 -17.057902) (xy 297.948103 -16.969994) (xy 273.881088 -16.969994)
			(xy 273.880587 -17.013994) (xy 273.872585 -17.101629) (xy 273.856647 -17.188173) (xy 273.832905 -17.272909)
			(xy 273.801556 -17.355135) (xy 273.762859 -17.43417) (xy 273.717136 -17.509358) (xy 273.664765 -17.580077)
			(xy 273.606181 -17.645741) (xy 273.541867 -17.705806) (xy 273.472359 -17.759773) (xy 273.398231 -17.807195)
			(xy 273.320097 -17.847681) (xy 273.238606 -17.880894) (xy 273.154432 -17.906558) (xy 273.068273 -17.924462)
			(xy 272.980843 -17.934457) (xy 272.892866 -17.936461) (xy 272.805072 -17.930455) (xy 272.718188 -17.916491)
			(xy 272.632933 -17.894684) (xy 272.550014 -17.865215) (xy 272.470119 -17.828328) (xy 272.39391 -17.784328)
			(xy 272.322017 -17.73358) (xy 272.255036 -17.676506) (xy 272.193524 -17.613576) (xy 272.137988 -17.545314)
			(xy 272.08889 -17.472285) (xy 272.046637 -17.395093) (xy 272.011578 -17.314379) (xy 271.984003 -17.230811)
			(xy 271.964143 -17.145082) (xy 271.95216 -17.057902) (xy 271.948155 -16.969994) (xy 247.88114 -16.969994)
			(xy 247.880639 -17.013994) (xy 247.872637 -17.101629) (xy 247.856699 -17.188173) (xy 247.832957 -17.272909)
			(xy 247.801608 -17.355135) (xy 247.762911 -17.43417) (xy 247.717188 -17.509358) (xy 247.664817 -17.580077)
			(xy 247.606233 -17.645741) (xy 247.541919 -17.705806) (xy 247.472411 -17.759773) (xy 247.398283 -17.807195)
			(xy 247.320149 -17.847681) (xy 247.238658 -17.880894) (xy 247.154484 -17.906558) (xy 247.068325 -17.924462)
			(xy 246.980895 -17.934457) (xy 246.892918 -17.936461) (xy 246.805124 -17.930455) (xy 246.71824 -17.916491)
			(xy 246.632985 -17.894684) (xy 246.550066 -17.865215) (xy 246.470171 -17.828328) (xy 246.393962 -17.784328)
			(xy 246.322069 -17.73358) (xy 246.255088 -17.676506) (xy 246.193576 -17.613576) (xy 246.13804 -17.545314)
			(xy 246.088942 -17.472285) (xy 246.046689 -17.395093) (xy 246.01163 -17.314379) (xy 245.984055 -17.230811)
			(xy 245.964195 -17.145082) (xy 245.952212 -17.057902) (xy 245.948207 -16.969994) (xy 209.78114 -16.969994)
			(xy 209.780639 -17.013994) (xy 209.772637 -17.101629) (xy 209.756699 -17.188173) (xy 209.732957 -17.272909)
			(xy 209.701608 -17.355135) (xy 209.662911 -17.43417) (xy 209.617188 -17.509358) (xy 209.564817 -17.580077)
			(xy 209.506233 -17.645741) (xy 209.441919 -17.705806) (xy 209.372411 -17.759773) (xy 209.298283 -17.807195)
			(xy 209.220149 -17.847681) (xy 209.138658 -17.880894) (xy 209.054484 -17.906558) (xy 208.968325 -17.924462)
			(xy 208.880895 -17.934457) (xy 208.792918 -17.936461) (xy 208.705124 -17.930455) (xy 208.61824 -17.916491)
			(xy 208.532985 -17.894684) (xy 208.450066 -17.865215) (xy 208.370171 -17.828328) (xy 208.293962 -17.784328)
			(xy 208.222069 -17.73358) (xy 208.155088 -17.676506) (xy 208.093576 -17.613576) (xy 208.03804 -17.545314)
			(xy 207.988942 -17.472285) (xy 207.946689 -17.395093) (xy 207.91163 -17.314379) (xy 207.884055 -17.230811)
			(xy 207.864195 -17.145082) (xy 207.852212 -17.057902) (xy 207.848207 -16.969994) (xy 183.781192 -16.969994)
			(xy 183.780691 -17.013994) (xy 183.772689 -17.101629) (xy 183.756751 -17.188173) (xy 183.733009 -17.272909)
			(xy 183.70166 -17.355135) (xy 183.662963 -17.43417) (xy 183.61724 -17.509358) (xy 183.564869 -17.580077)
			(xy 183.506285 -17.645741) (xy 183.441971 -17.705806) (xy 183.372463 -17.759773) (xy 183.298335 -17.807195)
			(xy 183.220201 -17.847681) (xy 183.13871 -17.880894) (xy 183.054536 -17.906558) (xy 182.968377 -17.924462)
			(xy 182.880947 -17.934457) (xy 182.79297 -17.936461) (xy 182.705176 -17.930455) (xy 182.618292 -17.916491)
			(xy 182.533037 -17.894684) (xy 182.450118 -17.865215) (xy 182.370223 -17.828328) (xy 182.294014 -17.784328)
			(xy 182.222121 -17.73358) (xy 182.15514 -17.676506) (xy 182.093628 -17.613576) (xy 182.038092 -17.545314)
			(xy 181.988994 -17.472285) (xy 181.946741 -17.395093) (xy 181.911682 -17.314379) (xy 181.884107 -17.230811)
			(xy 181.864247 -17.145082) (xy 181.852264 -17.057902) (xy 181.848259 -16.969994) (xy 157.781244 -16.969994)
			(xy 157.780743 -17.013994) (xy 157.772741 -17.101629) (xy 157.756803 -17.188173) (xy 157.733061 -17.272909)
			(xy 157.701712 -17.355135) (xy 157.663015 -17.43417) (xy 157.617292 -17.509358) (xy 157.564921 -17.580077)
			(xy 157.506337 -17.645741) (xy 157.442023 -17.705806) (xy 157.372515 -17.759773) (xy 157.298387 -17.807195)
			(xy 157.220253 -17.847681) (xy 157.138762 -17.880894) (xy 157.054588 -17.906558) (xy 156.968429 -17.924462)
			(xy 156.880999 -17.934457) (xy 156.793022 -17.936461) (xy 156.705228 -17.930455) (xy 156.618344 -17.916491)
			(xy 156.533089 -17.894684) (xy 156.45017 -17.865215) (xy 156.370275 -17.828328) (xy 156.294066 -17.784328)
			(xy 156.222173 -17.73358) (xy 156.155192 -17.676506) (xy 156.09368 -17.613576) (xy 156.038144 -17.545314)
			(xy 155.989046 -17.472285) (xy 155.946793 -17.395093) (xy 155.911734 -17.314379) (xy 155.884159 -17.230811)
			(xy 155.864299 -17.145082) (xy 155.852316 -17.057902) (xy 155.848311 -16.969994) (xy 131.781296 -16.969994)
			(xy 131.780795 -17.013994) (xy 131.772793 -17.101629) (xy 131.756855 -17.188173) (xy 131.733113 -17.272909)
			(xy 131.701764 -17.355135) (xy 131.663067 -17.43417) (xy 131.617344 -17.509358) (xy 131.564973 -17.580077)
			(xy 131.506389 -17.645741) (xy 131.442075 -17.705806) (xy 131.372567 -17.759773) (xy 131.298439 -17.807195)
			(xy 131.220305 -17.847681) (xy 131.138814 -17.880894) (xy 131.05464 -17.906558) (xy 130.968481 -17.924462)
			(xy 130.881051 -17.934457) (xy 130.793074 -17.936461) (xy 130.70528 -17.930455) (xy 130.618396 -17.916491)
			(xy 130.533141 -17.894684) (xy 130.450222 -17.865215) (xy 130.370327 -17.828328) (xy 130.294118 -17.784328)
			(xy 130.222225 -17.73358) (xy 130.155244 -17.676506) (xy 130.093732 -17.613576) (xy 130.038196 -17.545314)
			(xy 129.989098 -17.472285) (xy 129.946845 -17.395093) (xy 129.911786 -17.314379) (xy 129.884211 -17.230811)
			(xy 129.864351 -17.145082) (xy 129.852368 -17.057902) (xy 129.848363 -16.969994) (xy 93.681042 -16.969994)
			(xy 93.680541 -17.013994) (xy 93.672539 -17.101629) (xy 93.656601 -17.188173) (xy 93.632859 -17.272909)
			(xy 93.60151 -17.355135) (xy 93.562813 -17.43417) (xy 93.51709 -17.509358) (xy 93.464719 -17.580077)
			(xy 93.406135 -17.645741) (xy 93.341821 -17.705806) (xy 93.272313 -17.759773) (xy 93.198185 -17.807195)
			(xy 93.120051 -17.847681) (xy 93.03856 -17.880894) (xy 92.954386 -17.906558) (xy 92.868227 -17.924462)
			(xy 92.780797 -17.934457) (xy 92.69282 -17.936461) (xy 92.605026 -17.930455) (xy 92.518142 -17.916491)
			(xy 92.432887 -17.894684) (xy 92.349968 -17.865215) (xy 92.270073 -17.828328) (xy 92.193864 -17.784328)
			(xy 92.121971 -17.73358) (xy 92.05499 -17.676506) (xy 91.993478 -17.613576) (xy 91.937942 -17.545314)
			(xy 91.888844 -17.472285) (xy 91.846591 -17.395093) (xy 91.811532 -17.314379) (xy 91.783957 -17.230811)
			(xy 91.764097 -17.145082) (xy 91.752114 -17.057902) (xy 91.748109 -16.969994) (xy 67.681094 -16.969994)
			(xy 67.680593 -17.013994) (xy 67.672591 -17.101629) (xy 67.656653 -17.188173) (xy 67.632911 -17.272909)
			(xy 67.601562 -17.355135) (xy 67.562865 -17.43417) (xy 67.517142 -17.509358) (xy 67.464771 -17.580077)
			(xy 67.406187 -17.645741) (xy 67.341873 -17.705806) (xy 67.272365 -17.759773) (xy 67.198237 -17.807195)
			(xy 67.120103 -17.847681) (xy 67.038612 -17.880894) (xy 66.954438 -17.906558) (xy 66.868279 -17.924462)
			(xy 66.780849 -17.934457) (xy 66.692872 -17.936461) (xy 66.605078 -17.930455) (xy 66.518194 -17.916491)
			(xy 66.432939 -17.894684) (xy 66.35002 -17.865215) (xy 66.270125 -17.828328) (xy 66.193916 -17.784328)
			(xy 66.122023 -17.73358) (xy 66.055042 -17.676506) (xy 65.99353 -17.613576) (xy 65.937994 -17.545314)
			(xy 65.888896 -17.472285) (xy 65.846643 -17.395093) (xy 65.811584 -17.314379) (xy 65.784009 -17.230811)
			(xy 65.764149 -17.145082) (xy 65.752166 -17.057902) (xy 65.748161 -16.969994) (xy 41.681146 -16.969994)
			(xy 41.680645 -17.013994) (xy 41.672643 -17.101629) (xy 41.656705 -17.188173) (xy 41.632963 -17.272909)
			(xy 41.601614 -17.355135) (xy 41.562917 -17.43417) (xy 41.517194 -17.509358) (xy 41.464823 -17.580077)
			(xy 41.406239 -17.645741) (xy 41.341925 -17.705806) (xy 41.272417 -17.759773) (xy 41.198289 -17.807195)
			(xy 41.120155 -17.847681) (xy 41.038664 -17.880894) (xy 40.95449 -17.906558) (xy 40.868331 -17.924462)
			(xy 40.780901 -17.934457) (xy 40.692924 -17.936461) (xy 40.60513 -17.930455) (xy 40.518246 -17.916491)
			(xy 40.432991 -17.894684) (xy 40.350072 -17.865215) (xy 40.270177 -17.828328) (xy 40.193968 -17.784328)
			(xy 40.122075 -17.73358) (xy 40.055094 -17.676506) (xy 39.993582 -17.613576) (xy 39.938046 -17.545314)
			(xy 39.888948 -17.472285) (xy 39.846695 -17.395093) (xy 39.811636 -17.314379) (xy 39.784061 -17.230811)
			(xy 39.764201 -17.145082) (xy 39.752218 -17.057902) (xy 39.748213 -16.969994) (xy 15.681198 -16.969994)
			(xy 15.680697 -17.013994) (xy 15.672695 -17.101629) (xy 15.656757 -17.188173) (xy 15.633015 -17.272909)
			(xy 15.601666 -17.355135) (xy 15.562969 -17.43417) (xy 15.517246 -17.509358) (xy 15.464875 -17.580077)
			(xy 15.406291 -17.645741) (xy 15.341977 -17.705806) (xy 15.272469 -17.759773) (xy 15.198341 -17.807195)
			(xy 15.120207 -17.847681) (xy 15.038716 -17.880894) (xy 14.954542 -17.906558) (xy 14.868383 -17.924462)
			(xy 14.780953 -17.934457) (xy 14.692976 -17.936461) (xy 14.605182 -17.930455) (xy 14.518298 -17.916491)
			(xy 14.433043 -17.894684) (xy 14.350124 -17.865215) (xy 14.270229 -17.828328) (xy 14.19402 -17.784328)
			(xy 14.122127 -17.73358) (xy 14.055146 -17.676506) (xy 13.993634 -17.613576) (xy 13.938098 -17.545314)
			(xy 13.889 -17.472285) (xy 13.846747 -17.395093) (xy 13.811688 -17.314379) (xy 13.784113 -17.230811)
			(xy 13.764253 -17.145082) (xy 13.75227 -17.057902) (xy 13.748265 -16.969994) (xy 0.508 -16.969994)
			(xy 0.508 -27.342846) (xy 16.523716 -27.342846) (xy 16.523716 -26.479246) (xy 16.524206 -26.449278)
			(xy 16.532029 -26.389856) (xy 16.547542 -26.331963) (xy 16.570478 -26.27659) (xy 16.600445 -26.224684)
			(xy 16.636932 -26.177134) (xy 16.679312 -26.134754) (xy 16.726862 -26.098267) (xy 16.778768 -26.0683)
			(xy 16.834141 -26.045364) (xy 16.892034 -26.029851) (xy 16.951456 -26.022028) (xy 17.011392 -26.022028)
			(xy 17.070814 -26.029851) (xy 17.128707 -26.045364) (xy 17.18408 -26.0683) (xy 17.235986 -26.098267)
			(xy 17.283536 -26.134754) (xy 17.325916 -26.177134) (xy 17.362403 -26.224684) (xy 17.39237 -26.27659)
			(xy 17.415306 -26.331963) (xy 17.430819 -26.389856) (xy 17.438642 -26.449278) (xy 17.439132 -26.479246)
			(xy 17.439132 -27.342846) (xy 42.523664 -27.342846) (xy 42.523664 -26.479246) (xy 42.524154 -26.449278)
			(xy 42.531977 -26.389856) (xy 42.54749 -26.331963) (xy 42.570426 -26.27659) (xy 42.600393 -26.224684)
			(xy 42.63688 -26.177134) (xy 42.67926 -26.134754) (xy 42.72681 -26.098267) (xy 42.778716 -26.0683)
			(xy 42.834089 -26.045364) (xy 42.891982 -26.029851) (xy 42.951404 -26.022028) (xy 43.01134 -26.022028)
			(xy 43.070762 -26.029851) (xy 43.128655 -26.045364) (xy 43.184028 -26.0683) (xy 43.235934 -26.098267)
			(xy 43.283484 -26.134754) (xy 43.325864 -26.177134) (xy 43.362351 -26.224684) (xy 43.392318 -26.27659)
			(xy 43.415254 -26.331963) (xy 43.430767 -26.389856) (xy 43.43859 -26.449278) (xy 43.43908 -26.479246)
			(xy 43.43908 -27.342846) (xy 68.523612 -27.342846) (xy 68.523612 -26.479246) (xy 68.524102 -26.449278)
			(xy 68.531925 -26.389856) (xy 68.547438 -26.331963) (xy 68.570374 -26.27659) (xy 68.600341 -26.224684)
			(xy 68.636828 -26.177134) (xy 68.679208 -26.134754) (xy 68.726758 -26.098267) (xy 68.778664 -26.0683)
			(xy 68.834037 -26.045364) (xy 68.89193 -26.029851) (xy 68.951352 -26.022028) (xy 69.011288 -26.022028)
			(xy 69.07071 -26.029851) (xy 69.128603 -26.045364) (xy 69.183976 -26.0683) (xy 69.235882 -26.098267)
			(xy 69.283432 -26.134754) (xy 69.325812 -26.177134) (xy 69.362299 -26.224684) (xy 69.392266 -26.27659)
			(xy 69.415202 -26.331963) (xy 69.430715 -26.389856) (xy 69.438538 -26.449278) (xy 69.439028 -26.479246)
			(xy 69.439028 -27.342846) (xy 94.52356 -27.342846) (xy 94.52356 -26.479246) (xy 94.52405 -26.449278)
			(xy 94.531873 -26.389856) (xy 94.547386 -26.331963) (xy 94.570322 -26.27659) (xy 94.600289 -26.224684)
			(xy 94.636776 -26.177134) (xy 94.679156 -26.134754) (xy 94.726706 -26.098267) (xy 94.778612 -26.0683)
			(xy 94.833985 -26.045364) (xy 94.891878 -26.029851) (xy 94.9513 -26.022028) (xy 95.011236 -26.022028)
			(xy 95.070658 -26.029851) (xy 95.128551 -26.045364) (xy 95.183924 -26.0683) (xy 95.23583 -26.098267)
			(xy 95.28338 -26.134754) (xy 95.32576 -26.177134) (xy 95.362247 -26.224684) (xy 95.392214 -26.27659)
			(xy 95.41515 -26.331963) (xy 95.430663 -26.389856) (xy 95.438486 -26.449278) (xy 95.438976 -26.479246)
			(xy 95.438976 -27.342846) (xy 132.62356 -27.342846) (xy 132.62356 -26.479246) (xy 132.62405 -26.449262)
			(xy 132.631878 -26.389806) (xy 132.647399 -26.331881) (xy 132.670348 -26.276477) (xy 132.700332 -26.224543)
			(xy 132.736838 -26.176967) (xy 132.779243 -26.134562) (xy 132.826819 -26.098056) (xy 132.878753 -26.068072)
			(xy 132.934157 -26.045123) (xy 132.992082 -26.029602) (xy 133.051538 -26.021774) (xy 133.111506 -26.021774)
			(xy 133.170962 -26.029602) (xy 133.228887 -26.045123) (xy 133.284291 -26.068072) (xy 133.336225 -26.098056)
			(xy 133.383801 -26.134562) (xy 133.426206 -26.176967) (xy 133.462712 -26.224543) (xy 133.492696 -26.276477)
			(xy 133.515645 -26.331881) (xy 133.531166 -26.389806) (xy 133.538994 -26.449262) (xy 133.539484 -26.479246)
			(xy 133.539484 -27.342846) (xy 158.623508 -27.342846) (xy 158.623508 -26.479246) (xy 158.623998 -26.449262)
			(xy 158.631826 -26.389806) (xy 158.647347 -26.331881) (xy 158.670296 -26.276477) (xy 158.70028 -26.224543)
			(xy 158.736786 -26.176967) (xy 158.779191 -26.134562) (xy 158.826767 -26.098056) (xy 158.878701 -26.068072)
			(xy 158.934105 -26.045123) (xy 158.99203 -26.029602) (xy 159.051486 -26.021774) (xy 159.111454 -26.021774)
			(xy 159.17091 -26.029602) (xy 159.228835 -26.045123) (xy 159.284239 -26.068072) (xy 159.336173 -26.098056)
			(xy 159.383749 -26.134562) (xy 159.426154 -26.176967) (xy 159.46266 -26.224543) (xy 159.492644 -26.276477)
			(xy 159.515593 -26.331881) (xy 159.531114 -26.389806) (xy 159.538942 -26.449262) (xy 159.539432 -26.479246)
			(xy 159.539432 -27.342846) (xy 184.623456 -27.342846) (xy 184.623456 -26.479246) (xy 184.623946 -26.449262)
			(xy 184.631774 -26.389806) (xy 184.647295 -26.331881) (xy 184.670244 -26.276477) (xy 184.700228 -26.224543)
			(xy 184.736734 -26.176967) (xy 184.779139 -26.134562) (xy 184.826715 -26.098056) (xy 184.878649 -26.068072)
			(xy 184.934053 -26.045123) (xy 184.991978 -26.029602) (xy 185.051434 -26.021774) (xy 185.111402 -26.021774)
			(xy 185.170858 -26.029602) (xy 185.228783 -26.045123) (xy 185.284187 -26.068072) (xy 185.336121 -26.098056)
			(xy 185.383697 -26.134562) (xy 185.426102 -26.176967) (xy 185.462608 -26.224543) (xy 185.492592 -26.276477)
			(xy 185.515541 -26.331881) (xy 185.531062 -26.389806) (xy 185.53889 -26.449262) (xy 185.53938 -26.479246)
			(xy 185.53938 -27.342846) (xy 210.623404 -27.342846) (xy 210.623404 -26.479246) (xy 210.623894 -26.449262)
			(xy 210.631722 -26.389806) (xy 210.647243 -26.331881) (xy 210.670192 -26.276477) (xy 210.700176 -26.224543)
			(xy 210.736682 -26.176967) (xy 210.779087 -26.134562) (xy 210.826663 -26.098056) (xy 210.878597 -26.068072)
			(xy 210.934001 -26.045123) (xy 210.991926 -26.029602) (xy 211.051382 -26.021774) (xy 211.11135 -26.021774)
			(xy 211.170806 -26.029602) (xy 211.228731 -26.045123) (xy 211.284135 -26.068072) (xy 211.336069 -26.098056)
			(xy 211.383645 -26.134562) (xy 211.42605 -26.176967) (xy 211.462556 -26.224543) (xy 211.49254 -26.276477)
			(xy 211.515489 -26.331881) (xy 211.53101 -26.389806) (xy 211.538838 -26.449262) (xy 211.539328 -26.479246)
			(xy 211.539328 -27.342846) (xy 248.723404 -27.342846) (xy 248.723404 -26.479246) (xy 248.723894 -26.449262)
			(xy 248.731722 -26.389806) (xy 248.747243 -26.331881) (xy 248.770192 -26.276477) (xy 248.800176 -26.224543)
			(xy 248.836682 -26.176967) (xy 248.879087 -26.134562) (xy 248.926663 -26.098056) (xy 248.978597 -26.068072)
			(xy 249.034001 -26.045123) (xy 249.091926 -26.029602) (xy 249.151382 -26.021774) (xy 249.21135 -26.021774)
			(xy 249.270806 -26.029602) (xy 249.328731 -26.045123) (xy 249.384135 -26.068072) (xy 249.436069 -26.098056)
			(xy 249.483645 -26.134562) (xy 249.52605 -26.176967) (xy 249.562556 -26.224543) (xy 249.59254 -26.276477)
			(xy 249.615489 -26.331881) (xy 249.63101 -26.389806) (xy 249.638838 -26.449262) (xy 249.639328 -26.479246)
			(xy 249.639328 -27.342846) (xy 274.723352 -27.342846) (xy 274.723352 -26.479246) (xy 274.723842 -26.449262)
			(xy 274.73167 -26.389806) (xy 274.747191 -26.331881) (xy 274.77014 -26.276477) (xy 274.800124 -26.224543)
			(xy 274.83663 -26.176967) (xy 274.879035 -26.134562) (xy 274.926611 -26.098056) (xy 274.978545 -26.068072)
			(xy 275.033949 -26.045123) (xy 275.091874 -26.029602) (xy 275.15133 -26.021774) (xy 275.211298 -26.021774)
			(xy 275.270754 -26.029602) (xy 275.328679 -26.045123) (xy 275.384083 -26.068072) (xy 275.436017 -26.098056)
			(xy 275.483593 -26.134562) (xy 275.525998 -26.176967) (xy 275.562504 -26.224543) (xy 275.592488 -26.276477)
			(xy 275.615437 -26.331881) (xy 275.630958 -26.389806) (xy 275.638786 -26.449262) (xy 275.639276 -26.479246)
			(xy 275.639276 -27.342846) (xy 300.7233 -27.342846) (xy 300.7233 -26.479246) (xy 300.72379 -26.449262)
			(xy 300.731618 -26.389806) (xy 300.747139 -26.331881) (xy 300.770088 -26.276477) (xy 300.800072 -26.224543)
			(xy 300.836578 -26.176967) (xy 300.878983 -26.134562) (xy 300.926559 -26.098056) (xy 300.978493 -26.068072)
			(xy 301.033897 -26.045123) (xy 301.091822 -26.029602) (xy 301.151278 -26.021774) (xy 301.211246 -26.021774)
			(xy 301.270702 -26.029602) (xy 301.328627 -26.045123) (xy 301.384031 -26.068072) (xy 301.435965 -26.098056)
			(xy 301.483541 -26.134562) (xy 301.525946 -26.176967) (xy 301.562452 -26.224543) (xy 301.592436 -26.276477)
			(xy 301.615385 -26.331881) (xy 301.630906 -26.389806) (xy 301.638734 -26.449262) (xy 301.639224 -26.479246)
			(xy 301.639224 -27.342846) (xy 326.723248 -27.342846) (xy 326.723248 -26.479246) (xy 326.723738 -26.449262)
			(xy 326.731566 -26.389806) (xy 326.747087 -26.331881) (xy 326.770036 -26.276477) (xy 326.80002 -26.224543)
			(xy 326.836526 -26.176967) (xy 326.878931 -26.134562) (xy 326.926507 -26.098056) (xy 326.978441 -26.068072)
			(xy 327.033845 -26.045123) (xy 327.09177 -26.029602) (xy 327.151226 -26.021774) (xy 327.211194 -26.021774)
			(xy 327.27065 -26.029602) (xy 327.328575 -26.045123) (xy 327.383979 -26.068072) (xy 327.435913 -26.098056)
			(xy 327.483489 -26.134562) (xy 327.525894 -26.176967) (xy 327.5624 -26.224543) (xy 327.592384 -26.276477)
			(xy 327.615333 -26.331881) (xy 327.630854 -26.389806) (xy 327.638682 -26.449262) (xy 327.639172 -26.479246)
			(xy 327.639172 -27.342846) (xy 364.823756 -27.342846) (xy 364.823756 -26.479246) (xy 364.824246 -26.449278)
			(xy 364.832069 -26.389856) (xy 364.847582 -26.331963) (xy 364.870518 -26.27659) (xy 364.900485 -26.224684)
			(xy 364.936972 -26.177134) (xy 364.979352 -26.134754) (xy 365.026902 -26.098267) (xy 365.078808 -26.0683)
			(xy 365.134181 -26.045364) (xy 365.192074 -26.029851) (xy 365.251496 -26.022028) (xy 365.311432 -26.022028)
			(xy 365.370854 -26.029851) (xy 365.428747 -26.045364) (xy 365.48412 -26.0683) (xy 365.536026 -26.098267)
			(xy 365.583576 -26.134754) (xy 365.625956 -26.177134) (xy 365.662443 -26.224684) (xy 365.69241 -26.27659)
			(xy 365.715346 -26.331963) (xy 365.730859 -26.389856) (xy 365.738682 -26.449278) (xy 365.739172 -26.479246)
			(xy 365.739172 -27.342846) (xy 390.823704 -27.342846) (xy 390.823704 -26.479246) (xy 390.824194 -26.449278)
			(xy 390.832017 -26.389856) (xy 390.84753 -26.331963) (xy 390.870466 -26.27659) (xy 390.900433 -26.224684)
			(xy 390.93692 -26.177134) (xy 390.9793 -26.134754) (xy 391.02685 -26.098267) (xy 391.078756 -26.0683)
			(xy 391.134129 -26.045364) (xy 391.192022 -26.029851) (xy 391.251444 -26.022028) (xy 391.31138 -26.022028)
			(xy 391.370802 -26.029851) (xy 391.428695 -26.045364) (xy 391.484068 -26.0683) (xy 391.535974 -26.098267)
			(xy 391.583524 -26.134754) (xy 391.625904 -26.177134) (xy 391.662391 -26.224684) (xy 391.692358 -26.27659)
			(xy 391.715294 -26.331963) (xy 391.730807 -26.389856) (xy 391.73863 -26.449278) (xy 391.73912 -26.479246)
			(xy 391.73912 -27.342846) (xy 416.823652 -27.342846) (xy 416.823652 -26.479246) (xy 416.824142 -26.449278)
			(xy 416.831965 -26.389856) (xy 416.847478 -26.331963) (xy 416.870414 -26.27659) (xy 416.900381 -26.224684)
			(xy 416.936868 -26.177134) (xy 416.979248 -26.134754) (xy 417.026798 -26.098267) (xy 417.078704 -26.0683)
			(xy 417.134077 -26.045364) (xy 417.19197 -26.029851) (xy 417.251392 -26.022028) (xy 417.311328 -26.022028)
			(xy 417.37075 -26.029851) (xy 417.428643 -26.045364) (xy 417.484016 -26.0683) (xy 417.535922 -26.098267)
			(xy 417.583472 -26.134754) (xy 417.625852 -26.177134) (xy 417.662339 -26.224684) (xy 417.692306 -26.27659)
			(xy 417.715242 -26.331963) (xy 417.730755 -26.389856) (xy 417.738578 -26.449278) (xy 417.739068 -26.479246)
			(xy 417.739068 -27.342846) (xy 442.8236 -27.342846) (xy 442.8236 -26.479246) (xy 442.82409 -26.449278)
			(xy 442.831913 -26.389856) (xy 442.847426 -26.331963) (xy 442.870362 -26.27659) (xy 442.900329 -26.224684)
			(xy 442.936816 -26.177134) (xy 442.979196 -26.134754) (xy 443.026746 -26.098267) (xy 443.078652 -26.0683)
			(xy 443.134025 -26.045364) (xy 443.191918 -26.029851) (xy 443.25134 -26.022028) (xy 443.311276 -26.022028)
			(xy 443.370698 -26.029851) (xy 443.428591 -26.045364) (xy 443.483964 -26.0683) (xy 443.53587 -26.098267)
			(xy 443.58342 -26.134754) (xy 443.6258 -26.177134) (xy 443.662287 -26.224684) (xy 443.692254 -26.27659)
			(xy 443.71519 -26.331963) (xy 443.730703 -26.389856) (xy 443.738526 -26.449278) (xy 443.739016 -26.479246)
			(xy 443.739016 -27.342846) (xy 443.738526 -27.372814) (xy 443.730703 -27.432236) (xy 443.71519 -27.490129)
			(xy 443.692254 -27.545502) (xy 443.662287 -27.597408) (xy 443.6258 -27.644958) (xy 443.58342 -27.687338)
			(xy 443.53587 -27.723825) (xy 443.483964 -27.753792) (xy 443.428591 -27.776728) (xy 443.370698 -27.792241)
			(xy 443.311276 -27.800064) (xy 443.25134 -27.800064) (xy 443.191918 -27.792241) (xy 443.134025 -27.776728)
			(xy 443.078652 -27.753792) (xy 443.026746 -27.723825) (xy 442.979196 -27.687338) (xy 442.936816 -27.644958)
			(xy 442.900329 -27.597408) (xy 442.870362 -27.545502) (xy 442.847426 -27.490129) (xy 442.831913 -27.432236)
			(xy 442.82409 -27.372814) (xy 442.8236 -27.342846) (xy 417.739068 -27.342846) (xy 417.738578 -27.372814)
			(xy 417.730755 -27.432236) (xy 417.715242 -27.490129) (xy 417.692306 -27.545502) (xy 417.662339 -27.597408)
			(xy 417.625852 -27.644958) (xy 417.583472 -27.687338) (xy 417.535922 -27.723825) (xy 417.484016 -27.753792)
			(xy 417.428643 -27.776728) (xy 417.37075 -27.792241) (xy 417.311328 -27.800064) (xy 417.251392 -27.800064)
			(xy 417.19197 -27.792241) (xy 417.134077 -27.776728) (xy 417.078704 -27.753792) (xy 417.026798 -27.723825)
			(xy 416.979248 -27.687338) (xy 416.936868 -27.644958) (xy 416.900381 -27.597408) (xy 416.870414 -27.545502)
			(xy 416.847478 -27.490129) (xy 416.831965 -27.432236) (xy 416.824142 -27.372814) (xy 416.823652 -27.342846)
			(xy 391.73912 -27.342846) (xy 391.73863 -27.372814) (xy 391.730807 -27.432236) (xy 391.715294 -27.490129)
			(xy 391.692358 -27.545502) (xy 391.662391 -27.597408) (xy 391.625904 -27.644958) (xy 391.583524 -27.687338)
			(xy 391.535974 -27.723825) (xy 391.484068 -27.753792) (xy 391.428695 -27.776728) (xy 391.370802 -27.792241)
			(xy 391.31138 -27.800064) (xy 391.251444 -27.800064) (xy 391.192022 -27.792241) (xy 391.134129 -27.776728)
			(xy 391.078756 -27.753792) (xy 391.02685 -27.723825) (xy 390.9793 -27.687338) (xy 390.93692 -27.644958)
			(xy 390.900433 -27.597408) (xy 390.870466 -27.545502) (xy 390.84753 -27.490129) (xy 390.832017 -27.432236)
			(xy 390.824194 -27.372814) (xy 390.823704 -27.342846) (xy 365.739172 -27.342846) (xy 365.738682 -27.372814)
			(xy 365.730859 -27.432236) (xy 365.715346 -27.490129) (xy 365.69241 -27.545502) (xy 365.662443 -27.597408)
			(xy 365.625956 -27.644958) (xy 365.583576 -27.687338) (xy 365.536026 -27.723825) (xy 365.48412 -27.753792)
			(xy 365.428747 -27.776728) (xy 365.370854 -27.792241) (xy 365.311432 -27.800064) (xy 365.251496 -27.800064)
			(xy 365.192074 -27.792241) (xy 365.134181 -27.776728) (xy 365.078808 -27.753792) (xy 365.026902 -27.723825)
			(xy 364.979352 -27.687338) (xy 364.936972 -27.644958) (xy 364.900485 -27.597408) (xy 364.870518 -27.545502)
			(xy 364.847582 -27.490129) (xy 364.832069 -27.432236) (xy 364.824246 -27.372814) (xy 364.823756 -27.342846)
			(xy 327.639172 -27.342846) (xy 327.638682 -27.37283) (xy 327.630854 -27.432286) (xy 327.615333 -27.490211)
			(xy 327.592384 -27.545615) (xy 327.5624 -27.597549) (xy 327.525894 -27.645125) (xy 327.483489 -27.68753)
			(xy 327.435913 -27.724036) (xy 327.383979 -27.75402) (xy 327.328575 -27.776969) (xy 327.27065 -27.79249)
			(xy 327.211194 -27.800318) (xy 327.151226 -27.800318) (xy 327.09177 -27.79249) (xy 327.033845 -27.776969)
			(xy 326.978441 -27.75402) (xy 326.926507 -27.724036) (xy 326.878931 -27.68753) (xy 326.836526 -27.645125)
			(xy 326.80002 -27.597549) (xy 326.770036 -27.545615) (xy 326.747087 -27.490211) (xy 326.731566 -27.432286)
			(xy 326.723738 -27.37283) (xy 326.723248 -27.342846) (xy 301.639224 -27.342846) (xy 301.638734 -27.37283)
			(xy 301.630906 -27.432286) (xy 301.615385 -27.490211) (xy 301.592436 -27.545615) (xy 301.562452 -27.597549)
			(xy 301.525946 -27.645125) (xy 301.483541 -27.68753) (xy 301.435965 -27.724036) (xy 301.384031 -27.75402)
			(xy 301.328627 -27.776969) (xy 301.270702 -27.79249) (xy 301.211246 -27.800318) (xy 301.151278 -27.800318)
			(xy 301.091822 -27.79249) (xy 301.033897 -27.776969) (xy 300.978493 -27.75402) (xy 300.926559 -27.724036)
			(xy 300.878983 -27.68753) (xy 300.836578 -27.645125) (xy 300.800072 -27.597549) (xy 300.770088 -27.545615)
			(xy 300.747139 -27.490211) (xy 300.731618 -27.432286) (xy 300.72379 -27.37283) (xy 300.7233 -27.342846)
			(xy 275.639276 -27.342846) (xy 275.638786 -27.37283) (xy 275.630958 -27.432286) (xy 275.615437 -27.490211)
			(xy 275.592488 -27.545615) (xy 275.562504 -27.597549) (xy 275.525998 -27.645125) (xy 275.483593 -27.68753)
			(xy 275.436017 -27.724036) (xy 275.384083 -27.75402) (xy 275.328679 -27.776969) (xy 275.270754 -27.79249)
			(xy 275.211298 -27.800318) (xy 275.15133 -27.800318) (xy 275.091874 -27.79249) (xy 275.033949 -27.776969)
			(xy 274.978545 -27.75402) (xy 274.926611 -27.724036) (xy 274.879035 -27.68753) (xy 274.83663 -27.645125)
			(xy 274.800124 -27.597549) (xy 274.77014 -27.545615) (xy 274.747191 -27.490211) (xy 274.73167 -27.432286)
			(xy 274.723842 -27.37283) (xy 274.723352 -27.342846) (xy 249.639328 -27.342846) (xy 249.638838 -27.37283)
			(xy 249.63101 -27.432286) (xy 249.615489 -27.490211) (xy 249.59254 -27.545615) (xy 249.562556 -27.597549)
			(xy 249.52605 -27.645125) (xy 249.483645 -27.68753) (xy 249.436069 -27.724036) (xy 249.384135 -27.75402)
			(xy 249.328731 -27.776969) (xy 249.270806 -27.79249) (xy 249.21135 -27.800318) (xy 249.151382 -27.800318)
			(xy 249.091926 -27.79249) (xy 249.034001 -27.776969) (xy 248.978597 -27.75402) (xy 248.926663 -27.724036)
			(xy 248.879087 -27.68753) (xy 248.836682 -27.645125) (xy 248.800176 -27.597549) (xy 248.770192 -27.545615)
			(xy 248.747243 -27.490211) (xy 248.731722 -27.432286) (xy 248.723894 -27.37283) (xy 248.723404 -27.342846)
			(xy 211.539328 -27.342846) (xy 211.538838 -27.37283) (xy 211.53101 -27.432286) (xy 211.515489 -27.490211)
			(xy 211.49254 -27.545615) (xy 211.462556 -27.597549) (xy 211.42605 -27.645125) (xy 211.383645 -27.68753)
			(xy 211.336069 -27.724036) (xy 211.284135 -27.75402) (xy 211.228731 -27.776969) (xy 211.170806 -27.79249)
			(xy 211.11135 -27.800318) (xy 211.051382 -27.800318) (xy 210.991926 -27.79249) (xy 210.934001 -27.776969)
			(xy 210.878597 -27.75402) (xy 210.826663 -27.724036) (xy 210.779087 -27.68753) (xy 210.736682 -27.645125)
			(xy 210.700176 -27.597549) (xy 210.670192 -27.545615) (xy 210.647243 -27.490211) (xy 210.631722 -27.432286)
			(xy 210.623894 -27.37283) (xy 210.623404 -27.342846) (xy 185.53938 -27.342846) (xy 185.53889 -27.37283)
			(xy 185.531062 -27.432286) (xy 185.515541 -27.490211) (xy 185.492592 -27.545615) (xy 185.462608 -27.597549)
			(xy 185.426102 -27.645125) (xy 185.383697 -27.68753) (xy 185.336121 -27.724036) (xy 185.284187 -27.75402)
			(xy 185.228783 -27.776969) (xy 185.170858 -27.79249) (xy 185.111402 -27.800318) (xy 185.051434 -27.800318)
			(xy 184.991978 -27.79249) (xy 184.934053 -27.776969) (xy 184.878649 -27.75402) (xy 184.826715 -27.724036)
			(xy 184.779139 -27.68753) (xy 184.736734 -27.645125) (xy 184.700228 -27.597549) (xy 184.670244 -27.545615)
			(xy 184.647295 -27.490211) (xy 184.631774 -27.432286) (xy 184.623946 -27.37283) (xy 184.623456 -27.342846)
			(xy 159.539432 -27.342846) (xy 159.538942 -27.37283) (xy 159.531114 -27.432286) (xy 159.515593 -27.490211)
			(xy 159.492644 -27.545615) (xy 159.46266 -27.597549) (xy 159.426154 -27.645125) (xy 159.383749 -27.68753)
			(xy 159.336173 -27.724036) (xy 159.284239 -27.75402) (xy 159.228835 -27.776969) (xy 159.17091 -27.79249)
			(xy 159.111454 -27.800318) (xy 159.051486 -27.800318) (xy 158.99203 -27.79249) (xy 158.934105 -27.776969)
			(xy 158.878701 -27.75402) (xy 158.826767 -27.724036) (xy 158.779191 -27.68753) (xy 158.736786 -27.645125)
			(xy 158.70028 -27.597549) (xy 158.670296 -27.545615) (xy 158.647347 -27.490211) (xy 158.631826 -27.432286)
			(xy 158.623998 -27.37283) (xy 158.623508 -27.342846) (xy 133.539484 -27.342846) (xy 133.538994 -27.37283)
			(xy 133.531166 -27.432286) (xy 133.515645 -27.490211) (xy 133.492696 -27.545615) (xy 133.462712 -27.597549)
			(xy 133.426206 -27.645125) (xy 133.383801 -27.68753) (xy 133.336225 -27.724036) (xy 133.284291 -27.75402)
			(xy 133.228887 -27.776969) (xy 133.170962 -27.79249) (xy 133.111506 -27.800318) (xy 133.051538 -27.800318)
			(xy 132.992082 -27.79249) (xy 132.934157 -27.776969) (xy 132.878753 -27.75402) (xy 132.826819 -27.724036)
			(xy 132.779243 -27.68753) (xy 132.736838 -27.645125) (xy 132.700332 -27.597549) (xy 132.670348 -27.545615)
			(xy 132.647399 -27.490211) (xy 132.631878 -27.432286) (xy 132.62405 -27.37283) (xy 132.62356 -27.342846)
			(xy 95.438976 -27.342846) (xy 95.438486 -27.372814) (xy 95.430663 -27.432236) (xy 95.41515 -27.490129)
			(xy 95.392214 -27.545502) (xy 95.362247 -27.597408) (xy 95.32576 -27.644958) (xy 95.28338 -27.687338)
			(xy 95.23583 -27.723825) (xy 95.183924 -27.753792) (xy 95.128551 -27.776728) (xy 95.070658 -27.792241)
			(xy 95.011236 -27.800064) (xy 94.9513 -27.800064) (xy 94.891878 -27.792241) (xy 94.833985 -27.776728)
			(xy 94.778612 -27.753792) (xy 94.726706 -27.723825) (xy 94.679156 -27.687338) (xy 94.636776 -27.644958)
			(xy 94.600289 -27.597408) (xy 94.570322 -27.545502) (xy 94.547386 -27.490129) (xy 94.531873 -27.432236)
			(xy 94.52405 -27.372814) (xy 94.52356 -27.342846) (xy 69.439028 -27.342846) (xy 69.438538 -27.372814)
			(xy 69.430715 -27.432236) (xy 69.415202 -27.490129) (xy 69.392266 -27.545502) (xy 69.362299 -27.597408)
			(xy 69.325812 -27.644958) (xy 69.283432 -27.687338) (xy 69.235882 -27.723825) (xy 69.183976 -27.753792)
			(xy 69.128603 -27.776728) (xy 69.07071 -27.792241) (xy 69.011288 -27.800064) (xy 68.951352 -27.800064)
			(xy 68.89193 -27.792241) (xy 68.834037 -27.776728) (xy 68.778664 -27.753792) (xy 68.726758 -27.723825)
			(xy 68.679208 -27.687338) (xy 68.636828 -27.644958) (xy 68.600341 -27.597408) (xy 68.570374 -27.545502)
			(xy 68.547438 -27.490129) (xy 68.531925 -27.432236) (xy 68.524102 -27.372814) (xy 68.523612 -27.342846)
			(xy 43.43908 -27.342846) (xy 43.43859 -27.372814) (xy 43.430767 -27.432236) (xy 43.415254 -27.490129)
			(xy 43.392318 -27.545502) (xy 43.362351 -27.597408) (xy 43.325864 -27.644958) (xy 43.283484 -27.687338)
			(xy 43.235934 -27.723825) (xy 43.184028 -27.753792) (xy 43.128655 -27.776728) (xy 43.070762 -27.792241)
			(xy 43.01134 -27.800064) (xy 42.951404 -27.800064) (xy 42.891982 -27.792241) (xy 42.834089 -27.776728)
			(xy 42.778716 -27.753792) (xy 42.72681 -27.723825) (xy 42.67926 -27.687338) (xy 42.63688 -27.644958)
			(xy 42.600393 -27.597408) (xy 42.570426 -27.545502) (xy 42.54749 -27.490129) (xy 42.531977 -27.432236)
			(xy 42.524154 -27.372814) (xy 42.523664 -27.342846) (xy 17.439132 -27.342846) (xy 17.438642 -27.372814)
			(xy 17.430819 -27.432236) (xy 17.415306 -27.490129) (xy 17.39237 -27.545502) (xy 17.362403 -27.597408)
			(xy 17.325916 -27.644958) (xy 17.283536 -27.687338) (xy 17.235986 -27.723825) (xy 17.18408 -27.753792)
			(xy 17.128707 -27.776728) (xy 17.070814 -27.792241) (xy 17.011392 -27.800064) (xy 16.951456 -27.800064)
			(xy 16.892034 -27.792241) (xy 16.834141 -27.776728) (xy 16.778768 -27.753792) (xy 16.726862 -27.723825)
			(xy 16.679312 -27.687338) (xy 16.636932 -27.644958) (xy 16.600445 -27.597408) (xy 16.570478 -27.545502)
			(xy 16.547542 -27.490129) (xy 16.532029 -27.432236) (xy 16.524206 -27.372814) (xy 16.523716 -27.342846)
			(xy 0.508 -27.342846) (xy 0.508 -29.12237) (xy 8.607044 -29.12237) (xy 8.607044 -28.25877) (xy 8.607534 -28.228802)
			(xy 8.615357 -28.16938) (xy 8.63087 -28.111487) (xy 8.653806 -28.056114) (xy 8.683773 -28.004208)
			(xy 8.72026 -27.956658) (xy 8.76264 -27.914278) (xy 8.81019 -27.877791) (xy 8.862096 -27.847824)
			(xy 8.917469 -27.824888) (xy 8.975362 -27.809375) (xy 9.034784 -27.801552) (xy 9.09472 -27.801552)
			(xy 9.154142 -27.809375) (xy 9.212035 -27.824888) (xy 9.267408 -27.847824) (xy 9.319314 -27.877791)
			(xy 9.366864 -27.914278) (xy 9.409244 -27.956658) (xy 9.445731 -28.004208) (xy 9.475698 -28.056114)
			(xy 9.498634 -28.111487) (xy 9.514147 -28.16938) (xy 9.52197 -28.228802) (xy 9.52246 -28.25877) (xy 9.52246 -29.114242)
			(xy 18.847308 -29.114242) (xy 18.847308 -28.250642) (xy 18.847798 -28.220658) (xy 18.855626 -28.161202)
			(xy 18.871147 -28.103277) (xy 18.894096 -28.047873) (xy 18.92408 -27.995939) (xy 18.960586 -27.948363)
			(xy 19.002991 -27.905958) (xy 19.050567 -27.869452) (xy 19.102501 -27.839468) (xy 19.157905 -27.816519)
			(xy 19.21583 -27.800998) (xy 19.275286 -27.79317) (xy 19.335254 -27.79317) (xy 19.39471 -27.800998)
			(xy 19.452635 -27.816519) (xy 19.508039 -27.839468) (xy 19.559973 -27.869452) (xy 19.607549 -27.905958)
			(xy 19.649954 -27.948363) (xy 19.68646 -27.995939) (xy 19.716444 -28.047873) (xy 19.739393 -28.103277)
			(xy 19.754914 -28.161202) (xy 19.762742 -28.220658) (xy 19.763232 -28.250642) (xy 19.763232 -29.114242)
			(xy 19.763099 -29.12237) (xy 34.606992 -29.12237) (xy 34.606992 -28.25877) (xy 34.607482 -28.228802)
			(xy 34.615305 -28.16938) (xy 34.630818 -28.111487) (xy 34.653754 -28.056114) (xy 34.683721 -28.004208)
			(xy 34.720208 -27.956658) (xy 34.762588 -27.914278) (xy 34.810138 -27.877791) (xy 34.862044 -27.847824)
			(xy 34.917417 -27.824888) (xy 34.97531 -27.809375) (xy 35.034732 -27.801552) (xy 35.094668 -27.801552)
			(xy 35.15409 -27.809375) (xy 35.211983 -27.824888) (xy 35.267356 -27.847824) (xy 35.319262 -27.877791)
			(xy 35.366812 -27.914278) (xy 35.409192 -27.956658) (xy 35.445679 -28.004208) (xy 35.475646 -28.056114)
			(xy 35.498582 -28.111487) (xy 35.514095 -28.16938) (xy 35.521918 -28.228802) (xy 35.522408 -28.25877)
			(xy 35.522408 -29.114242) (xy 44.847256 -29.114242) (xy 44.847256 -28.250642) (xy 44.847746 -28.220658)
			(xy 44.855574 -28.161202) (xy 44.871095 -28.103277) (xy 44.894044 -28.047873) (xy 44.924028 -27.995939)
			(xy 44.960534 -27.948363) (xy 45.002939 -27.905958) (xy 45.050515 -27.869452) (xy 45.102449 -27.839468)
			(xy 45.157853 -27.816519) (xy 45.215778 -27.800998) (xy 45.275234 -27.79317) (xy 45.335202 -27.79317)
			(xy 45.394658 -27.800998) (xy 45.452583 -27.816519) (xy 45.507987 -27.839468) (xy 45.559921 -27.869452)
			(xy 45.607497 -27.905958) (xy 45.649902 -27.948363) (xy 45.686408 -27.995939) (xy 45.716392 -28.047873)
			(xy 45.739341 -28.103277) (xy 45.754862 -28.161202) (xy 45.76269 -28.220658) (xy 45.76318 -28.250642)
			(xy 45.76318 -29.114242) (xy 45.763047 -29.12237) (xy 60.60694 -29.12237) (xy 60.60694 -28.25877)
			(xy 60.60743 -28.228802) (xy 60.615253 -28.16938) (xy 60.630766 -28.111487) (xy 60.653702 -28.056114)
			(xy 60.683669 -28.004208) (xy 60.720156 -27.956658) (xy 60.762536 -27.914278) (xy 60.810086 -27.877791)
			(xy 60.861992 -27.847824) (xy 60.917365 -27.824888) (xy 60.975258 -27.809375) (xy 61.03468 -27.801552)
			(xy 61.094616 -27.801552) (xy 61.154038 -27.809375) (xy 61.211931 -27.824888) (xy 61.267304 -27.847824)
			(xy 61.31921 -27.877791) (xy 61.36676 -27.914278) (xy 61.40914 -27.956658) (xy 61.445627 -28.004208)
			(xy 61.475594 -28.056114) (xy 61.49853 -28.111487) (xy 61.514043 -28.16938) (xy 61.521866 -28.228802)
			(xy 61.522356 -28.25877) (xy 61.522356 -29.114242) (xy 70.847204 -29.114242) (xy 70.847204 -28.250642)
			(xy 70.847694 -28.220658) (xy 70.855522 -28.161202) (xy 70.871043 -28.103277) (xy 70.893992 -28.047873)
			(xy 70.923976 -27.995939) (xy 70.960482 -27.948363) (xy 71.002887 -27.905958) (xy 71.050463 -27.869452)
			(xy 71.102397 -27.839468) (xy 71.157801 -27.816519) (xy 71.215726 -27.800998) (xy 71.275182 -27.79317)
			(xy 71.33515 -27.79317) (xy 71.394606 -27.800998) (xy 71.452531 -27.816519) (xy 71.507935 -27.839468)
			(xy 71.559869 -27.869452) (xy 71.607445 -27.905958) (xy 71.64985 -27.948363) (xy 71.686356 -27.995939)
			(xy 71.71634 -28.047873) (xy 71.739289 -28.103277) (xy 71.75481 -28.161202) (xy 71.762638 -28.220658)
			(xy 71.763128 -28.250642) (xy 71.763128 -29.114242) (xy 71.762995 -29.12237) (xy 86.606888 -29.12237)
			(xy 86.606888 -28.25877) (xy 86.607378 -28.228802) (xy 86.615201 -28.16938) (xy 86.630714 -28.111487)
			(xy 86.65365 -28.056114) (xy 86.683617 -28.004208) (xy 86.720104 -27.956658) (xy 86.762484 -27.914278)
			(xy 86.810034 -27.877791) (xy 86.86194 -27.847824) (xy 86.917313 -27.824888) (xy 86.975206 -27.809375)
			(xy 87.034628 -27.801552) (xy 87.094564 -27.801552) (xy 87.153986 -27.809375) (xy 87.211879 -27.824888)
			(xy 87.267252 -27.847824) (xy 87.319158 -27.877791) (xy 87.366708 -27.914278) (xy 87.409088 -27.956658)
			(xy 87.445575 -28.004208) (xy 87.475542 -28.056114) (xy 87.498478 -28.111487) (xy 87.513991 -28.16938)
			(xy 87.521814 -28.228802) (xy 87.522304 -28.25877) (xy 87.522304 -29.114242) (xy 96.847152 -29.114242)
			(xy 96.847152 -28.250642) (xy 96.847642 -28.220658) (xy 96.85547 -28.161202) (xy 96.870991 -28.103277)
			(xy 96.89394 -28.047873) (xy 96.923924 -27.995939) (xy 96.96043 -27.948363) (xy 97.002835 -27.905958)
			(xy 97.050411 -27.869452) (xy 97.102345 -27.839468) (xy 97.157749 -27.816519) (xy 97.215674 -27.800998)
			(xy 97.27513 -27.79317) (xy 97.335098 -27.79317) (xy 97.394554 -27.800998) (xy 97.452479 -27.816519)
			(xy 97.507883 -27.839468) (xy 97.559817 -27.869452) (xy 97.607393 -27.905958) (xy 97.649798 -27.948363)
			(xy 97.686304 -27.995939) (xy 97.716288 -28.047873) (xy 97.739237 -28.103277) (xy 97.754758 -28.161202)
			(xy 97.762586 -28.220658) (xy 97.763076 -28.250642) (xy 97.763076 -29.114242) (xy 97.762943 -29.12237)
			(xy 124.706888 -29.12237) (xy 124.706888 -28.25877) (xy 124.707378 -28.228786) (xy 124.715206 -28.16933)
			(xy 124.730727 -28.111405) (xy 124.753676 -28.056001) (xy 124.78366 -28.004067) (xy 124.820166 -27.956491)
			(xy 124.862571 -27.914086) (xy 124.910147 -27.87758) (xy 124.962081 -27.847596) (xy 125.017485 -27.824647)
			(xy 125.07541 -27.809126) (xy 125.134866 -27.801298) (xy 125.194834 -27.801298) (xy 125.25429 -27.809126)
			(xy 125.312215 -27.824647) (xy 125.367619 -27.847596) (xy 125.419553 -27.87758) (xy 125.467129 -27.914086)
			(xy 125.509534 -27.956491) (xy 125.54604 -28.004067) (xy 125.576024 -28.056001) (xy 125.598973 -28.111405)
			(xy 125.614494 -28.16933) (xy 125.622322 -28.228786) (xy 125.622812 -28.25877) (xy 125.622812 -29.114242)
			(xy 134.94766 -29.114242) (xy 134.94766 -28.250642) (xy 134.94815 -28.220674) (xy 134.955973 -28.161252)
			(xy 134.971486 -28.103359) (xy 134.994422 -28.047986) (xy 135.024389 -27.99608) (xy 135.060876 -27.94853)
			(xy 135.103256 -27.90615) (xy 135.150806 -27.869663) (xy 135.202712 -27.839696) (xy 135.258085 -27.81676)
			(xy 135.315978 -27.801247) (xy 135.3754 -27.793424) (xy 135.435336 -27.793424) (xy 135.494758 -27.801247)
			(xy 135.552651 -27.81676) (xy 135.608024 -27.839696) (xy 135.65993 -27.869663) (xy 135.70748 -27.90615)
			(xy 135.74986 -27.94853) (xy 135.786347 -27.99608) (xy 135.816314 -28.047986) (xy 135.83925 -28.103359)
			(xy 135.854763 -28.161252) (xy 135.862586 -28.220674) (xy 135.863076 -28.250642) (xy 135.863076 -29.114242)
			(xy 135.862943 -29.12237) (xy 150.706836 -29.12237) (xy 150.706836 -28.25877) (xy 150.707326 -28.228786)
			(xy 150.715154 -28.16933) (xy 150.730675 -28.111405) (xy 150.753624 -28.056001) (xy 150.783608 -28.004067)
			(xy 150.820114 -27.956491) (xy 150.862519 -27.914086) (xy 150.910095 -27.87758) (xy 150.962029 -27.847596)
			(xy 151.017433 -27.824647) (xy 151.075358 -27.809126) (xy 151.134814 -27.801298) (xy 151.194782 -27.801298)
			(xy 151.254238 -27.809126) (xy 151.312163 -27.824647) (xy 151.367567 -27.847596) (xy 151.419501 -27.87758)
			(xy 151.467077 -27.914086) (xy 151.509482 -27.956491) (xy 151.545988 -28.004067) (xy 151.575972 -28.056001)
			(xy 151.598921 -28.111405) (xy 151.614442 -28.16933) (xy 151.62227 -28.228786) (xy 151.62276 -28.25877)
			(xy 151.62276 -29.114242) (xy 160.947608 -29.114242) (xy 160.947608 -28.250642) (xy 160.948098 -28.220674)
			(xy 160.955921 -28.161252) (xy 160.971434 -28.103359) (xy 160.99437 -28.047986) (xy 161.024337 -27.99608)
			(xy 161.060824 -27.94853) (xy 161.103204 -27.90615) (xy 161.150754 -27.869663) (xy 161.20266 -27.839696)
			(xy 161.258033 -27.81676) (xy 161.315926 -27.801247) (xy 161.375348 -27.793424) (xy 161.435284 -27.793424)
			(xy 161.494706 -27.801247) (xy 161.552599 -27.81676) (xy 161.607972 -27.839696) (xy 161.659878 -27.869663)
			(xy 161.707428 -27.90615) (xy 161.749808 -27.94853) (xy 161.786295 -27.99608) (xy 161.816262 -28.047986)
			(xy 161.839198 -28.103359) (xy 161.854711 -28.161252) (xy 161.862534 -28.220674) (xy 161.863024 -28.250642)
			(xy 161.863024 -29.114242) (xy 161.862891 -29.12237) (xy 176.706784 -29.12237) (xy 176.706784 -28.25877)
			(xy 176.707274 -28.228786) (xy 176.715102 -28.16933) (xy 176.730623 -28.111405) (xy 176.753572 -28.056001)
			(xy 176.783556 -28.004067) (xy 176.820062 -27.956491) (xy 176.862467 -27.914086) (xy 176.910043 -27.87758)
			(xy 176.961977 -27.847596) (xy 177.017381 -27.824647) (xy 177.075306 -27.809126) (xy 177.134762 -27.801298)
			(xy 177.19473 -27.801298) (xy 177.254186 -27.809126) (xy 177.312111 -27.824647) (xy 177.367515 -27.847596)
			(xy 177.419449 -27.87758) (xy 177.467025 -27.914086) (xy 177.50943 -27.956491) (xy 177.545936 -28.004067)
			(xy 177.57592 -28.056001) (xy 177.598869 -28.111405) (xy 177.61439 -28.16933) (xy 177.622218 -28.228786)
			(xy 177.622708 -28.25877) (xy 177.622708 -29.114242) (xy 186.947556 -29.114242) (xy 186.947556 -28.250642)
			(xy 186.948046 -28.220674) (xy 186.955869 -28.161252) (xy 186.971382 -28.103359) (xy 186.994318 -28.047986)
			(xy 187.024285 -27.99608) (xy 187.060772 -27.94853) (xy 187.103152 -27.90615) (xy 187.150702 -27.869663)
			(xy 187.202608 -27.839696) (xy 187.257981 -27.81676) (xy 187.315874 -27.801247) (xy 187.375296 -27.793424)
			(xy 187.435232 -27.793424) (xy 187.494654 -27.801247) (xy 187.552547 -27.81676) (xy 187.60792 -27.839696)
			(xy 187.659826 -27.869663) (xy 187.707376 -27.90615) (xy 187.749756 -27.94853) (xy 187.786243 -27.99608)
			(xy 187.81621 -28.047986) (xy 187.839146 -28.103359) (xy 187.854659 -28.161252) (xy 187.862482 -28.220674)
			(xy 187.862972 -28.250642) (xy 187.862972 -29.114242) (xy 187.862839 -29.12237) (xy 202.706732 -29.12237)
			(xy 202.706732 -28.25877) (xy 202.707222 -28.228786) (xy 202.71505 -28.16933) (xy 202.730571 -28.111405)
			(xy 202.75352 -28.056001) (xy 202.783504 -28.004067) (xy 202.82001 -27.956491) (xy 202.862415 -27.914086)
			(xy 202.909991 -27.87758) (xy 202.961925 -27.847596) (xy 203.017329 -27.824647) (xy 203.075254 -27.809126)
			(xy 203.13471 -27.801298) (xy 203.194678 -27.801298) (xy 203.254134 -27.809126) (xy 203.312059 -27.824647)
			(xy 203.367463 -27.847596) (xy 203.419397 -27.87758) (xy 203.466973 -27.914086) (xy 203.509378 -27.956491)
			(xy 203.545884 -28.004067) (xy 203.575868 -28.056001) (xy 203.598817 -28.111405) (xy 203.614338 -28.16933)
			(xy 203.622166 -28.228786) (xy 203.622656 -28.25877) (xy 203.622656 -29.114242) (xy 212.947504 -29.114242)
			(xy 212.947504 -28.250642) (xy 212.947994 -28.220674) (xy 212.955817 -28.161252) (xy 212.97133 -28.103359)
			(xy 212.994266 -28.047986) (xy 213.024233 -27.99608) (xy 213.06072 -27.94853) (xy 213.1031 -27.90615)
			(xy 213.15065 -27.869663) (xy 213.202556 -27.839696) (xy 213.257929 -27.81676) (xy 213.315822 -27.801247)
			(xy 213.375244 -27.793424) (xy 213.43518 -27.793424) (xy 213.494602 -27.801247) (xy 213.552495 -27.81676)
			(xy 213.607868 -27.839696) (xy 213.659774 -27.869663) (xy 213.707324 -27.90615) (xy 213.749704 -27.94853)
			(xy 213.786191 -27.99608) (xy 213.816158 -28.047986) (xy 213.839094 -28.103359) (xy 213.854607 -28.161252)
			(xy 213.86243 -28.220674) (xy 213.86292 -28.250642) (xy 213.86292 -29.114242) (xy 213.862787 -29.12237)
			(xy 240.806732 -29.12237) (xy 240.806732 -28.25877) (xy 240.807222 -28.228786) (xy 240.81505 -28.16933)
			(xy 240.830571 -28.111405) (xy 240.85352 -28.056001) (xy 240.883504 -28.004067) (xy 240.92001 -27.956491)
			(xy 240.962415 -27.914086) (xy 241.009991 -27.87758) (xy 241.061925 -27.847596) (xy 241.117329 -27.824647)
			(xy 241.175254 -27.809126) (xy 241.23471 -27.801298) (xy 241.294678 -27.801298) (xy 241.354134 -27.809126)
			(xy 241.412059 -27.824647) (xy 241.467463 -27.847596) (xy 241.519397 -27.87758) (xy 241.566973 -27.914086)
			(xy 241.609378 -27.956491) (xy 241.645884 -28.004067) (xy 241.675868 -28.056001) (xy 241.698817 -28.111405)
			(xy 241.714338 -28.16933) (xy 241.722166 -28.228786) (xy 241.722656 -28.25877) (xy 241.722656 -29.114242)
			(xy 251.047504 -29.114242) (xy 251.047504 -28.250642) (xy 251.047994 -28.220674) (xy 251.055817 -28.161252)
			(xy 251.07133 -28.103359) (xy 251.094266 -28.047986) (xy 251.124233 -27.99608) (xy 251.16072 -27.94853)
			(xy 251.2031 -27.90615) (xy 251.25065 -27.869663) (xy 251.302556 -27.839696) (xy 251.357929 -27.81676)
			(xy 251.415822 -27.801247) (xy 251.475244 -27.793424) (xy 251.53518 -27.793424) (xy 251.594602 -27.801247)
			(xy 251.652495 -27.81676) (xy 251.707868 -27.839696) (xy 251.759774 -27.869663) (xy 251.807324 -27.90615)
			(xy 251.849704 -27.94853) (xy 251.886191 -27.99608) (xy 251.916158 -28.047986) (xy 251.939094 -28.103359)
			(xy 251.954607 -28.161252) (xy 251.96243 -28.220674) (xy 251.96292 -28.250642) (xy 251.96292 -29.114242)
			(xy 251.962787 -29.12237) (xy 266.80668 -29.12237) (xy 266.80668 -28.25877) (xy 266.80717 -28.228786)
			(xy 266.814998 -28.16933) (xy 266.830519 -28.111405) (xy 266.853468 -28.056001) (xy 266.883452 -28.004067)
			(xy 266.919958 -27.956491) (xy 266.962363 -27.914086) (xy 267.009939 -27.87758) (xy 267.061873 -27.847596)
			(xy 267.117277 -27.824647) (xy 267.175202 -27.809126) (xy 267.234658 -27.801298) (xy 267.294626 -27.801298)
			(xy 267.354082 -27.809126) (xy 267.412007 -27.824647) (xy 267.467411 -27.847596) (xy 267.519345 -27.87758)
			(xy 267.566921 -27.914086) (xy 267.609326 -27.956491) (xy 267.645832 -28.004067) (xy 267.675816 -28.056001)
			(xy 267.698765 -28.111405) (xy 267.714286 -28.16933) (xy 267.722114 -28.228786) (xy 267.722604 -28.25877)
			(xy 267.722604 -29.114242) (xy 277.047452 -29.114242) (xy 277.047452 -28.250642) (xy 277.047942 -28.220674)
			(xy 277.055765 -28.161252) (xy 277.071278 -28.103359) (xy 277.094214 -28.047986) (xy 277.124181 -27.99608)
			(xy 277.160668 -27.94853) (xy 277.203048 -27.90615) (xy 277.250598 -27.869663) (xy 277.302504 -27.839696)
			(xy 277.357877 -27.81676) (xy 277.41577 -27.801247) (xy 277.475192 -27.793424) (xy 277.535128 -27.793424)
			(xy 277.59455 -27.801247) (xy 277.652443 -27.81676) (xy 277.707816 -27.839696) (xy 277.759722 -27.869663)
			(xy 277.807272 -27.90615) (xy 277.849652 -27.94853) (xy 277.886139 -27.99608) (xy 277.916106 -28.047986)
			(xy 277.939042 -28.103359) (xy 277.954555 -28.161252) (xy 277.962378 -28.220674) (xy 277.962868 -28.250642)
			(xy 277.962868 -29.114242) (xy 277.962735 -29.12237) (xy 292.806628 -29.12237) (xy 292.806628 -28.25877)
			(xy 292.807118 -28.228786) (xy 292.814946 -28.16933) (xy 292.830467 -28.111405) (xy 292.853416 -28.056001)
			(xy 292.8834 -28.004067) (xy 292.919906 -27.956491) (xy 292.962311 -27.914086) (xy 293.009887 -27.87758)
			(xy 293.061821 -27.847596) (xy 293.117225 -27.824647) (xy 293.17515 -27.809126) (xy 293.234606 -27.801298)
			(xy 293.294574 -27.801298) (xy 293.35403 -27.809126) (xy 293.411955 -27.824647) (xy 293.467359 -27.847596)
			(xy 293.519293 -27.87758) (xy 293.566869 -27.914086) (xy 293.609274 -27.956491) (xy 293.64578 -28.004067)
			(xy 293.675764 -28.056001) (xy 293.698713 -28.111405) (xy 293.714234 -28.16933) (xy 293.722062 -28.228786)
			(xy 293.722552 -28.25877) (xy 293.722552 -29.114242) (xy 303.0474 -29.114242) (xy 303.0474 -28.250642)
			(xy 303.04789 -28.220674) (xy 303.055713 -28.161252) (xy 303.071226 -28.103359) (xy 303.094162 -28.047986)
			(xy 303.124129 -27.99608) (xy 303.160616 -27.94853) (xy 303.202996 -27.90615) (xy 303.250546 -27.869663)
			(xy 303.302452 -27.839696) (xy 303.357825 -27.81676) (xy 303.415718 -27.801247) (xy 303.47514 -27.793424)
			(xy 303.535076 -27.793424) (xy 303.594498 -27.801247) (xy 303.652391 -27.81676) (xy 303.707764 -27.839696)
			(xy 303.75967 -27.869663) (xy 303.80722 -27.90615) (xy 303.8496 -27.94853) (xy 303.886087 -27.99608)
			(xy 303.916054 -28.047986) (xy 303.93899 -28.103359) (xy 303.954503 -28.161252) (xy 303.962326 -28.220674)
			(xy 303.962816 -28.250642) (xy 303.962816 -29.114242) (xy 303.962683 -29.12237) (xy 318.806576 -29.12237)
			(xy 318.806576 -28.25877) (xy 318.807066 -28.228786) (xy 318.814894 -28.16933) (xy 318.830415 -28.111405)
			(xy 318.853364 -28.056001) (xy 318.883348 -28.004067) (xy 318.919854 -27.956491) (xy 318.962259 -27.914086)
			(xy 319.009835 -27.87758) (xy 319.061769 -27.847596) (xy 319.117173 -27.824647) (xy 319.175098 -27.809126)
			(xy 319.234554 -27.801298) (xy 319.294522 -27.801298) (xy 319.353978 -27.809126) (xy 319.411903 -27.824647)
			(xy 319.467307 -27.847596) (xy 319.519241 -27.87758) (xy 319.566817 -27.914086) (xy 319.609222 -27.956491)
			(xy 319.645728 -28.004067) (xy 319.675712 -28.056001) (xy 319.698661 -28.111405) (xy 319.714182 -28.16933)
			(xy 319.72201 -28.228786) (xy 319.7225 -28.25877) (xy 319.7225 -29.114242) (xy 329.047348 -29.114242)
			(xy 329.047348 -28.250642) (xy 329.047838 -28.220674) (xy 329.055661 -28.161252) (xy 329.071174 -28.103359)
			(xy 329.09411 -28.047986) (xy 329.124077 -27.99608) (xy 329.160564 -27.94853) (xy 329.202944 -27.90615)
			(xy 329.250494 -27.869663) (xy 329.3024 -27.839696) (xy 329.357773 -27.81676) (xy 329.415666 -27.801247)
			(xy 329.475088 -27.793424) (xy 329.535024 -27.793424) (xy 329.594446 -27.801247) (xy 329.652339 -27.81676)
			(xy 329.707712 -27.839696) (xy 329.759618 -27.869663) (xy 329.807168 -27.90615) (xy 329.849548 -27.94853)
			(xy 329.886035 -27.99608) (xy 329.916002 -28.047986) (xy 329.938938 -28.103359) (xy 329.954451 -28.161252)
			(xy 329.962274 -28.220674) (xy 329.962764 -28.250642) (xy 329.962764 -29.114242) (xy 329.962631 -29.12237)
			(xy 356.907084 -29.12237) (xy 356.907084 -28.25877) (xy 356.907574 -28.228802) (xy 356.915397 -28.16938)
			(xy 356.93091 -28.111487) (xy 356.953846 -28.056114) (xy 356.983813 -28.004208) (xy 357.0203 -27.956658)
			(xy 357.06268 -27.914278) (xy 357.11023 -27.877791) (xy 357.162136 -27.847824) (xy 357.217509 -27.824888)
			(xy 357.275402 -27.809375) (xy 357.334824 -27.801552) (xy 357.39476 -27.801552) (xy 357.454182 -27.809375)
			(xy 357.512075 -27.824888) (xy 357.567448 -27.847824) (xy 357.619354 -27.877791) (xy 357.666904 -27.914278)
			(xy 357.709284 -27.956658) (xy 357.745771 -28.004208) (xy 357.775738 -28.056114) (xy 357.798674 -28.111487)
			(xy 357.814187 -28.16938) (xy 357.82201 -28.228802) (xy 357.8225 -28.25877) (xy 357.8225 -29.114242)
			(xy 367.147348 -29.114242) (xy 367.147348 -28.250642) (xy 367.147838 -28.220658) (xy 367.155666 -28.161202)
			(xy 367.171187 -28.103277) (xy 367.194136 -28.047873) (xy 367.22412 -27.995939) (xy 367.260626 -27.948363)
			(xy 367.303031 -27.905958) (xy 367.350607 -27.869452) (xy 367.402541 -27.839468) (xy 367.457945 -27.816519)
			(xy 367.51587 -27.800998) (xy 367.575326 -27.79317) (xy 367.635294 -27.79317) (xy 367.69475 -27.800998)
			(xy 367.752675 -27.816519) (xy 367.808079 -27.839468) (xy 367.860013 -27.869452) (xy 367.907589 -27.905958)
			(xy 367.949994 -27.948363) (xy 367.9865 -27.995939) (xy 368.016484 -28.047873) (xy 368.039433 -28.103277)
			(xy 368.054954 -28.161202) (xy 368.062782 -28.220658) (xy 368.063272 -28.250642) (xy 368.063272 -29.114242)
			(xy 368.063139 -29.12237) (xy 382.907032 -29.12237) (xy 382.907032 -28.25877) (xy 382.907522 -28.228802)
			(xy 382.915345 -28.16938) (xy 382.930858 -28.111487) (xy 382.953794 -28.056114) (xy 382.983761 -28.004208)
			(xy 383.020248 -27.956658) (xy 383.062628 -27.914278) (xy 383.110178 -27.877791) (xy 383.162084 -27.847824)
			(xy 383.217457 -27.824888) (xy 383.27535 -27.809375) (xy 383.334772 -27.801552) (xy 383.394708 -27.801552)
			(xy 383.45413 -27.809375) (xy 383.512023 -27.824888) (xy 383.567396 -27.847824) (xy 383.619302 -27.877791)
			(xy 383.666852 -27.914278) (xy 383.709232 -27.956658) (xy 383.745719 -28.004208) (xy 383.775686 -28.056114)
			(xy 383.798622 -28.111487) (xy 383.814135 -28.16938) (xy 383.821958 -28.228802) (xy 383.822448 -28.25877)
			(xy 383.822448 -29.114242) (xy 393.147296 -29.114242) (xy 393.147296 -28.250642) (xy 393.147786 -28.220658)
			(xy 393.155614 -28.161202) (xy 393.171135 -28.103277) (xy 393.194084 -28.047873) (xy 393.224068 -27.995939)
			(xy 393.260574 -27.948363) (xy 393.302979 -27.905958) (xy 393.350555 -27.869452) (xy 393.402489 -27.839468)
			(xy 393.457893 -27.816519) (xy 393.515818 -27.800998) (xy 393.575274 -27.79317) (xy 393.635242 -27.79317)
			(xy 393.694698 -27.800998) (xy 393.752623 -27.816519) (xy 393.808027 -27.839468) (xy 393.859961 -27.869452)
			(xy 393.907537 -27.905958) (xy 393.949942 -27.948363) (xy 393.986448 -27.995939) (xy 394.016432 -28.047873)
			(xy 394.039381 -28.103277) (xy 394.054902 -28.161202) (xy 394.06273 -28.220658) (xy 394.06322 -28.250642)
			(xy 394.06322 -29.114242) (xy 394.063087 -29.12237) (xy 408.90698 -29.12237) (xy 408.90698 -28.25877)
			(xy 408.90747 -28.228802) (xy 408.915293 -28.16938) (xy 408.930806 -28.111487) (xy 408.953742 -28.056114)
			(xy 408.983709 -28.004208) (xy 409.020196 -27.956658) (xy 409.062576 -27.914278) (xy 409.110126 -27.877791)
			(xy 409.162032 -27.847824) (xy 409.217405 -27.824888) (xy 409.275298 -27.809375) (xy 409.33472 -27.801552)
			(xy 409.394656 -27.801552) (xy 409.454078 -27.809375) (xy 409.511971 -27.824888) (xy 409.567344 -27.847824)
			(xy 409.61925 -27.877791) (xy 409.6668 -27.914278) (xy 409.70918 -27.956658) (xy 409.745667 -28.004208)
			(xy 409.775634 -28.056114) (xy 409.79857 -28.111487) (xy 409.814083 -28.16938) (xy 409.821906 -28.228802)
			(xy 409.822396 -28.25877) (xy 409.822396 -29.114242) (xy 419.147244 -29.114242) (xy 419.147244 -28.250642)
			(xy 419.147734 -28.220658) (xy 419.155562 -28.161202) (xy 419.171083 -28.103277) (xy 419.194032 -28.047873)
			(xy 419.224016 -27.995939) (xy 419.260522 -27.948363) (xy 419.302927 -27.905958) (xy 419.350503 -27.869452)
			(xy 419.402437 -27.839468) (xy 419.457841 -27.816519) (xy 419.515766 -27.800998) (xy 419.575222 -27.79317)
			(xy 419.63519 -27.79317) (xy 419.694646 -27.800998) (xy 419.752571 -27.816519) (xy 419.807975 -27.839468)
			(xy 419.859909 -27.869452) (xy 419.907485 -27.905958) (xy 419.94989 -27.948363) (xy 419.986396 -27.995939)
			(xy 420.01638 -28.047873) (xy 420.039329 -28.103277) (xy 420.05485 -28.161202) (xy 420.062678 -28.220658)
			(xy 420.063168 -28.250642) (xy 420.063168 -29.114242) (xy 420.063035 -29.12237) (xy 434.906928 -29.12237)
			(xy 434.906928 -28.25877) (xy 434.907418 -28.228802) (xy 434.915241 -28.16938) (xy 434.930754 -28.111487)
			(xy 434.95369 -28.056114) (xy 434.983657 -28.004208) (xy 435.020144 -27.956658) (xy 435.062524 -27.914278)
			(xy 435.110074 -27.877791) (xy 435.16198 -27.847824) (xy 435.217353 -27.824888) (xy 435.275246 -27.809375)
			(xy 435.334668 -27.801552) (xy 435.394604 -27.801552) (xy 435.454026 -27.809375) (xy 435.511919 -27.824888)
			(xy 435.567292 -27.847824) (xy 435.619198 -27.877791) (xy 435.666748 -27.914278) (xy 435.709128 -27.956658)
			(xy 435.745615 -28.004208) (xy 435.775582 -28.056114) (xy 435.798518 -28.111487) (xy 435.814031 -28.16938)
			(xy 435.821854 -28.228802) (xy 435.822344 -28.25877) (xy 435.822344 -29.114242) (xy 445.147192 -29.114242)
			(xy 445.147192 -28.250642) (xy 445.147682 -28.220658) (xy 445.15551 -28.161202) (xy 445.171031 -28.103277)
			(xy 445.19398 -28.047873) (xy 445.223964 -27.995939) (xy 445.26047 -27.948363) (xy 445.302875 -27.905958)
			(xy 445.350451 -27.869452) (xy 445.402385 -27.839468) (xy 445.457789 -27.816519) (xy 445.515714 -27.800998)
			(xy 445.57517 -27.79317) (xy 445.635138 -27.79317) (xy 445.694594 -27.800998) (xy 445.752519 -27.816519)
			(xy 445.807923 -27.839468) (xy 445.859857 -27.869452) (xy 445.907433 -27.905958) (xy 445.949838 -27.948363)
			(xy 445.986344 -27.995939) (xy 446.016328 -28.047873) (xy 446.039277 -28.103277) (xy 446.054798 -28.161202)
			(xy 446.062626 -28.220658) (xy 446.063116 -28.250642) (xy 446.063116 -29.114242) (xy 446.062626 -29.144226)
			(xy 446.054798 -29.203682) (xy 446.039277 -29.261607) (xy 446.016328 -29.317011) (xy 445.986344 -29.368945)
			(xy 445.949838 -29.416521) (xy 445.907433 -29.458926) (xy 445.859857 -29.495432) (xy 445.807923 -29.525416)
			(xy 445.752519 -29.548365) (xy 445.694594 -29.563886) (xy 445.635138 -29.571714) (xy 445.57517 -29.571714)
			(xy 445.515714 -29.563886) (xy 445.457789 -29.548365) (xy 445.402385 -29.525416) (xy 445.350451 -29.495432)
			(xy 445.302875 -29.458926) (xy 445.26047 -29.416521) (xy 445.223964 -29.368945) (xy 445.19398 -29.317011)
			(xy 445.171031 -29.261607) (xy 445.15551 -29.203682) (xy 445.147682 -29.144226) (xy 445.147192 -29.114242)
			(xy 435.822344 -29.114242) (xy 435.822344 -29.12237) (xy 435.821854 -29.152338) (xy 435.814031 -29.21176)
			(xy 435.798518 -29.269653) (xy 435.775582 -29.325026) (xy 435.745615 -29.376932) (xy 435.709128 -29.424482)
			(xy 435.666748 -29.466862) (xy 435.619198 -29.503349) (xy 435.567292 -29.533316) (xy 435.511919 -29.556252)
			(xy 435.454026 -29.571765) (xy 435.394604 -29.579588) (xy 435.334668 -29.579588) (xy 435.275246 -29.571765)
			(xy 435.217353 -29.556252) (xy 435.16198 -29.533316) (xy 435.110074 -29.503349) (xy 435.062524 -29.466862)
			(xy 435.020144 -29.424482) (xy 434.983657 -29.376932) (xy 434.95369 -29.325026) (xy 434.930754 -29.269653)
			(xy 434.915241 -29.21176) (xy 434.907418 -29.152338) (xy 434.906928 -29.12237) (xy 420.063035 -29.12237)
			(xy 420.062678 -29.144226) (xy 420.05485 -29.203682) (xy 420.039329 -29.261607) (xy 420.01638 -29.317011)
			(xy 419.986396 -29.368945) (xy 419.94989 -29.416521) (xy 419.907485 -29.458926) (xy 419.859909 -29.495432)
			(xy 419.807975 -29.525416) (xy 419.752571 -29.548365) (xy 419.694646 -29.563886) (xy 419.63519 -29.571714)
			(xy 419.575222 -29.571714) (xy 419.515766 -29.563886) (xy 419.457841 -29.548365) (xy 419.402437 -29.525416)
			(xy 419.350503 -29.495432) (xy 419.302927 -29.458926) (xy 419.260522 -29.416521) (xy 419.224016 -29.368945)
			(xy 419.194032 -29.317011) (xy 419.171083 -29.261607) (xy 419.155562 -29.203682) (xy 419.147734 -29.144226)
			(xy 419.147244 -29.114242) (xy 409.822396 -29.114242) (xy 409.822396 -29.12237) (xy 409.821906 -29.152338)
			(xy 409.814083 -29.21176) (xy 409.79857 -29.269653) (xy 409.775634 -29.325026) (xy 409.745667 -29.376932)
			(xy 409.70918 -29.424482) (xy 409.6668 -29.466862) (xy 409.61925 -29.503349) (xy 409.567344 -29.533316)
			(xy 409.511971 -29.556252) (xy 409.454078 -29.571765) (xy 409.394656 -29.579588) (xy 409.33472 -29.579588)
			(xy 409.275298 -29.571765) (xy 409.217405 -29.556252) (xy 409.162032 -29.533316) (xy 409.110126 -29.503349)
			(xy 409.062576 -29.466862) (xy 409.020196 -29.424482) (xy 408.983709 -29.376932) (xy 408.953742 -29.325026)
			(xy 408.930806 -29.269653) (xy 408.915293 -29.21176) (xy 408.90747 -29.152338) (xy 408.90698 -29.12237)
			(xy 394.063087 -29.12237) (xy 394.06273 -29.144226) (xy 394.054902 -29.203682) (xy 394.039381 -29.261607)
			(xy 394.016432 -29.317011) (xy 393.986448 -29.368945) (xy 393.949942 -29.416521) (xy 393.907537 -29.458926)
			(xy 393.859961 -29.495432) (xy 393.808027 -29.525416) (xy 393.752623 -29.548365) (xy 393.694698 -29.563886)
			(xy 393.635242 -29.571714) (xy 393.575274 -29.571714) (xy 393.515818 -29.563886) (xy 393.457893 -29.548365)
			(xy 393.402489 -29.525416) (xy 393.350555 -29.495432) (xy 393.302979 -29.458926) (xy 393.260574 -29.416521)
			(xy 393.224068 -29.368945) (xy 393.194084 -29.317011) (xy 393.171135 -29.261607) (xy 393.155614 -29.203682)
			(xy 393.147786 -29.144226) (xy 393.147296 -29.114242) (xy 383.822448 -29.114242) (xy 383.822448 -29.12237)
			(xy 383.821958 -29.152338) (xy 383.814135 -29.21176) (xy 383.798622 -29.269653) (xy 383.775686 -29.325026)
			(xy 383.745719 -29.376932) (xy 383.709232 -29.424482) (xy 383.666852 -29.466862) (xy 383.619302 -29.503349)
			(xy 383.567396 -29.533316) (xy 383.512023 -29.556252) (xy 383.45413 -29.571765) (xy 383.394708 -29.579588)
			(xy 383.334772 -29.579588) (xy 383.27535 -29.571765) (xy 383.217457 -29.556252) (xy 383.162084 -29.533316)
			(xy 383.110178 -29.503349) (xy 383.062628 -29.466862) (xy 383.020248 -29.424482) (xy 382.983761 -29.376932)
			(xy 382.953794 -29.325026) (xy 382.930858 -29.269653) (xy 382.915345 -29.21176) (xy 382.907522 -29.152338)
			(xy 382.907032 -29.12237) (xy 368.063139 -29.12237) (xy 368.062782 -29.144226) (xy 368.054954 -29.203682)
			(xy 368.039433 -29.261607) (xy 368.016484 -29.317011) (xy 367.9865 -29.368945) (xy 367.949994 -29.416521)
			(xy 367.907589 -29.458926) (xy 367.860013 -29.495432) (xy 367.808079 -29.525416) (xy 367.752675 -29.548365)
			(xy 367.69475 -29.563886) (xy 367.635294 -29.571714) (xy 367.575326 -29.571714) (xy 367.51587 -29.563886)
			(xy 367.457945 -29.548365) (xy 367.402541 -29.525416) (xy 367.350607 -29.495432) (xy 367.303031 -29.458926)
			(xy 367.260626 -29.416521) (xy 367.22412 -29.368945) (xy 367.194136 -29.317011) (xy 367.171187 -29.261607)
			(xy 367.155666 -29.203682) (xy 367.147838 -29.144226) (xy 367.147348 -29.114242) (xy 357.8225 -29.114242)
			(xy 357.8225 -29.12237) (xy 357.82201 -29.152338) (xy 357.814187 -29.21176) (xy 357.798674 -29.269653)
			(xy 357.775738 -29.325026) (xy 357.745771 -29.376932) (xy 357.709284 -29.424482) (xy 357.666904 -29.466862)
			(xy 357.619354 -29.503349) (xy 357.567448 -29.533316) (xy 357.512075 -29.556252) (xy 357.454182 -29.571765)
			(xy 357.39476 -29.579588) (xy 357.334824 -29.579588) (xy 357.275402 -29.571765) (xy 357.217509 -29.556252)
			(xy 357.162136 -29.533316) (xy 357.11023 -29.503349) (xy 357.06268 -29.466862) (xy 357.0203 -29.424482)
			(xy 356.983813 -29.376932) (xy 356.953846 -29.325026) (xy 356.93091 -29.269653) (xy 356.915397 -29.21176)
			(xy 356.907574 -29.152338) (xy 356.907084 -29.12237) (xy 329.962631 -29.12237) (xy 329.962274 -29.14421)
			(xy 329.954451 -29.203632) (xy 329.938938 -29.261525) (xy 329.916002 -29.316898) (xy 329.886035 -29.368804)
			(xy 329.849548 -29.416354) (xy 329.807168 -29.458734) (xy 329.759618 -29.495221) (xy 329.707712 -29.525188)
			(xy 329.652339 -29.548124) (xy 329.594446 -29.563637) (xy 329.535024 -29.57146) (xy 329.475088 -29.57146)
			(xy 329.415666 -29.563637) (xy 329.357773 -29.548124) (xy 329.3024 -29.525188) (xy 329.250494 -29.495221)
			(xy 329.202944 -29.458734) (xy 329.160564 -29.416354) (xy 329.124077 -29.368804) (xy 329.09411 -29.316898)
			(xy 329.071174 -29.261525) (xy 329.055661 -29.203632) (xy 329.047838 -29.14421) (xy 329.047348 -29.114242)
			(xy 319.7225 -29.114242) (xy 319.7225 -29.12237) (xy 319.72201 -29.152354) (xy 319.714182 -29.21181)
			(xy 319.698661 -29.269735) (xy 319.675712 -29.325139) (xy 319.645728 -29.377073) (xy 319.609222 -29.424649)
			(xy 319.566817 -29.467054) (xy 319.519241 -29.50356) (xy 319.467307 -29.533544) (xy 319.411903 -29.556493)
			(xy 319.353978 -29.572014) (xy 319.294522 -29.579842) (xy 319.234554 -29.579842) (xy 319.175098 -29.572014)
			(xy 319.117173 -29.556493) (xy 319.061769 -29.533544) (xy 319.009835 -29.50356) (xy 318.962259 -29.467054)
			(xy 318.919854 -29.424649) (xy 318.883348 -29.377073) (xy 318.853364 -29.325139) (xy 318.830415 -29.269735)
			(xy 318.814894 -29.21181) (xy 318.807066 -29.152354) (xy 318.806576 -29.12237) (xy 303.962683 -29.12237)
			(xy 303.962326 -29.14421) (xy 303.954503 -29.203632) (xy 303.93899 -29.261525) (xy 303.916054 -29.316898)
			(xy 303.886087 -29.368804) (xy 303.8496 -29.416354) (xy 303.80722 -29.458734) (xy 303.75967 -29.495221)
			(xy 303.707764 -29.525188) (xy 303.652391 -29.548124) (xy 303.594498 -29.563637) (xy 303.535076 -29.57146)
			(xy 303.47514 -29.57146) (xy 303.415718 -29.563637) (xy 303.357825 -29.548124) (xy 303.302452 -29.525188)
			(xy 303.250546 -29.495221) (xy 303.202996 -29.458734) (xy 303.160616 -29.416354) (xy 303.124129 -29.368804)
			(xy 303.094162 -29.316898) (xy 303.071226 -29.261525) (xy 303.055713 -29.203632) (xy 303.04789 -29.14421)
			(xy 303.0474 -29.114242) (xy 293.722552 -29.114242) (xy 293.722552 -29.12237) (xy 293.722062 -29.152354)
			(xy 293.714234 -29.21181) (xy 293.698713 -29.269735) (xy 293.675764 -29.325139) (xy 293.64578 -29.377073)
			(xy 293.609274 -29.424649) (xy 293.566869 -29.467054) (xy 293.519293 -29.50356) (xy 293.467359 -29.533544)
			(xy 293.411955 -29.556493) (xy 293.35403 -29.572014) (xy 293.294574 -29.579842) (xy 293.234606 -29.579842)
			(xy 293.17515 -29.572014) (xy 293.117225 -29.556493) (xy 293.061821 -29.533544) (xy 293.009887 -29.50356)
			(xy 292.962311 -29.467054) (xy 292.919906 -29.424649) (xy 292.8834 -29.377073) (xy 292.853416 -29.325139)
			(xy 292.830467 -29.269735) (xy 292.814946 -29.21181) (xy 292.807118 -29.152354) (xy 292.806628 -29.12237)
			(xy 277.962735 -29.12237) (xy 277.962378 -29.14421) (xy 277.954555 -29.203632) (xy 277.939042 -29.261525)
			(xy 277.916106 -29.316898) (xy 277.886139 -29.368804) (xy 277.849652 -29.416354) (xy 277.807272 -29.458734)
			(xy 277.759722 -29.495221) (xy 277.707816 -29.525188) (xy 277.652443 -29.548124) (xy 277.59455 -29.563637)
			(xy 277.535128 -29.57146) (xy 277.475192 -29.57146) (xy 277.41577 -29.563637) (xy 277.357877 -29.548124)
			(xy 277.302504 -29.525188) (xy 277.250598 -29.495221) (xy 277.203048 -29.458734) (xy 277.160668 -29.416354)
			(xy 277.124181 -29.368804) (xy 277.094214 -29.316898) (xy 277.071278 -29.261525) (xy 277.055765 -29.203632)
			(xy 277.047942 -29.14421) (xy 277.047452 -29.114242) (xy 267.722604 -29.114242) (xy 267.722604 -29.12237)
			(xy 267.722114 -29.152354) (xy 267.714286 -29.21181) (xy 267.698765 -29.269735) (xy 267.675816 -29.325139)
			(xy 267.645832 -29.377073) (xy 267.609326 -29.424649) (xy 267.566921 -29.467054) (xy 267.519345 -29.50356)
			(xy 267.467411 -29.533544) (xy 267.412007 -29.556493) (xy 267.354082 -29.572014) (xy 267.294626 -29.579842)
			(xy 267.234658 -29.579842) (xy 267.175202 -29.572014) (xy 267.117277 -29.556493) (xy 267.061873 -29.533544)
			(xy 267.009939 -29.50356) (xy 266.962363 -29.467054) (xy 266.919958 -29.424649) (xy 266.883452 -29.377073)
			(xy 266.853468 -29.325139) (xy 266.830519 -29.269735) (xy 266.814998 -29.21181) (xy 266.80717 -29.152354)
			(xy 266.80668 -29.12237) (xy 251.962787 -29.12237) (xy 251.96243 -29.14421) (xy 251.954607 -29.203632)
			(xy 251.939094 -29.261525) (xy 251.916158 -29.316898) (xy 251.886191 -29.368804) (xy 251.849704 -29.416354)
			(xy 251.807324 -29.458734) (xy 251.759774 -29.495221) (xy 251.707868 -29.525188) (xy 251.652495 -29.548124)
			(xy 251.594602 -29.563637) (xy 251.53518 -29.57146) (xy 251.475244 -29.57146) (xy 251.415822 -29.563637)
			(xy 251.357929 -29.548124) (xy 251.302556 -29.525188) (xy 251.25065 -29.495221) (xy 251.2031 -29.458734)
			(xy 251.16072 -29.416354) (xy 251.124233 -29.368804) (xy 251.094266 -29.316898) (xy 251.07133 -29.261525)
			(xy 251.055817 -29.203632) (xy 251.047994 -29.14421) (xy 251.047504 -29.114242) (xy 241.722656 -29.114242)
			(xy 241.722656 -29.12237) (xy 241.722166 -29.152354) (xy 241.714338 -29.21181) (xy 241.698817 -29.269735)
			(xy 241.675868 -29.325139) (xy 241.645884 -29.377073) (xy 241.609378 -29.424649) (xy 241.566973 -29.467054)
			(xy 241.519397 -29.50356) (xy 241.467463 -29.533544) (xy 241.412059 -29.556493) (xy 241.354134 -29.572014)
			(xy 241.294678 -29.579842) (xy 241.23471 -29.579842) (xy 241.175254 -29.572014) (xy 241.117329 -29.556493)
			(xy 241.061925 -29.533544) (xy 241.009991 -29.50356) (xy 240.962415 -29.467054) (xy 240.92001 -29.424649)
			(xy 240.883504 -29.377073) (xy 240.85352 -29.325139) (xy 240.830571 -29.269735) (xy 240.81505 -29.21181)
			(xy 240.807222 -29.152354) (xy 240.806732 -29.12237) (xy 213.862787 -29.12237) (xy 213.86243 -29.14421)
			(xy 213.854607 -29.203632) (xy 213.839094 -29.261525) (xy 213.816158 -29.316898) (xy 213.786191 -29.368804)
			(xy 213.749704 -29.416354) (xy 213.707324 -29.458734) (xy 213.659774 -29.495221) (xy 213.607868 -29.525188)
			(xy 213.552495 -29.548124) (xy 213.494602 -29.563637) (xy 213.43518 -29.57146) (xy 213.375244 -29.57146)
			(xy 213.315822 -29.563637) (xy 213.257929 -29.548124) (xy 213.202556 -29.525188) (xy 213.15065 -29.495221)
			(xy 213.1031 -29.458734) (xy 213.06072 -29.416354) (xy 213.024233 -29.368804) (xy 212.994266 -29.316898)
			(xy 212.97133 -29.261525) (xy 212.955817 -29.203632) (xy 212.947994 -29.14421) (xy 212.947504 -29.114242)
			(xy 203.622656 -29.114242) (xy 203.622656 -29.12237) (xy 203.622166 -29.152354) (xy 203.614338 -29.21181)
			(xy 203.598817 -29.269735) (xy 203.575868 -29.325139) (xy 203.545884 -29.377073) (xy 203.509378 -29.424649)
			(xy 203.466973 -29.467054) (xy 203.419397 -29.50356) (xy 203.367463 -29.533544) (xy 203.312059 -29.556493)
			(xy 203.254134 -29.572014) (xy 203.194678 -29.579842) (xy 203.13471 -29.579842) (xy 203.075254 -29.572014)
			(xy 203.017329 -29.556493) (xy 202.961925 -29.533544) (xy 202.909991 -29.50356) (xy 202.862415 -29.467054)
			(xy 202.82001 -29.424649) (xy 202.783504 -29.377073) (xy 202.75352 -29.325139) (xy 202.730571 -29.269735)
			(xy 202.71505 -29.21181) (xy 202.707222 -29.152354) (xy 202.706732 -29.12237) (xy 187.862839 -29.12237)
			(xy 187.862482 -29.14421) (xy 187.854659 -29.203632) (xy 187.839146 -29.261525) (xy 187.81621 -29.316898)
			(xy 187.786243 -29.368804) (xy 187.749756 -29.416354) (xy 187.707376 -29.458734) (xy 187.659826 -29.495221)
			(xy 187.60792 -29.525188) (xy 187.552547 -29.548124) (xy 187.494654 -29.563637) (xy 187.435232 -29.57146)
			(xy 187.375296 -29.57146) (xy 187.315874 -29.563637) (xy 187.257981 -29.548124) (xy 187.202608 -29.525188)
			(xy 187.150702 -29.495221) (xy 187.103152 -29.458734) (xy 187.060772 -29.416354) (xy 187.024285 -29.368804)
			(xy 186.994318 -29.316898) (xy 186.971382 -29.261525) (xy 186.955869 -29.203632) (xy 186.948046 -29.14421)
			(xy 186.947556 -29.114242) (xy 177.622708 -29.114242) (xy 177.622708 -29.12237) (xy 177.622218 -29.152354)
			(xy 177.61439 -29.21181) (xy 177.598869 -29.269735) (xy 177.57592 -29.325139) (xy 177.545936 -29.377073)
			(xy 177.50943 -29.424649) (xy 177.467025 -29.467054) (xy 177.419449 -29.50356) (xy 177.367515 -29.533544)
			(xy 177.312111 -29.556493) (xy 177.254186 -29.572014) (xy 177.19473 -29.579842) (xy 177.134762 -29.579842)
			(xy 177.075306 -29.572014) (xy 177.017381 -29.556493) (xy 176.961977 -29.533544) (xy 176.910043 -29.50356)
			(xy 176.862467 -29.467054) (xy 176.820062 -29.424649) (xy 176.783556 -29.377073) (xy 176.753572 -29.325139)
			(xy 176.730623 -29.269735) (xy 176.715102 -29.21181) (xy 176.707274 -29.152354) (xy 176.706784 -29.12237)
			(xy 161.862891 -29.12237) (xy 161.862534 -29.14421) (xy 161.854711 -29.203632) (xy 161.839198 -29.261525)
			(xy 161.816262 -29.316898) (xy 161.786295 -29.368804) (xy 161.749808 -29.416354) (xy 161.707428 -29.458734)
			(xy 161.659878 -29.495221) (xy 161.607972 -29.525188) (xy 161.552599 -29.548124) (xy 161.494706 -29.563637)
			(xy 161.435284 -29.57146) (xy 161.375348 -29.57146) (xy 161.315926 -29.563637) (xy 161.258033 -29.548124)
			(xy 161.20266 -29.525188) (xy 161.150754 -29.495221) (xy 161.103204 -29.458734) (xy 161.060824 -29.416354)
			(xy 161.024337 -29.368804) (xy 160.99437 -29.316898) (xy 160.971434 -29.261525) (xy 160.955921 -29.203632)
			(xy 160.948098 -29.14421) (xy 160.947608 -29.114242) (xy 151.62276 -29.114242) (xy 151.62276 -29.12237)
			(xy 151.62227 -29.152354) (xy 151.614442 -29.21181) (xy 151.598921 -29.269735) (xy 151.575972 -29.325139)
			(xy 151.545988 -29.377073) (xy 151.509482 -29.424649) (xy 151.467077 -29.467054) (xy 151.419501 -29.50356)
			(xy 151.367567 -29.533544) (xy 151.312163 -29.556493) (xy 151.254238 -29.572014) (xy 151.194782 -29.579842)
			(xy 151.134814 -29.579842) (xy 151.075358 -29.572014) (xy 151.017433 -29.556493) (xy 150.962029 -29.533544)
			(xy 150.910095 -29.50356) (xy 150.862519 -29.467054) (xy 150.820114 -29.424649) (xy 150.783608 -29.377073)
			(xy 150.753624 -29.325139) (xy 150.730675 -29.269735) (xy 150.715154 -29.21181) (xy 150.707326 -29.152354)
			(xy 150.706836 -29.12237) (xy 135.862943 -29.12237) (xy 135.862586 -29.14421) (xy 135.854763 -29.203632)
			(xy 135.83925 -29.261525) (xy 135.816314 -29.316898) (xy 135.786347 -29.368804) (xy 135.74986 -29.416354)
			(xy 135.70748 -29.458734) (xy 135.65993 -29.495221) (xy 135.608024 -29.525188) (xy 135.552651 -29.548124)
			(xy 135.494758 -29.563637) (xy 135.435336 -29.57146) (xy 135.3754 -29.57146) (xy 135.315978 -29.563637)
			(xy 135.258085 -29.548124) (xy 135.202712 -29.525188) (xy 135.150806 -29.495221) (xy 135.103256 -29.458734)
			(xy 135.060876 -29.416354) (xy 135.024389 -29.368804) (xy 134.994422 -29.316898) (xy 134.971486 -29.261525)
			(xy 134.955973 -29.203632) (xy 134.94815 -29.14421) (xy 134.94766 -29.114242) (xy 125.622812 -29.114242)
			(xy 125.622812 -29.12237) (xy 125.622322 -29.152354) (xy 125.614494 -29.21181) (xy 125.598973 -29.269735)
			(xy 125.576024 -29.325139) (xy 125.54604 -29.377073) (xy 125.509534 -29.424649) (xy 125.467129 -29.467054)
			(xy 125.419553 -29.50356) (xy 125.367619 -29.533544) (xy 125.312215 -29.556493) (xy 125.25429 -29.572014)
			(xy 125.194834 -29.579842) (xy 125.134866 -29.579842) (xy 125.07541 -29.572014) (xy 125.017485 -29.556493)
			(xy 124.962081 -29.533544) (xy 124.910147 -29.50356) (xy 124.862571 -29.467054) (xy 124.820166 -29.424649)
			(xy 124.78366 -29.377073) (xy 124.753676 -29.325139) (xy 124.730727 -29.269735) (xy 124.715206 -29.21181)
			(xy 124.707378 -29.152354) (xy 124.706888 -29.12237) (xy 97.762943 -29.12237) (xy 97.762586 -29.144226)
			(xy 97.754758 -29.203682) (xy 97.739237 -29.261607) (xy 97.716288 -29.317011) (xy 97.686304 -29.368945)
			(xy 97.649798 -29.416521) (xy 97.607393 -29.458926) (xy 97.559817 -29.495432) (xy 97.507883 -29.525416)
			(xy 97.452479 -29.548365) (xy 97.394554 -29.563886) (xy 97.335098 -29.571714) (xy 97.27513 -29.571714)
			(xy 97.215674 -29.563886) (xy 97.157749 -29.548365) (xy 97.102345 -29.525416) (xy 97.050411 -29.495432)
			(xy 97.002835 -29.458926) (xy 96.96043 -29.416521) (xy 96.923924 -29.368945) (xy 96.89394 -29.317011)
			(xy 96.870991 -29.261607) (xy 96.85547 -29.203682) (xy 96.847642 -29.144226) (xy 96.847152 -29.114242)
			(xy 87.522304 -29.114242) (xy 87.522304 -29.12237) (xy 87.521814 -29.152338) (xy 87.513991 -29.21176)
			(xy 87.498478 -29.269653) (xy 87.475542 -29.325026) (xy 87.445575 -29.376932) (xy 87.409088 -29.424482)
			(xy 87.366708 -29.466862) (xy 87.319158 -29.503349) (xy 87.267252 -29.533316) (xy 87.211879 -29.556252)
			(xy 87.153986 -29.571765) (xy 87.094564 -29.579588) (xy 87.034628 -29.579588) (xy 86.975206 -29.571765)
			(xy 86.917313 -29.556252) (xy 86.86194 -29.533316) (xy 86.810034 -29.503349) (xy 86.762484 -29.466862)
			(xy 86.720104 -29.424482) (xy 86.683617 -29.376932) (xy 86.65365 -29.325026) (xy 86.630714 -29.269653)
			(xy 86.615201 -29.21176) (xy 86.607378 -29.152338) (xy 86.606888 -29.12237) (xy 71.762995 -29.12237)
			(xy 71.762638 -29.144226) (xy 71.75481 -29.203682) (xy 71.739289 -29.261607) (xy 71.71634 -29.317011)
			(xy 71.686356 -29.368945) (xy 71.64985 -29.416521) (xy 71.607445 -29.458926) (xy 71.559869 -29.495432)
			(xy 71.507935 -29.525416) (xy 71.452531 -29.548365) (xy 71.394606 -29.563886) (xy 71.33515 -29.571714)
			(xy 71.275182 -29.571714) (xy 71.215726 -29.563886) (xy 71.157801 -29.548365) (xy 71.102397 -29.525416)
			(xy 71.050463 -29.495432) (xy 71.002887 -29.458926) (xy 70.960482 -29.416521) (xy 70.923976 -29.368945)
			(xy 70.893992 -29.317011) (xy 70.871043 -29.261607) (xy 70.855522 -29.203682) (xy 70.847694 -29.144226)
			(xy 70.847204 -29.114242) (xy 61.522356 -29.114242) (xy 61.522356 -29.12237) (xy 61.521866 -29.152338)
			(xy 61.514043 -29.21176) (xy 61.49853 -29.269653) (xy 61.475594 -29.325026) (xy 61.445627 -29.376932)
			(xy 61.40914 -29.424482) (xy 61.36676 -29.466862) (xy 61.31921 -29.503349) (xy 61.267304 -29.533316)
			(xy 61.211931 -29.556252) (xy 61.154038 -29.571765) (xy 61.094616 -29.579588) (xy 61.03468 -29.579588)
			(xy 60.975258 -29.571765) (xy 60.917365 -29.556252) (xy 60.861992 -29.533316) (xy 60.810086 -29.503349)
			(xy 60.762536 -29.466862) (xy 60.720156 -29.424482) (xy 60.683669 -29.376932) (xy 60.653702 -29.325026)
			(xy 60.630766 -29.269653) (xy 60.615253 -29.21176) (xy 60.60743 -29.152338) (xy 60.60694 -29.12237)
			(xy 45.763047 -29.12237) (xy 45.76269 -29.144226) (xy 45.754862 -29.203682) (xy 45.739341 -29.261607)
			(xy 45.716392 -29.317011) (xy 45.686408 -29.368945) (xy 45.649902 -29.416521) (xy 45.607497 -29.458926)
			(xy 45.559921 -29.495432) (xy 45.507987 -29.525416) (xy 45.452583 -29.548365) (xy 45.394658 -29.563886)
			(xy 45.335202 -29.571714) (xy 45.275234 -29.571714) (xy 45.215778 -29.563886) (xy 45.157853 -29.548365)
			(xy 45.102449 -29.525416) (xy 45.050515 -29.495432) (xy 45.002939 -29.458926) (xy 44.960534 -29.416521)
			(xy 44.924028 -29.368945) (xy 44.894044 -29.317011) (xy 44.871095 -29.261607) (xy 44.855574 -29.203682)
			(xy 44.847746 -29.144226) (xy 44.847256 -29.114242) (xy 35.522408 -29.114242) (xy 35.522408 -29.12237)
			(xy 35.521918 -29.152338) (xy 35.514095 -29.21176) (xy 35.498582 -29.269653) (xy 35.475646 -29.325026)
			(xy 35.445679 -29.376932) (xy 35.409192 -29.424482) (xy 35.366812 -29.466862) (xy 35.319262 -29.503349)
			(xy 35.267356 -29.533316) (xy 35.211983 -29.556252) (xy 35.15409 -29.571765) (xy 35.094668 -29.579588)
			(xy 35.034732 -29.579588) (xy 34.97531 -29.571765) (xy 34.917417 -29.556252) (xy 34.862044 -29.533316)
			(xy 34.810138 -29.503349) (xy 34.762588 -29.466862) (xy 34.720208 -29.424482) (xy 34.683721 -29.376932)
			(xy 34.653754 -29.325026) (xy 34.630818 -29.269653) (xy 34.615305 -29.21176) (xy 34.607482 -29.152338)
			(xy 34.606992 -29.12237) (xy 19.763099 -29.12237) (xy 19.762742 -29.144226) (xy 19.754914 -29.203682)
			(xy 19.739393 -29.261607) (xy 19.716444 -29.317011) (xy 19.68646 -29.368945) (xy 19.649954 -29.416521)
			(xy 19.607549 -29.458926) (xy 19.559973 -29.495432) (xy 19.508039 -29.525416) (xy 19.452635 -29.548365)
			(xy 19.39471 -29.563886) (xy 19.335254 -29.571714) (xy 19.275286 -29.571714) (xy 19.21583 -29.563886)
			(xy 19.157905 -29.548365) (xy 19.102501 -29.525416) (xy 19.050567 -29.495432) (xy 19.002991 -29.458926)
			(xy 18.960586 -29.416521) (xy 18.92408 -29.368945) (xy 18.894096 -29.317011) (xy 18.871147 -29.261607)
			(xy 18.855626 -29.203682) (xy 18.847798 -29.144226) (xy 18.847308 -29.114242) (xy 9.52246 -29.114242)
			(xy 9.52246 -29.12237) (xy 9.52197 -29.152338) (xy 9.514147 -29.21176) (xy 9.498634 -29.269653) (xy 9.475698 -29.325026)
			(xy 9.445731 -29.376932) (xy 9.409244 -29.424482) (xy 9.366864 -29.466862) (xy 9.319314 -29.503349)
			(xy 9.267408 -29.533316) (xy 9.212035 -29.556252) (xy 9.154142 -29.571765) (xy 9.09472 -29.579588)
			(xy 9.034784 -29.579588) (xy 8.975362 -29.571765) (xy 8.917469 -29.556252) (xy 8.862096 -29.533316)
			(xy 8.81019 -29.503349) (xy 8.76264 -29.466862) (xy 8.72026 -29.424482) (xy 8.683773 -29.376932)
			(xy 8.653806 -29.325026) (xy 8.63087 -29.269653) (xy 8.615357 -29.21176) (xy 8.607534 -29.152338)
			(xy 8.607044 -29.12237) (xy 0.508 -29.12237) (xy 0.508 -30.922468) (xy 6.752844 -30.922468) (xy 6.752844 -30.058868)
			(xy 6.753334 -30.0289) (xy 6.761157 -29.969478) (xy 6.77667 -29.911585) (xy 6.799606 -29.856212)
			(xy 6.829573 -29.804306) (xy 6.86606 -29.756756) (xy 6.90844 -29.714376) (xy 6.95599 -29.677889)
			(xy 7.007896 -29.647922) (xy 7.063269 -29.624986) (xy 7.121162 -29.609473) (xy 7.180584 -29.60165)
			(xy 7.24052 -29.60165) (xy 7.299942 -29.609473) (xy 7.357835 -29.624986) (xy 7.413208 -29.647922)
			(xy 7.465114 -29.677889) (xy 7.512664 -29.714376) (xy 7.555044 -29.756756) (xy 7.591531 -29.804306)
			(xy 7.621498 -29.856212) (xy 7.644434 -29.911585) (xy 7.659947 -29.969478) (xy 7.66777 -30.0289)
			(xy 7.66826 -30.058868) (xy 7.66826 -30.92069) (xy 21.489416 -30.92069) (xy 21.489416 -30.05709)
			(xy 21.489906 -30.027106) (xy 21.497734 -29.96765) (xy 21.513255 -29.909725) (xy 21.536204 -29.854321)
			(xy 21.566188 -29.802387) (xy 21.602694 -29.754811) (xy 21.645099 -29.712406) (xy 21.692675 -29.6759)
			(xy 21.744609 -29.645916) (xy 21.800013 -29.622967) (xy 21.857938 -29.607446) (xy 21.917394 -29.599618)
			(xy 21.977362 -29.599618) (xy 22.036818 -29.607446) (xy 22.094743 -29.622967) (xy 22.150147 -29.645916)
			(xy 22.202081 -29.6759) (xy 22.249657 -29.712406) (xy 22.292062 -29.754811) (xy 22.328568 -29.802387)
			(xy 22.358552 -29.854321) (xy 22.381501 -29.909725) (xy 22.397022 -29.96765) (xy 22.40485 -30.027106)
			(xy 22.40534 -30.05709) (xy 22.40534 -30.92069) (xy 22.405311 -30.922468) (xy 32.752792 -30.922468)
			(xy 32.752792 -30.058868) (xy 32.753282 -30.0289) (xy 32.761105 -29.969478) (xy 32.776618 -29.911585)
			(xy 32.799554 -29.856212) (xy 32.829521 -29.804306) (xy 32.866008 -29.756756) (xy 32.908388 -29.714376)
			(xy 32.955938 -29.677889) (xy 33.007844 -29.647922) (xy 33.063217 -29.624986) (xy 33.12111 -29.609473)
			(xy 33.180532 -29.60165) (xy 33.240468 -29.60165) (xy 33.29989 -29.609473) (xy 33.357783 -29.624986)
			(xy 33.413156 -29.647922) (xy 33.465062 -29.677889) (xy 33.512612 -29.714376) (xy 33.554992 -29.756756)
			(xy 33.591479 -29.804306) (xy 33.621446 -29.856212) (xy 33.644382 -29.911585) (xy 33.659895 -29.969478)
			(xy 33.667718 -30.0289) (xy 33.668208 -30.058868) (xy 33.668208 -30.92069) (xy 47.489364 -30.92069)
			(xy 47.489364 -30.05709) (xy 47.489854 -30.027106) (xy 47.497682 -29.96765) (xy 47.513203 -29.909725)
			(xy 47.536152 -29.854321) (xy 47.566136 -29.802387) (xy 47.602642 -29.754811) (xy 47.645047 -29.712406)
			(xy 47.692623 -29.6759) (xy 47.744557 -29.645916) (xy 47.799961 -29.622967) (xy 47.857886 -29.607446)
			(xy 47.917342 -29.599618) (xy 47.97731 -29.599618) (xy 48.036766 -29.607446) (xy 48.094691 -29.622967)
			(xy 48.150095 -29.645916) (xy 48.202029 -29.6759) (xy 48.249605 -29.712406) (xy 48.29201 -29.754811)
			(xy 48.328516 -29.802387) (xy 48.3585 -29.854321) (xy 48.381449 -29.909725) (xy 48.39697 -29.96765)
			(xy 48.404798 -30.027106) (xy 48.405288 -30.05709) (xy 48.405288 -30.92069) (xy 48.405259 -30.922468)
			(xy 58.75274 -30.922468) (xy 58.75274 -30.058868) (xy 58.75323 -30.0289) (xy 58.761053 -29.969478)
			(xy 58.776566 -29.911585) (xy 58.799502 -29.856212) (xy 58.829469 -29.804306) (xy 58.865956 -29.756756)
			(xy 58.908336 -29.714376) (xy 58.955886 -29.677889) (xy 59.007792 -29.647922) (xy 59.063165 -29.624986)
			(xy 59.121058 -29.609473) (xy 59.18048 -29.60165) (xy 59.240416 -29.60165) (xy 59.299838 -29.609473)
			(xy 59.357731 -29.624986) (xy 59.413104 -29.647922) (xy 59.46501 -29.677889) (xy 59.51256 -29.714376)
			(xy 59.55494 -29.756756) (xy 59.591427 -29.804306) (xy 59.621394 -29.856212) (xy 59.64433 -29.911585)
			(xy 59.659843 -29.969478) (xy 59.667666 -30.0289) (xy 59.668156 -30.058868) (xy 59.668156 -30.92069)
			(xy 73.489312 -30.92069) (xy 73.489312 -30.05709) (xy 73.489802 -30.027106) (xy 73.49763 -29.96765)
			(xy 73.513151 -29.909725) (xy 73.5361 -29.854321) (xy 73.566084 -29.802387) (xy 73.60259 -29.754811)
			(xy 73.644995 -29.712406) (xy 73.692571 -29.6759) (xy 73.744505 -29.645916) (xy 73.799909 -29.622967)
			(xy 73.857834 -29.607446) (xy 73.91729 -29.599618) (xy 73.977258 -29.599618) (xy 74.036714 -29.607446)
			(xy 74.094639 -29.622967) (xy 74.150043 -29.645916) (xy 74.201977 -29.6759) (xy 74.249553 -29.712406)
			(xy 74.291958 -29.754811) (xy 74.328464 -29.802387) (xy 74.358448 -29.854321) (xy 74.381397 -29.909725)
			(xy 74.396918 -29.96765) (xy 74.404746 -30.027106) (xy 74.405236 -30.05709) (xy 74.405236 -30.92069)
			(xy 74.405207 -30.922468) (xy 84.752688 -30.922468) (xy 84.752688 -30.058868) (xy 84.753178 -30.0289)
			(xy 84.761001 -29.969478) (xy 84.776514 -29.911585) (xy 84.79945 -29.856212) (xy 84.829417 -29.804306)
			(xy 84.865904 -29.756756) (xy 84.908284 -29.714376) (xy 84.955834 -29.677889) (xy 85.00774 -29.647922)
			(xy 85.063113 -29.624986) (xy 85.121006 -29.609473) (xy 85.180428 -29.60165) (xy 85.240364 -29.60165)
			(xy 85.299786 -29.609473) (xy 85.357679 -29.624986) (xy 85.413052 -29.647922) (xy 85.464958 -29.677889)
			(xy 85.512508 -29.714376) (xy 85.554888 -29.756756) (xy 85.591375 -29.804306) (xy 85.621342 -29.856212)
			(xy 85.644278 -29.911585) (xy 85.659791 -29.969478) (xy 85.667614 -30.0289) (xy 85.668104 -30.058868)
			(xy 85.668104 -30.92069) (xy 99.48926 -30.92069) (xy 99.48926 -30.05709) (xy 99.48975 -30.027106)
			(xy 99.497578 -29.96765) (xy 99.513099 -29.909725) (xy 99.536048 -29.854321) (xy 99.566032 -29.802387)
			(xy 99.602538 -29.754811) (xy 99.644943 -29.712406) (xy 99.692519 -29.6759) (xy 99.744453 -29.645916)
			(xy 99.799857 -29.622967) (xy 99.857782 -29.607446) (xy 99.917238 -29.599618) (xy 99.977206 -29.599618)
			(xy 100.036662 -29.607446) (xy 100.094587 -29.622967) (xy 100.149991 -29.645916) (xy 100.201925 -29.6759)
			(xy 100.249501 -29.712406) (xy 100.291906 -29.754811) (xy 100.328412 -29.802387) (xy 100.358396 -29.854321)
			(xy 100.381345 -29.909725) (xy 100.396866 -29.96765) (xy 100.404694 -30.027106) (xy 100.405184 -30.05709)
			(xy 100.405184 -30.92069) (xy 100.405155 -30.922468) (xy 122.852688 -30.922468) (xy 122.852688 -30.058868)
			(xy 122.853178 -30.028884) (xy 122.861006 -29.969428) (xy 122.876527 -29.911503) (xy 122.899476 -29.856099)
			(xy 122.92946 -29.804165) (xy 122.965966 -29.756589) (xy 123.008371 -29.714184) (xy 123.055947 -29.677678)
			(xy 123.107881 -29.647694) (xy 123.163285 -29.624745) (xy 123.22121 -29.609224) (xy 123.280666 -29.601396)
			(xy 123.340634 -29.601396) (xy 123.40009 -29.609224) (xy 123.458015 -29.624745) (xy 123.513419 -29.647694)
			(xy 123.565353 -29.677678) (xy 123.612929 -29.714184) (xy 123.655334 -29.756589) (xy 123.69184 -29.804165)
			(xy 123.721824 -29.856099) (xy 123.744773 -29.911503) (xy 123.760294 -29.969428) (xy 123.768122 -30.028884)
			(xy 123.768612 -30.058868) (xy 123.768612 -30.92069) (xy 137.589768 -30.92069) (xy 137.589768 -30.05709)
			(xy 137.590258 -30.027122) (xy 137.598081 -29.9677) (xy 137.613594 -29.909807) (xy 137.63653 -29.854434)
			(xy 137.666497 -29.802528) (xy 137.702984 -29.754978) (xy 137.745364 -29.712598) (xy 137.792914 -29.676111)
			(xy 137.84482 -29.646144) (xy 137.900193 -29.623208) (xy 137.958086 -29.607695) (xy 138.017508 -29.599872)
			(xy 138.077444 -29.599872) (xy 138.136866 -29.607695) (xy 138.194759 -29.623208) (xy 138.250132 -29.646144)
			(xy 138.302038 -29.676111) (xy 138.349588 -29.712598) (xy 138.391968 -29.754978) (xy 138.428455 -29.802528)
			(xy 138.458422 -29.854434) (xy 138.481358 -29.909807) (xy 138.496871 -29.9677) (xy 138.504694 -30.027122)
			(xy 138.505184 -30.05709) (xy 138.505184 -30.92069) (xy 138.505155 -30.922468) (xy 148.852636 -30.922468)
			(xy 148.852636 -30.058868) (xy 148.853126 -30.028884) (xy 148.860954 -29.969428) (xy 148.876475 -29.911503)
			(xy 148.899424 -29.856099) (xy 148.929408 -29.804165) (xy 148.965914 -29.756589) (xy 149.008319 -29.714184)
			(xy 149.055895 -29.677678) (xy 149.107829 -29.647694) (xy 149.163233 -29.624745) (xy 149.221158 -29.609224)
			(xy 149.280614 -29.601396) (xy 149.340582 -29.601396) (xy 149.400038 -29.609224) (xy 149.457963 -29.624745)
			(xy 149.513367 -29.647694) (xy 149.565301 -29.677678) (xy 149.612877 -29.714184) (xy 149.655282 -29.756589)
			(xy 149.691788 -29.804165) (xy 149.721772 -29.856099) (xy 149.744721 -29.911503) (xy 149.760242 -29.969428)
			(xy 149.76807 -30.028884) (xy 149.76856 -30.058868) (xy 149.76856 -30.92069) (xy 163.589716 -30.92069)
			(xy 163.589716 -30.05709) (xy 163.590206 -30.027122) (xy 163.598029 -29.9677) (xy 163.613542 -29.909807)
			(xy 163.636478 -29.854434) (xy 163.666445 -29.802528) (xy 163.702932 -29.754978) (xy 163.745312 -29.712598)
			(xy 163.792862 -29.676111) (xy 163.844768 -29.646144) (xy 163.900141 -29.623208) (xy 163.958034 -29.607695)
			(xy 164.017456 -29.599872) (xy 164.077392 -29.599872) (xy 164.136814 -29.607695) (xy 164.194707 -29.623208)
			(xy 164.25008 -29.646144) (xy 164.301986 -29.676111) (xy 164.349536 -29.712598) (xy 164.391916 -29.754978)
			(xy 164.428403 -29.802528) (xy 164.45837 -29.854434) (xy 164.481306 -29.909807) (xy 164.496819 -29.9677)
			(xy 164.504642 -30.027122) (xy 164.505132 -30.05709) (xy 164.505132 -30.92069) (xy 164.505103 -30.922468)
			(xy 174.852584 -30.922468) (xy 174.852584 -30.058868) (xy 174.853074 -30.028884) (xy 174.860902 -29.969428)
			(xy 174.876423 -29.911503) (xy 174.899372 -29.856099) (xy 174.929356 -29.804165) (xy 174.965862 -29.756589)
			(xy 175.008267 -29.714184) (xy 175.055843 -29.677678) (xy 175.107777 -29.647694) (xy 175.163181 -29.624745)
			(xy 175.221106 -29.609224) (xy 175.280562 -29.601396) (xy 175.34053 -29.601396) (xy 175.399986 -29.609224)
			(xy 175.457911 -29.624745) (xy 175.513315 -29.647694) (xy 175.565249 -29.677678) (xy 175.612825 -29.714184)
			(xy 175.65523 -29.756589) (xy 175.691736 -29.804165) (xy 175.72172 -29.856099) (xy 175.744669 -29.911503)
			(xy 175.76019 -29.969428) (xy 175.768018 -30.028884) (xy 175.768508 -30.058868) (xy 175.768508 -30.92069)
			(xy 189.589664 -30.92069) (xy 189.589664 -30.05709) (xy 189.590154 -30.027122) (xy 189.597977 -29.9677)
			(xy 189.61349 -29.909807) (xy 189.636426 -29.854434) (xy 189.666393 -29.802528) (xy 189.70288 -29.754978)
			(xy 189.74526 -29.712598) (xy 189.79281 -29.676111) (xy 189.844716 -29.646144) (xy 189.900089 -29.623208)
			(xy 189.957982 -29.607695) (xy 190.017404 -29.599872) (xy 190.07734 -29.599872) (xy 190.136762 -29.607695)
			(xy 190.194655 -29.623208) (xy 190.250028 -29.646144) (xy 190.301934 -29.676111) (xy 190.349484 -29.712598)
			(xy 190.391864 -29.754978) (xy 190.428351 -29.802528) (xy 190.458318 -29.854434) (xy 190.481254 -29.909807)
			(xy 190.496767 -29.9677) (xy 190.50459 -30.027122) (xy 190.50508 -30.05709) (xy 190.50508 -30.92069)
			(xy 190.505051 -30.922468) (xy 200.852532 -30.922468) (xy 200.852532 -30.058868) (xy 200.853022 -30.028884)
			(xy 200.86085 -29.969428) (xy 200.876371 -29.911503) (xy 200.89932 -29.856099) (xy 200.929304 -29.804165)
			(xy 200.96581 -29.756589) (xy 201.008215 -29.714184) (xy 201.055791 -29.677678) (xy 201.107725 -29.647694)
			(xy 201.163129 -29.624745) (xy 201.221054 -29.609224) (xy 201.28051 -29.601396) (xy 201.340478 -29.601396)
			(xy 201.399934 -29.609224) (xy 201.457859 -29.624745) (xy 201.513263 -29.647694) (xy 201.565197 -29.677678)
			(xy 201.612773 -29.714184) (xy 201.655178 -29.756589) (xy 201.691684 -29.804165) (xy 201.721668 -29.856099)
			(xy 201.744617 -29.911503) (xy 201.760138 -29.969428) (xy 201.767966 -30.028884) (xy 201.768456 -30.058868)
			(xy 201.768456 -30.92069) (xy 215.589612 -30.92069) (xy 215.589612 -30.05709) (xy 215.590102 -30.027122)
			(xy 215.597925 -29.9677) (xy 215.613438 -29.909807) (xy 215.636374 -29.854434) (xy 215.666341 -29.802528)
			(xy 215.702828 -29.754978) (xy 215.745208 -29.712598) (xy 215.792758 -29.676111) (xy 215.844664 -29.646144)
			(xy 215.900037 -29.623208) (xy 215.95793 -29.607695) (xy 216.017352 -29.599872) (xy 216.077288 -29.599872)
			(xy 216.13671 -29.607695) (xy 216.194603 -29.623208) (xy 216.249976 -29.646144) (xy 216.301882 -29.676111)
			(xy 216.349432 -29.712598) (xy 216.391812 -29.754978) (xy 216.428299 -29.802528) (xy 216.458266 -29.854434)
			(xy 216.481202 -29.909807) (xy 216.496715 -29.9677) (xy 216.504538 -30.027122) (xy 216.505028 -30.05709)
			(xy 216.505028 -30.92069) (xy 216.504999 -30.922468) (xy 238.952532 -30.922468) (xy 238.952532 -30.058868)
			(xy 238.953022 -30.028884) (xy 238.96085 -29.969428) (xy 238.976371 -29.911503) (xy 238.99932 -29.856099)
			(xy 239.029304 -29.804165) (xy 239.06581 -29.756589) (xy 239.108215 -29.714184) (xy 239.155791 -29.677678)
			(xy 239.207725 -29.647694) (xy 239.263129 -29.624745) (xy 239.321054 -29.609224) (xy 239.38051 -29.601396)
			(xy 239.440478 -29.601396) (xy 239.499934 -29.609224) (xy 239.557859 -29.624745) (xy 239.613263 -29.647694)
			(xy 239.665197 -29.677678) (xy 239.712773 -29.714184) (xy 239.755178 -29.756589) (xy 239.791684 -29.804165)
			(xy 239.821668 -29.856099) (xy 239.844617 -29.911503) (xy 239.860138 -29.969428) (xy 239.867966 -30.028884)
			(xy 239.868456 -30.058868) (xy 239.868456 -30.92069) (xy 253.689612 -30.92069) (xy 253.689612 -30.05709)
			(xy 253.690102 -30.027122) (xy 253.697925 -29.9677) (xy 253.713438 -29.909807) (xy 253.736374 -29.854434)
			(xy 253.766341 -29.802528) (xy 253.802828 -29.754978) (xy 253.845208 -29.712598) (xy 253.892758 -29.676111)
			(xy 253.944664 -29.646144) (xy 254.000037 -29.623208) (xy 254.05793 -29.607695) (xy 254.117352 -29.599872)
			(xy 254.177288 -29.599872) (xy 254.23671 -29.607695) (xy 254.294603 -29.623208) (xy 254.349976 -29.646144)
			(xy 254.401882 -29.676111) (xy 254.449432 -29.712598) (xy 254.491812 -29.754978) (xy 254.528299 -29.802528)
			(xy 254.558266 -29.854434) (xy 254.581202 -29.909807) (xy 254.596715 -29.9677) (xy 254.604538 -30.027122)
			(xy 254.605028 -30.05709) (xy 254.605028 -30.92069) (xy 254.604999 -30.922468) (xy 264.95248 -30.922468)
			(xy 264.95248 -30.058868) (xy 264.95297 -30.028884) (xy 264.960798 -29.969428) (xy 264.976319 -29.911503)
			(xy 264.999268 -29.856099) (xy 265.029252 -29.804165) (xy 265.065758 -29.756589) (xy 265.108163 -29.714184)
			(xy 265.155739 -29.677678) (xy 265.207673 -29.647694) (xy 265.263077 -29.624745) (xy 265.321002 -29.609224)
			(xy 265.380458 -29.601396) (xy 265.440426 -29.601396) (xy 265.499882 -29.609224) (xy 265.557807 -29.624745)
			(xy 265.613211 -29.647694) (xy 265.665145 -29.677678) (xy 265.712721 -29.714184) (xy 265.755126 -29.756589)
			(xy 265.791632 -29.804165) (xy 265.821616 -29.856099) (xy 265.844565 -29.911503) (xy 265.860086 -29.969428)
			(xy 265.867914 -30.028884) (xy 265.868404 -30.058868) (xy 265.868404 -30.92069) (xy 279.68956 -30.92069)
			(xy 279.68956 -30.05709) (xy 279.69005 -30.027122) (xy 279.697873 -29.9677) (xy 279.713386 -29.909807)
			(xy 279.736322 -29.854434) (xy 279.766289 -29.802528) (xy 279.802776 -29.754978) (xy 279.845156 -29.712598)
			(xy 279.892706 -29.676111) (xy 279.944612 -29.646144) (xy 279.999985 -29.623208) (xy 280.057878 -29.607695)
			(xy 280.1173 -29.599872) (xy 280.177236 -29.599872) (xy 280.236658 -29.607695) (xy 280.294551 -29.623208)
			(xy 280.349924 -29.646144) (xy 280.40183 -29.676111) (xy 280.44938 -29.712598) (xy 280.49176 -29.754978)
			(xy 280.528247 -29.802528) (xy 280.558214 -29.854434) (xy 280.58115 -29.909807) (xy 280.596663 -29.9677)
			(xy 280.604486 -30.027122) (xy 280.604976 -30.05709) (xy 280.604976 -30.92069) (xy 280.604947 -30.922468)
			(xy 290.952428 -30.922468) (xy 290.952428 -30.058868) (xy 290.952918 -30.028884) (xy 290.960746 -29.969428)
			(xy 290.976267 -29.911503) (xy 290.999216 -29.856099) (xy 291.0292 -29.804165) (xy 291.065706 -29.756589)
			(xy 291.108111 -29.714184) (xy 291.155687 -29.677678) (xy 291.207621 -29.647694) (xy 291.263025 -29.624745)
			(xy 291.32095 -29.609224) (xy 291.380406 -29.601396) (xy 291.440374 -29.601396) (xy 291.49983 -29.609224)
			(xy 291.557755 -29.624745) (xy 291.613159 -29.647694) (xy 291.665093 -29.677678) (xy 291.712669 -29.714184)
			(xy 291.755074 -29.756589) (xy 291.79158 -29.804165) (xy 291.821564 -29.856099) (xy 291.844513 -29.911503)
			(xy 291.860034 -29.969428) (xy 291.867862 -30.028884) (xy 291.868352 -30.058868) (xy 291.868352 -30.92069)
			(xy 305.689508 -30.92069) (xy 305.689508 -30.05709) (xy 305.689998 -30.027122) (xy 305.697821 -29.9677)
			(xy 305.713334 -29.909807) (xy 305.73627 -29.854434) (xy 305.766237 -29.802528) (xy 305.802724 -29.754978)
			(xy 305.845104 -29.712598) (xy 305.892654 -29.676111) (xy 305.94456 -29.646144) (xy 305.999933 -29.623208)
			(xy 306.057826 -29.607695) (xy 306.117248 -29.599872) (xy 306.177184 -29.599872) (xy 306.236606 -29.607695)
			(xy 306.294499 -29.623208) (xy 306.349872 -29.646144) (xy 306.401778 -29.676111) (xy 306.449328 -29.712598)
			(xy 306.491708 -29.754978) (xy 306.528195 -29.802528) (xy 306.558162 -29.854434) (xy 306.581098 -29.909807)
			(xy 306.596611 -29.9677) (xy 306.604434 -30.027122) (xy 306.604924 -30.05709) (xy 306.604924 -30.92069)
			(xy 306.604895 -30.922468) (xy 316.952376 -30.922468) (xy 316.952376 -30.058868) (xy 316.952866 -30.028884)
			(xy 316.960694 -29.969428) (xy 316.976215 -29.911503) (xy 316.999164 -29.856099) (xy 317.029148 -29.804165)
			(xy 317.065654 -29.756589) (xy 317.108059 -29.714184) (xy 317.155635 -29.677678) (xy 317.207569 -29.647694)
			(xy 317.262973 -29.624745) (xy 317.320898 -29.609224) (xy 317.380354 -29.601396) (xy 317.440322 -29.601396)
			(xy 317.499778 -29.609224) (xy 317.557703 -29.624745) (xy 317.613107 -29.647694) (xy 317.665041 -29.677678)
			(xy 317.712617 -29.714184) (xy 317.755022 -29.756589) (xy 317.791528 -29.804165) (xy 317.821512 -29.856099)
			(xy 317.844461 -29.911503) (xy 317.859982 -29.969428) (xy 317.86781 -30.028884) (xy 317.8683 -30.058868)
			(xy 317.8683 -30.92069) (xy 331.689456 -30.92069) (xy 331.689456 -30.05709) (xy 331.689946 -30.027122)
			(xy 331.697769 -29.9677) (xy 331.713282 -29.909807) (xy 331.736218 -29.854434) (xy 331.766185 -29.802528)
			(xy 331.802672 -29.754978) (xy 331.845052 -29.712598) (xy 331.892602 -29.676111) (xy 331.944508 -29.646144)
			(xy 331.999881 -29.623208) (xy 332.057774 -29.607695) (xy 332.117196 -29.599872) (xy 332.177132 -29.599872)
			(xy 332.236554 -29.607695) (xy 332.294447 -29.623208) (xy 332.34982 -29.646144) (xy 332.401726 -29.676111)
			(xy 332.449276 -29.712598) (xy 332.491656 -29.754978) (xy 332.528143 -29.802528) (xy 332.55811 -29.854434)
			(xy 332.581046 -29.909807) (xy 332.596559 -29.9677) (xy 332.604382 -30.027122) (xy 332.604872 -30.05709)
			(xy 332.604872 -30.92069) (xy 332.604843 -30.922468) (xy 355.052884 -30.922468) (xy 355.052884 -30.058868)
			(xy 355.053374 -30.0289) (xy 355.061197 -29.969478) (xy 355.07671 -29.911585) (xy 355.099646 -29.856212)
			(xy 355.129613 -29.804306) (xy 355.1661 -29.756756) (xy 355.20848 -29.714376) (xy 355.25603 -29.677889)
			(xy 355.307936 -29.647922) (xy 355.363309 -29.624986) (xy 355.421202 -29.609473) (xy 355.480624 -29.60165)
			(xy 355.54056 -29.60165) (xy 355.599982 -29.609473) (xy 355.657875 -29.624986) (xy 355.713248 -29.647922)
			(xy 355.765154 -29.677889) (xy 355.812704 -29.714376) (xy 355.855084 -29.756756) (xy 355.891571 -29.804306)
			(xy 355.921538 -29.856212) (xy 355.944474 -29.911585) (xy 355.959987 -29.969478) (xy 355.96781 -30.0289)
			(xy 355.9683 -30.058868) (xy 355.9683 -30.92069) (xy 369.789456 -30.92069) (xy 369.789456 -30.05709)
			(xy 369.789946 -30.027106) (xy 369.797774 -29.96765) (xy 369.813295 -29.909725) (xy 369.836244 -29.854321)
			(xy 369.866228 -29.802387) (xy 369.902734 -29.754811) (xy 369.945139 -29.712406) (xy 369.992715 -29.6759)
			(xy 370.044649 -29.645916) (xy 370.100053 -29.622967) (xy 370.157978 -29.607446) (xy 370.217434 -29.599618)
			(xy 370.277402 -29.599618) (xy 370.336858 -29.607446) (xy 370.394783 -29.622967) (xy 370.450187 -29.645916)
			(xy 370.502121 -29.6759) (xy 370.549697 -29.712406) (xy 370.592102 -29.754811) (xy 370.628608 -29.802387)
			(xy 370.658592 -29.854321) (xy 370.681541 -29.909725) (xy 370.697062 -29.96765) (xy 370.70489 -30.027106)
			(xy 370.70538 -30.05709) (xy 370.70538 -30.92069) (xy 370.705351 -30.922468) (xy 381.052832 -30.922468)
			(xy 381.052832 -30.058868) (xy 381.053322 -30.0289) (xy 381.061145 -29.969478) (xy 381.076658 -29.911585)
			(xy 381.099594 -29.856212) (xy 381.129561 -29.804306) (xy 381.166048 -29.756756) (xy 381.208428 -29.714376)
			(xy 381.255978 -29.677889) (xy 381.307884 -29.647922) (xy 381.363257 -29.624986) (xy 381.42115 -29.609473)
			(xy 381.480572 -29.60165) (xy 381.540508 -29.60165) (xy 381.59993 -29.609473) (xy 381.657823 -29.624986)
			(xy 381.713196 -29.647922) (xy 381.765102 -29.677889) (xy 381.812652 -29.714376) (xy 381.855032 -29.756756)
			(xy 381.891519 -29.804306) (xy 381.921486 -29.856212) (xy 381.944422 -29.911585) (xy 381.959935 -29.969478)
			(xy 381.967758 -30.0289) (xy 381.968248 -30.058868) (xy 381.968248 -30.92069) (xy 395.789404 -30.92069)
			(xy 395.789404 -30.05709) (xy 395.789894 -30.027106) (xy 395.797722 -29.96765) (xy 395.813243 -29.909725)
			(xy 395.836192 -29.854321) (xy 395.866176 -29.802387) (xy 395.902682 -29.754811) (xy 395.945087 -29.712406)
			(xy 395.992663 -29.6759) (xy 396.044597 -29.645916) (xy 396.100001 -29.622967) (xy 396.157926 -29.607446)
			(xy 396.217382 -29.599618) (xy 396.27735 -29.599618) (xy 396.336806 -29.607446) (xy 396.394731 -29.622967)
			(xy 396.450135 -29.645916) (xy 396.502069 -29.6759) (xy 396.549645 -29.712406) (xy 396.59205 -29.754811)
			(xy 396.628556 -29.802387) (xy 396.65854 -29.854321) (xy 396.681489 -29.909725) (xy 396.69701 -29.96765)
			(xy 396.704838 -30.027106) (xy 396.705328 -30.05709) (xy 396.705328 -30.92069) (xy 396.705299 -30.922468)
			(xy 407.05278 -30.922468) (xy 407.05278 -30.058868) (xy 407.05327 -30.0289) (xy 407.061093 -29.969478)
			(xy 407.076606 -29.911585) (xy 407.099542 -29.856212) (xy 407.129509 -29.804306) (xy 407.165996 -29.756756)
			(xy 407.208376 -29.714376) (xy 407.255926 -29.677889) (xy 407.307832 -29.647922) (xy 407.363205 -29.624986)
			(xy 407.421098 -29.609473) (xy 407.48052 -29.60165) (xy 407.540456 -29.60165) (xy 407.599878 -29.609473)
			(xy 407.657771 -29.624986) (xy 407.713144 -29.647922) (xy 407.76505 -29.677889) (xy 407.8126 -29.714376)
			(xy 407.85498 -29.756756) (xy 407.891467 -29.804306) (xy 407.921434 -29.856212) (xy 407.94437 -29.911585)
			(xy 407.959883 -29.969478) (xy 407.967706 -30.0289) (xy 407.968196 -30.058868) (xy 407.968196 -30.92069)
			(xy 421.789352 -30.92069) (xy 421.789352 -30.05709) (xy 421.789842 -30.027106) (xy 421.79767 -29.96765)
			(xy 421.813191 -29.909725) (xy 421.83614 -29.854321) (xy 421.866124 -29.802387) (xy 421.90263 -29.754811)
			(xy 421.945035 -29.712406) (xy 421.992611 -29.6759) (xy 422.044545 -29.645916) (xy 422.099949 -29.622967)
			(xy 422.157874 -29.607446) (xy 422.21733 -29.599618) (xy 422.277298 -29.599618) (xy 422.336754 -29.607446)
			(xy 422.394679 -29.622967) (xy 422.450083 -29.645916) (xy 422.502017 -29.6759) (xy 422.549593 -29.712406)
			(xy 422.591998 -29.754811) (xy 422.628504 -29.802387) (xy 422.658488 -29.854321) (xy 422.681437 -29.909725)
			(xy 422.696958 -29.96765) (xy 422.704786 -30.027106) (xy 422.705276 -30.05709) (xy 422.705276 -30.92069)
			(xy 422.705247 -30.922468) (xy 433.052728 -30.922468) (xy 433.052728 -30.058868) (xy 433.053218 -30.0289)
			(xy 433.061041 -29.969478) (xy 433.076554 -29.911585) (xy 433.09949 -29.856212) (xy 433.129457 -29.804306)
			(xy 433.165944 -29.756756) (xy 433.208324 -29.714376) (xy 433.255874 -29.677889) (xy 433.30778 -29.647922)
			(xy 433.363153 -29.624986) (xy 433.421046 -29.609473) (xy 433.480468 -29.60165) (xy 433.540404 -29.60165)
			(xy 433.599826 -29.609473) (xy 433.657719 -29.624986) (xy 433.713092 -29.647922) (xy 433.764998 -29.677889)
			(xy 433.812548 -29.714376) (xy 433.854928 -29.756756) (xy 433.891415 -29.804306) (xy 433.921382 -29.856212)
			(xy 433.944318 -29.911585) (xy 433.959831 -29.969478) (xy 433.967654 -30.0289) (xy 433.968144 -30.058868)
			(xy 433.968144 -30.92069) (xy 447.7893 -30.92069) (xy 447.7893 -30.05709) (xy 447.78979 -30.027106)
			(xy 447.797618 -29.96765) (xy 447.813139 -29.909725) (xy 447.836088 -29.854321) (xy 447.866072 -29.802387)
			(xy 447.902578 -29.754811) (xy 447.944983 -29.712406) (xy 447.992559 -29.6759) (xy 448.044493 -29.645916)
			(xy 448.099897 -29.622967) (xy 448.157822 -29.607446) (xy 448.217278 -29.599618) (xy 448.277246 -29.599618)
			(xy 448.336702 -29.607446) (xy 448.394627 -29.622967) (xy 448.450031 -29.645916) (xy 448.501965 -29.6759)
			(xy 448.549541 -29.712406) (xy 448.591946 -29.754811) (xy 448.628452 -29.802387) (xy 448.658436 -29.854321)
			(xy 448.681385 -29.909725) (xy 448.696906 -29.96765) (xy 448.704734 -30.027106) (xy 448.705224 -30.05709)
			(xy 448.705224 -30.745738) (xy 457.614517 -30.745738) (xy 457.614517 -30.616598) (xy 457.622467 -30.487703)
			(xy 457.638337 -30.359543) (xy 457.662066 -30.232602) (xy 457.693565 -30.107363) (xy 457.732714 -29.9843)
			(xy 457.779365 -29.863881) (xy 457.83334 -29.746562) (xy 457.894435 -29.632788) (xy 457.962418 -29.522991)
			(xy 458.037032 -29.417588) (xy 458.117993 -29.316978) (xy 458.204993 -29.221543) (xy 458.297704 -29.131644)
			(xy 458.395774 -29.047623) (xy 458.498829 -28.969799) (xy 458.60648 -28.898467) (xy 458.718319 -28.833897)
			(xy 458.83392 -28.776335) (xy 458.952845 -28.725998) (xy 459.074644 -28.683078) (xy 459.198854 -28.647737)
			(xy 459.325003 -28.62011) (xy 459.452615 -28.600301) (xy 459.581204 -28.588385) (xy 459.710282 -28.584409)
			(xy 459.83936 -28.588385) (xy 459.967949 -28.600301) (xy 460.095561 -28.62011) (xy 460.22171 -28.647737)
			(xy 460.34592 -28.683078) (xy 460.467719 -28.725998) (xy 460.586644 -28.776335) (xy 460.702245 -28.833897)
			(xy 460.814084 -28.898467) (xy 460.921735 -28.969799) (xy 461.02479 -29.047623) (xy 461.12286 -29.131644)
			(xy 461.215571 -29.221543) (xy 461.302571 -29.316978) (xy 461.383532 -29.417588) (xy 461.458146 -29.522991)
			(xy 461.526129 -29.632788) (xy 461.587224 -29.746562) (xy 461.641199 -29.863881) (xy 461.68785 -29.9843)
			(xy 461.726999 -30.107363) (xy 461.758498 -30.232602) (xy 461.782227 -30.359543) (xy 461.798097 -30.487703)
			(xy 461.806047 -30.616598) (xy 461.806544 -30.681168) (xy 461.806047 -30.745738) (xy 461.798097 -30.874633)
			(xy 461.782227 -31.002793) (xy 461.758498 -31.129734) (xy 461.726999 -31.254973) (xy 461.68785 -31.378036)
			(xy 461.641199 -31.498455) (xy 461.587224 -31.615774) (xy 461.526129 -31.729548) (xy 461.458146 -31.839345)
			(xy 461.383532 -31.944748) (xy 461.302571 -32.045358) (xy 461.215571 -32.140793) (xy 461.12286 -32.230692)
			(xy 461.02479 -32.314713) (xy 460.921735 -32.392537) (xy 460.814084 -32.463869) (xy 460.702245 -32.528439)
			(xy 460.586644 -32.586001) (xy 460.467719 -32.636338) (xy 460.34592 -32.679258) (xy 460.22171 -32.714599)
			(xy 460.095561 -32.742226) (xy 459.967949 -32.762035) (xy 459.83936 -32.773951) (xy 459.710282 -32.777928)
			(xy 459.581204 -32.773951) (xy 459.452615 -32.762035) (xy 459.325003 -32.742226) (xy 459.198854 -32.714599)
			(xy 459.074644 -32.679258) (xy 458.952845 -32.636338) (xy 458.83392 -32.586001) (xy 458.718319 -32.528439)
			(xy 458.60648 -32.463869) (xy 458.498829 -32.392537) (xy 458.395774 -32.314713) (xy 458.297704 -32.230692)
			(xy 458.204993 -32.140793) (xy 458.117993 -32.045358) (xy 458.037032 -31.944748) (xy 457.962418 -31.839345)
			(xy 457.894435 -31.729548) (xy 457.83334 -31.615774) (xy 457.779365 -31.498455) (xy 457.732714 -31.378036)
			(xy 457.693565 -31.254973) (xy 457.662066 -31.129734) (xy 457.638337 -31.002793) (xy 457.622467 -30.874633)
			(xy 457.614517 -30.745738) (xy 448.705224 -30.745738) (xy 448.705224 -30.92069) (xy 448.704734 -30.950674)
			(xy 448.696906 -31.01013) (xy 448.681385 -31.068055) (xy 448.658436 -31.123459) (xy 448.628452 -31.175393)
			(xy 448.591946 -31.222969) (xy 448.549541 -31.265374) (xy 448.501965 -31.30188) (xy 448.450031 -31.331864)
			(xy 448.394627 -31.354813) (xy 448.336702 -31.370334) (xy 448.277246 -31.378162) (xy 448.217278 -31.378162)
			(xy 448.157822 -31.370334) (xy 448.099897 -31.354813) (xy 448.044493 -31.331864) (xy 447.992559 -31.30188)
			(xy 447.944983 -31.265374) (xy 447.902578 -31.222969) (xy 447.866072 -31.175393) (xy 447.836088 -31.123459)
			(xy 447.813139 -31.068055) (xy 447.797618 -31.01013) (xy 447.78979 -30.950674) (xy 447.7893 -30.92069)
			(xy 433.968144 -30.92069) (xy 433.968144 -30.922468) (xy 433.967654 -30.952436) (xy 433.959831 -31.011858)
			(xy 433.944318 -31.069751) (xy 433.921382 -31.125124) (xy 433.891415 -31.17703) (xy 433.854928 -31.22458)
			(xy 433.812548 -31.26696) (xy 433.764998 -31.303447) (xy 433.713092 -31.333414) (xy 433.657719 -31.35635)
			(xy 433.599826 -31.371863) (xy 433.540404 -31.379686) (xy 433.480468 -31.379686) (xy 433.421046 -31.371863)
			(xy 433.363153 -31.35635) (xy 433.30778 -31.333414) (xy 433.255874 -31.303447) (xy 433.208324 -31.26696)
			(xy 433.165944 -31.22458) (xy 433.129457 -31.17703) (xy 433.09949 -31.125124) (xy 433.076554 -31.069751)
			(xy 433.061041 -31.011858) (xy 433.053218 -30.952436) (xy 433.052728 -30.922468) (xy 422.705247 -30.922468)
			(xy 422.704786 -30.950674) (xy 422.696958 -31.01013) (xy 422.681437 -31.068055) (xy 422.658488 -31.123459)
			(xy 422.628504 -31.175393) (xy 422.591998 -31.222969) (xy 422.549593 -31.265374) (xy 422.502017 -31.30188)
			(xy 422.450083 -31.331864) (xy 422.394679 -31.354813) (xy 422.336754 -31.370334) (xy 422.277298 -31.378162)
			(xy 422.21733 -31.378162) (xy 422.157874 -31.370334) (xy 422.099949 -31.354813) (xy 422.044545 -31.331864)
			(xy 421.992611 -31.30188) (xy 421.945035 -31.265374) (xy 421.90263 -31.222969) (xy 421.866124 -31.175393)
			(xy 421.83614 -31.123459) (xy 421.813191 -31.068055) (xy 421.79767 -31.01013) (xy 421.789842 -30.950674)
			(xy 421.789352 -30.92069) (xy 407.968196 -30.92069) (xy 407.968196 -30.922468) (xy 407.967706 -30.952436)
			(xy 407.959883 -31.011858) (xy 407.94437 -31.069751) (xy 407.921434 -31.125124) (xy 407.891467 -31.17703)
			(xy 407.85498 -31.22458) (xy 407.8126 -31.26696) (xy 407.76505 -31.303447) (xy 407.713144 -31.333414)
			(xy 407.657771 -31.35635) (xy 407.599878 -31.371863) (xy 407.540456 -31.379686) (xy 407.48052 -31.379686)
			(xy 407.421098 -31.371863) (xy 407.363205 -31.35635) (xy 407.307832 -31.333414) (xy 407.255926 -31.303447)
			(xy 407.208376 -31.26696) (xy 407.165996 -31.22458) (xy 407.129509 -31.17703) (xy 407.099542 -31.125124)
			(xy 407.076606 -31.069751) (xy 407.061093 -31.011858) (xy 407.05327 -30.952436) (xy 407.05278 -30.922468)
			(xy 396.705299 -30.922468) (xy 396.704838 -30.950674) (xy 396.69701 -31.01013) (xy 396.681489 -31.068055)
			(xy 396.65854 -31.123459) (xy 396.628556 -31.175393) (xy 396.59205 -31.222969) (xy 396.549645 -31.265374)
			(xy 396.502069 -31.30188) (xy 396.450135 -31.331864) (xy 396.394731 -31.354813) (xy 396.336806 -31.370334)
			(xy 396.27735 -31.378162) (xy 396.217382 -31.378162) (xy 396.157926 -31.370334) (xy 396.100001 -31.354813)
			(xy 396.044597 -31.331864) (xy 395.992663 -31.30188) (xy 395.945087 -31.265374) (xy 395.902682 -31.222969)
			(xy 395.866176 -31.175393) (xy 395.836192 -31.123459) (xy 395.813243 -31.068055) (xy 395.797722 -31.01013)
			(xy 395.789894 -30.950674) (xy 395.789404 -30.92069) (xy 381.968248 -30.92069) (xy 381.968248 -30.922468)
			(xy 381.967758 -30.952436) (xy 381.959935 -31.011858) (xy 381.944422 -31.069751) (xy 381.921486 -31.125124)
			(xy 381.891519 -31.17703) (xy 381.855032 -31.22458) (xy 381.812652 -31.26696) (xy 381.765102 -31.303447)
			(xy 381.713196 -31.333414) (xy 381.657823 -31.35635) (xy 381.59993 -31.371863) (xy 381.540508 -31.379686)
			(xy 381.480572 -31.379686) (xy 381.42115 -31.371863) (xy 381.363257 -31.35635) (xy 381.307884 -31.333414)
			(xy 381.255978 -31.303447) (xy 381.208428 -31.26696) (xy 381.166048 -31.22458) (xy 381.129561 -31.17703)
			(xy 381.099594 -31.125124) (xy 381.076658 -31.069751) (xy 381.061145 -31.011858) (xy 381.053322 -30.952436)
			(xy 381.052832 -30.922468) (xy 370.705351 -30.922468) (xy 370.70489 -30.950674) (xy 370.697062 -31.01013)
			(xy 370.681541 -31.068055) (xy 370.658592 -31.123459) (xy 370.628608 -31.175393) (xy 370.592102 -31.222969)
			(xy 370.549697 -31.265374) (xy 370.502121 -31.30188) (xy 370.450187 -31.331864) (xy 370.394783 -31.354813)
			(xy 370.336858 -31.370334) (xy 370.277402 -31.378162) (xy 370.217434 -31.378162) (xy 370.157978 -31.370334)
			(xy 370.100053 -31.354813) (xy 370.044649 -31.331864) (xy 369.992715 -31.30188) (xy 369.945139 -31.265374)
			(xy 369.902734 -31.222969) (xy 369.866228 -31.175393) (xy 369.836244 -31.123459) (xy 369.813295 -31.068055)
			(xy 369.797774 -31.01013) (xy 369.789946 -30.950674) (xy 369.789456 -30.92069) (xy 355.9683 -30.92069)
			(xy 355.9683 -30.922468) (xy 355.96781 -30.952436) (xy 355.959987 -31.011858) (xy 355.944474 -31.069751)
			(xy 355.921538 -31.125124) (xy 355.891571 -31.17703) (xy 355.855084 -31.22458) (xy 355.812704 -31.26696)
			(xy 355.765154 -31.303447) (xy 355.713248 -31.333414) (xy 355.657875 -31.35635) (xy 355.599982 -31.371863)
			(xy 355.54056 -31.379686) (xy 355.480624 -31.379686) (xy 355.421202 -31.371863) (xy 355.363309 -31.35635)
			(xy 355.307936 -31.333414) (xy 355.25603 -31.303447) (xy 355.20848 -31.26696) (xy 355.1661 -31.22458)
			(xy 355.129613 -31.17703) (xy 355.099646 -31.125124) (xy 355.07671 -31.069751) (xy 355.061197 -31.011858)
			(xy 355.053374 -30.952436) (xy 355.052884 -30.922468) (xy 332.604843 -30.922468) (xy 332.604382 -30.950658)
			(xy 332.596559 -31.01008) (xy 332.581046 -31.067973) (xy 332.55811 -31.123346) (xy 332.528143 -31.175252)
			(xy 332.491656 -31.222802) (xy 332.449276 -31.265182) (xy 332.401726 -31.301669) (xy 332.34982 -31.331636)
			(xy 332.294447 -31.354572) (xy 332.236554 -31.370085) (xy 332.177132 -31.377908) (xy 332.117196 -31.377908)
			(xy 332.057774 -31.370085) (xy 331.999881 -31.354572) (xy 331.944508 -31.331636) (xy 331.892602 -31.301669)
			(xy 331.845052 -31.265182) (xy 331.802672 -31.222802) (xy 331.766185 -31.175252) (xy 331.736218 -31.123346)
			(xy 331.713282 -31.067973) (xy 331.697769 -31.01008) (xy 331.689946 -30.950658) (xy 331.689456 -30.92069)
			(xy 317.8683 -30.92069) (xy 317.8683 -30.922468) (xy 317.86781 -30.952452) (xy 317.859982 -31.011908)
			(xy 317.844461 -31.069833) (xy 317.821512 -31.125237) (xy 317.791528 -31.177171) (xy 317.755022 -31.224747)
			(xy 317.712617 -31.267152) (xy 317.665041 -31.303658) (xy 317.613107 -31.333642) (xy 317.557703 -31.356591)
			(xy 317.499778 -31.372112) (xy 317.440322 -31.37994) (xy 317.380354 -31.37994) (xy 317.320898 -31.372112)
			(xy 317.262973 -31.356591) (xy 317.207569 -31.333642) (xy 317.155635 -31.303658) (xy 317.108059 -31.267152)
			(xy 317.065654 -31.224747) (xy 317.029148 -31.177171) (xy 316.999164 -31.125237) (xy 316.976215 -31.069833)
			(xy 316.960694 -31.011908) (xy 316.952866 -30.952452) (xy 316.952376 -30.922468) (xy 306.604895 -30.922468)
			(xy 306.604434 -30.950658) (xy 306.596611 -31.01008) (xy 306.581098 -31.067973) (xy 306.558162 -31.123346)
			(xy 306.528195 -31.175252) (xy 306.491708 -31.222802) (xy 306.449328 -31.265182) (xy 306.401778 -31.301669)
			(xy 306.349872 -31.331636) (xy 306.294499 -31.354572) (xy 306.236606 -31.370085) (xy 306.177184 -31.377908)
			(xy 306.117248 -31.377908) (xy 306.057826 -31.370085) (xy 305.999933 -31.354572) (xy 305.94456 -31.331636)
			(xy 305.892654 -31.301669) (xy 305.845104 -31.265182) (xy 305.802724 -31.222802) (xy 305.766237 -31.175252)
			(xy 305.73627 -31.123346) (xy 305.713334 -31.067973) (xy 305.697821 -31.01008) (xy 305.689998 -30.950658)
			(xy 305.689508 -30.92069) (xy 291.868352 -30.92069) (xy 291.868352 -30.922468) (xy 291.867862 -30.952452)
			(xy 291.860034 -31.011908) (xy 291.844513 -31.069833) (xy 291.821564 -31.125237) (xy 291.79158 -31.177171)
			(xy 291.755074 -31.224747) (xy 291.712669 -31.267152) (xy 291.665093 -31.303658) (xy 291.613159 -31.333642)
			(xy 291.557755 -31.356591) (xy 291.49983 -31.372112) (xy 291.440374 -31.37994) (xy 291.380406 -31.37994)
			(xy 291.32095 -31.372112) (xy 291.263025 -31.356591) (xy 291.207621 -31.333642) (xy 291.155687 -31.303658)
			(xy 291.108111 -31.267152) (xy 291.065706 -31.224747) (xy 291.0292 -31.177171) (xy 290.999216 -31.125237)
			(xy 290.976267 -31.069833) (xy 290.960746 -31.011908) (xy 290.952918 -30.952452) (xy 290.952428 -30.922468)
			(xy 280.604947 -30.922468) (xy 280.604486 -30.950658) (xy 280.596663 -31.01008) (xy 280.58115 -31.067973)
			(xy 280.558214 -31.123346) (xy 280.528247 -31.175252) (xy 280.49176 -31.222802) (xy 280.44938 -31.265182)
			(xy 280.40183 -31.301669) (xy 280.349924 -31.331636) (xy 280.294551 -31.354572) (xy 280.236658 -31.370085)
			(xy 280.177236 -31.377908) (xy 280.1173 -31.377908) (xy 280.057878 -31.370085) (xy 279.999985 -31.354572)
			(xy 279.944612 -31.331636) (xy 279.892706 -31.301669) (xy 279.845156 -31.265182) (xy 279.802776 -31.222802)
			(xy 279.766289 -31.175252) (xy 279.736322 -31.123346) (xy 279.713386 -31.067973) (xy 279.697873 -31.01008)
			(xy 279.69005 -30.950658) (xy 279.68956 -30.92069) (xy 265.868404 -30.92069) (xy 265.868404 -30.922468)
			(xy 265.867914 -30.952452) (xy 265.860086 -31.011908) (xy 265.844565 -31.069833) (xy 265.821616 -31.125237)
			(xy 265.791632 -31.177171) (xy 265.755126 -31.224747) (xy 265.712721 -31.267152) (xy 265.665145 -31.303658)
			(xy 265.613211 -31.333642) (xy 265.557807 -31.356591) (xy 265.499882 -31.372112) (xy 265.440426 -31.37994)
			(xy 265.380458 -31.37994) (xy 265.321002 -31.372112) (xy 265.263077 -31.356591) (xy 265.207673 -31.333642)
			(xy 265.155739 -31.303658) (xy 265.108163 -31.267152) (xy 265.065758 -31.224747) (xy 265.029252 -31.177171)
			(xy 264.999268 -31.125237) (xy 264.976319 -31.069833) (xy 264.960798 -31.011908) (xy 264.95297 -30.952452)
			(xy 264.95248 -30.922468) (xy 254.604999 -30.922468) (xy 254.604538 -30.950658) (xy 254.596715 -31.01008)
			(xy 254.581202 -31.067973) (xy 254.558266 -31.123346) (xy 254.528299 -31.175252) (xy 254.491812 -31.222802)
			(xy 254.449432 -31.265182) (xy 254.401882 -31.301669) (xy 254.349976 -31.331636) (xy 254.294603 -31.354572)
			(xy 254.23671 -31.370085) (xy 254.177288 -31.377908) (xy 254.117352 -31.377908) (xy 254.05793 -31.370085)
			(xy 254.000037 -31.354572) (xy 253.944664 -31.331636) (xy 253.892758 -31.301669) (xy 253.845208 -31.265182)
			(xy 253.802828 -31.222802) (xy 253.766341 -31.175252) (xy 253.736374 -31.123346) (xy 253.713438 -31.067973)
			(xy 253.697925 -31.01008) (xy 253.690102 -30.950658) (xy 253.689612 -30.92069) (xy 239.868456 -30.92069)
			(xy 239.868456 -30.922468) (xy 239.867966 -30.952452) (xy 239.860138 -31.011908) (xy 239.844617 -31.069833)
			(xy 239.821668 -31.125237) (xy 239.791684 -31.177171) (xy 239.755178 -31.224747) (xy 239.712773 -31.267152)
			(xy 239.665197 -31.303658) (xy 239.613263 -31.333642) (xy 239.557859 -31.356591) (xy 239.499934 -31.372112)
			(xy 239.440478 -31.37994) (xy 239.38051 -31.37994) (xy 239.321054 -31.372112) (xy 239.263129 -31.356591)
			(xy 239.207725 -31.333642) (xy 239.155791 -31.303658) (xy 239.108215 -31.267152) (xy 239.06581 -31.224747)
			(xy 239.029304 -31.177171) (xy 238.99932 -31.125237) (xy 238.976371 -31.069833) (xy 238.96085 -31.011908)
			(xy 238.953022 -30.952452) (xy 238.952532 -30.922468) (xy 216.504999 -30.922468) (xy 216.504538 -30.950658)
			(xy 216.496715 -31.01008) (xy 216.481202 -31.067973) (xy 216.458266 -31.123346) (xy 216.428299 -31.175252)
			(xy 216.391812 -31.222802) (xy 216.349432 -31.265182) (xy 216.301882 -31.301669) (xy 216.249976 -31.331636)
			(xy 216.194603 -31.354572) (xy 216.13671 -31.370085) (xy 216.077288 -31.377908) (xy 216.017352 -31.377908)
			(xy 215.95793 -31.370085) (xy 215.900037 -31.354572) (xy 215.844664 -31.331636) (xy 215.792758 -31.301669)
			(xy 215.745208 -31.265182) (xy 215.702828 -31.222802) (xy 215.666341 -31.175252) (xy 215.636374 -31.123346)
			(xy 215.613438 -31.067973) (xy 215.597925 -31.01008) (xy 215.590102 -30.950658) (xy 215.589612 -30.92069)
			(xy 201.768456 -30.92069) (xy 201.768456 -30.922468) (xy 201.767966 -30.952452) (xy 201.760138 -31.011908)
			(xy 201.744617 -31.069833) (xy 201.721668 -31.125237) (xy 201.691684 -31.177171) (xy 201.655178 -31.224747)
			(xy 201.612773 -31.267152) (xy 201.565197 -31.303658) (xy 201.513263 -31.333642) (xy 201.457859 -31.356591)
			(xy 201.399934 -31.372112) (xy 201.340478 -31.37994) (xy 201.28051 -31.37994) (xy 201.221054 -31.372112)
			(xy 201.163129 -31.356591) (xy 201.107725 -31.333642) (xy 201.055791 -31.303658) (xy 201.008215 -31.267152)
			(xy 200.96581 -31.224747) (xy 200.929304 -31.177171) (xy 200.89932 -31.125237) (xy 200.876371 -31.069833)
			(xy 200.86085 -31.011908) (xy 200.853022 -30.952452) (xy 200.852532 -30.922468) (xy 190.505051 -30.922468)
			(xy 190.50459 -30.950658) (xy 190.496767 -31.01008) (xy 190.481254 -31.067973) (xy 190.458318 -31.123346)
			(xy 190.428351 -31.175252) (xy 190.391864 -31.222802) (xy 190.349484 -31.265182) (xy 190.301934 -31.301669)
			(xy 190.250028 -31.331636) (xy 190.194655 -31.354572) (xy 190.136762 -31.370085) (xy 190.07734 -31.377908)
			(xy 190.017404 -31.377908) (xy 189.957982 -31.370085) (xy 189.900089 -31.354572) (xy 189.844716 -31.331636)
			(xy 189.79281 -31.301669) (xy 189.74526 -31.265182) (xy 189.70288 -31.222802) (xy 189.666393 -31.175252)
			(xy 189.636426 -31.123346) (xy 189.61349 -31.067973) (xy 189.597977 -31.01008) (xy 189.590154 -30.950658)
			(xy 189.589664 -30.92069) (xy 175.768508 -30.92069) (xy 175.768508 -30.922468) (xy 175.768018 -30.952452)
			(xy 175.76019 -31.011908) (xy 175.744669 -31.069833) (xy 175.72172 -31.125237) (xy 175.691736 -31.177171)
			(xy 175.65523 -31.224747) (xy 175.612825 -31.267152) (xy 175.565249 -31.303658) (xy 175.513315 -31.333642)
			(xy 175.457911 -31.356591) (xy 175.399986 -31.372112) (xy 175.34053 -31.37994) (xy 175.280562 -31.37994)
			(xy 175.221106 -31.372112) (xy 175.163181 -31.356591) (xy 175.107777 -31.333642) (xy 175.055843 -31.303658)
			(xy 175.008267 -31.267152) (xy 174.965862 -31.224747) (xy 174.929356 -31.177171) (xy 174.899372 -31.125237)
			(xy 174.876423 -31.069833) (xy 174.860902 -31.011908) (xy 174.853074 -30.952452) (xy 174.852584 -30.922468)
			(xy 164.505103 -30.922468) (xy 164.504642 -30.950658) (xy 164.496819 -31.01008) (xy 164.481306 -31.067973)
			(xy 164.45837 -31.123346) (xy 164.428403 -31.175252) (xy 164.391916 -31.222802) (xy 164.349536 -31.265182)
			(xy 164.301986 -31.301669) (xy 164.25008 -31.331636) (xy 164.194707 -31.354572) (xy 164.136814 -31.370085)
			(xy 164.077392 -31.377908) (xy 164.017456 -31.377908) (xy 163.958034 -31.370085) (xy 163.900141 -31.354572)
			(xy 163.844768 -31.331636) (xy 163.792862 -31.301669) (xy 163.745312 -31.265182) (xy 163.702932 -31.222802)
			(xy 163.666445 -31.175252) (xy 163.636478 -31.123346) (xy 163.613542 -31.067973) (xy 163.598029 -31.01008)
			(xy 163.590206 -30.950658) (xy 163.589716 -30.92069) (xy 149.76856 -30.92069) (xy 149.76856 -30.922468)
			(xy 149.76807 -30.952452) (xy 149.760242 -31.011908) (xy 149.744721 -31.069833) (xy 149.721772 -31.125237)
			(xy 149.691788 -31.177171) (xy 149.655282 -31.224747) (xy 149.612877 -31.267152) (xy 149.565301 -31.303658)
			(xy 149.513367 -31.333642) (xy 149.457963 -31.356591) (xy 149.400038 -31.372112) (xy 149.340582 -31.37994)
			(xy 149.280614 -31.37994) (xy 149.221158 -31.372112) (xy 149.163233 -31.356591) (xy 149.107829 -31.333642)
			(xy 149.055895 -31.303658) (xy 149.008319 -31.267152) (xy 148.965914 -31.224747) (xy 148.929408 -31.177171)
			(xy 148.899424 -31.125237) (xy 148.876475 -31.069833) (xy 148.860954 -31.011908) (xy 148.853126 -30.952452)
			(xy 148.852636 -30.922468) (xy 138.505155 -30.922468) (xy 138.504694 -30.950658) (xy 138.496871 -31.01008)
			(xy 138.481358 -31.067973) (xy 138.458422 -31.123346) (xy 138.428455 -31.175252) (xy 138.391968 -31.222802)
			(xy 138.349588 -31.265182) (xy 138.302038 -31.301669) (xy 138.250132 -31.331636) (xy 138.194759 -31.354572)
			(xy 138.136866 -31.370085) (xy 138.077444 -31.377908) (xy 138.017508 -31.377908) (xy 137.958086 -31.370085)
			(xy 137.900193 -31.354572) (xy 137.84482 -31.331636) (xy 137.792914 -31.301669) (xy 137.745364 -31.265182)
			(xy 137.702984 -31.222802) (xy 137.666497 -31.175252) (xy 137.63653 -31.123346) (xy 137.613594 -31.067973)
			(xy 137.598081 -31.01008) (xy 137.590258 -30.950658) (xy 137.589768 -30.92069) (xy 123.768612 -30.92069)
			(xy 123.768612 -30.922468) (xy 123.768122 -30.952452) (xy 123.760294 -31.011908) (xy 123.744773 -31.069833)
			(xy 123.721824 -31.125237) (xy 123.69184 -31.177171) (xy 123.655334 -31.224747) (xy 123.612929 -31.267152)
			(xy 123.565353 -31.303658) (xy 123.513419 -31.333642) (xy 123.458015 -31.356591) (xy 123.40009 -31.372112)
			(xy 123.340634 -31.37994) (xy 123.280666 -31.37994) (xy 123.22121 -31.372112) (xy 123.163285 -31.356591)
			(xy 123.107881 -31.333642) (xy 123.055947 -31.303658) (xy 123.008371 -31.267152) (xy 122.965966 -31.224747)
			(xy 122.92946 -31.177171) (xy 122.899476 -31.125237) (xy 122.876527 -31.069833) (xy 122.861006 -31.011908)
			(xy 122.853178 -30.952452) (xy 122.852688 -30.922468) (xy 100.405155 -30.922468) (xy 100.404694 -30.950674)
			(xy 100.396866 -31.01013) (xy 100.381345 -31.068055) (xy 100.358396 -31.123459) (xy 100.328412 -31.175393)
			(xy 100.291906 -31.222969) (xy 100.249501 -31.265374) (xy 100.201925 -31.30188) (xy 100.149991 -31.331864)
			(xy 100.094587 -31.354813) (xy 100.036662 -31.370334) (xy 99.977206 -31.378162) (xy 99.917238 -31.378162)
			(xy 99.857782 -31.370334) (xy 99.799857 -31.354813) (xy 99.744453 -31.331864) (xy 99.692519 -31.30188)
			(xy 99.644943 -31.265374) (xy 99.602538 -31.222969) (xy 99.566032 -31.175393) (xy 99.536048 -31.123459)
			(xy 99.513099 -31.068055) (xy 99.497578 -31.01013) (xy 99.48975 -30.950674) (xy 99.48926 -30.92069)
			(xy 85.668104 -30.92069) (xy 85.668104 -30.922468) (xy 85.667614 -30.952436) (xy 85.659791 -31.011858)
			(xy 85.644278 -31.069751) (xy 85.621342 -31.125124) (xy 85.591375 -31.17703) (xy 85.554888 -31.22458)
			(xy 85.512508 -31.26696) (xy 85.464958 -31.303447) (xy 85.413052 -31.333414) (xy 85.357679 -31.35635)
			(xy 85.299786 -31.371863) (xy 85.240364 -31.379686) (xy 85.180428 -31.379686) (xy 85.121006 -31.371863)
			(xy 85.063113 -31.35635) (xy 85.00774 -31.333414) (xy 84.955834 -31.303447) (xy 84.908284 -31.26696)
			(xy 84.865904 -31.22458) (xy 84.829417 -31.17703) (xy 84.79945 -31.125124) (xy 84.776514 -31.069751)
			(xy 84.761001 -31.011858) (xy 84.753178 -30.952436) (xy 84.752688 -30.922468) (xy 74.405207 -30.922468)
			(xy 74.404746 -30.950674) (xy 74.396918 -31.01013) (xy 74.381397 -31.068055) (xy 74.358448 -31.123459)
			(xy 74.328464 -31.175393) (xy 74.291958 -31.222969) (xy 74.249553 -31.265374) (xy 74.201977 -31.30188)
			(xy 74.150043 -31.331864) (xy 74.094639 -31.354813) (xy 74.036714 -31.370334) (xy 73.977258 -31.378162)
			(xy 73.91729 -31.378162) (xy 73.857834 -31.370334) (xy 73.799909 -31.354813) (xy 73.744505 -31.331864)
			(xy 73.692571 -31.30188) (xy 73.644995 -31.265374) (xy 73.60259 -31.222969) (xy 73.566084 -31.175393)
			(xy 73.5361 -31.123459) (xy 73.513151 -31.068055) (xy 73.49763 -31.01013) (xy 73.489802 -30.950674)
			(xy 73.489312 -30.92069) (xy 59.668156 -30.92069) (xy 59.668156 -30.922468) (xy 59.667666 -30.952436)
			(xy 59.659843 -31.011858) (xy 59.64433 -31.069751) (xy 59.621394 -31.125124) (xy 59.591427 -31.17703)
			(xy 59.55494 -31.22458) (xy 59.51256 -31.26696) (xy 59.46501 -31.303447) (xy 59.413104 -31.333414)
			(xy 59.357731 -31.35635) (xy 59.299838 -31.371863) (xy 59.240416 -31.379686) (xy 59.18048 -31.379686)
			(xy 59.121058 -31.371863) (xy 59.063165 -31.35635) (xy 59.007792 -31.333414) (xy 58.955886 -31.303447)
			(xy 58.908336 -31.26696) (xy 58.865956 -31.22458) (xy 58.829469 -31.17703) (xy 58.799502 -31.125124)
			(xy 58.776566 -31.069751) (xy 58.761053 -31.011858) (xy 58.75323 -30.952436) (xy 58.75274 -30.922468)
			(xy 48.405259 -30.922468) (xy 48.404798 -30.950674) (xy 48.39697 -31.01013) (xy 48.381449 -31.068055)
			(xy 48.3585 -31.123459) (xy 48.328516 -31.175393) (xy 48.29201 -31.222969) (xy 48.249605 -31.265374)
			(xy 48.202029 -31.30188) (xy 48.150095 -31.331864) (xy 48.094691 -31.354813) (xy 48.036766 -31.370334)
			(xy 47.97731 -31.378162) (xy 47.917342 -31.378162) (xy 47.857886 -31.370334) (xy 47.799961 -31.354813)
			(xy 47.744557 -31.331864) (xy 47.692623 -31.30188) (xy 47.645047 -31.265374) (xy 47.602642 -31.222969)
			(xy 47.566136 -31.175393) (xy 47.536152 -31.123459) (xy 47.513203 -31.068055) (xy 47.497682 -31.01013)
			(xy 47.489854 -30.950674) (xy 47.489364 -30.92069) (xy 33.668208 -30.92069) (xy 33.668208 -30.922468)
			(xy 33.667718 -30.952436) (xy 33.659895 -31.011858) (xy 33.644382 -31.069751) (xy 33.621446 -31.125124)
			(xy 33.591479 -31.17703) (xy 33.554992 -31.22458) (xy 33.512612 -31.26696) (xy 33.465062 -31.303447)
			(xy 33.413156 -31.333414) (xy 33.357783 -31.35635) (xy 33.29989 -31.371863) (xy 33.240468 -31.379686)
			(xy 33.180532 -31.379686) (xy 33.12111 -31.371863) (xy 33.063217 -31.35635) (xy 33.007844 -31.333414)
			(xy 32.955938 -31.303447) (xy 32.908388 -31.26696) (xy 32.866008 -31.22458) (xy 32.829521 -31.17703)
			(xy 32.799554 -31.125124) (xy 32.776618 -31.069751) (xy 32.761105 -31.011858) (xy 32.753282 -30.952436)
			(xy 32.752792 -30.922468) (xy 22.405311 -30.922468) (xy 22.40485 -30.950674) (xy 22.397022 -31.01013)
			(xy 22.381501 -31.068055) (xy 22.358552 -31.123459) (xy 22.328568 -31.175393) (xy 22.292062 -31.222969)
			(xy 22.249657 -31.265374) (xy 22.202081 -31.30188) (xy 22.150147 -31.331864) (xy 22.094743 -31.354813)
			(xy 22.036818 -31.370334) (xy 21.977362 -31.378162) (xy 21.917394 -31.378162) (xy 21.857938 -31.370334)
			(xy 21.800013 -31.354813) (xy 21.744609 -31.331864) (xy 21.692675 -31.30188) (xy 21.645099 -31.265374)
			(xy 21.602694 -31.222969) (xy 21.566188 -31.175393) (xy 21.536204 -31.123459) (xy 21.513255 -31.068055)
			(xy 21.497734 -31.01013) (xy 21.489906 -30.950674) (xy 21.489416 -30.92069) (xy 7.66826 -30.92069)
			(xy 7.66826 -30.922468) (xy 7.66777 -30.952436) (xy 7.659947 -31.011858) (xy 7.644434 -31.069751)
			(xy 7.621498 -31.125124) (xy 7.591531 -31.17703) (xy 7.555044 -31.22458) (xy 7.512664 -31.26696)
			(xy 7.465114 -31.303447) (xy 7.413208 -31.333414) (xy 7.357835 -31.35635) (xy 7.299942 -31.371863)
			(xy 7.24052 -31.379686) (xy 7.180584 -31.379686) (xy 7.121162 -31.371863) (xy 7.063269 -31.35635)
			(xy 7.007896 -31.333414) (xy 6.95599 -31.303447) (xy 6.90844 -31.26696) (xy 6.86606 -31.22458) (xy 6.829573 -31.17703)
			(xy 6.799606 -31.125124) (xy 6.77667 -31.069751) (xy 6.761157 -31.011858) (xy 6.753334 -30.952436)
			(xy 6.752844 -30.922468) (xy 0.508 -30.922468) (xy 0.508 -32.722312) (xy 8.607044 -32.722312) (xy 8.607044 -31.858712)
			(xy 8.607534 -31.828744) (xy 8.615357 -31.769322) (xy 8.63087 -31.711429) (xy 8.653806 -31.656056)
			(xy 8.683773 -31.60415) (xy 8.72026 -31.5566) (xy 8.76264 -31.51422) (xy 8.81019 -31.477733) (xy 8.862096 -31.447766)
			(xy 8.917469 -31.42483) (xy 8.975362 -31.409317) (xy 9.034784 -31.401494) (xy 9.09472 -31.401494)
			(xy 9.154142 -31.409317) (xy 9.212035 -31.42483) (xy 9.267408 -31.447766) (xy 9.319314 -31.477733)
			(xy 9.366864 -31.51422) (xy 9.409244 -31.5566) (xy 9.445731 -31.60415) (xy 9.475698 -31.656056) (xy 9.498634 -31.711429)
			(xy 9.514147 -31.769322) (xy 9.52197 -31.828744) (xy 9.52246 -31.858712) (xy 9.52246 -32.714184)
			(xy 18.847308 -32.714184) (xy 18.847308 -31.850584) (xy 18.847798 -31.8206) (xy 18.855626 -31.761144)
			(xy 18.871147 -31.703219) (xy 18.894096 -31.647815) (xy 18.92408 -31.595881) (xy 18.960586 -31.548305)
			(xy 19.002991 -31.5059) (xy 19.050567 -31.469394) (xy 19.102501 -31.43941) (xy 19.157905 -31.416461)
			(xy 19.21583 -31.40094) (xy 19.275286 -31.393112) (xy 19.335254 -31.393112) (xy 19.39471 -31.40094)
			(xy 19.452635 -31.416461) (xy 19.508039 -31.43941) (xy 19.559973 -31.469394) (xy 19.607549 -31.5059)
			(xy 19.649954 -31.548305) (xy 19.68646 -31.595881) (xy 19.716444 -31.647815) (xy 19.739393 -31.703219)
			(xy 19.754914 -31.761144) (xy 19.762742 -31.8206) (xy 19.763232 -31.850584) (xy 19.763232 -32.714184)
			(xy 19.763099 -32.722312) (xy 34.606992 -32.722312) (xy 34.606992 -31.858712) (xy 34.607482 -31.828744)
			(xy 34.615305 -31.769322) (xy 34.630818 -31.711429) (xy 34.653754 -31.656056) (xy 34.683721 -31.60415)
			(xy 34.720208 -31.5566) (xy 34.762588 -31.51422) (xy 34.810138 -31.477733) (xy 34.862044 -31.447766)
			(xy 34.917417 -31.42483) (xy 34.97531 -31.409317) (xy 35.034732 -31.401494) (xy 35.094668 -31.401494)
			(xy 35.15409 -31.409317) (xy 35.211983 -31.42483) (xy 35.267356 -31.447766) (xy 35.319262 -31.477733)
			(xy 35.366812 -31.51422) (xy 35.409192 -31.5566) (xy 35.445679 -31.60415) (xy 35.475646 -31.656056)
			(xy 35.498582 -31.711429) (xy 35.514095 -31.769322) (xy 35.521918 -31.828744) (xy 35.522408 -31.858712)
			(xy 35.522408 -32.714184) (xy 44.847256 -32.714184) (xy 44.847256 -31.850584) (xy 44.847746 -31.8206)
			(xy 44.855574 -31.761144) (xy 44.871095 -31.703219) (xy 44.894044 -31.647815) (xy 44.924028 -31.595881)
			(xy 44.960534 -31.548305) (xy 45.002939 -31.5059) (xy 45.050515 -31.469394) (xy 45.102449 -31.43941)
			(xy 45.157853 -31.416461) (xy 45.215778 -31.40094) (xy 45.275234 -31.393112) (xy 45.335202 -31.393112)
			(xy 45.394658 -31.40094) (xy 45.452583 -31.416461) (xy 45.507987 -31.43941) (xy 45.559921 -31.469394)
			(xy 45.607497 -31.5059) (xy 45.649902 -31.548305) (xy 45.686408 -31.595881) (xy 45.716392 -31.647815)
			(xy 45.739341 -31.703219) (xy 45.754862 -31.761144) (xy 45.76269 -31.8206) (xy 45.76318 -31.850584)
			(xy 45.76318 -32.714184) (xy 45.763047 -32.722312) (xy 60.60694 -32.722312) (xy 60.60694 -31.858712)
			(xy 60.60743 -31.828744) (xy 60.615253 -31.769322) (xy 60.630766 -31.711429) (xy 60.653702 -31.656056)
			(xy 60.683669 -31.60415) (xy 60.720156 -31.5566) (xy 60.762536 -31.51422) (xy 60.810086 -31.477733)
			(xy 60.861992 -31.447766) (xy 60.917365 -31.42483) (xy 60.975258 -31.409317) (xy 61.03468 -31.401494)
			(xy 61.094616 -31.401494) (xy 61.154038 -31.409317) (xy 61.211931 -31.42483) (xy 61.267304 -31.447766)
			(xy 61.31921 -31.477733) (xy 61.36676 -31.51422) (xy 61.40914 -31.5566) (xy 61.445627 -31.60415)
			(xy 61.475594 -31.656056) (xy 61.49853 -31.711429) (xy 61.514043 -31.769322) (xy 61.521866 -31.828744)
			(xy 61.522356 -31.858712) (xy 61.522356 -32.714184) (xy 70.847204 -32.714184) (xy 70.847204 -31.850584)
			(xy 70.847694 -31.8206) (xy 70.855522 -31.761144) (xy 70.871043 -31.703219) (xy 70.893992 -31.647815)
			(xy 70.923976 -31.595881) (xy 70.960482 -31.548305) (xy 71.002887 -31.5059) (xy 71.050463 -31.469394)
			(xy 71.102397 -31.43941) (xy 71.157801 -31.416461) (xy 71.215726 -31.40094) (xy 71.275182 -31.393112)
			(xy 71.33515 -31.393112) (xy 71.394606 -31.40094) (xy 71.452531 -31.416461) (xy 71.507935 -31.43941)
			(xy 71.559869 -31.469394) (xy 71.607445 -31.5059) (xy 71.64985 -31.548305) (xy 71.686356 -31.595881)
			(xy 71.71634 -31.647815) (xy 71.739289 -31.703219) (xy 71.75481 -31.761144) (xy 71.762638 -31.8206)
			(xy 71.763128 -31.850584) (xy 71.763128 -32.714184) (xy 71.762995 -32.722312) (xy 86.606888 -32.722312)
			(xy 86.606888 -31.858712) (xy 86.607378 -31.828744) (xy 86.615201 -31.769322) (xy 86.630714 -31.711429)
			(xy 86.65365 -31.656056) (xy 86.683617 -31.60415) (xy 86.720104 -31.5566) (xy 86.762484 -31.51422)
			(xy 86.810034 -31.477733) (xy 86.86194 -31.447766) (xy 86.917313 -31.42483) (xy 86.975206 -31.409317)
			(xy 87.034628 -31.401494) (xy 87.094564 -31.401494) (xy 87.153986 -31.409317) (xy 87.211879 -31.42483)
			(xy 87.267252 -31.447766) (xy 87.319158 -31.477733) (xy 87.366708 -31.51422) (xy 87.409088 -31.5566)
			(xy 87.445575 -31.60415) (xy 87.475542 -31.656056) (xy 87.498478 -31.711429) (xy 87.513991 -31.769322)
			(xy 87.521814 -31.828744) (xy 87.522304 -31.858712) (xy 87.522304 -32.714184) (xy 96.847152 -32.714184)
			(xy 96.847152 -31.850584) (xy 96.847642 -31.8206) (xy 96.85547 -31.761144) (xy 96.870991 -31.703219)
			(xy 96.89394 -31.647815) (xy 96.923924 -31.595881) (xy 96.96043 -31.548305) (xy 97.002835 -31.5059)
			(xy 97.050411 -31.469394) (xy 97.102345 -31.43941) (xy 97.157749 -31.416461) (xy 97.215674 -31.40094)
			(xy 97.27513 -31.393112) (xy 97.335098 -31.393112) (xy 97.394554 -31.40094) (xy 97.452479 -31.416461)
			(xy 97.507883 -31.43941) (xy 97.559817 -31.469394) (xy 97.607393 -31.5059) (xy 97.649798 -31.548305)
			(xy 97.686304 -31.595881) (xy 97.716288 -31.647815) (xy 97.739237 -31.703219) (xy 97.754758 -31.761144)
			(xy 97.762586 -31.8206) (xy 97.763076 -31.850584) (xy 97.763076 -32.714184) (xy 97.762943 -32.722312)
			(xy 124.706888 -32.722312) (xy 124.706888 -31.858712) (xy 124.707378 -31.828728) (xy 124.715206 -31.769272)
			(xy 124.730727 -31.711347) (xy 124.753676 -31.655943) (xy 124.78366 -31.604009) (xy 124.820166 -31.556433)
			(xy 124.862571 -31.514028) (xy 124.910147 -31.477522) (xy 124.962081 -31.447538) (xy 125.017485 -31.424589)
			(xy 125.07541 -31.409068) (xy 125.134866 -31.40124) (xy 125.194834 -31.40124) (xy 125.25429 -31.409068)
			(xy 125.312215 -31.424589) (xy 125.367619 -31.447538) (xy 125.419553 -31.477522) (xy 125.467129 -31.514028)
			(xy 125.509534 -31.556433) (xy 125.54604 -31.604009) (xy 125.576024 -31.655943) (xy 125.598973 -31.711347)
			(xy 125.614494 -31.769272) (xy 125.622322 -31.828728) (xy 125.622812 -31.858712) (xy 125.622812 -32.714184)
			(xy 134.94766 -32.714184) (xy 134.94766 -31.850584) (xy 134.94815 -31.820616) (xy 134.955973 -31.761194)
			(xy 134.971486 -31.703301) (xy 134.994422 -31.647928) (xy 135.024389 -31.596022) (xy 135.060876 -31.548472)
			(xy 135.103256 -31.506092) (xy 135.150806 -31.469605) (xy 135.202712 -31.439638) (xy 135.258085 -31.416702)
			(xy 135.315978 -31.401189) (xy 135.3754 -31.393366) (xy 135.435336 -31.393366) (xy 135.494758 -31.401189)
			(xy 135.552651 -31.416702) (xy 135.608024 -31.439638) (xy 135.65993 -31.469605) (xy 135.70748 -31.506092)
			(xy 135.74986 -31.548472) (xy 135.786347 -31.596022) (xy 135.816314 -31.647928) (xy 135.83925 -31.703301)
			(xy 135.854763 -31.761194) (xy 135.862586 -31.820616) (xy 135.863076 -31.850584) (xy 135.863076 -32.714184)
			(xy 135.862943 -32.722312) (xy 150.706836 -32.722312) (xy 150.706836 -31.858712) (xy 150.707326 -31.828728)
			(xy 150.715154 -31.769272) (xy 150.730675 -31.711347) (xy 150.753624 -31.655943) (xy 150.783608 -31.604009)
			(xy 150.820114 -31.556433) (xy 150.862519 -31.514028) (xy 150.910095 -31.477522) (xy 150.962029 -31.447538)
			(xy 151.017433 -31.424589) (xy 151.075358 -31.409068) (xy 151.134814 -31.40124) (xy 151.194782 -31.40124)
			(xy 151.254238 -31.409068) (xy 151.312163 -31.424589) (xy 151.367567 -31.447538) (xy 151.419501 -31.477522)
			(xy 151.467077 -31.514028) (xy 151.509482 -31.556433) (xy 151.545988 -31.604009) (xy 151.575972 -31.655943)
			(xy 151.598921 -31.711347) (xy 151.614442 -31.769272) (xy 151.62227 -31.828728) (xy 151.62276 -31.858712)
			(xy 151.62276 -32.714184) (xy 160.947608 -32.714184) (xy 160.947608 -31.850584) (xy 160.948098 -31.820616)
			(xy 160.955921 -31.761194) (xy 160.971434 -31.703301) (xy 160.99437 -31.647928) (xy 161.024337 -31.596022)
			(xy 161.060824 -31.548472) (xy 161.103204 -31.506092) (xy 161.150754 -31.469605) (xy 161.20266 -31.439638)
			(xy 161.258033 -31.416702) (xy 161.315926 -31.401189) (xy 161.375348 -31.393366) (xy 161.435284 -31.393366)
			(xy 161.494706 -31.401189) (xy 161.552599 -31.416702) (xy 161.607972 -31.439638) (xy 161.659878 -31.469605)
			(xy 161.707428 -31.506092) (xy 161.749808 -31.548472) (xy 161.786295 -31.596022) (xy 161.816262 -31.647928)
			(xy 161.839198 -31.703301) (xy 161.854711 -31.761194) (xy 161.862534 -31.820616) (xy 161.863024 -31.850584)
			(xy 161.863024 -32.714184) (xy 161.862891 -32.722312) (xy 176.706784 -32.722312) (xy 176.706784 -31.858712)
			(xy 176.707274 -31.828728) (xy 176.715102 -31.769272) (xy 176.730623 -31.711347) (xy 176.753572 -31.655943)
			(xy 176.783556 -31.604009) (xy 176.820062 -31.556433) (xy 176.862467 -31.514028) (xy 176.910043 -31.477522)
			(xy 176.961977 -31.447538) (xy 177.017381 -31.424589) (xy 177.075306 -31.409068) (xy 177.134762 -31.40124)
			(xy 177.19473 -31.40124) (xy 177.254186 -31.409068) (xy 177.312111 -31.424589) (xy 177.367515 -31.447538)
			(xy 177.419449 -31.477522) (xy 177.467025 -31.514028) (xy 177.50943 -31.556433) (xy 177.545936 -31.604009)
			(xy 177.57592 -31.655943) (xy 177.598869 -31.711347) (xy 177.61439 -31.769272) (xy 177.622218 -31.828728)
			(xy 177.622708 -31.858712) (xy 177.622708 -32.714184) (xy 186.947556 -32.714184) (xy 186.947556 -31.850584)
			(xy 186.948046 -31.820616) (xy 186.955869 -31.761194) (xy 186.971382 -31.703301) (xy 186.994318 -31.647928)
			(xy 187.024285 -31.596022) (xy 187.060772 -31.548472) (xy 187.103152 -31.506092) (xy 187.150702 -31.469605)
			(xy 187.202608 -31.439638) (xy 187.257981 -31.416702) (xy 187.315874 -31.401189) (xy 187.375296 -31.393366)
			(xy 187.435232 -31.393366) (xy 187.494654 -31.401189) (xy 187.552547 -31.416702) (xy 187.60792 -31.439638)
			(xy 187.659826 -31.469605) (xy 187.707376 -31.506092) (xy 187.749756 -31.548472) (xy 187.786243 -31.596022)
			(xy 187.81621 -31.647928) (xy 187.839146 -31.703301) (xy 187.854659 -31.761194) (xy 187.862482 -31.820616)
			(xy 187.862972 -31.850584) (xy 187.862972 -32.714184) (xy 187.862839 -32.722312) (xy 202.706732 -32.722312)
			(xy 202.706732 -31.858712) (xy 202.707222 -31.828728) (xy 202.71505 -31.769272) (xy 202.730571 -31.711347)
			(xy 202.75352 -31.655943) (xy 202.783504 -31.604009) (xy 202.82001 -31.556433) (xy 202.862415 -31.514028)
			(xy 202.909991 -31.477522) (xy 202.961925 -31.447538) (xy 203.017329 -31.424589) (xy 203.075254 -31.409068)
			(xy 203.13471 -31.40124) (xy 203.194678 -31.40124) (xy 203.254134 -31.409068) (xy 203.312059 -31.424589)
			(xy 203.367463 -31.447538) (xy 203.419397 -31.477522) (xy 203.466973 -31.514028) (xy 203.509378 -31.556433)
			(xy 203.545884 -31.604009) (xy 203.575868 -31.655943) (xy 203.598817 -31.711347) (xy 203.614338 -31.769272)
			(xy 203.622166 -31.828728) (xy 203.622656 -31.858712) (xy 203.622656 -32.714184) (xy 212.947504 -32.714184)
			(xy 212.947504 -31.850584) (xy 212.947994 -31.820616) (xy 212.955817 -31.761194) (xy 212.97133 -31.703301)
			(xy 212.994266 -31.647928) (xy 213.024233 -31.596022) (xy 213.06072 -31.548472) (xy 213.1031 -31.506092)
			(xy 213.15065 -31.469605) (xy 213.202556 -31.439638) (xy 213.257929 -31.416702) (xy 213.315822 -31.401189)
			(xy 213.375244 -31.393366) (xy 213.43518 -31.393366) (xy 213.494602 -31.401189) (xy 213.552495 -31.416702)
			(xy 213.607868 -31.439638) (xy 213.659774 -31.469605) (xy 213.707324 -31.506092) (xy 213.749704 -31.548472)
			(xy 213.786191 -31.596022) (xy 213.816158 -31.647928) (xy 213.839094 -31.703301) (xy 213.854607 -31.761194)
			(xy 213.86243 -31.820616) (xy 213.86292 -31.850584) (xy 213.86292 -32.714184) (xy 213.862787 -32.722312)
			(xy 240.806732 -32.722312) (xy 240.806732 -31.858712) (xy 240.807222 -31.828728) (xy 240.81505 -31.769272)
			(xy 240.830571 -31.711347) (xy 240.85352 -31.655943) (xy 240.883504 -31.604009) (xy 240.92001 -31.556433)
			(xy 240.962415 -31.514028) (xy 241.009991 -31.477522) (xy 241.061925 -31.447538) (xy 241.117329 -31.424589)
			(xy 241.175254 -31.409068) (xy 241.23471 -31.40124) (xy 241.294678 -31.40124) (xy 241.354134 -31.409068)
			(xy 241.412059 -31.424589) (xy 241.467463 -31.447538) (xy 241.519397 -31.477522) (xy 241.566973 -31.514028)
			(xy 241.609378 -31.556433) (xy 241.645884 -31.604009) (xy 241.675868 -31.655943) (xy 241.698817 -31.711347)
			(xy 241.714338 -31.769272) (xy 241.722166 -31.828728) (xy 241.722656 -31.858712) (xy 241.722656 -32.714184)
			(xy 251.047504 -32.714184) (xy 251.047504 -31.850584) (xy 251.047994 -31.820616) (xy 251.055817 -31.761194)
			(xy 251.07133 -31.703301) (xy 251.094266 -31.647928) (xy 251.124233 -31.596022) (xy 251.16072 -31.548472)
			(xy 251.2031 -31.506092) (xy 251.25065 -31.469605) (xy 251.302556 -31.439638) (xy 251.357929 -31.416702)
			(xy 251.415822 -31.401189) (xy 251.475244 -31.393366) (xy 251.53518 -31.393366) (xy 251.594602 -31.401189)
			(xy 251.652495 -31.416702) (xy 251.707868 -31.439638) (xy 251.759774 -31.469605) (xy 251.807324 -31.506092)
			(xy 251.849704 -31.548472) (xy 251.886191 -31.596022) (xy 251.916158 -31.647928) (xy 251.939094 -31.703301)
			(xy 251.954607 -31.761194) (xy 251.96243 -31.820616) (xy 251.96292 -31.850584) (xy 251.96292 -32.714184)
			(xy 251.962787 -32.722312) (xy 266.80668 -32.722312) (xy 266.80668 -31.858712) (xy 266.80717 -31.828728)
			(xy 266.814998 -31.769272) (xy 266.830519 -31.711347) (xy 266.853468 -31.655943) (xy 266.883452 -31.604009)
			(xy 266.919958 -31.556433) (xy 266.962363 -31.514028) (xy 267.009939 -31.477522) (xy 267.061873 -31.447538)
			(xy 267.117277 -31.424589) (xy 267.175202 -31.409068) (xy 267.234658 -31.40124) (xy 267.294626 -31.40124)
			(xy 267.354082 -31.409068) (xy 267.412007 -31.424589) (xy 267.467411 -31.447538) (xy 267.519345 -31.477522)
			(xy 267.566921 -31.514028) (xy 267.609326 -31.556433) (xy 267.645832 -31.604009) (xy 267.675816 -31.655943)
			(xy 267.698765 -31.711347) (xy 267.714286 -31.769272) (xy 267.722114 -31.828728) (xy 267.722604 -31.858712)
			(xy 267.722604 -32.714184) (xy 277.047452 -32.714184) (xy 277.047452 -31.850584) (xy 277.047942 -31.820616)
			(xy 277.055765 -31.761194) (xy 277.071278 -31.703301) (xy 277.094214 -31.647928) (xy 277.124181 -31.596022)
			(xy 277.160668 -31.548472) (xy 277.203048 -31.506092) (xy 277.250598 -31.469605) (xy 277.302504 -31.439638)
			(xy 277.357877 -31.416702) (xy 277.41577 -31.401189) (xy 277.475192 -31.393366) (xy 277.535128 -31.393366)
			(xy 277.59455 -31.401189) (xy 277.652443 -31.416702) (xy 277.707816 -31.439638) (xy 277.759722 -31.469605)
			(xy 277.807272 -31.506092) (xy 277.849652 -31.548472) (xy 277.886139 -31.596022) (xy 277.916106 -31.647928)
			(xy 277.939042 -31.703301) (xy 277.954555 -31.761194) (xy 277.962378 -31.820616) (xy 277.962868 -31.850584)
			(xy 277.962868 -32.714184) (xy 277.962735 -32.722312) (xy 292.806628 -32.722312) (xy 292.806628 -31.858712)
			(xy 292.807118 -31.828728) (xy 292.814946 -31.769272) (xy 292.830467 -31.711347) (xy 292.853416 -31.655943)
			(xy 292.8834 -31.604009) (xy 292.919906 -31.556433) (xy 292.962311 -31.514028) (xy 293.009887 -31.477522)
			(xy 293.061821 -31.447538) (xy 293.117225 -31.424589) (xy 293.17515 -31.409068) (xy 293.234606 -31.40124)
			(xy 293.294574 -31.40124) (xy 293.35403 -31.409068) (xy 293.411955 -31.424589) (xy 293.467359 -31.447538)
			(xy 293.519293 -31.477522) (xy 293.566869 -31.514028) (xy 293.609274 -31.556433) (xy 293.64578 -31.604009)
			(xy 293.675764 -31.655943) (xy 293.698713 -31.711347) (xy 293.714234 -31.769272) (xy 293.722062 -31.828728)
			(xy 293.722552 -31.858712) (xy 293.722552 -32.714184) (xy 303.0474 -32.714184) (xy 303.0474 -31.850584)
			(xy 303.04789 -31.820616) (xy 303.055713 -31.761194) (xy 303.071226 -31.703301) (xy 303.094162 -31.647928)
			(xy 303.124129 -31.596022) (xy 303.160616 -31.548472) (xy 303.202996 -31.506092) (xy 303.250546 -31.469605)
			(xy 303.302452 -31.439638) (xy 303.357825 -31.416702) (xy 303.415718 -31.401189) (xy 303.47514 -31.393366)
			(xy 303.535076 -31.393366) (xy 303.594498 -31.401189) (xy 303.652391 -31.416702) (xy 303.707764 -31.439638)
			(xy 303.75967 -31.469605) (xy 303.80722 -31.506092) (xy 303.8496 -31.548472) (xy 303.886087 -31.596022)
			(xy 303.916054 -31.647928) (xy 303.93899 -31.703301) (xy 303.954503 -31.761194) (xy 303.962326 -31.820616)
			(xy 303.962816 -31.850584) (xy 303.962816 -32.714184) (xy 303.962683 -32.722312) (xy 318.806576 -32.722312)
			(xy 318.806576 -31.858712) (xy 318.807066 -31.828728) (xy 318.814894 -31.769272) (xy 318.830415 -31.711347)
			(xy 318.853364 -31.655943) (xy 318.883348 -31.604009) (xy 318.919854 -31.556433) (xy 318.962259 -31.514028)
			(xy 319.009835 -31.477522) (xy 319.061769 -31.447538) (xy 319.117173 -31.424589) (xy 319.175098 -31.409068)
			(xy 319.234554 -31.40124) (xy 319.294522 -31.40124) (xy 319.353978 -31.409068) (xy 319.411903 -31.424589)
			(xy 319.467307 -31.447538) (xy 319.519241 -31.477522) (xy 319.566817 -31.514028) (xy 319.609222 -31.556433)
			(xy 319.645728 -31.604009) (xy 319.675712 -31.655943) (xy 319.698661 -31.711347) (xy 319.714182 -31.769272)
			(xy 319.72201 -31.828728) (xy 319.7225 -31.858712) (xy 319.7225 -32.714184) (xy 329.047348 -32.714184)
			(xy 329.047348 -31.850584) (xy 329.047838 -31.820616) (xy 329.055661 -31.761194) (xy 329.071174 -31.703301)
			(xy 329.09411 -31.647928) (xy 329.124077 -31.596022) (xy 329.160564 -31.548472) (xy 329.202944 -31.506092)
			(xy 329.250494 -31.469605) (xy 329.3024 -31.439638) (xy 329.357773 -31.416702) (xy 329.415666 -31.401189)
			(xy 329.475088 -31.393366) (xy 329.535024 -31.393366) (xy 329.594446 -31.401189) (xy 329.652339 -31.416702)
			(xy 329.707712 -31.439638) (xy 329.759618 -31.469605) (xy 329.807168 -31.506092) (xy 329.849548 -31.548472)
			(xy 329.886035 -31.596022) (xy 329.916002 -31.647928) (xy 329.938938 -31.703301) (xy 329.954451 -31.761194)
			(xy 329.962274 -31.820616) (xy 329.962764 -31.850584) (xy 329.962764 -32.714184) (xy 329.962631 -32.722312)
			(xy 356.907084 -32.722312) (xy 356.907084 -31.858712) (xy 356.907574 -31.828744) (xy 356.915397 -31.769322)
			(xy 356.93091 -31.711429) (xy 356.953846 -31.656056) (xy 356.983813 -31.60415) (xy 357.0203 -31.5566)
			(xy 357.06268 -31.51422) (xy 357.11023 -31.477733) (xy 357.162136 -31.447766) (xy 357.217509 -31.42483)
			(xy 357.275402 -31.409317) (xy 357.334824 -31.401494) (xy 357.39476 -31.401494) (xy 357.454182 -31.409317)
			(xy 357.512075 -31.42483) (xy 357.567448 -31.447766) (xy 357.619354 -31.477733) (xy 357.666904 -31.51422)
			(xy 357.709284 -31.5566) (xy 357.745771 -31.60415) (xy 357.775738 -31.656056) (xy 357.798674 -31.711429)
			(xy 357.814187 -31.769322) (xy 357.82201 -31.828744) (xy 357.8225 -31.858712) (xy 357.8225 -32.714184)
			(xy 367.147348 -32.714184) (xy 367.147348 -31.850584) (xy 367.147838 -31.8206) (xy 367.155666 -31.761144)
			(xy 367.171187 -31.703219) (xy 367.194136 -31.647815) (xy 367.22412 -31.595881) (xy 367.260626 -31.548305)
			(xy 367.303031 -31.5059) (xy 367.350607 -31.469394) (xy 367.402541 -31.43941) (xy 367.457945 -31.416461)
			(xy 367.51587 -31.40094) (xy 367.575326 -31.393112) (xy 367.635294 -31.393112) (xy 367.69475 -31.40094)
			(xy 367.752675 -31.416461) (xy 367.808079 -31.43941) (xy 367.860013 -31.469394) (xy 367.907589 -31.5059)
			(xy 367.949994 -31.548305) (xy 367.9865 -31.595881) (xy 368.016484 -31.647815) (xy 368.039433 -31.703219)
			(xy 368.054954 -31.761144) (xy 368.062782 -31.8206) (xy 368.063272 -31.850584) (xy 368.063272 -32.714184)
			(xy 368.063139 -32.722312) (xy 382.907032 -32.722312) (xy 382.907032 -31.858712) (xy 382.907522 -31.828744)
			(xy 382.915345 -31.769322) (xy 382.930858 -31.711429) (xy 382.953794 -31.656056) (xy 382.983761 -31.60415)
			(xy 383.020248 -31.5566) (xy 383.062628 -31.51422) (xy 383.110178 -31.477733) (xy 383.162084 -31.447766)
			(xy 383.217457 -31.42483) (xy 383.27535 -31.409317) (xy 383.334772 -31.401494) (xy 383.394708 -31.401494)
			(xy 383.45413 -31.409317) (xy 383.512023 -31.42483) (xy 383.567396 -31.447766) (xy 383.619302 -31.477733)
			(xy 383.666852 -31.51422) (xy 383.709232 -31.5566) (xy 383.745719 -31.60415) (xy 383.775686 -31.656056)
			(xy 383.798622 -31.711429) (xy 383.814135 -31.769322) (xy 383.821958 -31.828744) (xy 383.822448 -31.858712)
			(xy 383.822448 -32.714184) (xy 393.147296 -32.714184) (xy 393.147296 -31.850584) (xy 393.147786 -31.8206)
			(xy 393.155614 -31.761144) (xy 393.171135 -31.703219) (xy 393.194084 -31.647815) (xy 393.224068 -31.595881)
			(xy 393.260574 -31.548305) (xy 393.302979 -31.5059) (xy 393.350555 -31.469394) (xy 393.402489 -31.43941)
			(xy 393.457893 -31.416461) (xy 393.515818 -31.40094) (xy 393.575274 -31.393112) (xy 393.635242 -31.393112)
			(xy 393.694698 -31.40094) (xy 393.752623 -31.416461) (xy 393.808027 -31.43941) (xy 393.859961 -31.469394)
			(xy 393.907537 -31.5059) (xy 393.949942 -31.548305) (xy 393.986448 -31.595881) (xy 394.016432 -31.647815)
			(xy 394.039381 -31.703219) (xy 394.054902 -31.761144) (xy 394.06273 -31.8206) (xy 394.06322 -31.850584)
			(xy 394.06322 -32.714184) (xy 394.063087 -32.722312) (xy 408.90698 -32.722312) (xy 408.90698 -31.858712)
			(xy 408.90747 -31.828744) (xy 408.915293 -31.769322) (xy 408.930806 -31.711429) (xy 408.953742 -31.656056)
			(xy 408.983709 -31.60415) (xy 409.020196 -31.5566) (xy 409.062576 -31.51422) (xy 409.110126 -31.477733)
			(xy 409.162032 -31.447766) (xy 409.217405 -31.42483) (xy 409.275298 -31.409317) (xy 409.33472 -31.401494)
			(xy 409.394656 -31.401494) (xy 409.454078 -31.409317) (xy 409.511971 -31.42483) (xy 409.567344 -31.447766)
			(xy 409.61925 -31.477733) (xy 409.6668 -31.51422) (xy 409.70918 -31.5566) (xy 409.745667 -31.60415)
			(xy 409.775634 -31.656056) (xy 409.79857 -31.711429) (xy 409.814083 -31.769322) (xy 409.821906 -31.828744)
			(xy 409.822396 -31.858712) (xy 409.822396 -32.714184) (xy 419.147244 -32.714184) (xy 419.147244 -31.850584)
			(xy 419.147734 -31.8206) (xy 419.155562 -31.761144) (xy 419.171083 -31.703219) (xy 419.194032 -31.647815)
			(xy 419.224016 -31.595881) (xy 419.260522 -31.548305) (xy 419.302927 -31.5059) (xy 419.350503 -31.469394)
			(xy 419.402437 -31.43941) (xy 419.457841 -31.416461) (xy 419.515766 -31.40094) (xy 419.575222 -31.393112)
			(xy 419.63519 -31.393112) (xy 419.694646 -31.40094) (xy 419.752571 -31.416461) (xy 419.807975 -31.43941)
			(xy 419.859909 -31.469394) (xy 419.907485 -31.5059) (xy 419.94989 -31.548305) (xy 419.986396 -31.595881)
			(xy 420.01638 -31.647815) (xy 420.039329 -31.703219) (xy 420.05485 -31.761144) (xy 420.062678 -31.8206)
			(xy 420.063168 -31.850584) (xy 420.063168 -32.714184) (xy 420.063035 -32.722312) (xy 434.906928 -32.722312)
			(xy 434.906928 -31.858712) (xy 434.907418 -31.828744) (xy 434.915241 -31.769322) (xy 434.930754 -31.711429)
			(xy 434.95369 -31.656056) (xy 434.983657 -31.60415) (xy 435.020144 -31.5566) (xy 435.062524 -31.51422)
			(xy 435.110074 -31.477733) (xy 435.16198 -31.447766) (xy 435.217353 -31.42483) (xy 435.275246 -31.409317)
			(xy 435.334668 -31.401494) (xy 435.394604 -31.401494) (xy 435.454026 -31.409317) (xy 435.511919 -31.42483)
			(xy 435.567292 -31.447766) (xy 435.619198 -31.477733) (xy 435.666748 -31.51422) (xy 435.709128 -31.5566)
			(xy 435.745615 -31.60415) (xy 435.775582 -31.656056) (xy 435.798518 -31.711429) (xy 435.814031 -31.769322)
			(xy 435.821854 -31.828744) (xy 435.822344 -31.858712) (xy 435.822344 -32.714184) (xy 445.147192 -32.714184)
			(xy 445.147192 -31.850584) (xy 445.147682 -31.8206) (xy 445.15551 -31.761144) (xy 445.171031 -31.703219)
			(xy 445.19398 -31.647815) (xy 445.223964 -31.595881) (xy 445.26047 -31.548305) (xy 445.302875 -31.5059)
			(xy 445.350451 -31.469394) (xy 445.402385 -31.43941) (xy 445.457789 -31.416461) (xy 445.515714 -31.40094)
			(xy 445.57517 -31.393112) (xy 445.635138 -31.393112) (xy 445.694594 -31.40094) (xy 445.752519 -31.416461)
			(xy 445.807923 -31.43941) (xy 445.859857 -31.469394) (xy 445.907433 -31.5059) (xy 445.949838 -31.548305)
			(xy 445.986344 -31.595881) (xy 446.016328 -31.647815) (xy 446.039277 -31.703219) (xy 446.054798 -31.761144)
			(xy 446.062626 -31.8206) (xy 446.063116 -31.850584) (xy 446.063116 -32.714184) (xy 446.062626 -32.744168)
			(xy 446.054798 -32.803624) (xy 446.039277 -32.861549) (xy 446.016328 -32.916953) (xy 445.986344 -32.968887)
			(xy 445.949838 -33.016463) (xy 445.907433 -33.058868) (xy 445.859857 -33.095374) (xy 445.807923 -33.125358)
			(xy 445.752519 -33.148307) (xy 445.694594 -33.163828) (xy 445.635138 -33.171656) (xy 445.57517 -33.171656)
			(xy 445.515714 -33.163828) (xy 445.457789 -33.148307) (xy 445.402385 -33.125358) (xy 445.350451 -33.095374)
			(xy 445.302875 -33.058868) (xy 445.26047 -33.016463) (xy 445.223964 -32.968887) (xy 445.19398 -32.916953)
			(xy 445.171031 -32.861549) (xy 445.15551 -32.803624) (xy 445.147682 -32.744168) (xy 445.147192 -32.714184)
			(xy 435.822344 -32.714184) (xy 435.822344 -32.722312) (xy 435.821854 -32.75228) (xy 435.814031 -32.811702)
			(xy 435.798518 -32.869595) (xy 435.775582 -32.924968) (xy 435.745615 -32.976874) (xy 435.709128 -33.024424)
			(xy 435.666748 -33.066804) (xy 435.619198 -33.103291) (xy 435.567292 -33.133258) (xy 435.511919 -33.156194)
			(xy 435.454026 -33.171707) (xy 435.394604 -33.17953) (xy 435.334668 -33.17953) (xy 435.275246 -33.171707)
			(xy 435.217353 -33.156194) (xy 435.16198 -33.133258) (xy 435.110074 -33.103291) (xy 435.062524 -33.066804)
			(xy 435.020144 -33.024424) (xy 434.983657 -32.976874) (xy 434.95369 -32.924968) (xy 434.930754 -32.869595)
			(xy 434.915241 -32.811702) (xy 434.907418 -32.75228) (xy 434.906928 -32.722312) (xy 420.063035 -32.722312)
			(xy 420.062678 -32.744168) (xy 420.05485 -32.803624) (xy 420.039329 -32.861549) (xy 420.01638 -32.916953)
			(xy 419.986396 -32.968887) (xy 419.94989 -33.016463) (xy 419.907485 -33.058868) (xy 419.859909 -33.095374)
			(xy 419.807975 -33.125358) (xy 419.752571 -33.148307) (xy 419.694646 -33.163828) (xy 419.63519 -33.171656)
			(xy 419.575222 -33.171656) (xy 419.515766 -33.163828) (xy 419.457841 -33.148307) (xy 419.402437 -33.125358)
			(xy 419.350503 -33.095374) (xy 419.302927 -33.058868) (xy 419.260522 -33.016463) (xy 419.224016 -32.968887)
			(xy 419.194032 -32.916953) (xy 419.171083 -32.861549) (xy 419.155562 -32.803624) (xy 419.147734 -32.744168)
			(xy 419.147244 -32.714184) (xy 409.822396 -32.714184) (xy 409.822396 -32.722312) (xy 409.821906 -32.75228)
			(xy 409.814083 -32.811702) (xy 409.79857 -32.869595) (xy 409.775634 -32.924968) (xy 409.745667 -32.976874)
			(xy 409.70918 -33.024424) (xy 409.6668 -33.066804) (xy 409.61925 -33.103291) (xy 409.567344 -33.133258)
			(xy 409.511971 -33.156194) (xy 409.454078 -33.171707) (xy 409.394656 -33.17953) (xy 409.33472 -33.17953)
			(xy 409.275298 -33.171707) (xy 409.217405 -33.156194) (xy 409.162032 -33.133258) (xy 409.110126 -33.103291)
			(xy 409.062576 -33.066804) (xy 409.020196 -33.024424) (xy 408.983709 -32.976874) (xy 408.953742 -32.924968)
			(xy 408.930806 -32.869595) (xy 408.915293 -32.811702) (xy 408.90747 -32.75228) (xy 408.90698 -32.722312)
			(xy 394.063087 -32.722312) (xy 394.06273 -32.744168) (xy 394.054902 -32.803624) (xy 394.039381 -32.861549)
			(xy 394.016432 -32.916953) (xy 393.986448 -32.968887) (xy 393.949942 -33.016463) (xy 393.907537 -33.058868)
			(xy 393.859961 -33.095374) (xy 393.808027 -33.125358) (xy 393.752623 -33.148307) (xy 393.694698 -33.163828)
			(xy 393.635242 -33.171656) (xy 393.575274 -33.171656) (xy 393.515818 -33.163828) (xy 393.457893 -33.148307)
			(xy 393.402489 -33.125358) (xy 393.350555 -33.095374) (xy 393.302979 -33.058868) (xy 393.260574 -33.016463)
			(xy 393.224068 -32.968887) (xy 393.194084 -32.916953) (xy 393.171135 -32.861549) (xy 393.155614 -32.803624)
			(xy 393.147786 -32.744168) (xy 393.147296 -32.714184) (xy 383.822448 -32.714184) (xy 383.822448 -32.722312)
			(xy 383.821958 -32.75228) (xy 383.814135 -32.811702) (xy 383.798622 -32.869595) (xy 383.775686 -32.924968)
			(xy 383.745719 -32.976874) (xy 383.709232 -33.024424) (xy 383.666852 -33.066804) (xy 383.619302 -33.103291)
			(xy 383.567396 -33.133258) (xy 383.512023 -33.156194) (xy 383.45413 -33.171707) (xy 383.394708 -33.17953)
			(xy 383.334772 -33.17953) (xy 383.27535 -33.171707) (xy 383.217457 -33.156194) (xy 383.162084 -33.133258)
			(xy 383.110178 -33.103291) (xy 383.062628 -33.066804) (xy 383.020248 -33.024424) (xy 382.983761 -32.976874)
			(xy 382.953794 -32.924968) (xy 382.930858 -32.869595) (xy 382.915345 -32.811702) (xy 382.907522 -32.75228)
			(xy 382.907032 -32.722312) (xy 368.063139 -32.722312) (xy 368.062782 -32.744168) (xy 368.054954 -32.803624)
			(xy 368.039433 -32.861549) (xy 368.016484 -32.916953) (xy 367.9865 -32.968887) (xy 367.949994 -33.016463)
			(xy 367.907589 -33.058868) (xy 367.860013 -33.095374) (xy 367.808079 -33.125358) (xy 367.752675 -33.148307)
			(xy 367.69475 -33.163828) (xy 367.635294 -33.171656) (xy 367.575326 -33.171656) (xy 367.51587 -33.163828)
			(xy 367.457945 -33.148307) (xy 367.402541 -33.125358) (xy 367.350607 -33.095374) (xy 367.303031 -33.058868)
			(xy 367.260626 -33.016463) (xy 367.22412 -32.968887) (xy 367.194136 -32.916953) (xy 367.171187 -32.861549)
			(xy 367.155666 -32.803624) (xy 367.147838 -32.744168) (xy 367.147348 -32.714184) (xy 357.8225 -32.714184)
			(xy 357.8225 -32.722312) (xy 357.82201 -32.75228) (xy 357.814187 -32.811702) (xy 357.798674 -32.869595)
			(xy 357.775738 -32.924968) (xy 357.745771 -32.976874) (xy 357.709284 -33.024424) (xy 357.666904 -33.066804)
			(xy 357.619354 -33.103291) (xy 357.567448 -33.133258) (xy 357.512075 -33.156194) (xy 357.454182 -33.171707)
			(xy 357.39476 -33.17953) (xy 357.334824 -33.17953) (xy 357.275402 -33.171707) (xy 357.217509 -33.156194)
			(xy 357.162136 -33.133258) (xy 357.11023 -33.103291) (xy 357.06268 -33.066804) (xy 357.0203 -33.024424)
			(xy 356.983813 -32.976874) (xy 356.953846 -32.924968) (xy 356.93091 -32.869595) (xy 356.915397 -32.811702)
			(xy 356.907574 -32.75228) (xy 356.907084 -32.722312) (xy 329.962631 -32.722312) (xy 329.962274 -32.744152)
			(xy 329.954451 -32.803574) (xy 329.938938 -32.861467) (xy 329.916002 -32.91684) (xy 329.886035 -32.968746)
			(xy 329.849548 -33.016296) (xy 329.807168 -33.058676) (xy 329.759618 -33.095163) (xy 329.707712 -33.12513)
			(xy 329.652339 -33.148066) (xy 329.594446 -33.163579) (xy 329.535024 -33.171402) (xy 329.475088 -33.171402)
			(xy 329.415666 -33.163579) (xy 329.357773 -33.148066) (xy 329.3024 -33.12513) (xy 329.250494 -33.095163)
			(xy 329.202944 -33.058676) (xy 329.160564 -33.016296) (xy 329.124077 -32.968746) (xy 329.09411 -32.91684)
			(xy 329.071174 -32.861467) (xy 329.055661 -32.803574) (xy 329.047838 -32.744152) (xy 329.047348 -32.714184)
			(xy 319.7225 -32.714184) (xy 319.7225 -32.722312) (xy 319.72201 -32.752296) (xy 319.714182 -32.811752)
			(xy 319.698661 -32.869677) (xy 319.675712 -32.925081) (xy 319.645728 -32.977015) (xy 319.609222 -33.024591)
			(xy 319.566817 -33.066996) (xy 319.519241 -33.103502) (xy 319.467307 -33.133486) (xy 319.411903 -33.156435)
			(xy 319.353978 -33.171956) (xy 319.294522 -33.179784) (xy 319.234554 -33.179784) (xy 319.175098 -33.171956)
			(xy 319.117173 -33.156435) (xy 319.061769 -33.133486) (xy 319.009835 -33.103502) (xy 318.962259 -33.066996)
			(xy 318.919854 -33.024591) (xy 318.883348 -32.977015) (xy 318.853364 -32.925081) (xy 318.830415 -32.869677)
			(xy 318.814894 -32.811752) (xy 318.807066 -32.752296) (xy 318.806576 -32.722312) (xy 303.962683 -32.722312)
			(xy 303.962326 -32.744152) (xy 303.954503 -32.803574) (xy 303.93899 -32.861467) (xy 303.916054 -32.91684)
			(xy 303.886087 -32.968746) (xy 303.8496 -33.016296) (xy 303.80722 -33.058676) (xy 303.75967 -33.095163)
			(xy 303.707764 -33.12513) (xy 303.652391 -33.148066) (xy 303.594498 -33.163579) (xy 303.535076 -33.171402)
			(xy 303.47514 -33.171402) (xy 303.415718 -33.163579) (xy 303.357825 -33.148066) (xy 303.302452 -33.12513)
			(xy 303.250546 -33.095163) (xy 303.202996 -33.058676) (xy 303.160616 -33.016296) (xy 303.124129 -32.968746)
			(xy 303.094162 -32.91684) (xy 303.071226 -32.861467) (xy 303.055713 -32.803574) (xy 303.04789 -32.744152)
			(xy 303.0474 -32.714184) (xy 293.722552 -32.714184) (xy 293.722552 -32.722312) (xy 293.722062 -32.752296)
			(xy 293.714234 -32.811752) (xy 293.698713 -32.869677) (xy 293.675764 -32.925081) (xy 293.64578 -32.977015)
			(xy 293.609274 -33.024591) (xy 293.566869 -33.066996) (xy 293.519293 -33.103502) (xy 293.467359 -33.133486)
			(xy 293.411955 -33.156435) (xy 293.35403 -33.171956) (xy 293.294574 -33.179784) (xy 293.234606 -33.179784)
			(xy 293.17515 -33.171956) (xy 293.117225 -33.156435) (xy 293.061821 -33.133486) (xy 293.009887 -33.103502)
			(xy 292.962311 -33.066996) (xy 292.919906 -33.024591) (xy 292.8834 -32.977015) (xy 292.853416 -32.925081)
			(xy 292.830467 -32.869677) (xy 292.814946 -32.811752) (xy 292.807118 -32.752296) (xy 292.806628 -32.722312)
			(xy 277.962735 -32.722312) (xy 277.962378 -32.744152) (xy 277.954555 -32.803574) (xy 277.939042 -32.861467)
			(xy 277.916106 -32.91684) (xy 277.886139 -32.968746) (xy 277.849652 -33.016296) (xy 277.807272 -33.058676)
			(xy 277.759722 -33.095163) (xy 277.707816 -33.12513) (xy 277.652443 -33.148066) (xy 277.59455 -33.163579)
			(xy 277.535128 -33.171402) (xy 277.475192 -33.171402) (xy 277.41577 -33.163579) (xy 277.357877 -33.148066)
			(xy 277.302504 -33.12513) (xy 277.250598 -33.095163) (xy 277.203048 -33.058676) (xy 277.160668 -33.016296)
			(xy 277.124181 -32.968746) (xy 277.094214 -32.91684) (xy 277.071278 -32.861467) (xy 277.055765 -32.803574)
			(xy 277.047942 -32.744152) (xy 277.047452 -32.714184) (xy 267.722604 -32.714184) (xy 267.722604 -32.722312)
			(xy 267.722114 -32.752296) (xy 267.714286 -32.811752) (xy 267.698765 -32.869677) (xy 267.675816 -32.925081)
			(xy 267.645832 -32.977015) (xy 267.609326 -33.024591) (xy 267.566921 -33.066996) (xy 267.519345 -33.103502)
			(xy 267.467411 -33.133486) (xy 267.412007 -33.156435) (xy 267.354082 -33.171956) (xy 267.294626 -33.179784)
			(xy 267.234658 -33.179784) (xy 267.175202 -33.171956) (xy 267.117277 -33.156435) (xy 267.061873 -33.133486)
			(xy 267.009939 -33.103502) (xy 266.962363 -33.066996) (xy 266.919958 -33.024591) (xy 266.883452 -32.977015)
			(xy 266.853468 -32.925081) (xy 266.830519 -32.869677) (xy 266.814998 -32.811752) (xy 266.80717 -32.752296)
			(xy 266.80668 -32.722312) (xy 251.962787 -32.722312) (xy 251.96243 -32.744152) (xy 251.954607 -32.803574)
			(xy 251.939094 -32.861467) (xy 251.916158 -32.91684) (xy 251.886191 -32.968746) (xy 251.849704 -33.016296)
			(xy 251.807324 -33.058676) (xy 251.759774 -33.095163) (xy 251.707868 -33.12513) (xy 251.652495 -33.148066)
			(xy 251.594602 -33.163579) (xy 251.53518 -33.171402) (xy 251.475244 -33.171402) (xy 251.415822 -33.163579)
			(xy 251.357929 -33.148066) (xy 251.302556 -33.12513) (xy 251.25065 -33.095163) (xy 251.2031 -33.058676)
			(xy 251.16072 -33.016296) (xy 251.124233 -32.968746) (xy 251.094266 -32.91684) (xy 251.07133 -32.861467)
			(xy 251.055817 -32.803574) (xy 251.047994 -32.744152) (xy 251.047504 -32.714184) (xy 241.722656 -32.714184)
			(xy 241.722656 -32.722312) (xy 241.722166 -32.752296) (xy 241.714338 -32.811752) (xy 241.698817 -32.869677)
			(xy 241.675868 -32.925081) (xy 241.645884 -32.977015) (xy 241.609378 -33.024591) (xy 241.566973 -33.066996)
			(xy 241.519397 -33.103502) (xy 241.467463 -33.133486) (xy 241.412059 -33.156435) (xy 241.354134 -33.171956)
			(xy 241.294678 -33.179784) (xy 241.23471 -33.179784) (xy 241.175254 -33.171956) (xy 241.117329 -33.156435)
			(xy 241.061925 -33.133486) (xy 241.009991 -33.103502) (xy 240.962415 -33.066996) (xy 240.92001 -33.024591)
			(xy 240.883504 -32.977015) (xy 240.85352 -32.925081) (xy 240.830571 -32.869677) (xy 240.81505 -32.811752)
			(xy 240.807222 -32.752296) (xy 240.806732 -32.722312) (xy 213.862787 -32.722312) (xy 213.86243 -32.744152)
			(xy 213.854607 -32.803574) (xy 213.839094 -32.861467) (xy 213.816158 -32.91684) (xy 213.786191 -32.968746)
			(xy 213.749704 -33.016296) (xy 213.707324 -33.058676) (xy 213.659774 -33.095163) (xy 213.607868 -33.12513)
			(xy 213.552495 -33.148066) (xy 213.494602 -33.163579) (xy 213.43518 -33.171402) (xy 213.375244 -33.171402)
			(xy 213.315822 -33.163579) (xy 213.257929 -33.148066) (xy 213.202556 -33.12513) (xy 213.15065 -33.095163)
			(xy 213.1031 -33.058676) (xy 213.06072 -33.016296) (xy 213.024233 -32.968746) (xy 212.994266 -32.91684)
			(xy 212.97133 -32.861467) (xy 212.955817 -32.803574) (xy 212.947994 -32.744152) (xy 212.947504 -32.714184)
			(xy 203.622656 -32.714184) (xy 203.622656 -32.722312) (xy 203.622166 -32.752296) (xy 203.614338 -32.811752)
			(xy 203.598817 -32.869677) (xy 203.575868 -32.925081) (xy 203.545884 -32.977015) (xy 203.509378 -33.024591)
			(xy 203.466973 -33.066996) (xy 203.419397 -33.103502) (xy 203.367463 -33.133486) (xy 203.312059 -33.156435)
			(xy 203.254134 -33.171956) (xy 203.194678 -33.179784) (xy 203.13471 -33.179784) (xy 203.075254 -33.171956)
			(xy 203.017329 -33.156435) (xy 202.961925 -33.133486) (xy 202.909991 -33.103502) (xy 202.862415 -33.066996)
			(xy 202.82001 -33.024591) (xy 202.783504 -32.977015) (xy 202.75352 -32.925081) (xy 202.730571 -32.869677)
			(xy 202.71505 -32.811752) (xy 202.707222 -32.752296) (xy 202.706732 -32.722312) (xy 187.862839 -32.722312)
			(xy 187.862482 -32.744152) (xy 187.854659 -32.803574) (xy 187.839146 -32.861467) (xy 187.81621 -32.91684)
			(xy 187.786243 -32.968746) (xy 187.749756 -33.016296) (xy 187.707376 -33.058676) (xy 187.659826 -33.095163)
			(xy 187.60792 -33.12513) (xy 187.552547 -33.148066) (xy 187.494654 -33.163579) (xy 187.435232 -33.171402)
			(xy 187.375296 -33.171402) (xy 187.315874 -33.163579) (xy 187.257981 -33.148066) (xy 187.202608 -33.12513)
			(xy 187.150702 -33.095163) (xy 187.103152 -33.058676) (xy 187.060772 -33.016296) (xy 187.024285 -32.968746)
			(xy 186.994318 -32.91684) (xy 186.971382 -32.861467) (xy 186.955869 -32.803574) (xy 186.948046 -32.744152)
			(xy 186.947556 -32.714184) (xy 177.622708 -32.714184) (xy 177.622708 -32.722312) (xy 177.622218 -32.752296)
			(xy 177.61439 -32.811752) (xy 177.598869 -32.869677) (xy 177.57592 -32.925081) (xy 177.545936 -32.977015)
			(xy 177.50943 -33.024591) (xy 177.467025 -33.066996) (xy 177.419449 -33.103502) (xy 177.367515 -33.133486)
			(xy 177.312111 -33.156435) (xy 177.254186 -33.171956) (xy 177.19473 -33.179784) (xy 177.134762 -33.179784)
			(xy 177.075306 -33.171956) (xy 177.017381 -33.156435) (xy 176.961977 -33.133486) (xy 176.910043 -33.103502)
			(xy 176.862467 -33.066996) (xy 176.820062 -33.024591) (xy 176.783556 -32.977015) (xy 176.753572 -32.925081)
			(xy 176.730623 -32.869677) (xy 176.715102 -32.811752) (xy 176.707274 -32.752296) (xy 176.706784 -32.722312)
			(xy 161.862891 -32.722312) (xy 161.862534 -32.744152) (xy 161.854711 -32.803574) (xy 161.839198 -32.861467)
			(xy 161.816262 -32.91684) (xy 161.786295 -32.968746) (xy 161.749808 -33.016296) (xy 161.707428 -33.058676)
			(xy 161.659878 -33.095163) (xy 161.607972 -33.12513) (xy 161.552599 -33.148066) (xy 161.494706 -33.163579)
			(xy 161.435284 -33.171402) (xy 161.375348 -33.171402) (xy 161.315926 -33.163579) (xy 161.258033 -33.148066)
			(xy 161.20266 -33.12513) (xy 161.150754 -33.095163) (xy 161.103204 -33.058676) (xy 161.060824 -33.016296)
			(xy 161.024337 -32.968746) (xy 160.99437 -32.91684) (xy 160.971434 -32.861467) (xy 160.955921 -32.803574)
			(xy 160.948098 -32.744152) (xy 160.947608 -32.714184) (xy 151.62276 -32.714184) (xy 151.62276 -32.722312)
			(xy 151.62227 -32.752296) (xy 151.614442 -32.811752) (xy 151.598921 -32.869677) (xy 151.575972 -32.925081)
			(xy 151.545988 -32.977015) (xy 151.509482 -33.024591) (xy 151.467077 -33.066996) (xy 151.419501 -33.103502)
			(xy 151.367567 -33.133486) (xy 151.312163 -33.156435) (xy 151.254238 -33.171956) (xy 151.194782 -33.179784)
			(xy 151.134814 -33.179784) (xy 151.075358 -33.171956) (xy 151.017433 -33.156435) (xy 150.962029 -33.133486)
			(xy 150.910095 -33.103502) (xy 150.862519 -33.066996) (xy 150.820114 -33.024591) (xy 150.783608 -32.977015)
			(xy 150.753624 -32.925081) (xy 150.730675 -32.869677) (xy 150.715154 -32.811752) (xy 150.707326 -32.752296)
			(xy 150.706836 -32.722312) (xy 135.862943 -32.722312) (xy 135.862586 -32.744152) (xy 135.854763 -32.803574)
			(xy 135.83925 -32.861467) (xy 135.816314 -32.91684) (xy 135.786347 -32.968746) (xy 135.74986 -33.016296)
			(xy 135.70748 -33.058676) (xy 135.65993 -33.095163) (xy 135.608024 -33.12513) (xy 135.552651 -33.148066)
			(xy 135.494758 -33.163579) (xy 135.435336 -33.171402) (xy 135.3754 -33.171402) (xy 135.315978 -33.163579)
			(xy 135.258085 -33.148066) (xy 135.202712 -33.12513) (xy 135.150806 -33.095163) (xy 135.103256 -33.058676)
			(xy 135.060876 -33.016296) (xy 135.024389 -32.968746) (xy 134.994422 -32.91684) (xy 134.971486 -32.861467)
			(xy 134.955973 -32.803574) (xy 134.94815 -32.744152) (xy 134.94766 -32.714184) (xy 125.622812 -32.714184)
			(xy 125.622812 -32.722312) (xy 125.622322 -32.752296) (xy 125.614494 -32.811752) (xy 125.598973 -32.869677)
			(xy 125.576024 -32.925081) (xy 125.54604 -32.977015) (xy 125.509534 -33.024591) (xy 125.467129 -33.066996)
			(xy 125.419553 -33.103502) (xy 125.367619 -33.133486) (xy 125.312215 -33.156435) (xy 125.25429 -33.171956)
			(xy 125.194834 -33.179784) (xy 125.134866 -33.179784) (xy 125.07541 -33.171956) (xy 125.017485 -33.156435)
			(xy 124.962081 -33.133486) (xy 124.910147 -33.103502) (xy 124.862571 -33.066996) (xy 124.820166 -33.024591)
			(xy 124.78366 -32.977015) (xy 124.753676 -32.925081) (xy 124.730727 -32.869677) (xy 124.715206 -32.811752)
			(xy 124.707378 -32.752296) (xy 124.706888 -32.722312) (xy 97.762943 -32.722312) (xy 97.762586 -32.744168)
			(xy 97.754758 -32.803624) (xy 97.739237 -32.861549) (xy 97.716288 -32.916953) (xy 97.686304 -32.968887)
			(xy 97.649798 -33.016463) (xy 97.607393 -33.058868) (xy 97.559817 -33.095374) (xy 97.507883 -33.125358)
			(xy 97.452479 -33.148307) (xy 97.394554 -33.163828) (xy 97.335098 -33.171656) (xy 97.27513 -33.171656)
			(xy 97.215674 -33.163828) (xy 97.157749 -33.148307) (xy 97.102345 -33.125358) (xy 97.050411 -33.095374)
			(xy 97.002835 -33.058868) (xy 96.96043 -33.016463) (xy 96.923924 -32.968887) (xy 96.89394 -32.916953)
			(xy 96.870991 -32.861549) (xy 96.85547 -32.803624) (xy 96.847642 -32.744168) (xy 96.847152 -32.714184)
			(xy 87.522304 -32.714184) (xy 87.522304 -32.722312) (xy 87.521814 -32.75228) (xy 87.513991 -32.811702)
			(xy 87.498478 -32.869595) (xy 87.475542 -32.924968) (xy 87.445575 -32.976874) (xy 87.409088 -33.024424)
			(xy 87.366708 -33.066804) (xy 87.319158 -33.103291) (xy 87.267252 -33.133258) (xy 87.211879 -33.156194)
			(xy 87.153986 -33.171707) (xy 87.094564 -33.17953) (xy 87.034628 -33.17953) (xy 86.975206 -33.171707)
			(xy 86.917313 -33.156194) (xy 86.86194 -33.133258) (xy 86.810034 -33.103291) (xy 86.762484 -33.066804)
			(xy 86.720104 -33.024424) (xy 86.683617 -32.976874) (xy 86.65365 -32.924968) (xy 86.630714 -32.869595)
			(xy 86.615201 -32.811702) (xy 86.607378 -32.75228) (xy 86.606888 -32.722312) (xy 71.762995 -32.722312)
			(xy 71.762638 -32.744168) (xy 71.75481 -32.803624) (xy 71.739289 -32.861549) (xy 71.71634 -32.916953)
			(xy 71.686356 -32.968887) (xy 71.64985 -33.016463) (xy 71.607445 -33.058868) (xy 71.559869 -33.095374)
			(xy 71.507935 -33.125358) (xy 71.452531 -33.148307) (xy 71.394606 -33.163828) (xy 71.33515 -33.171656)
			(xy 71.275182 -33.171656) (xy 71.215726 -33.163828) (xy 71.157801 -33.148307) (xy 71.102397 -33.125358)
			(xy 71.050463 -33.095374) (xy 71.002887 -33.058868) (xy 70.960482 -33.016463) (xy 70.923976 -32.968887)
			(xy 70.893992 -32.916953) (xy 70.871043 -32.861549) (xy 70.855522 -32.803624) (xy 70.847694 -32.744168)
			(xy 70.847204 -32.714184) (xy 61.522356 -32.714184) (xy 61.522356 -32.722312) (xy 61.521866 -32.75228)
			(xy 61.514043 -32.811702) (xy 61.49853 -32.869595) (xy 61.475594 -32.924968) (xy 61.445627 -32.976874)
			(xy 61.40914 -33.024424) (xy 61.36676 -33.066804) (xy 61.31921 -33.103291) (xy 61.267304 -33.133258)
			(xy 61.211931 -33.156194) (xy 61.154038 -33.171707) (xy 61.094616 -33.17953) (xy 61.03468 -33.17953)
			(xy 60.975258 -33.171707) (xy 60.917365 -33.156194) (xy 60.861992 -33.133258) (xy 60.810086 -33.103291)
			(xy 60.762536 -33.066804) (xy 60.720156 -33.024424) (xy 60.683669 -32.976874) (xy 60.653702 -32.924968)
			(xy 60.630766 -32.869595) (xy 60.615253 -32.811702) (xy 60.60743 -32.75228) (xy 60.60694 -32.722312)
			(xy 45.763047 -32.722312) (xy 45.76269 -32.744168) (xy 45.754862 -32.803624) (xy 45.739341 -32.861549)
			(xy 45.716392 -32.916953) (xy 45.686408 -32.968887) (xy 45.649902 -33.016463) (xy 45.607497 -33.058868)
			(xy 45.559921 -33.095374) (xy 45.507987 -33.125358) (xy 45.452583 -33.148307) (xy 45.394658 -33.163828)
			(xy 45.335202 -33.171656) (xy 45.275234 -33.171656) (xy 45.215778 -33.163828) (xy 45.157853 -33.148307)
			(xy 45.102449 -33.125358) (xy 45.050515 -33.095374) (xy 45.002939 -33.058868) (xy 44.960534 -33.016463)
			(xy 44.924028 -32.968887) (xy 44.894044 -32.916953) (xy 44.871095 -32.861549) (xy 44.855574 -32.803624)
			(xy 44.847746 -32.744168) (xy 44.847256 -32.714184) (xy 35.522408 -32.714184) (xy 35.522408 -32.722312)
			(xy 35.521918 -32.75228) (xy 35.514095 -32.811702) (xy 35.498582 -32.869595) (xy 35.475646 -32.924968)
			(xy 35.445679 -32.976874) (xy 35.409192 -33.024424) (xy 35.366812 -33.066804) (xy 35.319262 -33.103291)
			(xy 35.267356 -33.133258) (xy 35.211983 -33.156194) (xy 35.15409 -33.171707) (xy 35.094668 -33.17953)
			(xy 35.034732 -33.17953) (xy 34.97531 -33.171707) (xy 34.917417 -33.156194) (xy 34.862044 -33.133258)
			(xy 34.810138 -33.103291) (xy 34.762588 -33.066804) (xy 34.720208 -33.024424) (xy 34.683721 -32.976874)
			(xy 34.653754 -32.924968) (xy 34.630818 -32.869595) (xy 34.615305 -32.811702) (xy 34.607482 -32.75228)
			(xy 34.606992 -32.722312) (xy 19.763099 -32.722312) (xy 19.762742 -32.744168) (xy 19.754914 -32.803624)
			(xy 19.739393 -32.861549) (xy 19.716444 -32.916953) (xy 19.68646 -32.968887) (xy 19.649954 -33.016463)
			(xy 19.607549 -33.058868) (xy 19.559973 -33.095374) (xy 19.508039 -33.125358) (xy 19.452635 -33.148307)
			(xy 19.39471 -33.163828) (xy 19.335254 -33.171656) (xy 19.275286 -33.171656) (xy 19.21583 -33.163828)
			(xy 19.157905 -33.148307) (xy 19.102501 -33.125358) (xy 19.050567 -33.095374) (xy 19.002991 -33.058868)
			(xy 18.960586 -33.016463) (xy 18.92408 -32.968887) (xy 18.894096 -32.916953) (xy 18.871147 -32.861549)
			(xy 18.855626 -32.803624) (xy 18.847798 -32.744168) (xy 18.847308 -32.714184) (xy 9.52246 -32.714184)
			(xy 9.52246 -32.722312) (xy 9.52197 -32.75228) (xy 9.514147 -32.811702) (xy 9.498634 -32.869595)
			(xy 9.475698 -32.924968) (xy 9.445731 -32.976874) (xy 9.409244 -33.024424) (xy 9.366864 -33.066804)
			(xy 9.319314 -33.103291) (xy 9.267408 -33.133258) (xy 9.212035 -33.156194) (xy 9.154142 -33.171707)
			(xy 9.09472 -33.17953) (xy 9.034784 -33.17953) (xy 8.975362 -33.171707) (xy 8.917469 -33.156194)
			(xy 8.862096 -33.133258) (xy 8.81019 -33.103291) (xy 8.76264 -33.066804) (xy 8.72026 -33.024424)
			(xy 8.683773 -32.976874) (xy 8.653806 -32.924968) (xy 8.63087 -32.869595) (xy 8.615357 -32.811702)
			(xy 8.607534 -32.75228) (xy 8.607044 -32.722312) (xy 0.508 -32.722312) (xy 0.508 -34.52241) (xy 6.752844 -34.52241)
			(xy 6.752844 -33.65881) (xy 6.753334 -33.628842) (xy 6.761157 -33.56942) (xy 6.77667 -33.511527)
			(xy 6.799606 -33.456154) (xy 6.829573 -33.404248) (xy 6.86606 -33.356698) (xy 6.90844 -33.314318)
			(xy 6.95599 -33.277831) (xy 7.007896 -33.247864) (xy 7.063269 -33.224928) (xy 7.121162 -33.209415)
			(xy 7.180584 -33.201592) (xy 7.24052 -33.201592) (xy 7.299942 -33.209415) (xy 7.357835 -33.224928)
			(xy 7.413208 -33.247864) (xy 7.465114 -33.277831) (xy 7.512664 -33.314318) (xy 7.555044 -33.356698)
			(xy 7.591531 -33.404248) (xy 7.621498 -33.456154) (xy 7.644434 -33.511527) (xy 7.659947 -33.56942)
			(xy 7.66777 -33.628842) (xy 7.66826 -33.65881) (xy 7.66826 -34.520886) (xy 21.489416 -34.520886)
			(xy 21.489416 -33.657286) (xy 21.489906 -33.627302) (xy 21.497734 -33.567846) (xy 21.513255 -33.509921)
			(xy 21.536204 -33.454517) (xy 21.566188 -33.402583) (xy 21.602694 -33.355007) (xy 21.645099 -33.312602)
			(xy 21.692675 -33.276096) (xy 21.744609 -33.246112) (xy 21.800013 -33.223163) (xy 21.857938 -33.207642)
			(xy 21.917394 -33.199814) (xy 21.977362 -33.199814) (xy 22.036818 -33.207642) (xy 22.094743 -33.223163)
			(xy 22.150147 -33.246112) (xy 22.202081 -33.276096) (xy 22.249657 -33.312602) (xy 22.292062 -33.355007)
			(xy 22.328568 -33.402583) (xy 22.358552 -33.454517) (xy 22.381501 -33.509921) (xy 22.397022 -33.567846)
			(xy 22.40485 -33.627302) (xy 22.40534 -33.657286) (xy 22.40534 -34.520886) (xy 22.405315 -34.52241)
			(xy 32.752792 -34.52241) (xy 32.752792 -33.65881) (xy 32.753282 -33.628842) (xy 32.761105 -33.56942)
			(xy 32.776618 -33.511527) (xy 32.799554 -33.456154) (xy 32.829521 -33.404248) (xy 32.866008 -33.356698)
			(xy 32.908388 -33.314318) (xy 32.955938 -33.277831) (xy 33.007844 -33.247864) (xy 33.063217 -33.224928)
			(xy 33.12111 -33.209415) (xy 33.180532 -33.201592) (xy 33.240468 -33.201592) (xy 33.29989 -33.209415)
			(xy 33.357783 -33.224928) (xy 33.413156 -33.247864) (xy 33.465062 -33.277831) (xy 33.512612 -33.314318)
			(xy 33.554992 -33.356698) (xy 33.591479 -33.404248) (xy 33.621446 -33.456154) (xy 33.644382 -33.511527)
			(xy 33.659895 -33.56942) (xy 33.667718 -33.628842) (xy 33.668208 -33.65881) (xy 33.668208 -34.520886)
			(xy 47.489364 -34.520886) (xy 47.489364 -33.657286) (xy 47.489854 -33.627302) (xy 47.497682 -33.567846)
			(xy 47.513203 -33.509921) (xy 47.536152 -33.454517) (xy 47.566136 -33.402583) (xy 47.602642 -33.355007)
			(xy 47.645047 -33.312602) (xy 47.692623 -33.276096) (xy 47.744557 -33.246112) (xy 47.799961 -33.223163)
			(xy 47.857886 -33.207642) (xy 47.917342 -33.199814) (xy 47.97731 -33.199814) (xy 48.036766 -33.207642)
			(xy 48.094691 -33.223163) (xy 48.150095 -33.246112) (xy 48.202029 -33.276096) (xy 48.249605 -33.312602)
			(xy 48.29201 -33.355007) (xy 48.328516 -33.402583) (xy 48.3585 -33.454517) (xy 48.381449 -33.509921)
			(xy 48.39697 -33.567846) (xy 48.404798 -33.627302) (xy 48.405288 -33.657286) (xy 48.405288 -34.520886)
			(xy 48.405263 -34.52241) (xy 58.75274 -34.52241) (xy 58.75274 -33.65881) (xy 58.75323 -33.628842)
			(xy 58.761053 -33.56942) (xy 58.776566 -33.511527) (xy 58.799502 -33.456154) (xy 58.829469 -33.404248)
			(xy 58.865956 -33.356698) (xy 58.908336 -33.314318) (xy 58.955886 -33.277831) (xy 59.007792 -33.247864)
			(xy 59.063165 -33.224928) (xy 59.121058 -33.209415) (xy 59.18048 -33.201592) (xy 59.240416 -33.201592)
			(xy 59.299838 -33.209415) (xy 59.357731 -33.224928) (xy 59.413104 -33.247864) (xy 59.46501 -33.277831)
			(xy 59.51256 -33.314318) (xy 59.55494 -33.356698) (xy 59.591427 -33.404248) (xy 59.621394 -33.456154)
			(xy 59.64433 -33.511527) (xy 59.659843 -33.56942) (xy 59.667666 -33.628842) (xy 59.668156 -33.65881)
			(xy 59.668156 -34.520886) (xy 73.489312 -34.520886) (xy 73.489312 -33.657286) (xy 73.489802 -33.627302)
			(xy 73.49763 -33.567846) (xy 73.513151 -33.509921) (xy 73.5361 -33.454517) (xy 73.566084 -33.402583)
			(xy 73.60259 -33.355007) (xy 73.644995 -33.312602) (xy 73.692571 -33.276096) (xy 73.744505 -33.246112)
			(xy 73.799909 -33.223163) (xy 73.857834 -33.207642) (xy 73.91729 -33.199814) (xy 73.977258 -33.199814)
			(xy 74.036714 -33.207642) (xy 74.094639 -33.223163) (xy 74.150043 -33.246112) (xy 74.201977 -33.276096)
			(xy 74.249553 -33.312602) (xy 74.291958 -33.355007) (xy 74.328464 -33.402583) (xy 74.358448 -33.454517)
			(xy 74.381397 -33.509921) (xy 74.396918 -33.567846) (xy 74.404746 -33.627302) (xy 74.405236 -33.657286)
			(xy 74.405236 -34.520886) (xy 74.405211 -34.52241) (xy 84.752688 -34.52241) (xy 84.752688 -33.65881)
			(xy 84.753178 -33.628842) (xy 84.761001 -33.56942) (xy 84.776514 -33.511527) (xy 84.79945 -33.456154)
			(xy 84.829417 -33.404248) (xy 84.865904 -33.356698) (xy 84.908284 -33.314318) (xy 84.955834 -33.277831)
			(xy 85.00774 -33.247864) (xy 85.063113 -33.224928) (xy 85.121006 -33.209415) (xy 85.180428 -33.201592)
			(xy 85.240364 -33.201592) (xy 85.299786 -33.209415) (xy 85.357679 -33.224928) (xy 85.413052 -33.247864)
			(xy 85.464958 -33.277831) (xy 85.512508 -33.314318) (xy 85.554888 -33.356698) (xy 85.591375 -33.404248)
			(xy 85.621342 -33.456154) (xy 85.644278 -33.511527) (xy 85.659791 -33.56942) (xy 85.667614 -33.628842)
			(xy 85.668104 -33.65881) (xy 85.668104 -34.520886) (xy 99.48926 -34.520886) (xy 99.48926 -33.657286)
			(xy 99.48975 -33.627302) (xy 99.497578 -33.567846) (xy 99.513099 -33.509921) (xy 99.536048 -33.454517)
			(xy 99.566032 -33.402583) (xy 99.602538 -33.355007) (xy 99.644943 -33.312602) (xy 99.692519 -33.276096)
			(xy 99.744453 -33.246112) (xy 99.799857 -33.223163) (xy 99.857782 -33.207642) (xy 99.917238 -33.199814)
			(xy 99.977206 -33.199814) (xy 100.036662 -33.207642) (xy 100.094587 -33.223163) (xy 100.149991 -33.246112)
			(xy 100.201925 -33.276096) (xy 100.249501 -33.312602) (xy 100.291906 -33.355007) (xy 100.328412 -33.402583)
			(xy 100.358396 -33.454517) (xy 100.381345 -33.509921) (xy 100.396866 -33.567846) (xy 100.404694 -33.627302)
			(xy 100.405184 -33.657286) (xy 100.405184 -34.520886) (xy 100.405159 -34.52241) (xy 122.852688 -34.52241)
			(xy 122.852688 -33.65881) (xy 122.853178 -33.628826) (xy 122.861006 -33.56937) (xy 122.876527 -33.511445)
			(xy 122.899476 -33.456041) (xy 122.92946 -33.404107) (xy 122.965966 -33.356531) (xy 123.008371 -33.314126)
			(xy 123.055947 -33.27762) (xy 123.107881 -33.247636) (xy 123.163285 -33.224687) (xy 123.22121 -33.209166)
			(xy 123.280666 -33.201338) (xy 123.340634 -33.201338) (xy 123.40009 -33.209166) (xy 123.458015 -33.224687)
			(xy 123.513419 -33.247636) (xy 123.565353 -33.27762) (xy 123.612929 -33.314126) (xy 123.655334 -33.356531)
			(xy 123.69184 -33.404107) (xy 123.721824 -33.456041) (xy 123.744773 -33.511445) (xy 123.760294 -33.56937)
			(xy 123.768122 -33.628826) (xy 123.768612 -33.65881) (xy 123.768612 -34.520886) (xy 137.589768 -34.520886)
			(xy 137.589768 -33.657286) (xy 137.590258 -33.627318) (xy 137.598081 -33.567896) (xy 137.613594 -33.510003)
			(xy 137.63653 -33.45463) (xy 137.666497 -33.402724) (xy 137.702984 -33.355174) (xy 137.745364 -33.312794)
			(xy 137.792914 -33.276307) (xy 137.84482 -33.24634) (xy 137.900193 -33.223404) (xy 137.958086 -33.207891)
			(xy 138.017508 -33.200068) (xy 138.077444 -33.200068) (xy 138.136866 -33.207891) (xy 138.194759 -33.223404)
			(xy 138.250132 -33.24634) (xy 138.302038 -33.276307) (xy 138.349588 -33.312794) (xy 138.391968 -33.355174)
			(xy 138.428455 -33.402724) (xy 138.458422 -33.45463) (xy 138.481358 -33.510003) (xy 138.496871 -33.567896)
			(xy 138.504694 -33.627318) (xy 138.505184 -33.657286) (xy 138.505184 -34.520886) (xy 138.505159 -34.52241)
			(xy 148.852636 -34.52241) (xy 148.852636 -33.65881) (xy 148.853126 -33.628826) (xy 148.860954 -33.56937)
			(xy 148.876475 -33.511445) (xy 148.899424 -33.456041) (xy 148.929408 -33.404107) (xy 148.965914 -33.356531)
			(xy 149.008319 -33.314126) (xy 149.055895 -33.27762) (xy 149.107829 -33.247636) (xy 149.163233 -33.224687)
			(xy 149.221158 -33.209166) (xy 149.280614 -33.201338) (xy 149.340582 -33.201338) (xy 149.400038 -33.209166)
			(xy 149.457963 -33.224687) (xy 149.513367 -33.247636) (xy 149.565301 -33.27762) (xy 149.612877 -33.314126)
			(xy 149.655282 -33.356531) (xy 149.691788 -33.404107) (xy 149.721772 -33.456041) (xy 149.744721 -33.511445)
			(xy 149.760242 -33.56937) (xy 149.76807 -33.628826) (xy 149.76856 -33.65881) (xy 149.76856 -34.520886)
			(xy 163.589716 -34.520886) (xy 163.589716 -33.657286) (xy 163.590206 -33.627318) (xy 163.598029 -33.567896)
			(xy 163.613542 -33.510003) (xy 163.636478 -33.45463) (xy 163.666445 -33.402724) (xy 163.702932 -33.355174)
			(xy 163.745312 -33.312794) (xy 163.792862 -33.276307) (xy 163.844768 -33.24634) (xy 163.900141 -33.223404)
			(xy 163.958034 -33.207891) (xy 164.017456 -33.200068) (xy 164.077392 -33.200068) (xy 164.136814 -33.207891)
			(xy 164.194707 -33.223404) (xy 164.25008 -33.24634) (xy 164.301986 -33.276307) (xy 164.349536 -33.312794)
			(xy 164.391916 -33.355174) (xy 164.428403 -33.402724) (xy 164.45837 -33.45463) (xy 164.481306 -33.510003)
			(xy 164.496819 -33.567896) (xy 164.504642 -33.627318) (xy 164.505132 -33.657286) (xy 164.505132 -34.520886)
			(xy 164.505107 -34.52241) (xy 174.852584 -34.52241) (xy 174.852584 -33.65881) (xy 174.853074 -33.628826)
			(xy 174.860902 -33.56937) (xy 174.876423 -33.511445) (xy 174.899372 -33.456041) (xy 174.929356 -33.404107)
			(xy 174.965862 -33.356531) (xy 175.008267 -33.314126) (xy 175.055843 -33.27762) (xy 175.107777 -33.247636)
			(xy 175.163181 -33.224687) (xy 175.221106 -33.209166) (xy 175.280562 -33.201338) (xy 175.34053 -33.201338)
			(xy 175.399986 -33.209166) (xy 175.457911 -33.224687) (xy 175.513315 -33.247636) (xy 175.565249 -33.27762)
			(xy 175.612825 -33.314126) (xy 175.65523 -33.356531) (xy 175.691736 -33.404107) (xy 175.72172 -33.456041)
			(xy 175.744669 -33.511445) (xy 175.76019 -33.56937) (xy 175.768018 -33.628826) (xy 175.768508 -33.65881)
			(xy 175.768508 -34.520886) (xy 189.589664 -34.520886) (xy 189.589664 -33.657286) (xy 189.590154 -33.627318)
			(xy 189.597977 -33.567896) (xy 189.61349 -33.510003) (xy 189.636426 -33.45463) (xy 189.666393 -33.402724)
			(xy 189.70288 -33.355174) (xy 189.74526 -33.312794) (xy 189.79281 -33.276307) (xy 189.844716 -33.24634)
			(xy 189.900089 -33.223404) (xy 189.957982 -33.207891) (xy 190.017404 -33.200068) (xy 190.07734 -33.200068)
			(xy 190.136762 -33.207891) (xy 190.194655 -33.223404) (xy 190.250028 -33.24634) (xy 190.301934 -33.276307)
			(xy 190.349484 -33.312794) (xy 190.391864 -33.355174) (xy 190.428351 -33.402724) (xy 190.458318 -33.45463)
			(xy 190.481254 -33.510003) (xy 190.496767 -33.567896) (xy 190.50459 -33.627318) (xy 190.50508 -33.657286)
			(xy 190.50508 -34.520886) (xy 190.505055 -34.52241) (xy 200.852532 -34.52241) (xy 200.852532 -33.65881)
			(xy 200.853022 -33.628826) (xy 200.86085 -33.56937) (xy 200.876371 -33.511445) (xy 200.89932 -33.456041)
			(xy 200.929304 -33.404107) (xy 200.96581 -33.356531) (xy 201.008215 -33.314126) (xy 201.055791 -33.27762)
			(xy 201.107725 -33.247636) (xy 201.163129 -33.224687) (xy 201.221054 -33.209166) (xy 201.28051 -33.201338)
			(xy 201.340478 -33.201338) (xy 201.399934 -33.209166) (xy 201.457859 -33.224687) (xy 201.513263 -33.247636)
			(xy 201.565197 -33.27762) (xy 201.612773 -33.314126) (xy 201.655178 -33.356531) (xy 201.691684 -33.404107)
			(xy 201.721668 -33.456041) (xy 201.744617 -33.511445) (xy 201.760138 -33.56937) (xy 201.767966 -33.628826)
			(xy 201.768456 -33.65881) (xy 201.768456 -34.520886) (xy 215.589612 -34.520886) (xy 215.589612 -33.657286)
			(xy 215.590102 -33.627318) (xy 215.597925 -33.567896) (xy 215.613438 -33.510003) (xy 215.636374 -33.45463)
			(xy 215.666341 -33.402724) (xy 215.702828 -33.355174) (xy 215.745208 -33.312794) (xy 215.792758 -33.276307)
			(xy 215.844664 -33.24634) (xy 215.900037 -33.223404) (xy 215.95793 -33.207891) (xy 216.017352 -33.200068)
			(xy 216.077288 -33.200068) (xy 216.13671 -33.207891) (xy 216.194603 -33.223404) (xy 216.249976 -33.24634)
			(xy 216.301882 -33.276307) (xy 216.349432 -33.312794) (xy 216.391812 -33.355174) (xy 216.428299 -33.402724)
			(xy 216.458266 -33.45463) (xy 216.481202 -33.510003) (xy 216.496715 -33.567896) (xy 216.504538 -33.627318)
			(xy 216.505028 -33.657286) (xy 216.505028 -34.520886) (xy 216.505003 -34.52241) (xy 238.952532 -34.52241)
			(xy 238.952532 -33.65881) (xy 238.953022 -33.628826) (xy 238.96085 -33.56937) (xy 238.976371 -33.511445)
			(xy 238.99932 -33.456041) (xy 239.029304 -33.404107) (xy 239.06581 -33.356531) (xy 239.108215 -33.314126)
			(xy 239.155791 -33.27762) (xy 239.207725 -33.247636) (xy 239.263129 -33.224687) (xy 239.321054 -33.209166)
			(xy 239.38051 -33.201338) (xy 239.440478 -33.201338) (xy 239.499934 -33.209166) (xy 239.557859 -33.224687)
			(xy 239.613263 -33.247636) (xy 239.665197 -33.27762) (xy 239.712773 -33.314126) (xy 239.755178 -33.356531)
			(xy 239.791684 -33.404107) (xy 239.821668 -33.456041) (xy 239.844617 -33.511445) (xy 239.860138 -33.56937)
			(xy 239.867966 -33.628826) (xy 239.868456 -33.65881) (xy 239.868456 -34.520886) (xy 253.689612 -34.520886)
			(xy 253.689612 -33.657286) (xy 253.690102 -33.627318) (xy 253.697925 -33.567896) (xy 253.713438 -33.510003)
			(xy 253.736374 -33.45463) (xy 253.766341 -33.402724) (xy 253.802828 -33.355174) (xy 253.845208 -33.312794)
			(xy 253.892758 -33.276307) (xy 253.944664 -33.24634) (xy 254.000037 -33.223404) (xy 254.05793 -33.207891)
			(xy 254.117352 -33.200068) (xy 254.177288 -33.200068) (xy 254.23671 -33.207891) (xy 254.294603 -33.223404)
			(xy 254.349976 -33.24634) (xy 254.401882 -33.276307) (xy 254.449432 -33.312794) (xy 254.491812 -33.355174)
			(xy 254.528299 -33.402724) (xy 254.558266 -33.45463) (xy 254.581202 -33.510003) (xy 254.596715 -33.567896)
			(xy 254.604538 -33.627318) (xy 254.605028 -33.657286) (xy 254.605028 -34.520886) (xy 254.605003 -34.52241)
			(xy 264.95248 -34.52241) (xy 264.95248 -33.65881) (xy 264.95297 -33.628826) (xy 264.960798 -33.56937)
			(xy 264.976319 -33.511445) (xy 264.999268 -33.456041) (xy 265.029252 -33.404107) (xy 265.065758 -33.356531)
			(xy 265.108163 -33.314126) (xy 265.155739 -33.27762) (xy 265.207673 -33.247636) (xy 265.263077 -33.224687)
			(xy 265.321002 -33.209166) (xy 265.380458 -33.201338) (xy 265.440426 -33.201338) (xy 265.499882 -33.209166)
			(xy 265.557807 -33.224687) (xy 265.613211 -33.247636) (xy 265.665145 -33.27762) (xy 265.712721 -33.314126)
			(xy 265.755126 -33.356531) (xy 265.791632 -33.404107) (xy 265.821616 -33.456041) (xy 265.844565 -33.511445)
			(xy 265.860086 -33.56937) (xy 265.867914 -33.628826) (xy 265.868404 -33.65881) (xy 265.868404 -34.520886)
			(xy 279.68956 -34.520886) (xy 279.68956 -33.657286) (xy 279.69005 -33.627318) (xy 279.697873 -33.567896)
			(xy 279.713386 -33.510003) (xy 279.736322 -33.45463) (xy 279.766289 -33.402724) (xy 279.802776 -33.355174)
			(xy 279.845156 -33.312794) (xy 279.892706 -33.276307) (xy 279.944612 -33.24634) (xy 279.999985 -33.223404)
			(xy 280.057878 -33.207891) (xy 280.1173 -33.200068) (xy 280.177236 -33.200068) (xy 280.236658 -33.207891)
			(xy 280.294551 -33.223404) (xy 280.349924 -33.24634) (xy 280.40183 -33.276307) (xy 280.44938 -33.312794)
			(xy 280.49176 -33.355174) (xy 280.528247 -33.402724) (xy 280.558214 -33.45463) (xy 280.58115 -33.510003)
			(xy 280.596663 -33.567896) (xy 280.604486 -33.627318) (xy 280.604976 -33.657286) (xy 280.604976 -34.520886)
			(xy 280.604951 -34.52241) (xy 290.952428 -34.52241) (xy 290.952428 -33.65881) (xy 290.952918 -33.628826)
			(xy 290.960746 -33.56937) (xy 290.976267 -33.511445) (xy 290.999216 -33.456041) (xy 291.0292 -33.404107)
			(xy 291.065706 -33.356531) (xy 291.108111 -33.314126) (xy 291.155687 -33.27762) (xy 291.207621 -33.247636)
			(xy 291.263025 -33.224687) (xy 291.32095 -33.209166) (xy 291.380406 -33.201338) (xy 291.440374 -33.201338)
			(xy 291.49983 -33.209166) (xy 291.557755 -33.224687) (xy 291.613159 -33.247636) (xy 291.665093 -33.27762)
			(xy 291.712669 -33.314126) (xy 291.755074 -33.356531) (xy 291.79158 -33.404107) (xy 291.821564 -33.456041)
			(xy 291.844513 -33.511445) (xy 291.860034 -33.56937) (xy 291.867862 -33.628826) (xy 291.868352 -33.65881)
			(xy 291.868352 -34.520886) (xy 305.689508 -34.520886) (xy 305.689508 -33.657286) (xy 305.689998 -33.627318)
			(xy 305.697821 -33.567896) (xy 305.713334 -33.510003) (xy 305.73627 -33.45463) (xy 305.766237 -33.402724)
			(xy 305.802724 -33.355174) (xy 305.845104 -33.312794) (xy 305.892654 -33.276307) (xy 305.94456 -33.24634)
			(xy 305.999933 -33.223404) (xy 306.057826 -33.207891) (xy 306.117248 -33.200068) (xy 306.177184 -33.200068)
			(xy 306.236606 -33.207891) (xy 306.294499 -33.223404) (xy 306.349872 -33.24634) (xy 306.401778 -33.276307)
			(xy 306.449328 -33.312794) (xy 306.491708 -33.355174) (xy 306.528195 -33.402724) (xy 306.558162 -33.45463)
			(xy 306.581098 -33.510003) (xy 306.596611 -33.567896) (xy 306.604434 -33.627318) (xy 306.604924 -33.657286)
			(xy 306.604924 -34.520886) (xy 306.604899 -34.52241) (xy 316.952376 -34.52241) (xy 316.952376 -33.65881)
			(xy 316.952866 -33.628826) (xy 316.960694 -33.56937) (xy 316.976215 -33.511445) (xy 316.999164 -33.456041)
			(xy 317.029148 -33.404107) (xy 317.065654 -33.356531) (xy 317.108059 -33.314126) (xy 317.155635 -33.27762)
			(xy 317.207569 -33.247636) (xy 317.262973 -33.224687) (xy 317.320898 -33.209166) (xy 317.380354 -33.201338)
			(xy 317.440322 -33.201338) (xy 317.499778 -33.209166) (xy 317.557703 -33.224687) (xy 317.613107 -33.247636)
			(xy 317.665041 -33.27762) (xy 317.712617 -33.314126) (xy 317.755022 -33.356531) (xy 317.791528 -33.404107)
			(xy 317.821512 -33.456041) (xy 317.844461 -33.511445) (xy 317.859982 -33.56937) (xy 317.86781 -33.628826)
			(xy 317.8683 -33.65881) (xy 317.8683 -34.520886) (xy 331.689456 -34.520886) (xy 331.689456 -33.657286)
			(xy 331.689946 -33.627318) (xy 331.697769 -33.567896) (xy 331.713282 -33.510003) (xy 331.736218 -33.45463)
			(xy 331.766185 -33.402724) (xy 331.802672 -33.355174) (xy 331.845052 -33.312794) (xy 331.892602 -33.276307)
			(xy 331.944508 -33.24634) (xy 331.999881 -33.223404) (xy 332.057774 -33.207891) (xy 332.117196 -33.200068)
			(xy 332.177132 -33.200068) (xy 332.236554 -33.207891) (xy 332.294447 -33.223404) (xy 332.34982 -33.24634)
			(xy 332.401726 -33.276307) (xy 332.449276 -33.312794) (xy 332.491656 -33.355174) (xy 332.528143 -33.402724)
			(xy 332.55811 -33.45463) (xy 332.581046 -33.510003) (xy 332.596559 -33.567896) (xy 332.604382 -33.627318)
			(xy 332.604872 -33.657286) (xy 332.604872 -34.520886) (xy 332.604847 -34.52241) (xy 355.052884 -34.52241)
			(xy 355.052884 -33.65881) (xy 355.053374 -33.628842) (xy 355.061197 -33.56942) (xy 355.07671 -33.511527)
			(xy 355.099646 -33.456154) (xy 355.129613 -33.404248) (xy 355.1661 -33.356698) (xy 355.20848 -33.314318)
			(xy 355.25603 -33.277831) (xy 355.307936 -33.247864) (xy 355.363309 -33.224928) (xy 355.421202 -33.209415)
			(xy 355.480624 -33.201592) (xy 355.54056 -33.201592) (xy 355.599982 -33.209415) (xy 355.657875 -33.224928)
			(xy 355.713248 -33.247864) (xy 355.765154 -33.277831) (xy 355.812704 -33.314318) (xy 355.855084 -33.356698)
			(xy 355.891571 -33.404248) (xy 355.921538 -33.456154) (xy 355.944474 -33.511527) (xy 355.959987 -33.56942)
			(xy 355.96781 -33.628842) (xy 355.9683 -33.65881) (xy 355.9683 -34.520886) (xy 369.789456 -34.520886)
			(xy 369.789456 -33.657286) (xy 369.789946 -33.627302) (xy 369.797774 -33.567846) (xy 369.813295 -33.509921)
			(xy 369.836244 -33.454517) (xy 369.866228 -33.402583) (xy 369.902734 -33.355007) (xy 369.945139 -33.312602)
			(xy 369.992715 -33.276096) (xy 370.044649 -33.246112) (xy 370.100053 -33.223163) (xy 370.157978 -33.207642)
			(xy 370.217434 -33.199814) (xy 370.277402 -33.199814) (xy 370.336858 -33.207642) (xy 370.394783 -33.223163)
			(xy 370.450187 -33.246112) (xy 370.502121 -33.276096) (xy 370.549697 -33.312602) (xy 370.592102 -33.355007)
			(xy 370.628608 -33.402583) (xy 370.658592 -33.454517) (xy 370.681541 -33.509921) (xy 370.697062 -33.567846)
			(xy 370.70489 -33.627302) (xy 370.70538 -33.657286) (xy 370.70538 -34.520886) (xy 370.705355 -34.52241)
			(xy 381.052832 -34.52241) (xy 381.052832 -33.65881) (xy 381.053322 -33.628842) (xy 381.061145 -33.56942)
			(xy 381.076658 -33.511527) (xy 381.099594 -33.456154) (xy 381.129561 -33.404248) (xy 381.166048 -33.356698)
			(xy 381.208428 -33.314318) (xy 381.255978 -33.277831) (xy 381.307884 -33.247864) (xy 381.363257 -33.224928)
			(xy 381.42115 -33.209415) (xy 381.480572 -33.201592) (xy 381.540508 -33.201592) (xy 381.59993 -33.209415)
			(xy 381.657823 -33.224928) (xy 381.713196 -33.247864) (xy 381.765102 -33.277831) (xy 381.812652 -33.314318)
			(xy 381.855032 -33.356698) (xy 381.891519 -33.404248) (xy 381.921486 -33.456154) (xy 381.944422 -33.511527)
			(xy 381.959935 -33.56942) (xy 381.967758 -33.628842) (xy 381.968248 -33.65881) (xy 381.968248 -34.520886)
			(xy 395.789404 -34.520886) (xy 395.789404 -33.657286) (xy 395.789894 -33.627302) (xy 395.797722 -33.567846)
			(xy 395.813243 -33.509921) (xy 395.836192 -33.454517) (xy 395.866176 -33.402583) (xy 395.902682 -33.355007)
			(xy 395.945087 -33.312602) (xy 395.992663 -33.276096) (xy 396.044597 -33.246112) (xy 396.100001 -33.223163)
			(xy 396.157926 -33.207642) (xy 396.217382 -33.199814) (xy 396.27735 -33.199814) (xy 396.336806 -33.207642)
			(xy 396.394731 -33.223163) (xy 396.450135 -33.246112) (xy 396.502069 -33.276096) (xy 396.549645 -33.312602)
			(xy 396.59205 -33.355007) (xy 396.628556 -33.402583) (xy 396.65854 -33.454517) (xy 396.681489 -33.509921)
			(xy 396.69701 -33.567846) (xy 396.704838 -33.627302) (xy 396.705328 -33.657286) (xy 396.705328 -34.520886)
			(xy 396.705303 -34.52241) (xy 407.05278 -34.52241) (xy 407.05278 -33.65881) (xy 407.05327 -33.628842)
			(xy 407.061093 -33.56942) (xy 407.076606 -33.511527) (xy 407.099542 -33.456154) (xy 407.129509 -33.404248)
			(xy 407.165996 -33.356698) (xy 407.208376 -33.314318) (xy 407.255926 -33.277831) (xy 407.307832 -33.247864)
			(xy 407.363205 -33.224928) (xy 407.421098 -33.209415) (xy 407.48052 -33.201592) (xy 407.540456 -33.201592)
			(xy 407.599878 -33.209415) (xy 407.657771 -33.224928) (xy 407.713144 -33.247864) (xy 407.76505 -33.277831)
			(xy 407.8126 -33.314318) (xy 407.85498 -33.356698) (xy 407.891467 -33.404248) (xy 407.921434 -33.456154)
			(xy 407.94437 -33.511527) (xy 407.959883 -33.56942) (xy 407.967706 -33.628842) (xy 407.968196 -33.65881)
			(xy 407.968196 -34.520886) (xy 421.789352 -34.520886) (xy 421.789352 -33.657286) (xy 421.789842 -33.627302)
			(xy 421.79767 -33.567846) (xy 421.813191 -33.509921) (xy 421.83614 -33.454517) (xy 421.866124 -33.402583)
			(xy 421.90263 -33.355007) (xy 421.945035 -33.312602) (xy 421.992611 -33.276096) (xy 422.044545 -33.246112)
			(xy 422.099949 -33.223163) (xy 422.157874 -33.207642) (xy 422.21733 -33.199814) (xy 422.277298 -33.199814)
			(xy 422.336754 -33.207642) (xy 422.394679 -33.223163) (xy 422.450083 -33.246112) (xy 422.502017 -33.276096)
			(xy 422.549593 -33.312602) (xy 422.591998 -33.355007) (xy 422.628504 -33.402583) (xy 422.658488 -33.454517)
			(xy 422.681437 -33.509921) (xy 422.696958 -33.567846) (xy 422.704786 -33.627302) (xy 422.705276 -33.657286)
			(xy 422.705276 -34.520886) (xy 422.705251 -34.52241) (xy 433.052728 -34.52241) (xy 433.052728 -33.65881)
			(xy 433.053218 -33.628842) (xy 433.061041 -33.56942) (xy 433.076554 -33.511527) (xy 433.09949 -33.456154)
			(xy 433.129457 -33.404248) (xy 433.165944 -33.356698) (xy 433.208324 -33.314318) (xy 433.255874 -33.277831)
			(xy 433.30778 -33.247864) (xy 433.363153 -33.224928) (xy 433.421046 -33.209415) (xy 433.480468 -33.201592)
			(xy 433.540404 -33.201592) (xy 433.599826 -33.209415) (xy 433.657719 -33.224928) (xy 433.713092 -33.247864)
			(xy 433.764998 -33.277831) (xy 433.812548 -33.314318) (xy 433.854928 -33.356698) (xy 433.891415 -33.404248)
			(xy 433.921382 -33.456154) (xy 433.944318 -33.511527) (xy 433.959831 -33.56942) (xy 433.967654 -33.628842)
			(xy 433.968144 -33.65881) (xy 433.968144 -34.520886) (xy 447.7893 -34.520886) (xy 447.7893 -33.657286)
			(xy 447.78979 -33.627302) (xy 447.797618 -33.567846) (xy 447.813139 -33.509921) (xy 447.836088 -33.454517)
			(xy 447.866072 -33.402583) (xy 447.902578 -33.355007) (xy 447.944983 -33.312602) (xy 447.992559 -33.276096)
			(xy 448.044493 -33.246112) (xy 448.099897 -33.223163) (xy 448.157822 -33.207642) (xy 448.217278 -33.199814)
			(xy 448.277246 -33.199814) (xy 448.336702 -33.207642) (xy 448.394627 -33.223163) (xy 448.450031 -33.246112)
			(xy 448.501965 -33.276096) (xy 448.549541 -33.312602) (xy 448.591946 -33.355007) (xy 448.628452 -33.402583)
			(xy 448.658436 -33.454517) (xy 448.681385 -33.509921) (xy 448.696906 -33.567846) (xy 448.704734 -33.627302)
			(xy 448.705224 -33.657286) (xy 448.705224 -34.520886) (xy 448.704734 -34.55087) (xy 448.696906 -34.610326)
			(xy 448.681385 -34.668251) (xy 448.658436 -34.723655) (xy 448.628452 -34.775589) (xy 448.591946 -34.823165)
			(xy 448.549541 -34.86557) (xy 448.501965 -34.902076) (xy 448.450031 -34.93206) (xy 448.394627 -34.955009)
			(xy 448.336702 -34.97053) (xy 448.277246 -34.978358) (xy 448.217278 -34.978358) (xy 448.157822 -34.97053)
			(xy 448.099897 -34.955009) (xy 448.044493 -34.93206) (xy 447.992559 -34.902076) (xy 447.944983 -34.86557)
			(xy 447.902578 -34.823165) (xy 447.866072 -34.775589) (xy 447.836088 -34.723655) (xy 447.813139 -34.668251)
			(xy 447.797618 -34.610326) (xy 447.78979 -34.55087) (xy 447.7893 -34.520886) (xy 433.968144 -34.520886)
			(xy 433.968144 -34.52241) (xy 433.967654 -34.552378) (xy 433.959831 -34.6118) (xy 433.944318 -34.669693)
			(xy 433.921382 -34.725066) (xy 433.891415 -34.776972) (xy 433.854928 -34.824522) (xy 433.812548 -34.866902)
			(xy 433.764998 -34.903389) (xy 433.713092 -34.933356) (xy 433.657719 -34.956292) (xy 433.599826 -34.971805)
			(xy 433.540404 -34.979628) (xy 433.480468 -34.979628) (xy 433.421046 -34.971805) (xy 433.363153 -34.956292)
			(xy 433.30778 -34.933356) (xy 433.255874 -34.903389) (xy 433.208324 -34.866902) (xy 433.165944 -34.824522)
			(xy 433.129457 -34.776972) (xy 433.09949 -34.725066) (xy 433.076554 -34.669693) (xy 433.061041 -34.6118)
			(xy 433.053218 -34.552378) (xy 433.052728 -34.52241) (xy 422.705251 -34.52241) (xy 422.704786 -34.55087)
			(xy 422.696958 -34.610326) (xy 422.681437 -34.668251) (xy 422.658488 -34.723655) (xy 422.628504 -34.775589)
			(xy 422.591998 -34.823165) (xy 422.549593 -34.86557) (xy 422.502017 -34.902076) (xy 422.450083 -34.93206)
			(xy 422.394679 -34.955009) (xy 422.336754 -34.97053) (xy 422.277298 -34.978358) (xy 422.21733 -34.978358)
			(xy 422.157874 -34.97053) (xy 422.099949 -34.955009) (xy 422.044545 -34.93206) (xy 421.992611 -34.902076)
			(xy 421.945035 -34.86557) (xy 421.90263 -34.823165) (xy 421.866124 -34.775589) (xy 421.83614 -34.723655)
			(xy 421.813191 -34.668251) (xy 421.79767 -34.610326) (xy 421.789842 -34.55087) (xy 421.789352 -34.520886)
			(xy 407.968196 -34.520886) (xy 407.968196 -34.52241) (xy 407.967706 -34.552378) (xy 407.959883 -34.6118)
			(xy 407.94437 -34.669693) (xy 407.921434 -34.725066) (xy 407.891467 -34.776972) (xy 407.85498 -34.824522)
			(xy 407.8126 -34.866902) (xy 407.76505 -34.903389) (xy 407.713144 -34.933356) (xy 407.657771 -34.956292)
			(xy 407.599878 -34.971805) (xy 407.540456 -34.979628) (xy 407.48052 -34.979628) (xy 407.421098 -34.971805)
			(xy 407.363205 -34.956292) (xy 407.307832 -34.933356) (xy 407.255926 -34.903389) (xy 407.208376 -34.866902)
			(xy 407.165996 -34.824522) (xy 407.129509 -34.776972) (xy 407.099542 -34.725066) (xy 407.076606 -34.669693)
			(xy 407.061093 -34.6118) (xy 407.05327 -34.552378) (xy 407.05278 -34.52241) (xy 396.705303 -34.52241)
			(xy 396.704838 -34.55087) (xy 396.69701 -34.610326) (xy 396.681489 -34.668251) (xy 396.65854 -34.723655)
			(xy 396.628556 -34.775589) (xy 396.59205 -34.823165) (xy 396.549645 -34.86557) (xy 396.502069 -34.902076)
			(xy 396.450135 -34.93206) (xy 396.394731 -34.955009) (xy 396.336806 -34.97053) (xy 396.27735 -34.978358)
			(xy 396.217382 -34.978358) (xy 396.157926 -34.97053) (xy 396.100001 -34.955009) (xy 396.044597 -34.93206)
			(xy 395.992663 -34.902076) (xy 395.945087 -34.86557) (xy 395.902682 -34.823165) (xy 395.866176 -34.775589)
			(xy 395.836192 -34.723655) (xy 395.813243 -34.668251) (xy 395.797722 -34.610326) (xy 395.789894 -34.55087)
			(xy 395.789404 -34.520886) (xy 381.968248 -34.520886) (xy 381.968248 -34.52241) (xy 381.967758 -34.552378)
			(xy 381.959935 -34.6118) (xy 381.944422 -34.669693) (xy 381.921486 -34.725066) (xy 381.891519 -34.776972)
			(xy 381.855032 -34.824522) (xy 381.812652 -34.866902) (xy 381.765102 -34.903389) (xy 381.713196 -34.933356)
			(xy 381.657823 -34.956292) (xy 381.59993 -34.971805) (xy 381.540508 -34.979628) (xy 381.480572 -34.979628)
			(xy 381.42115 -34.971805) (xy 381.363257 -34.956292) (xy 381.307884 -34.933356) (xy 381.255978 -34.903389)
			(xy 381.208428 -34.866902) (xy 381.166048 -34.824522) (xy 381.129561 -34.776972) (xy 381.099594 -34.725066)
			(xy 381.076658 -34.669693) (xy 381.061145 -34.6118) (xy 381.053322 -34.552378) (xy 381.052832 -34.52241)
			(xy 370.705355 -34.52241) (xy 370.70489 -34.55087) (xy 370.697062 -34.610326) (xy 370.681541 -34.668251)
			(xy 370.658592 -34.723655) (xy 370.628608 -34.775589) (xy 370.592102 -34.823165) (xy 370.549697 -34.86557)
			(xy 370.502121 -34.902076) (xy 370.450187 -34.93206) (xy 370.394783 -34.955009) (xy 370.336858 -34.97053)
			(xy 370.277402 -34.978358) (xy 370.217434 -34.978358) (xy 370.157978 -34.97053) (xy 370.100053 -34.955009)
			(xy 370.044649 -34.93206) (xy 369.992715 -34.902076) (xy 369.945139 -34.86557) (xy 369.902734 -34.823165)
			(xy 369.866228 -34.775589) (xy 369.836244 -34.723655) (xy 369.813295 -34.668251) (xy 369.797774 -34.610326)
			(xy 369.789946 -34.55087) (xy 369.789456 -34.520886) (xy 355.9683 -34.520886) (xy 355.9683 -34.52241)
			(xy 355.96781 -34.552378) (xy 355.959987 -34.6118) (xy 355.944474 -34.669693) (xy 355.921538 -34.725066)
			(xy 355.891571 -34.776972) (xy 355.855084 -34.824522) (xy 355.812704 -34.866902) (xy 355.765154 -34.903389)
			(xy 355.713248 -34.933356) (xy 355.657875 -34.956292) (xy 355.599982 -34.971805) (xy 355.54056 -34.979628)
			(xy 355.480624 -34.979628) (xy 355.421202 -34.971805) (xy 355.363309 -34.956292) (xy 355.307936 -34.933356)
			(xy 355.25603 -34.903389) (xy 355.20848 -34.866902) (xy 355.1661 -34.824522) (xy 355.129613 -34.776972)
			(xy 355.099646 -34.725066) (xy 355.07671 -34.669693) (xy 355.061197 -34.6118) (xy 355.053374 -34.552378)
			(xy 355.052884 -34.52241) (xy 332.604847 -34.52241) (xy 332.604382 -34.550854) (xy 332.596559 -34.610276)
			(xy 332.581046 -34.668169) (xy 332.55811 -34.723542) (xy 332.528143 -34.775448) (xy 332.491656 -34.822998)
			(xy 332.449276 -34.865378) (xy 332.401726 -34.901865) (xy 332.34982 -34.931832) (xy 332.294447 -34.954768)
			(xy 332.236554 -34.970281) (xy 332.177132 -34.978104) (xy 332.117196 -34.978104) (xy 332.057774 -34.970281)
			(xy 331.999881 -34.954768) (xy 331.944508 -34.931832) (xy 331.892602 -34.901865) (xy 331.845052 -34.865378)
			(xy 331.802672 -34.822998) (xy 331.766185 -34.775448) (xy 331.736218 -34.723542) (xy 331.713282 -34.668169)
			(xy 331.697769 -34.610276) (xy 331.689946 -34.550854) (xy 331.689456 -34.520886) (xy 317.8683 -34.520886)
			(xy 317.8683 -34.52241) (xy 317.86781 -34.552394) (xy 317.859982 -34.61185) (xy 317.844461 -34.669775)
			(xy 317.821512 -34.725179) (xy 317.791528 -34.777113) (xy 317.755022 -34.824689) (xy 317.712617 -34.867094)
			(xy 317.665041 -34.9036) (xy 317.613107 -34.933584) (xy 317.557703 -34.956533) (xy 317.499778 -34.972054)
			(xy 317.440322 -34.979882) (xy 317.380354 -34.979882) (xy 317.320898 -34.972054) (xy 317.262973 -34.956533)
			(xy 317.207569 -34.933584) (xy 317.155635 -34.9036) (xy 317.108059 -34.867094) (xy 317.065654 -34.824689)
			(xy 317.029148 -34.777113) (xy 316.999164 -34.725179) (xy 316.976215 -34.669775) (xy 316.960694 -34.61185)
			(xy 316.952866 -34.552394) (xy 316.952376 -34.52241) (xy 306.604899 -34.52241) (xy 306.604434 -34.550854)
			(xy 306.596611 -34.610276) (xy 306.581098 -34.668169) (xy 306.558162 -34.723542) (xy 306.528195 -34.775448)
			(xy 306.491708 -34.822998) (xy 306.449328 -34.865378) (xy 306.401778 -34.901865) (xy 306.349872 -34.931832)
			(xy 306.294499 -34.954768) (xy 306.236606 -34.970281) (xy 306.177184 -34.978104) (xy 306.117248 -34.978104)
			(xy 306.057826 -34.970281) (xy 305.999933 -34.954768) (xy 305.94456 -34.931832) (xy 305.892654 -34.901865)
			(xy 305.845104 -34.865378) (xy 305.802724 -34.822998) (xy 305.766237 -34.775448) (xy 305.73627 -34.723542)
			(xy 305.713334 -34.668169) (xy 305.697821 -34.610276) (xy 305.689998 -34.550854) (xy 305.689508 -34.520886)
			(xy 291.868352 -34.520886) (xy 291.868352 -34.52241) (xy 291.867862 -34.552394) (xy 291.860034 -34.61185)
			(xy 291.844513 -34.669775) (xy 291.821564 -34.725179) (xy 291.79158 -34.777113) (xy 291.755074 -34.824689)
			(xy 291.712669 -34.867094) (xy 291.665093 -34.9036) (xy 291.613159 -34.933584) (xy 291.557755 -34.956533)
			(xy 291.49983 -34.972054) (xy 291.440374 -34.979882) (xy 291.380406 -34.979882) (xy 291.32095 -34.972054)
			(xy 291.263025 -34.956533) (xy 291.207621 -34.933584) (xy 291.155687 -34.9036) (xy 291.108111 -34.867094)
			(xy 291.065706 -34.824689) (xy 291.0292 -34.777113) (xy 290.999216 -34.725179) (xy 290.976267 -34.669775)
			(xy 290.960746 -34.61185) (xy 290.952918 -34.552394) (xy 290.952428 -34.52241) (xy 280.604951 -34.52241)
			(xy 280.604486 -34.550854) (xy 280.596663 -34.610276) (xy 280.58115 -34.668169) (xy 280.558214 -34.723542)
			(xy 280.528247 -34.775448) (xy 280.49176 -34.822998) (xy 280.44938 -34.865378) (xy 280.40183 -34.901865)
			(xy 280.349924 -34.931832) (xy 280.294551 -34.954768) (xy 280.236658 -34.970281) (xy 280.177236 -34.978104)
			(xy 280.1173 -34.978104) (xy 280.057878 -34.970281) (xy 279.999985 -34.954768) (xy 279.944612 -34.931832)
			(xy 279.892706 -34.901865) (xy 279.845156 -34.865378) (xy 279.802776 -34.822998) (xy 279.766289 -34.775448)
			(xy 279.736322 -34.723542) (xy 279.713386 -34.668169) (xy 279.697873 -34.610276) (xy 279.69005 -34.550854)
			(xy 279.68956 -34.520886) (xy 265.868404 -34.520886) (xy 265.868404 -34.52241) (xy 265.867914 -34.552394)
			(xy 265.860086 -34.61185) (xy 265.844565 -34.669775) (xy 265.821616 -34.725179) (xy 265.791632 -34.777113)
			(xy 265.755126 -34.824689) (xy 265.712721 -34.867094) (xy 265.665145 -34.9036) (xy 265.613211 -34.933584)
			(xy 265.557807 -34.956533) (xy 265.499882 -34.972054) (xy 265.440426 -34.979882) (xy 265.380458 -34.979882)
			(xy 265.321002 -34.972054) (xy 265.263077 -34.956533) (xy 265.207673 -34.933584) (xy 265.155739 -34.9036)
			(xy 265.108163 -34.867094) (xy 265.065758 -34.824689) (xy 265.029252 -34.777113) (xy 264.999268 -34.725179)
			(xy 264.976319 -34.669775) (xy 264.960798 -34.61185) (xy 264.95297 -34.552394) (xy 264.95248 -34.52241)
			(xy 254.605003 -34.52241) (xy 254.604538 -34.550854) (xy 254.596715 -34.610276) (xy 254.581202 -34.668169)
			(xy 254.558266 -34.723542) (xy 254.528299 -34.775448) (xy 254.491812 -34.822998) (xy 254.449432 -34.865378)
			(xy 254.401882 -34.901865) (xy 254.349976 -34.931832) (xy 254.294603 -34.954768) (xy 254.23671 -34.970281)
			(xy 254.177288 -34.978104) (xy 254.117352 -34.978104) (xy 254.05793 -34.970281) (xy 254.000037 -34.954768)
			(xy 253.944664 -34.931832) (xy 253.892758 -34.901865) (xy 253.845208 -34.865378) (xy 253.802828 -34.822998)
			(xy 253.766341 -34.775448) (xy 253.736374 -34.723542) (xy 253.713438 -34.668169) (xy 253.697925 -34.610276)
			(xy 253.690102 -34.550854) (xy 253.689612 -34.520886) (xy 239.868456 -34.520886) (xy 239.868456 -34.52241)
			(xy 239.867966 -34.552394) (xy 239.860138 -34.61185) (xy 239.844617 -34.669775) (xy 239.821668 -34.725179)
			(xy 239.791684 -34.777113) (xy 239.755178 -34.824689) (xy 239.712773 -34.867094) (xy 239.665197 -34.9036)
			(xy 239.613263 -34.933584) (xy 239.557859 -34.956533) (xy 239.499934 -34.972054) (xy 239.440478 -34.979882)
			(xy 239.38051 -34.979882) (xy 239.321054 -34.972054) (xy 239.263129 -34.956533) (xy 239.207725 -34.933584)
			(xy 239.155791 -34.9036) (xy 239.108215 -34.867094) (xy 239.06581 -34.824689) (xy 239.029304 -34.777113)
			(xy 238.99932 -34.725179) (xy 238.976371 -34.669775) (xy 238.96085 -34.61185) (xy 238.953022 -34.552394)
			(xy 238.952532 -34.52241) (xy 216.505003 -34.52241) (xy 216.504538 -34.550854) (xy 216.496715 -34.610276)
			(xy 216.481202 -34.668169) (xy 216.458266 -34.723542) (xy 216.428299 -34.775448) (xy 216.391812 -34.822998)
			(xy 216.349432 -34.865378) (xy 216.301882 -34.901865) (xy 216.249976 -34.931832) (xy 216.194603 -34.954768)
			(xy 216.13671 -34.970281) (xy 216.077288 -34.978104) (xy 216.017352 -34.978104) (xy 215.95793 -34.970281)
			(xy 215.900037 -34.954768) (xy 215.844664 -34.931832) (xy 215.792758 -34.901865) (xy 215.745208 -34.865378)
			(xy 215.702828 -34.822998) (xy 215.666341 -34.775448) (xy 215.636374 -34.723542) (xy 215.613438 -34.668169)
			(xy 215.597925 -34.610276) (xy 215.590102 -34.550854) (xy 215.589612 -34.520886) (xy 201.768456 -34.520886)
			(xy 201.768456 -34.52241) (xy 201.767966 -34.552394) (xy 201.760138 -34.61185) (xy 201.744617 -34.669775)
			(xy 201.721668 -34.725179) (xy 201.691684 -34.777113) (xy 201.655178 -34.824689) (xy 201.612773 -34.867094)
			(xy 201.565197 -34.9036) (xy 201.513263 -34.933584) (xy 201.457859 -34.956533) (xy 201.399934 -34.972054)
			(xy 201.340478 -34.979882) (xy 201.28051 -34.979882) (xy 201.221054 -34.972054) (xy 201.163129 -34.956533)
			(xy 201.107725 -34.933584) (xy 201.055791 -34.9036) (xy 201.008215 -34.867094) (xy 200.96581 -34.824689)
			(xy 200.929304 -34.777113) (xy 200.89932 -34.725179) (xy 200.876371 -34.669775) (xy 200.86085 -34.61185)
			(xy 200.853022 -34.552394) (xy 200.852532 -34.52241) (xy 190.505055 -34.52241) (xy 190.50459 -34.550854)
			(xy 190.496767 -34.610276) (xy 190.481254 -34.668169) (xy 190.458318 -34.723542) (xy 190.428351 -34.775448)
			(xy 190.391864 -34.822998) (xy 190.349484 -34.865378) (xy 190.301934 -34.901865) (xy 190.250028 -34.931832)
			(xy 190.194655 -34.954768) (xy 190.136762 -34.970281) (xy 190.07734 -34.978104) (xy 190.017404 -34.978104)
			(xy 189.957982 -34.970281) (xy 189.900089 -34.954768) (xy 189.844716 -34.931832) (xy 189.79281 -34.901865)
			(xy 189.74526 -34.865378) (xy 189.70288 -34.822998) (xy 189.666393 -34.775448) (xy 189.636426 -34.723542)
			(xy 189.61349 -34.668169) (xy 189.597977 -34.610276) (xy 189.590154 -34.550854) (xy 189.589664 -34.520886)
			(xy 175.768508 -34.520886) (xy 175.768508 -34.52241) (xy 175.768018 -34.552394) (xy 175.76019 -34.61185)
			(xy 175.744669 -34.669775) (xy 175.72172 -34.725179) (xy 175.691736 -34.777113) (xy 175.65523 -34.824689)
			(xy 175.612825 -34.867094) (xy 175.565249 -34.9036) (xy 175.513315 -34.933584) (xy 175.457911 -34.956533)
			(xy 175.399986 -34.972054) (xy 175.34053 -34.979882) (xy 175.280562 -34.979882) (xy 175.221106 -34.972054)
			(xy 175.163181 -34.956533) (xy 175.107777 -34.933584) (xy 175.055843 -34.9036) (xy 175.008267 -34.867094)
			(xy 174.965862 -34.824689) (xy 174.929356 -34.777113) (xy 174.899372 -34.725179) (xy 174.876423 -34.669775)
			(xy 174.860902 -34.61185) (xy 174.853074 -34.552394) (xy 174.852584 -34.52241) (xy 164.505107 -34.52241)
			(xy 164.504642 -34.550854) (xy 164.496819 -34.610276) (xy 164.481306 -34.668169) (xy 164.45837 -34.723542)
			(xy 164.428403 -34.775448) (xy 164.391916 -34.822998) (xy 164.349536 -34.865378) (xy 164.301986 -34.901865)
			(xy 164.25008 -34.931832) (xy 164.194707 -34.954768) (xy 164.136814 -34.970281) (xy 164.077392 -34.978104)
			(xy 164.017456 -34.978104) (xy 163.958034 -34.970281) (xy 163.900141 -34.954768) (xy 163.844768 -34.931832)
			(xy 163.792862 -34.901865) (xy 163.745312 -34.865378) (xy 163.702932 -34.822998) (xy 163.666445 -34.775448)
			(xy 163.636478 -34.723542) (xy 163.613542 -34.668169) (xy 163.598029 -34.610276) (xy 163.590206 -34.550854)
			(xy 163.589716 -34.520886) (xy 149.76856 -34.520886) (xy 149.76856 -34.52241) (xy 149.76807 -34.552394)
			(xy 149.760242 -34.61185) (xy 149.744721 -34.669775) (xy 149.721772 -34.725179) (xy 149.691788 -34.777113)
			(xy 149.655282 -34.824689) (xy 149.612877 -34.867094) (xy 149.565301 -34.9036) (xy 149.513367 -34.933584)
			(xy 149.457963 -34.956533) (xy 149.400038 -34.972054) (xy 149.340582 -34.979882) (xy 149.280614 -34.979882)
			(xy 149.221158 -34.972054) (xy 149.163233 -34.956533) (xy 149.107829 -34.933584) (xy 149.055895 -34.9036)
			(xy 149.008319 -34.867094) (xy 148.965914 -34.824689) (xy 148.929408 -34.777113) (xy 148.899424 -34.725179)
			(xy 148.876475 -34.669775) (xy 148.860954 -34.61185) (xy 148.853126 -34.552394) (xy 148.852636 -34.52241)
			(xy 138.505159 -34.52241) (xy 138.504694 -34.550854) (xy 138.496871 -34.610276) (xy 138.481358 -34.668169)
			(xy 138.458422 -34.723542) (xy 138.428455 -34.775448) (xy 138.391968 -34.822998) (xy 138.349588 -34.865378)
			(xy 138.302038 -34.901865) (xy 138.250132 -34.931832) (xy 138.194759 -34.954768) (xy 138.136866 -34.970281)
			(xy 138.077444 -34.978104) (xy 138.017508 -34.978104) (xy 137.958086 -34.970281) (xy 137.900193 -34.954768)
			(xy 137.84482 -34.931832) (xy 137.792914 -34.901865) (xy 137.745364 -34.865378) (xy 137.702984 -34.822998)
			(xy 137.666497 -34.775448) (xy 137.63653 -34.723542) (xy 137.613594 -34.668169) (xy 137.598081 -34.610276)
			(xy 137.590258 -34.550854) (xy 137.589768 -34.520886) (xy 123.768612 -34.520886) (xy 123.768612 -34.52241)
			(xy 123.768122 -34.552394) (xy 123.760294 -34.61185) (xy 123.744773 -34.669775) (xy 123.721824 -34.725179)
			(xy 123.69184 -34.777113) (xy 123.655334 -34.824689) (xy 123.612929 -34.867094) (xy 123.565353 -34.9036)
			(xy 123.513419 -34.933584) (xy 123.458015 -34.956533) (xy 123.40009 -34.972054) (xy 123.340634 -34.979882)
			(xy 123.280666 -34.979882) (xy 123.22121 -34.972054) (xy 123.163285 -34.956533) (xy 123.107881 -34.933584)
			(xy 123.055947 -34.9036) (xy 123.008371 -34.867094) (xy 122.965966 -34.824689) (xy 122.92946 -34.777113)
			(xy 122.899476 -34.725179) (xy 122.876527 -34.669775) (xy 122.861006 -34.61185) (xy 122.853178 -34.552394)
			(xy 122.852688 -34.52241) (xy 100.405159 -34.52241) (xy 100.404694 -34.55087) (xy 100.396866 -34.610326)
			(xy 100.381345 -34.668251) (xy 100.358396 -34.723655) (xy 100.328412 -34.775589) (xy 100.291906 -34.823165)
			(xy 100.249501 -34.86557) (xy 100.201925 -34.902076) (xy 100.149991 -34.93206) (xy 100.094587 -34.955009)
			(xy 100.036662 -34.97053) (xy 99.977206 -34.978358) (xy 99.917238 -34.978358) (xy 99.857782 -34.97053)
			(xy 99.799857 -34.955009) (xy 99.744453 -34.93206) (xy 99.692519 -34.902076) (xy 99.644943 -34.86557)
			(xy 99.602538 -34.823165) (xy 99.566032 -34.775589) (xy 99.536048 -34.723655) (xy 99.513099 -34.668251)
			(xy 99.497578 -34.610326) (xy 99.48975 -34.55087) (xy 99.48926 -34.520886) (xy 85.668104 -34.520886)
			(xy 85.668104 -34.52241) (xy 85.667614 -34.552378) (xy 85.659791 -34.6118) (xy 85.644278 -34.669693)
			(xy 85.621342 -34.725066) (xy 85.591375 -34.776972) (xy 85.554888 -34.824522) (xy 85.512508 -34.866902)
			(xy 85.464958 -34.903389) (xy 85.413052 -34.933356) (xy 85.357679 -34.956292) (xy 85.299786 -34.971805)
			(xy 85.240364 -34.979628) (xy 85.180428 -34.979628) (xy 85.121006 -34.971805) (xy 85.063113 -34.956292)
			(xy 85.00774 -34.933356) (xy 84.955834 -34.903389) (xy 84.908284 -34.866902) (xy 84.865904 -34.824522)
			(xy 84.829417 -34.776972) (xy 84.79945 -34.725066) (xy 84.776514 -34.669693) (xy 84.761001 -34.6118)
			(xy 84.753178 -34.552378) (xy 84.752688 -34.52241) (xy 74.405211 -34.52241) (xy 74.404746 -34.55087)
			(xy 74.396918 -34.610326) (xy 74.381397 -34.668251) (xy 74.358448 -34.723655) (xy 74.328464 -34.775589)
			(xy 74.291958 -34.823165) (xy 74.249553 -34.86557) (xy 74.201977 -34.902076) (xy 74.150043 -34.93206)
			(xy 74.094639 -34.955009) (xy 74.036714 -34.97053) (xy 73.977258 -34.978358) (xy 73.91729 -34.978358)
			(xy 73.857834 -34.97053) (xy 73.799909 -34.955009) (xy 73.744505 -34.93206) (xy 73.692571 -34.902076)
			(xy 73.644995 -34.86557) (xy 73.60259 -34.823165) (xy 73.566084 -34.775589) (xy 73.5361 -34.723655)
			(xy 73.513151 -34.668251) (xy 73.49763 -34.610326) (xy 73.489802 -34.55087) (xy 73.489312 -34.520886)
			(xy 59.668156 -34.520886) (xy 59.668156 -34.52241) (xy 59.667666 -34.552378) (xy 59.659843 -34.6118)
			(xy 59.64433 -34.669693) (xy 59.621394 -34.725066) (xy 59.591427 -34.776972) (xy 59.55494 -34.824522)
			(xy 59.51256 -34.866902) (xy 59.46501 -34.903389) (xy 59.413104 -34.933356) (xy 59.357731 -34.956292)
			(xy 59.299838 -34.971805) (xy 59.240416 -34.979628) (xy 59.18048 -34.979628) (xy 59.121058 -34.971805)
			(xy 59.063165 -34.956292) (xy 59.007792 -34.933356) (xy 58.955886 -34.903389) (xy 58.908336 -34.866902)
			(xy 58.865956 -34.824522) (xy 58.829469 -34.776972) (xy 58.799502 -34.725066) (xy 58.776566 -34.669693)
			(xy 58.761053 -34.6118) (xy 58.75323 -34.552378) (xy 58.75274 -34.52241) (xy 48.405263 -34.52241)
			(xy 48.404798 -34.55087) (xy 48.39697 -34.610326) (xy 48.381449 -34.668251) (xy 48.3585 -34.723655)
			(xy 48.328516 -34.775589) (xy 48.29201 -34.823165) (xy 48.249605 -34.86557) (xy 48.202029 -34.902076)
			(xy 48.150095 -34.93206) (xy 48.094691 -34.955009) (xy 48.036766 -34.97053) (xy 47.97731 -34.978358)
			(xy 47.917342 -34.978358) (xy 47.857886 -34.97053) (xy 47.799961 -34.955009) (xy 47.744557 -34.93206)
			(xy 47.692623 -34.902076) (xy 47.645047 -34.86557) (xy 47.602642 -34.823165) (xy 47.566136 -34.775589)
			(xy 47.536152 -34.723655) (xy 47.513203 -34.668251) (xy 47.497682 -34.610326) (xy 47.489854 -34.55087)
			(xy 47.489364 -34.520886) (xy 33.668208 -34.520886) (xy 33.668208 -34.52241) (xy 33.667718 -34.552378)
			(xy 33.659895 -34.6118) (xy 33.644382 -34.669693) (xy 33.621446 -34.725066) (xy 33.591479 -34.776972)
			(xy 33.554992 -34.824522) (xy 33.512612 -34.866902) (xy 33.465062 -34.903389) (xy 33.413156 -34.933356)
			(xy 33.357783 -34.956292) (xy 33.29989 -34.971805) (xy 33.240468 -34.979628) (xy 33.180532 -34.979628)
			(xy 33.12111 -34.971805) (xy 33.063217 -34.956292) (xy 33.007844 -34.933356) (xy 32.955938 -34.903389)
			(xy 32.908388 -34.866902) (xy 32.866008 -34.824522) (xy 32.829521 -34.776972) (xy 32.799554 -34.725066)
			(xy 32.776618 -34.669693) (xy 32.761105 -34.6118) (xy 32.753282 -34.552378) (xy 32.752792 -34.52241)
			(xy 22.405315 -34.52241) (xy 22.40485 -34.55087) (xy 22.397022 -34.610326) (xy 22.381501 -34.668251)
			(xy 22.358552 -34.723655) (xy 22.328568 -34.775589) (xy 22.292062 -34.823165) (xy 22.249657 -34.86557)
			(xy 22.202081 -34.902076) (xy 22.150147 -34.93206) (xy 22.094743 -34.955009) (xy 22.036818 -34.97053)
			(xy 21.977362 -34.978358) (xy 21.917394 -34.978358) (xy 21.857938 -34.97053) (xy 21.800013 -34.955009)
			(xy 21.744609 -34.93206) (xy 21.692675 -34.902076) (xy 21.645099 -34.86557) (xy 21.602694 -34.823165)
			(xy 21.566188 -34.775589) (xy 21.536204 -34.723655) (xy 21.513255 -34.668251) (xy 21.497734 -34.610326)
			(xy 21.489906 -34.55087) (xy 21.489416 -34.520886) (xy 7.66826 -34.520886) (xy 7.66826 -34.52241)
			(xy 7.66777 -34.552378) (xy 7.659947 -34.6118) (xy 7.644434 -34.669693) (xy 7.621498 -34.725066)
			(xy 7.591531 -34.776972) (xy 7.555044 -34.824522) (xy 7.512664 -34.866902) (xy 7.465114 -34.903389)
			(xy 7.413208 -34.933356) (xy 7.357835 -34.956292) (xy 7.299942 -34.971805) (xy 7.24052 -34.979628)
			(xy 7.180584 -34.979628) (xy 7.121162 -34.971805) (xy 7.063269 -34.956292) (xy 7.007896 -34.933356)
			(xy 6.95599 -34.903389) (xy 6.90844 -34.866902) (xy 6.86606 -34.824522) (xy 6.829573 -34.776972)
			(xy 6.799606 -34.725066) (xy 6.77667 -34.669693) (xy 6.761157 -34.6118) (xy 6.753334 -34.552378)
			(xy 6.752844 -34.52241) (xy 0.508 -34.52241) (xy 0.508 -36.60013) (xy 11.998205 -36.60013) (xy 12.00221 -36.512222)
			(xy 12.014193 -36.425042) (xy 12.034053 -36.339313) (xy 12.061628 -36.255745) (xy 12.096687 -36.175031)
			(xy 12.13894 -36.097839) (xy 12.188038 -36.02481) (xy 12.243574 -35.956548) (xy 12.305086 -35.893618)
			(xy 12.372067 -35.836544) (xy 12.44396 -35.785796) (xy 12.520169 -35.741796) (xy 12.600064 -35.704909)
			(xy 12.682983 -35.67544) (xy 12.768238 -35.653633) (xy 12.855122 -35.639669) (xy 12.942916 -35.633663)
			(xy 13.030893 -35.635667) (xy 13.118323 -35.645662) (xy 13.204482 -35.663566) (xy 13.288656 -35.68923)
			(xy 13.370147 -35.722443) (xy 13.448281 -35.762929) (xy 13.522409 -35.810351) (xy 13.591917 -35.864318)
			(xy 13.656231 -35.924383) (xy 13.714815 -35.990047) (xy 13.767186 -36.060766) (xy 13.812909 -36.135954)
			(xy 13.851606 -36.214989) (xy 13.882955 -36.297215) (xy 13.906697 -36.381951) (xy 13.922635 -36.468495)
			(xy 13.930637 -36.55613) (xy 13.931138 -36.60013) (xy 37.998153 -36.60013) (xy 38.002158 -36.512222)
			(xy 38.014141 -36.425042) (xy 38.034001 -36.339313) (xy 38.061576 -36.255745) (xy 38.096635 -36.175031)
			(xy 38.138888 -36.097839) (xy 38.187986 -36.02481) (xy 38.243522 -35.956548) (xy 38.305034 -35.893618)
			(xy 38.372015 -35.836544) (xy 38.443908 -35.785796) (xy 38.520117 -35.741796) (xy 38.600012 -35.704909)
			(xy 38.682931 -35.67544) (xy 38.768186 -35.653633) (xy 38.85507 -35.639669) (xy 38.942864 -35.633663)
			(xy 39.030841 -35.635667) (xy 39.118271 -35.645662) (xy 39.20443 -35.663566) (xy 39.288604 -35.68923)
			(xy 39.370095 -35.722443) (xy 39.448229 -35.762929) (xy 39.522357 -35.810351) (xy 39.591865 -35.864318)
			(xy 39.656179 -35.924383) (xy 39.714763 -35.990047) (xy 39.767134 -36.060766) (xy 39.812857 -36.135954)
			(xy 39.851554 -36.214989) (xy 39.882903 -36.297215) (xy 39.906645 -36.381951) (xy 39.922583 -36.468495)
			(xy 39.930585 -36.55613) (xy 39.931086 -36.60013) (xy 63.998101 -36.60013) (xy 64.002106 -36.512222)
			(xy 64.014089 -36.425042) (xy 64.033949 -36.339313) (xy 64.061524 -36.255745) (xy 64.096583 -36.175031)
			(xy 64.138836 -36.097839) (xy 64.187934 -36.02481) (xy 64.24347 -35.956548) (xy 64.304982 -35.893618)
			(xy 64.371963 -35.836544) (xy 64.443856 -35.785796) (xy 64.520065 -35.741796) (xy 64.59996 -35.704909)
			(xy 64.682879 -35.67544) (xy 64.768134 -35.653633) (xy 64.855018 -35.639669) (xy 64.942812 -35.633663)
			(xy 65.030789 -35.635667) (xy 65.118219 -35.645662) (xy 65.204378 -35.663566) (xy 65.288552 -35.68923)
			(xy 65.370043 -35.722443) (xy 65.448177 -35.762929) (xy 65.522305 -35.810351) (xy 65.591813 -35.864318)
			(xy 65.656127 -35.924383) (xy 65.714711 -35.990047) (xy 65.767082 -36.060766) (xy 65.812805 -36.135954)
			(xy 65.851502 -36.214989) (xy 65.882851 -36.297215) (xy 65.906593 -36.381951) (xy 65.922531 -36.468495)
			(xy 65.930533 -36.55613) (xy 65.931034 -36.60013) (xy 89.998049 -36.60013) (xy 90.002054 -36.512222)
			(xy 90.014037 -36.425042) (xy 90.033897 -36.339313) (xy 90.061472 -36.255745) (xy 90.096531 -36.175031)
			(xy 90.138784 -36.097839) (xy 90.187882 -36.02481) (xy 90.243418 -35.956548) (xy 90.30493 -35.893618)
			(xy 90.371911 -35.836544) (xy 90.443804 -35.785796) (xy 90.520013 -35.741796) (xy 90.599908 -35.704909)
			(xy 90.682827 -35.67544) (xy 90.768082 -35.653633) (xy 90.854966 -35.639669) (xy 90.94276 -35.633663)
			(xy 91.030737 -35.635667) (xy 91.118167 -35.645662) (xy 91.204326 -35.663566) (xy 91.2885 -35.68923)
			(xy 91.369991 -35.722443) (xy 91.448125 -35.762929) (xy 91.522253 -35.810351) (xy 91.591761 -35.864318)
			(xy 91.656075 -35.924383) (xy 91.714659 -35.990047) (xy 91.76703 -36.060766) (xy 91.812753 -36.135954)
			(xy 91.85145 -36.214989) (xy 91.882799 -36.297215) (xy 91.906541 -36.381951) (xy 91.922479 -36.468495)
			(xy 91.930481 -36.55613) (xy 91.930982 -36.60013) (xy 128.098303 -36.60013) (xy 128.102308 -36.512222)
			(xy 128.114291 -36.425042) (xy 128.134151 -36.339313) (xy 128.161726 -36.255745) (xy 128.196785 -36.175031)
			(xy 128.239038 -36.097839) (xy 128.288136 -36.02481) (xy 128.343672 -35.956548) (xy 128.405184 -35.893618)
			(xy 128.472165 -35.836544) (xy 128.544058 -35.785796) (xy 128.620267 -35.741796) (xy 128.700162 -35.704909)
			(xy 128.783081 -35.67544) (xy 128.868336 -35.653633) (xy 128.95522 -35.639669) (xy 129.043014 -35.633663)
			(xy 129.130991 -35.635667) (xy 129.218421 -35.645662) (xy 129.30458 -35.663566) (xy 129.388754 -35.68923)
			(xy 129.470245 -35.722443) (xy 129.548379 -35.762929) (xy 129.622507 -35.810351) (xy 129.692015 -35.864318)
			(xy 129.756329 -35.924383) (xy 129.814913 -35.990047) (xy 129.867284 -36.060766) (xy 129.913007 -36.135954)
			(xy 129.951704 -36.214989) (xy 129.983053 -36.297215) (xy 130.006795 -36.381951) (xy 130.022733 -36.468495)
			(xy 130.030735 -36.55613) (xy 130.031236 -36.60013) (xy 154.098251 -36.60013) (xy 154.102256 -36.512222)
			(xy 154.114239 -36.425042) (xy 154.134099 -36.339313) (xy 154.161674 -36.255745) (xy 154.196733 -36.175031)
			(xy 154.238986 -36.097839) (xy 154.288084 -36.02481) (xy 154.34362 -35.956548) (xy 154.405132 -35.893618)
			(xy 154.472113 -35.836544) (xy 154.544006 -35.785796) (xy 154.620215 -35.741796) (xy 154.70011 -35.704909)
			(xy 154.783029 -35.67544) (xy 154.868284 -35.653633) (xy 154.955168 -35.639669) (xy 155.042962 -35.633663)
			(xy 155.130939 -35.635667) (xy 155.218369 -35.645662) (xy 155.304528 -35.663566) (xy 155.388702 -35.68923)
			(xy 155.470193 -35.722443) (xy 155.548327 -35.762929) (xy 155.622455 -35.810351) (xy 155.691963 -35.864318)
			(xy 155.756277 -35.924383) (xy 155.814861 -35.990047) (xy 155.867232 -36.060766) (xy 155.912955 -36.135954)
			(xy 155.951652 -36.214989) (xy 155.983001 -36.297215) (xy 156.006743 -36.381951) (xy 156.022681 -36.468495)
			(xy 156.030683 -36.55613) (xy 156.031184 -36.60013) (xy 180.098199 -36.60013) (xy 180.102204 -36.512222)
			(xy 180.114187 -36.425042) (xy 180.134047 -36.339313) (xy 180.161622 -36.255745) (xy 180.196681 -36.175031)
			(xy 180.238934 -36.097839) (xy 180.288032 -36.02481) (xy 180.343568 -35.956548) (xy 180.40508 -35.893618)
			(xy 180.472061 -35.836544) (xy 180.543954 -35.785796) (xy 180.620163 -35.741796) (xy 180.700058 -35.704909)
			(xy 180.782977 -35.67544) (xy 180.868232 -35.653633) (xy 180.955116 -35.639669) (xy 181.04291 -35.633663)
			(xy 181.130887 -35.635667) (xy 181.218317 -35.645662) (xy 181.304476 -35.663566) (xy 181.38865 -35.68923)
			(xy 181.470141 -35.722443) (xy 181.548275 -35.762929) (xy 181.622403 -35.810351) (xy 181.691911 -35.864318)
			(xy 181.756225 -35.924383) (xy 181.814809 -35.990047) (xy 181.86718 -36.060766) (xy 181.912903 -36.135954)
			(xy 181.9516 -36.214989) (xy 181.982949 -36.297215) (xy 182.006691 -36.381951) (xy 182.022629 -36.468495)
			(xy 182.030631 -36.55613) (xy 182.031132 -36.60013) (xy 206.098655 -36.60013) (xy 206.102659 -36.512245)
			(xy 206.114639 -36.425088) (xy 206.134494 -36.339381) (xy 206.162061 -36.255836) (xy 206.197111 -36.175143)
			(xy 206.239353 -36.097971) (xy 206.288438 -36.024961) (xy 206.343959 -35.956717) (xy 206.405456 -35.893804)
			(xy 206.472418 -35.836744) (xy 206.544292 -35.78601) (xy 206.620482 -35.742022) (xy 206.700356 -35.705144)
			(xy 206.783253 -35.675683) (xy 206.868485 -35.653881) (xy 206.955347 -35.639921) (xy 207.043118 -35.633917)
			(xy 207.131072 -35.63592) (xy 207.218479 -35.645912) (xy 207.304615 -35.663812) (xy 207.388767 -35.68947)
			(xy 207.470237 -35.722674) (xy 207.54835 -35.763148) (xy 207.622458 -35.810559) (xy 207.691949 -35.864512)
			(xy 207.756245 -35.92456) (xy 207.814814 -35.990207) (xy 207.867171 -36.060907) (xy 207.912883 -36.136076)
			(xy 207.951569 -36.21509) (xy 207.98291 -36.297295) (xy 208.006645 -36.382009) (xy 208.022579 -36.46853)
			(xy 208.030579 -36.556142) (xy 208.03108 -36.60013) (xy 244.198655 -36.60013) (xy 244.202659 -36.512245)
			(xy 244.214639 -36.425088) (xy 244.234494 -36.339381) (xy 244.262061 -36.255836) (xy 244.297111 -36.175143)
			(xy 244.339353 -36.097971) (xy 244.388438 -36.024961) (xy 244.443959 -35.956717) (xy 244.505456 -35.893804)
			(xy 244.572418 -35.836744) (xy 244.644292 -35.78601) (xy 244.720482 -35.742022) (xy 244.800356 -35.705144)
			(xy 244.883253 -35.675683) (xy 244.968485 -35.653881) (xy 245.055347 -35.639921) (xy 245.143118 -35.633917)
			(xy 245.231072 -35.63592) (xy 245.318479 -35.645912) (xy 245.404615 -35.663812) (xy 245.488767 -35.68947)
			(xy 245.570237 -35.722674) (xy 245.64835 -35.763148) (xy 245.722458 -35.810559) (xy 245.791949 -35.864512)
			(xy 245.856245 -35.92456) (xy 245.914814 -35.990207) (xy 245.967171 -36.060907) (xy 246.012883 -36.136076)
			(xy 246.051569 -36.21509) (xy 246.08291 -36.297295) (xy 246.106645 -36.382009) (xy 246.122579 -36.46853)
			(xy 246.130579 -36.556142) (xy 246.13108 -36.60013) (xy 270.198603 -36.60013) (xy 270.202607 -36.512245)
			(xy 270.214587 -36.425088) (xy 270.234442 -36.339381) (xy 270.262009 -36.255836) (xy 270.297059 -36.175143)
			(xy 270.339301 -36.097971) (xy 270.388386 -36.024961) (xy 270.443907 -35.956717) (xy 270.505404 -35.893804)
			(xy 270.572366 -35.836744) (xy 270.64424 -35.78601) (xy 270.72043 -35.742022) (xy 270.800304 -35.705144)
			(xy 270.883201 -35.675683) (xy 270.968433 -35.653881) (xy 271.055295 -35.639921) (xy 271.143066 -35.633917)
			(xy 271.23102 -35.63592) (xy 271.318427 -35.645912) (xy 271.404563 -35.663812) (xy 271.488715 -35.68947)
			(xy 271.570185 -35.722674) (xy 271.648298 -35.763148) (xy 271.722406 -35.810559) (xy 271.791897 -35.864512)
			(xy 271.856193 -35.92456) (xy 271.914762 -35.990207) (xy 271.967119 -36.060907) (xy 272.012831 -36.136076)
			(xy 272.051517 -36.21509) (xy 272.082858 -36.297295) (xy 272.106593 -36.382009) (xy 272.122527 -36.46853)
			(xy 272.130527 -36.556142) (xy 272.131028 -36.60013) (xy 296.198551 -36.60013) (xy 296.202555 -36.512245)
			(xy 296.214535 -36.425088) (xy 296.23439 -36.339381) (xy 296.261957 -36.255836) (xy 296.297007 -36.175143)
			(xy 296.339249 -36.097971) (xy 296.388334 -36.024961) (xy 296.443855 -35.956717) (xy 296.505352 -35.893804)
			(xy 296.572314 -35.836744) (xy 296.644188 -35.78601) (xy 296.720378 -35.742022) (xy 296.800252 -35.705144)
			(xy 296.883149 -35.675683) (xy 296.968381 -35.653881) (xy 297.055243 -35.639921) (xy 297.143014 -35.633917)
			(xy 297.230968 -35.63592) (xy 297.318375 -35.645912) (xy 297.404511 -35.663812) (xy 297.488663 -35.68947)
			(xy 297.570133 -35.722674) (xy 297.648246 -35.763148) (xy 297.722354 -35.810559) (xy 297.791845 -35.864512)
			(xy 297.856141 -35.92456) (xy 297.91471 -35.990207) (xy 297.967067 -36.060907) (xy 298.012779 -36.136076)
			(xy 298.051465 -36.21509) (xy 298.082806 -36.297295) (xy 298.106541 -36.382009) (xy 298.122475 -36.46853)
			(xy 298.130475 -36.556142) (xy 298.130976 -36.60013) (xy 322.197991 -36.60013) (xy 322.201996 -36.512222)
			(xy 322.213979 -36.425042) (xy 322.233839 -36.339313) (xy 322.261414 -36.255745) (xy 322.296473 -36.175031)
			(xy 322.338726 -36.097839) (xy 322.387824 -36.02481) (xy 322.44336 -35.956548) (xy 322.504872 -35.893618)
			(xy 322.571853 -35.836544) (xy 322.643746 -35.785796) (xy 322.719955 -35.741796) (xy 322.79985 -35.704909)
			(xy 322.882769 -35.67544) (xy 322.968024 -35.653633) (xy 323.054908 -35.639669) (xy 323.142702 -35.633663)
			(xy 323.230679 -35.635667) (xy 323.318109 -35.645662) (xy 323.404268 -35.663566) (xy 323.488442 -35.68923)
			(xy 323.569933 -35.722443) (xy 323.648067 -35.762929) (xy 323.722195 -35.810351) (xy 323.791703 -35.864318)
			(xy 323.856017 -35.924383) (xy 323.914601 -35.990047) (xy 323.966972 -36.060766) (xy 324.012695 -36.135954)
			(xy 324.051392 -36.214989) (xy 324.082741 -36.297215) (xy 324.106483 -36.381951) (xy 324.122421 -36.468495)
			(xy 324.130423 -36.55613) (xy 324.130924 -36.60013) (xy 360.298245 -36.60013) (xy 360.30225 -36.512222)
			(xy 360.314233 -36.425042) (xy 360.334093 -36.339313) (xy 360.361668 -36.255745) (xy 360.396727 -36.175031)
			(xy 360.43898 -36.097839) (xy 360.488078 -36.02481) (xy 360.543614 -35.956548) (xy 360.605126 -35.893618)
			(xy 360.672107 -35.836544) (xy 360.744 -35.785796) (xy 360.820209 -35.741796) (xy 360.900104 -35.704909)
			(xy 360.983023 -35.67544) (xy 361.068278 -35.653633) (xy 361.155162 -35.639669) (xy 361.242956 -35.633663)
			(xy 361.330933 -35.635667) (xy 361.418363 -35.645662) (xy 361.504522 -35.663566) (xy 361.588696 -35.68923)
			(xy 361.670187 -35.722443) (xy 361.748321 -35.762929) (xy 361.822449 -35.810351) (xy 361.891957 -35.864318)
			(xy 361.956271 -35.924383) (xy 362.014855 -35.990047) (xy 362.067226 -36.060766) (xy 362.112949 -36.135954)
			(xy 362.151646 -36.214989) (xy 362.182995 -36.297215) (xy 362.206737 -36.381951) (xy 362.222675 -36.468495)
			(xy 362.230677 -36.55613) (xy 362.231178 -36.60013) (xy 386.298193 -36.60013) (xy 386.302198 -36.512222)
			(xy 386.314181 -36.425042) (xy 386.334041 -36.339313) (xy 386.361616 -36.255745) (xy 386.396675 -36.175031)
			(xy 386.438928 -36.097839) (xy 386.488026 -36.02481) (xy 386.543562 -35.956548) (xy 386.605074 -35.893618)
			(xy 386.672055 -35.836544) (xy 386.743948 -35.785796) (xy 386.820157 -35.741796) (xy 386.900052 -35.704909)
			(xy 386.982971 -35.67544) (xy 387.068226 -35.653633) (xy 387.15511 -35.639669) (xy 387.242904 -35.633663)
			(xy 387.330881 -35.635667) (xy 387.418311 -35.645662) (xy 387.50447 -35.663566) (xy 387.588644 -35.68923)
			(xy 387.670135 -35.722443) (xy 387.748269 -35.762929) (xy 387.822397 -35.810351) (xy 387.891905 -35.864318)
			(xy 387.956219 -35.924383) (xy 388.014803 -35.990047) (xy 388.067174 -36.060766) (xy 388.112897 -36.135954)
			(xy 388.151594 -36.214989) (xy 388.182943 -36.297215) (xy 388.206685 -36.381951) (xy 388.222623 -36.468495)
			(xy 388.230625 -36.55613) (xy 388.231126 -36.60013) (xy 412.298649 -36.60013) (xy 412.302653 -36.512245)
			(xy 412.314633 -36.425088) (xy 412.334488 -36.339381) (xy 412.362055 -36.255836) (xy 412.397105 -36.175143)
			(xy 412.439347 -36.097971) (xy 412.488432 -36.024961) (xy 412.543953 -35.956717) (xy 412.60545 -35.893804)
			(xy 412.672412 -35.836744) (xy 412.744286 -35.78601) (xy 412.820476 -35.742022) (xy 412.90035 -35.705144)
			(xy 412.983247 -35.675683) (xy 413.068479 -35.653881) (xy 413.155341 -35.639921) (xy 413.243112 -35.633917)
			(xy 413.331066 -35.63592) (xy 413.418473 -35.645912) (xy 413.504609 -35.663812) (xy 413.588761 -35.68947)
			(xy 413.670231 -35.722674) (xy 413.748344 -35.763148) (xy 413.822452 -35.810559) (xy 413.891943 -35.864512)
			(xy 413.956239 -35.92456) (xy 414.014808 -35.990207) (xy 414.067165 -36.060907) (xy 414.112877 -36.136076)
			(xy 414.151563 -36.21509) (xy 414.182904 -36.297295) (xy 414.206639 -36.382009) (xy 414.222573 -36.46853)
			(xy 414.230573 -36.556142) (xy 414.231074 -36.60013) (xy 438.298597 -36.60013) (xy 438.302601 -36.512245)
			(xy 438.314581 -36.425088) (xy 438.334436 -36.339381) (xy 438.362003 -36.255836) (xy 438.397053 -36.175143)
			(xy 438.439295 -36.097971) (xy 438.48838 -36.024961) (xy 438.543901 -35.956717) (xy 438.605398 -35.893804)
			(xy 438.67236 -35.836744) (xy 438.744234 -35.78601) (xy 438.820424 -35.742022) (xy 438.900298 -35.705144)
			(xy 438.983195 -35.675683) (xy 439.068427 -35.653881) (xy 439.155289 -35.639921) (xy 439.24306 -35.633917)
			(xy 439.331014 -35.63592) (xy 439.418421 -35.645912) (xy 439.504557 -35.663812) (xy 439.588709 -35.68947)
			(xy 439.670179 -35.722674) (xy 439.748292 -35.763148) (xy 439.8224 -35.810559) (xy 439.891891 -35.864512)
			(xy 439.956187 -35.92456) (xy 440.014756 -35.990207) (xy 440.067113 -36.060907) (xy 440.112825 -36.136076)
			(xy 440.151511 -36.21509) (xy 440.182852 -36.297295) (xy 440.206587 -36.382009) (xy 440.222521 -36.46853)
			(xy 440.230521 -36.556142) (xy 440.231022 -36.60013) (xy 440.230521 -36.644118) (xy 440.222521 -36.73173)
			(xy 440.206587 -36.818251) (xy 440.182852 -36.902965) (xy 440.151511 -36.98517) (xy 440.112825 -37.064184)
			(xy 440.067113 -37.139353) (xy 440.014756 -37.210053) (xy 439.956187 -37.2757) (xy 439.891891 -37.335748)
			(xy 439.8224 -37.389701) (xy 439.748292 -37.437112) (xy 439.670179 -37.477586) (xy 439.588709 -37.51079)
			(xy 439.504557 -37.536448) (xy 439.418421 -37.554348) (xy 439.331014 -37.56434) (xy 439.24306 -37.566343)
			(xy 439.155289 -37.560339) (xy 439.068427 -37.546379) (xy 438.983195 -37.524577) (xy 438.900298 -37.495116)
			(xy 438.820424 -37.458238) (xy 438.744234 -37.41425) (xy 438.67236 -37.363516) (xy 438.605398 -37.306456)
			(xy 438.543901 -37.243543) (xy 438.48838 -37.175299) (xy 438.439295 -37.102289) (xy 438.397053 -37.025117)
			(xy 438.362003 -36.944424) (xy 438.334436 -36.860879) (xy 438.314581 -36.775172) (xy 438.302601 -36.688015)
			(xy 438.298597 -36.60013) (xy 414.231074 -36.60013) (xy 414.230573 -36.644118) (xy 414.222573 -36.73173)
			(xy 414.206639 -36.818251) (xy 414.182904 -36.902965) (xy 414.151563 -36.98517) (xy 414.112877 -37.064184)
			(xy 414.067165 -37.139353) (xy 414.014808 -37.210053) (xy 413.956239 -37.2757) (xy 413.891943 -37.335748)
			(xy 413.822452 -37.389701) (xy 413.748344 -37.437112) (xy 413.670231 -37.477586) (xy 413.588761 -37.51079)
			(xy 413.504609 -37.536448) (xy 413.418473 -37.554348) (xy 413.331066 -37.56434) (xy 413.243112 -37.566343)
			(xy 413.155341 -37.560339) (xy 413.068479 -37.546379) (xy 412.983247 -37.524577) (xy 412.90035 -37.495116)
			(xy 412.820476 -37.458238) (xy 412.744286 -37.41425) (xy 412.672412 -37.363516) (xy 412.60545 -37.306456)
			(xy 412.543953 -37.243543) (xy 412.488432 -37.175299) (xy 412.439347 -37.102289) (xy 412.397105 -37.025117)
			(xy 412.362055 -36.944424) (xy 412.334488 -36.860879) (xy 412.314633 -36.775172) (xy 412.302653 -36.688015)
			(xy 412.298649 -36.60013) (xy 388.231126 -36.60013) (xy 388.230625 -36.64413) (xy 388.222623 -36.731765)
			(xy 388.206685 -36.818309) (xy 388.182943 -36.903045) (xy 388.151594 -36.985271) (xy 388.112897 -37.064306)
			(xy 388.067174 -37.139494) (xy 388.014803 -37.210213) (xy 387.956219 -37.275877) (xy 387.891905 -37.335942)
			(xy 387.822397 -37.389909) (xy 387.748269 -37.437331) (xy 387.670135 -37.477817) (xy 387.588644 -37.51103)
			(xy 387.50447 -37.536694) (xy 387.418311 -37.554598) (xy 387.330881 -37.564593) (xy 387.242904 -37.566597)
			(xy 387.15511 -37.560591) (xy 387.068226 -37.546627) (xy 386.982971 -37.52482) (xy 386.900052 -37.495351)
			(xy 386.820157 -37.458464) (xy 386.743948 -37.414464) (xy 386.672055 -37.363716) (xy 386.605074 -37.306642)
			(xy 386.543562 -37.243712) (xy 386.488026 -37.17545) (xy 386.438928 -37.102421) (xy 386.396675 -37.025229)
			(xy 386.361616 -36.944515) (xy 386.334041 -36.860947) (xy 386.314181 -36.775218) (xy 386.302198 -36.688038)
			(xy 386.298193 -36.60013) (xy 362.231178 -36.60013) (xy 362.230677 -36.64413) (xy 362.222675 -36.731765)
			(xy 362.206737 -36.818309) (xy 362.182995 -36.903045) (xy 362.151646 -36.985271) (xy 362.112949 -37.064306)
			(xy 362.067226 -37.139494) (xy 362.014855 -37.210213) (xy 361.956271 -37.275877) (xy 361.891957 -37.335942)
			(xy 361.822449 -37.389909) (xy 361.748321 -37.437331) (xy 361.670187 -37.477817) (xy 361.588696 -37.51103)
			(xy 361.504522 -37.536694) (xy 361.418363 -37.554598) (xy 361.330933 -37.564593) (xy 361.242956 -37.566597)
			(xy 361.155162 -37.560591) (xy 361.068278 -37.546627) (xy 360.983023 -37.52482) (xy 360.900104 -37.495351)
			(xy 360.820209 -37.458464) (xy 360.744 -37.414464) (xy 360.672107 -37.363716) (xy 360.605126 -37.306642)
			(xy 360.543614 -37.243712) (xy 360.488078 -37.17545) (xy 360.43898 -37.102421) (xy 360.396727 -37.025229)
			(xy 360.361668 -36.944515) (xy 360.334093 -36.860947) (xy 360.314233 -36.775218) (xy 360.30225 -36.688038)
			(xy 360.298245 -36.60013) (xy 324.130924 -36.60013) (xy 324.130423 -36.64413) (xy 324.122421 -36.731765)
			(xy 324.106483 -36.818309) (xy 324.082741 -36.903045) (xy 324.051392 -36.985271) (xy 324.012695 -37.064306)
			(xy 323.966972 -37.139494) (xy 323.914601 -37.210213) (xy 323.856017 -37.275877) (xy 323.791703 -37.335942)
			(xy 323.722195 -37.389909) (xy 323.648067 -37.437331) (xy 323.569933 -37.477817) (xy 323.488442 -37.51103)
			(xy 323.404268 -37.536694) (xy 323.318109 -37.554598) (xy 323.230679 -37.564593) (xy 323.142702 -37.566597)
			(xy 323.054908 -37.560591) (xy 322.968024 -37.546627) (xy 322.882769 -37.52482) (xy 322.79985 -37.495351)
			(xy 322.719955 -37.458464) (xy 322.643746 -37.414464) (xy 322.571853 -37.363716) (xy 322.504872 -37.306642)
			(xy 322.44336 -37.243712) (xy 322.387824 -37.17545) (xy 322.338726 -37.102421) (xy 322.296473 -37.025229)
			(xy 322.261414 -36.944515) (xy 322.233839 -36.860947) (xy 322.213979 -36.775218) (xy 322.201996 -36.688038)
			(xy 322.197991 -36.60013) (xy 298.130976 -36.60013) (xy 298.130475 -36.644118) (xy 298.122475 -36.73173)
			(xy 298.106541 -36.818251) (xy 298.082806 -36.902965) (xy 298.051465 -36.98517) (xy 298.012779 -37.064184)
			(xy 297.967067 -37.139353) (xy 297.91471 -37.210053) (xy 297.856141 -37.2757) (xy 297.791845 -37.335748)
			(xy 297.722354 -37.389701) (xy 297.648246 -37.437112) (xy 297.570133 -37.477586) (xy 297.488663 -37.51079)
			(xy 297.404511 -37.536448) (xy 297.318375 -37.554348) (xy 297.230968 -37.56434) (xy 297.143014 -37.566343)
			(xy 297.055243 -37.560339) (xy 296.968381 -37.546379) (xy 296.883149 -37.524577) (xy 296.800252 -37.495116)
			(xy 296.720378 -37.458238) (xy 296.644188 -37.41425) (xy 296.572314 -37.363516) (xy 296.505352 -37.306456)
			(xy 296.443855 -37.243543) (xy 296.388334 -37.175299) (xy 296.339249 -37.102289) (xy 296.297007 -37.025117)
			(xy 296.261957 -36.944424) (xy 296.23439 -36.860879) (xy 296.214535 -36.775172) (xy 296.202555 -36.688015)
			(xy 296.198551 -36.60013) (xy 272.131028 -36.60013) (xy 272.130527 -36.644118) (xy 272.122527 -36.73173)
			(xy 272.106593 -36.818251) (xy 272.082858 -36.902965) (xy 272.051517 -36.98517) (xy 272.012831 -37.064184)
			(xy 271.967119 -37.139353) (xy 271.914762 -37.210053) (xy 271.856193 -37.2757) (xy 271.791897 -37.335748)
			(xy 271.722406 -37.389701) (xy 271.648298 -37.437112) (xy 271.570185 -37.477586) (xy 271.488715 -37.51079)
			(xy 271.404563 -37.536448) (xy 271.318427 -37.554348) (xy 271.23102 -37.56434) (xy 271.143066 -37.566343)
			(xy 271.055295 -37.560339) (xy 270.968433 -37.546379) (xy 270.883201 -37.524577) (xy 270.800304 -37.495116)
			(xy 270.72043 -37.458238) (xy 270.64424 -37.41425) (xy 270.572366 -37.363516) (xy 270.505404 -37.306456)
			(xy 270.443907 -37.243543) (xy 270.388386 -37.175299) (xy 270.339301 -37.102289) (xy 270.297059 -37.025117)
			(xy 270.262009 -36.944424) (xy 270.234442 -36.860879) (xy 270.214587 -36.775172) (xy 270.202607 -36.688015)
			(xy 270.198603 -36.60013) (xy 246.13108 -36.60013) (xy 246.130579 -36.644118) (xy 246.122579 -36.73173)
			(xy 246.106645 -36.818251) (xy 246.08291 -36.902965) (xy 246.051569 -36.98517) (xy 246.012883 -37.064184)
			(xy 245.967171 -37.139353) (xy 245.914814 -37.210053) (xy 245.856245 -37.2757) (xy 245.791949 -37.335748)
			(xy 245.722458 -37.389701) (xy 245.64835 -37.437112) (xy 245.570237 -37.477586) (xy 245.488767 -37.51079)
			(xy 245.404615 -37.536448) (xy 245.318479 -37.554348) (xy 245.231072 -37.56434) (xy 245.143118 -37.566343)
			(xy 245.055347 -37.560339) (xy 244.968485 -37.546379) (xy 244.883253 -37.524577) (xy 244.800356 -37.495116)
			(xy 244.720482 -37.458238) (xy 244.644292 -37.41425) (xy 244.572418 -37.363516) (xy 244.505456 -37.306456)
			(xy 244.443959 -37.243543) (xy 244.388438 -37.175299) (xy 244.339353 -37.102289) (xy 244.297111 -37.025117)
			(xy 244.262061 -36.944424) (xy 244.234494 -36.860879) (xy 244.214639 -36.775172) (xy 244.202659 -36.688015)
			(xy 244.198655 -36.60013) (xy 208.03108 -36.60013) (xy 208.030579 -36.644118) (xy 208.022579 -36.73173)
			(xy 208.006645 -36.818251) (xy 207.98291 -36.902965) (xy 207.951569 -36.98517) (xy 207.912883 -37.064184)
			(xy 207.867171 -37.139353) (xy 207.814814 -37.210053) (xy 207.756245 -37.2757) (xy 207.691949 -37.335748)
			(xy 207.622458 -37.389701) (xy 207.54835 -37.437112) (xy 207.470237 -37.477586) (xy 207.388767 -37.51079)
			(xy 207.304615 -37.536448) (xy 207.218479 -37.554348) (xy 207.131072 -37.56434) (xy 207.043118 -37.566343)
			(xy 206.955347 -37.560339) (xy 206.868485 -37.546379) (xy 206.783253 -37.524577) (xy 206.700356 -37.495116)
			(xy 206.620482 -37.458238) (xy 206.544292 -37.41425) (xy 206.472418 -37.363516) (xy 206.405456 -37.306456)
			(xy 206.343959 -37.243543) (xy 206.288438 -37.175299) (xy 206.239353 -37.102289) (xy 206.197111 -37.025117)
			(xy 206.162061 -36.944424) (xy 206.134494 -36.860879) (xy 206.114639 -36.775172) (xy 206.102659 -36.688015)
			(xy 206.098655 -36.60013) (xy 182.031132 -36.60013) (xy 182.030631 -36.64413) (xy 182.022629 -36.731765)
			(xy 182.006691 -36.818309) (xy 181.982949 -36.903045) (xy 181.9516 -36.985271) (xy 181.912903 -37.064306)
			(xy 181.86718 -37.139494) (xy 181.814809 -37.210213) (xy 181.756225 -37.275877) (xy 181.691911 -37.335942)
			(xy 181.622403 -37.389909) (xy 181.548275 -37.437331) (xy 181.470141 -37.477817) (xy 181.38865 -37.51103)
			(xy 181.304476 -37.536694) (xy 181.218317 -37.554598) (xy 181.130887 -37.564593) (xy 181.04291 -37.566597)
			(xy 180.955116 -37.560591) (xy 180.868232 -37.546627) (xy 180.782977 -37.52482) (xy 180.700058 -37.495351)
			(xy 180.620163 -37.458464) (xy 180.543954 -37.414464) (xy 180.472061 -37.363716) (xy 180.40508 -37.306642)
			(xy 180.343568 -37.243712) (xy 180.288032 -37.17545) (xy 180.238934 -37.102421) (xy 180.196681 -37.025229)
			(xy 180.161622 -36.944515) (xy 180.134047 -36.860947) (xy 180.114187 -36.775218) (xy 180.102204 -36.688038)
			(xy 180.098199 -36.60013) (xy 156.031184 -36.60013) (xy 156.030683 -36.64413) (xy 156.022681 -36.731765)
			(xy 156.006743 -36.818309) (xy 155.983001 -36.903045) (xy 155.951652 -36.985271) (xy 155.912955 -37.064306)
			(xy 155.867232 -37.139494) (xy 155.814861 -37.210213) (xy 155.756277 -37.275877) (xy 155.691963 -37.335942)
			(xy 155.622455 -37.389909) (xy 155.548327 -37.437331) (xy 155.470193 -37.477817) (xy 155.388702 -37.51103)
			(xy 155.304528 -37.536694) (xy 155.218369 -37.554598) (xy 155.130939 -37.564593) (xy 155.042962 -37.566597)
			(xy 154.955168 -37.560591) (xy 154.868284 -37.546627) (xy 154.783029 -37.52482) (xy 154.70011 -37.495351)
			(xy 154.620215 -37.458464) (xy 154.544006 -37.414464) (xy 154.472113 -37.363716) (xy 154.405132 -37.306642)
			(xy 154.34362 -37.243712) (xy 154.288084 -37.17545) (xy 154.238986 -37.102421) (xy 154.196733 -37.025229)
			(xy 154.161674 -36.944515) (xy 154.134099 -36.860947) (xy 154.114239 -36.775218) (xy 154.102256 -36.688038)
			(xy 154.098251 -36.60013) (xy 130.031236 -36.60013) (xy 130.030735 -36.64413) (xy 130.022733 -36.731765)
			(xy 130.006795 -36.818309) (xy 129.983053 -36.903045) (xy 129.951704 -36.985271) (xy 129.913007 -37.064306)
			(xy 129.867284 -37.139494) (xy 129.814913 -37.210213) (xy 129.756329 -37.275877) (xy 129.692015 -37.335942)
			(xy 129.622507 -37.389909) (xy 129.548379 -37.437331) (xy 129.470245 -37.477817) (xy 129.388754 -37.51103)
			(xy 129.30458 -37.536694) (xy 129.218421 -37.554598) (xy 129.130991 -37.564593) (xy 129.043014 -37.566597)
			(xy 128.95522 -37.560591) (xy 128.868336 -37.546627) (xy 128.783081 -37.52482) (xy 128.700162 -37.495351)
			(xy 128.620267 -37.458464) (xy 128.544058 -37.414464) (xy 128.472165 -37.363716) (xy 128.405184 -37.306642)
			(xy 128.343672 -37.243712) (xy 128.288136 -37.17545) (xy 128.239038 -37.102421) (xy 128.196785 -37.025229)
			(xy 128.161726 -36.944515) (xy 128.134151 -36.860947) (xy 128.114291 -36.775218) (xy 128.102308 -36.688038)
			(xy 128.098303 -36.60013) (xy 91.930982 -36.60013) (xy 91.930481 -36.64413) (xy 91.922479 -36.731765)
			(xy 91.906541 -36.818309) (xy 91.882799 -36.903045) (xy 91.85145 -36.985271) (xy 91.812753 -37.064306)
			(xy 91.76703 -37.139494) (xy 91.714659 -37.210213) (xy 91.656075 -37.275877) (xy 91.591761 -37.335942)
			(xy 91.522253 -37.389909) (xy 91.448125 -37.437331) (xy 91.369991 -37.477817) (xy 91.2885 -37.51103)
			(xy 91.204326 -37.536694) (xy 91.118167 -37.554598) (xy 91.030737 -37.564593) (xy 90.94276 -37.566597)
			(xy 90.854966 -37.560591) (xy 90.768082 -37.546627) (xy 90.682827 -37.52482) (xy 90.599908 -37.495351)
			(xy 90.520013 -37.458464) (xy 90.443804 -37.414464) (xy 90.371911 -37.363716) (xy 90.30493 -37.306642)
			(xy 90.243418 -37.243712) (xy 90.187882 -37.17545) (xy 90.138784 -37.102421) (xy 90.096531 -37.025229)
			(xy 90.061472 -36.944515) (xy 90.033897 -36.860947) (xy 90.014037 -36.775218) (xy 90.002054 -36.688038)
			(xy 89.998049 -36.60013) (xy 65.931034 -36.60013) (xy 65.930533 -36.64413) (xy 65.922531 -36.731765)
			(xy 65.906593 -36.818309) (xy 65.882851 -36.903045) (xy 65.851502 -36.985271) (xy 65.812805 -37.064306)
			(xy 65.767082 -37.139494) (xy 65.714711 -37.210213) (xy 65.656127 -37.275877) (xy 65.591813 -37.335942)
			(xy 65.522305 -37.389909) (xy 65.448177 -37.437331) (xy 65.370043 -37.477817) (xy 65.288552 -37.51103)
			(xy 65.204378 -37.536694) (xy 65.118219 -37.554598) (xy 65.030789 -37.564593) (xy 64.942812 -37.566597)
			(xy 64.855018 -37.560591) (xy 64.768134 -37.546627) (xy 64.682879 -37.52482) (xy 64.59996 -37.495351)
			(xy 64.520065 -37.458464) (xy 64.443856 -37.414464) (xy 64.371963 -37.363716) (xy 64.304982 -37.306642)
			(xy 64.24347 -37.243712) (xy 64.187934 -37.17545) (xy 64.138836 -37.102421) (xy 64.096583 -37.025229)
			(xy 64.061524 -36.944515) (xy 64.033949 -36.860947) (xy 64.014089 -36.775218) (xy 64.002106 -36.688038)
			(xy 63.998101 -36.60013) (xy 39.931086 -36.60013) (xy 39.930585 -36.64413) (xy 39.922583 -36.731765)
			(xy 39.906645 -36.818309) (xy 39.882903 -36.903045) (xy 39.851554 -36.985271) (xy 39.812857 -37.064306)
			(xy 39.767134 -37.139494) (xy 39.714763 -37.210213) (xy 39.656179 -37.275877) (xy 39.591865 -37.335942)
			(xy 39.522357 -37.389909) (xy 39.448229 -37.437331) (xy 39.370095 -37.477817) (xy 39.288604 -37.51103)
			(xy 39.20443 -37.536694) (xy 39.118271 -37.554598) (xy 39.030841 -37.564593) (xy 38.942864 -37.566597)
			(xy 38.85507 -37.560591) (xy 38.768186 -37.546627) (xy 38.682931 -37.52482) (xy 38.600012 -37.495351)
			(xy 38.520117 -37.458464) (xy 38.443908 -37.414464) (xy 38.372015 -37.363716) (xy 38.305034 -37.306642)
			(xy 38.243522 -37.243712) (xy 38.187986 -37.17545) (xy 38.138888 -37.102421) (xy 38.096635 -37.025229)
			(xy 38.061576 -36.944515) (xy 38.034001 -36.860947) (xy 38.014141 -36.775218) (xy 38.002158 -36.688038)
			(xy 37.998153 -36.60013) (xy 13.931138 -36.60013) (xy 13.930637 -36.64413) (xy 13.922635 -36.731765)
			(xy 13.906697 -36.818309) (xy 13.882955 -36.903045) (xy 13.851606 -36.985271) (xy 13.812909 -37.064306)
			(xy 13.767186 -37.139494) (xy 13.714815 -37.210213) (xy 13.656231 -37.275877) (xy 13.591917 -37.335942)
			(xy 13.522409 -37.389909) (xy 13.448281 -37.437331) (xy 13.370147 -37.477817) (xy 13.288656 -37.51103)
			(xy 13.204482 -37.536694) (xy 13.118323 -37.554598) (xy 13.030893 -37.564593) (xy 12.942916 -37.566597)
			(xy 12.855122 -37.560591) (xy 12.768238 -37.546627) (xy 12.682983 -37.52482) (xy 12.600064 -37.495351)
			(xy 12.520169 -37.458464) (xy 12.44396 -37.414464) (xy 12.372067 -37.363716) (xy 12.305086 -37.306642)
			(xy 12.243574 -37.243712) (xy 12.188038 -37.17545) (xy 12.13894 -37.102421) (xy 12.096687 -37.025229)
			(xy 12.061628 -36.944515) (xy 12.034053 -36.860947) (xy 12.014193 -36.775218) (xy 12.00221 -36.688038)
			(xy 11.998205 -36.60013) (xy 0.508 -36.60013) (xy 0.508 -58.698471) (xy 229.808523 -58.698471) (xy 229.808523 -58.601777)
			(xy 229.816508 -58.505414) (xy 229.832424 -58.410039) (xy 229.85616 -58.316305) (xy 229.887557 -58.22485)
			(xy 229.926398 -58.136301) (xy 229.972419 -58.051261) (xy 230.025305 -57.970313) (xy 230.084696 -57.894008)
			(xy 230.150184 -57.822868) (xy 230.221324 -57.75738) (xy 230.297629 -57.697989) (xy 230.378577 -57.645103)
			(xy 230.463617 -57.599082) (xy 230.552166 -57.560241) (xy 230.643621 -57.528844) (xy 230.737355 -57.505108)
			(xy 230.83273 -57.489192) (xy 230.929093 -57.481207) (xy 231.025787 -57.481207) (xy 231.12215 -57.489192)
			(xy 231.217525 -57.505108) (xy 231.311259 -57.528844) (xy 231.402714 -57.560241) (xy 231.491263 -57.599082)
			(xy 231.576303 -57.645103) (xy 231.657251 -57.697989) (xy 231.733556 -57.75738) (xy 231.804696 -57.822868)
			(xy 231.870184 -57.894008) (xy 231.929575 -57.970313) (xy 231.982461 -58.051261) (xy 232.028482 -58.136301)
			(xy 232.067323 -58.22485) (xy 232.09872 -58.316305) (xy 232.122456 -58.410039) (xy 232.138372 -58.505414)
			(xy 232.146357 -58.601777) (xy 232.146856 -58.650124) (xy 232.146357 -58.698471) (xy 232.138372 -58.794834)
			(xy 232.122456 -58.890209) (xy 232.09872 -58.983943) (xy 232.067323 -59.075398) (xy 232.028482 -59.163947)
			(xy 231.982461 -59.248987) (xy 231.929575 -59.329935) (xy 231.870184 -59.40624) (xy 231.804696 -59.47738)
			(xy 231.733556 -59.542868) (xy 231.657251 -59.602259) (xy 231.576303 -59.655145) (xy 231.491263 -59.701166)
			(xy 231.402714 -59.740007) (xy 231.311259 -59.771404) (xy 231.217525 -59.79514) (xy 231.12215 -59.811056)
			(xy 231.025787 -59.819041) (xy 230.929093 -59.819041) (xy 230.83273 -59.811056) (xy 230.737355 -59.79514)
			(xy 230.643621 -59.771404) (xy 230.552166 -59.740007) (xy 230.463617 -59.701166) (xy 230.378577 -59.655145)
			(xy 230.297629 -59.602259) (xy 230.221324 -59.542868) (xy 230.150184 -59.47738) (xy 230.084696 -59.40624)
			(xy 230.025305 -59.329935) (xy 229.972419 -59.248987) (xy 229.926398 -59.163947) (xy 229.887557 -59.075398)
			(xy 229.85616 -58.983943) (xy 229.832424 -58.890209) (xy 229.816508 -58.794834) (xy 229.808523 -58.698471)
			(xy 0.508 -58.698471) (xy 0.508 -60.13196) (xy 226.436428 -60.13196) (xy 226.436428 -59.26836) (xy 226.436918 -59.238392)
			(xy 226.444741 -59.17897) (xy 226.460254 -59.121077) (xy 226.48319 -59.065704) (xy 226.513157 -59.013798)
			(xy 226.549644 -58.966248) (xy 226.592024 -58.923868) (xy 226.639574 -58.887381) (xy 226.69148 -58.857414)
			(xy 226.746853 -58.834478) (xy 226.804746 -58.818965) (xy 226.864168 -58.811142) (xy 226.924104 -58.811142)
			(xy 226.983526 -58.818965) (xy 227.041419 -58.834478) (xy 227.096792 -58.857414) (xy 227.148698 -58.887381)
			(xy 227.196248 -58.923868) (xy 227.238628 -58.966248) (xy 227.275115 -59.013798) (xy 227.305082 -59.065704)
			(xy 227.328018 -59.121077) (xy 227.343531 -59.17897) (xy 227.351354 -59.238392) (xy 227.351844 -59.26836)
			(xy 227.351844 -60.13196) (xy 227.351354 -60.161928) (xy 227.343531 -60.22135) (xy 227.328018 -60.279243)
			(xy 227.305082 -60.334616) (xy 227.275115 -60.386522) (xy 227.238628 -60.434072) (xy 227.196248 -60.476452)
			(xy 227.148698 -60.512939) (xy 227.096792 -60.542906) (xy 227.041419 -60.565842) (xy 226.983526 -60.581355)
			(xy 226.924104 -60.589178) (xy 226.864168 -60.589178) (xy 226.804746 -60.581355) (xy 226.746853 -60.565842)
			(xy 226.69148 -60.542906) (xy 226.639574 -60.512939) (xy 226.592024 -60.476452) (xy 226.549644 -60.434072)
			(xy 226.513157 -60.386522) (xy 226.48319 -60.334616) (xy 226.460254 -60.279243) (xy 226.444741 -60.22135)
			(xy 226.436918 -60.161928) (xy 226.436428 -60.13196) (xy 0.508 -60.13196) (xy 0.508 -69.798271) (xy 229.808523 -69.798271)
			(xy 229.808523 -69.701577) (xy 229.816508 -69.605214) (xy 229.832424 -69.509839) (xy 229.85616 -69.416105)
			(xy 229.887557 -69.32465) (xy 229.926398 -69.236101) (xy 229.972419 -69.151061) (xy 230.025305 -69.070113)
			(xy 230.084696 -68.993808) (xy 230.150184 -68.922668) (xy 230.221324 -68.85718) (xy 230.297629 -68.797789)
			(xy 230.378577 -68.744903) (xy 230.463617 -68.698882) (xy 230.552166 -68.660041) (xy 230.643621 -68.628644)
			(xy 230.737355 -68.604908) (xy 230.83273 -68.588992) (xy 230.929093 -68.581007) (xy 231.025787 -68.581007)
			(xy 231.12215 -68.588992) (xy 231.217525 -68.604908) (xy 231.311259 -68.628644) (xy 231.402714 -68.660041)
			(xy 231.491263 -68.698882) (xy 231.576303 -68.744903) (xy 231.657251 -68.797789) (xy 231.733556 -68.85718)
			(xy 231.804696 -68.922668) (xy 231.870184 -68.993808) (xy 231.929575 -69.070113) (xy 231.982461 -69.151061)
			(xy 232.028482 -69.236101) (xy 232.067323 -69.32465) (xy 232.09872 -69.416105) (xy 232.122456 -69.509839)
			(xy 232.138372 -69.605214) (xy 232.146357 -69.701577) (xy 232.146856 -69.749924) (xy 232.146357 -69.798271)
			(xy 232.138372 -69.894634) (xy 232.122456 -69.990009) (xy 232.09872 -70.083743) (xy 232.067323 -70.175198)
			(xy 232.028482 -70.263747) (xy 231.982461 -70.348787) (xy 231.929575 -70.429735) (xy 231.870184 -70.50604)
			(xy 231.804696 -70.57718) (xy 231.733556 -70.642668) (xy 231.657251 -70.702059) (xy 231.576303 -70.754945)
			(xy 231.491263 -70.800966) (xy 231.402714 -70.839807) (xy 231.311259 -70.871204) (xy 231.217525 -70.89494)
			(xy 231.12215 -70.910856) (xy 231.025787 -70.918841) (xy 230.929093 -70.918841) (xy 230.83273 -70.910856)
			(xy 230.737355 -70.89494) (xy 230.643621 -70.871204) (xy 230.552166 -70.839807) (xy 230.463617 -70.800966)
			(xy 230.378577 -70.754945) (xy 230.297629 -70.702059) (xy 230.221324 -70.642668) (xy 230.150184 -70.57718)
			(xy 230.084696 -70.50604) (xy 230.025305 -70.429735) (xy 229.972419 -70.348787) (xy 229.926398 -70.263747)
			(xy 229.887557 -70.175198) (xy 229.85616 -70.083743) (xy 229.832424 -69.990009) (xy 229.816508 -69.894634)
			(xy 229.808523 -69.798271) (xy 0.508 -69.798271) (xy 0.508 -75.288385) (xy 262.150829 -75.288385)
			(xy 262.150829 -75.228415) (xy 262.158657 -75.168959) (xy 262.174178 -75.111033) (xy 262.197128 -75.055628)
			(xy 262.227114 -75.003693) (xy 262.263621 -74.956116) (xy 262.306027 -74.913712) (xy 262.353605 -74.877206)
			(xy 262.405541 -74.847222) (xy 262.460946 -74.824274) (xy 262.518872 -74.808754) (xy 262.578329 -74.800928)
			(xy 262.608314 -74.80046) (xy 263.471914 -74.80046) (xy 263.501899 -74.800907) (xy 263.561356 -74.808736)
			(xy 263.619283 -74.824259) (xy 263.674687 -74.84721) (xy 263.726623 -74.877196) (xy 263.7742 -74.913705)
			(xy 263.816604 -74.956111) (xy 263.853111 -75.003689) (xy 263.883096 -75.055625) (xy 263.906045 -75.111031)
			(xy 263.921566 -75.168958) (xy 263.929394 -75.228415) (xy 263.929394 -75.288385) (xy 263.921566 -75.347842)
			(xy 263.906045 -75.405769) (xy 263.883096 -75.461175) (xy 263.853111 -75.513111) (xy 263.816604 -75.560689)
			(xy 263.7742 -75.603095) (xy 263.726623 -75.639604) (xy 263.674687 -75.66959) (xy 263.619283 -75.692541)
			(xy 263.561356 -75.708064) (xy 263.501899 -75.715893) (xy 263.471914 -75.716384) (xy 262.608314 -75.716384)
			(xy 262.578329 -75.715872) (xy 262.518872 -75.708046) (xy 262.460946 -75.692526) (xy 262.405541 -75.669578)
			(xy 262.353605 -75.639594) (xy 262.306027 -75.603088) (xy 262.263621 -75.560684) (xy 262.227114 -75.513107)
			(xy 262.197128 -75.461172) (xy 262.174178 -75.405767) (xy 262.158657 -75.347841) (xy 262.150829 -75.288385)
			(xy 0.508 -75.288385) (xy 0.508 -76.826085) (xy 229.640845 -76.826085) (xy 229.640845 -76.766115)
			(xy 229.648673 -76.706658) (xy 229.664196 -76.648731) (xy 229.687147 -76.593327) (xy 229.717134 -76.541392)
			(xy 229.753643 -76.493816) (xy 229.796051 -76.451413) (xy 229.84363 -76.414908) (xy 229.895568 -76.384926)
			(xy 229.950975 -76.361981) (xy 230.008903 -76.346464) (xy 230.068361 -76.338642) (xy 230.098346 -76.338176)
			(xy 230.961946 -76.338176) (xy 230.991931 -76.338593) (xy 231.051387 -76.346426) (xy 231.109312 -76.361952)
			(xy 231.164715 -76.384906) (xy 231.216648 -76.414894) (xy 231.264223 -76.451404) (xy 231.306626 -76.493811)
			(xy 231.343131 -76.54139) (xy 231.373114 -76.593326) (xy 231.396063 -76.648732) (xy 231.411583 -76.706658)
			(xy 231.41941 -76.766115) (xy 231.41941 -76.826085) (xy 231.411583 -76.885542) (xy 231.396063 -76.943468)
			(xy 231.373114 -76.998874) (xy 231.343131 -77.05081) (xy 231.306626 -77.098389) (xy 231.264223 -77.140796)
			(xy 231.216648 -77.177306) (xy 231.164715 -77.207294) (xy 231.109312 -77.230248) (xy 231.051387 -77.245774)
			(xy 230.991931 -77.253607) (xy 230.961946 -77.2541) (xy 230.098346 -77.2541) (xy 230.068361 -77.253558)
			(xy 230.008903 -77.245736) (xy 229.950975 -77.230219) (xy 229.895568 -77.207274) (xy 229.84363 -77.177292)
			(xy 229.796051 -77.140787) (xy 229.753643 -77.098384) (xy 229.717134 -77.050808) (xy 229.687147 -76.998873)
			(xy 229.664196 -76.943469) (xy 229.648673 -76.885542) (xy 229.640845 -76.826085) (xy 0.508 -76.826085)
			(xy 0.508 -77.365367) (xy 105.150162 -77.365367) (xy 105.150162 -77.305433) (xy 105.157985 -77.246011)
			(xy 105.173496 -77.188119) (xy 105.19643 -77.132746) (xy 105.226396 -77.08084) (xy 105.26288 -77.03329)
			(xy 105.305258 -76.990908) (xy 105.352805 -76.954419) (xy 105.404708 -76.924449) (xy 105.460079 -76.901509)
			(xy 105.51797 -76.885993) (xy 105.577391 -76.878165) (xy 105.607358 -76.877672) (xy 106.470958 -76.877672)
			(xy 106.500928 -76.878178) (xy 106.560354 -76.885997) (xy 106.618252 -76.901506) (xy 106.67363 -76.92444)
			(xy 106.72554 -76.954406) (xy 106.773095 -76.990892) (xy 106.81548 -77.033273) (xy 106.851971 -77.080825)
			(xy 106.881942 -77.132732) (xy 106.904881 -77.188108) (xy 106.920395 -77.246004) (xy 106.928219 -77.305431)
			(xy 106.928219 -77.365367) (xy 109.150162 -77.365367) (xy 109.150162 -77.305433) (xy 109.157984 -77.246012)
			(xy 109.173495 -77.18812) (xy 109.196429 -77.132748) (xy 109.226394 -77.080843) (xy 109.262878 -77.033292)
			(xy 109.305255 -76.990911) (xy 109.352801 -76.954422) (xy 109.404703 -76.924452) (xy 109.460073 -76.901511)
			(xy 109.517963 -76.885994) (xy 109.577383 -76.878165) (xy 109.60735 -76.877672) (xy 110.47095 -76.877672)
			(xy 110.50092 -76.878178) (xy 110.560347 -76.885996) (xy 110.618246 -76.901504) (xy 110.673625 -76.924437)
			(xy 110.725536 -76.954403) (xy 110.773092 -76.990889) (xy 110.815478 -77.03327) (xy 110.851969 -77.080822)
			(xy 110.881941 -77.13273) (xy 110.90488 -77.188107) (xy 110.920395 -77.246003) (xy 110.928219 -77.30543)
			(xy 110.928219 -77.36537) (xy 110.920395 -77.424797) (xy 110.90488 -77.482693) (xy 110.881941 -77.53807)
			(xy 110.851969 -77.589978) (xy 110.815478 -77.63753) (xy 110.773092 -77.679911) (xy 110.725536 -77.716397)
			(xy 110.673625 -77.746363) (xy 110.618246 -77.769296) (xy 110.560347 -77.784804) (xy 110.50092 -77.792622)
			(xy 110.47095 -77.793088) (xy 109.60735 -77.793088) (xy 109.577383 -77.792635) (xy 109.517963 -77.784806)
			(xy 109.460073 -77.769289) (xy 109.404703 -77.746348) (xy 109.352801 -77.716378) (xy 109.305255 -77.679889)
			(xy 109.262878 -77.637508) (xy 109.226394 -77.589957) (xy 109.196429 -77.538052) (xy 109.173495 -77.48268)
			(xy 109.157984 -77.424788) (xy 109.150162 -77.365367) (xy 106.928219 -77.365367) (xy 106.928219 -77.365369)
			(xy 106.920395 -77.424796) (xy 106.904881 -77.482692) (xy 106.881942 -77.538068) (xy 106.851971 -77.589975)
			(xy 106.81548 -77.637527) (xy 106.773095 -77.679908) (xy 106.72554 -77.716394) (xy 106.67363 -77.74636)
			(xy 106.618252 -77.769294) (xy 106.560354 -77.784803) (xy 106.500928 -77.792622) (xy 106.470958 -77.793088)
			(xy 105.607358 -77.793088) (xy 105.577391 -77.792635) (xy 105.51797 -77.784807) (xy 105.460079 -77.769291)
			(xy 105.404708 -77.746351) (xy 105.352805 -77.716381) (xy 105.305258 -77.679892) (xy 105.26288 -77.63751)
			(xy 105.226396 -77.58996) (xy 105.19643 -77.538054) (xy 105.173496 -77.482681) (xy 105.157985 -77.424789)
			(xy 105.150162 -77.365367) (xy 0.508 -77.365367) (xy 0.508 -78.127367) (xy 107.150162 -78.127367)
			(xy 107.150162 -78.067433) (xy 107.157984 -78.008012) (xy 107.173496 -77.950119) (xy 107.19643 -77.894747)
			(xy 107.226395 -77.842842) (xy 107.262879 -77.795291) (xy 107.305256 -77.752909) (xy 107.352803 -77.716421)
			(xy 107.404706 -77.68645) (xy 107.460076 -77.66351) (xy 107.517966 -77.647993) (xy 107.577387 -77.640165)
			(xy 107.607354 -77.639672) (xy 108.470954 -77.639672) (xy 108.500924 -77.640178) (xy 108.560351 -77.647996)
			(xy 108.618249 -77.663505) (xy 108.673627 -77.686438) (xy 108.725538 -77.716405) (xy 108.773094 -77.752891)
			(xy 108.815479 -77.795272) (xy 108.85197 -77.842823) (xy 108.881941 -77.894731) (xy 108.90488 -77.950107)
			(xy 108.920395 -78.008004) (xy 108.928219 -78.06743) (xy 108.928219 -78.12737) (xy 108.920395 -78.186796)
			(xy 108.90488 -78.244693) (xy 108.881941 -78.300069) (xy 108.85197 -78.351977) (xy 108.815479 -78.399528)
			(xy 108.773093 -78.441909) (xy 108.725538 -78.478395) (xy 108.673627 -78.508362) (xy 108.618249 -78.531295)
			(xy 108.560351 -78.546804) (xy 108.500924 -78.554622) (xy 108.470954 -78.555088) (xy 107.607354 -78.555088)
			(xy 107.577387 -78.554635) (xy 107.517966 -78.546807) (xy 107.460076 -78.53129) (xy 107.404706 -78.50835)
			(xy 107.352803 -78.478379) (xy 107.305256 -78.441891) (xy 107.262879 -78.399509) (xy 107.226395 -78.351958)
			(xy 107.19643 -78.300053) (xy 107.173496 -78.244681) (xy 107.157984 -78.186788) (xy 107.150162 -78.127367)
			(xy 0.508 -78.127367) (xy 0.508 -79.238094) (xy 227.9777 -79.238094) (xy 227.9777 -78.374494) (xy 227.97819 -78.344526)
			(xy 227.986013 -78.285104) (xy 228.001526 -78.227211) (xy 228.024462 -78.171838) (xy 228.054429 -78.119932)
			(xy 228.090916 -78.072382) (xy 228.133296 -78.030002) (xy 228.180846 -77.993515) (xy 228.232752 -77.963548)
			(xy 228.288125 -77.940612) (xy 228.346018 -77.925099) (xy 228.40544 -77.917276) (xy 228.465376 -77.917276)
			(xy 228.524798 -77.925099) (xy 228.582691 -77.940612) (xy 228.638064 -77.963548) (xy 228.68997 -77.993515)
			(xy 228.73752 -78.030002) (xy 228.7799 -78.072382) (xy 228.816387 -78.119932) (xy 228.83413 -78.150664)
			(xy 336.40703 -78.150664) (xy 336.40703 -78.090736) (xy 336.414852 -78.031319) (xy 336.430363 -77.973433)
			(xy 336.453297 -77.918066) (xy 336.483261 -77.866166) (xy 336.519743 -77.818621) (xy 336.562119 -77.776245)
			(xy 336.609664 -77.739762) (xy 336.661564 -77.709797) (xy 336.716931 -77.686864) (xy 336.774817 -77.671353)
			(xy 336.834234 -77.66353) (xy 336.864198 -77.66304) (xy 337.727798 -77.66304) (xy 337.75777 -77.663413)
			(xy 337.817202 -77.671237) (xy 337.875104 -77.686751) (xy 337.930486 -77.709691) (xy 337.982399 -77.739663)
			(xy 338.029957 -77.776155) (xy 338.072344 -77.818542) (xy 338.108836 -77.866099) (xy 338.138808 -77.918013)
			(xy 338.161748 -77.973394) (xy 338.177263 -78.031296) (xy 338.185087 -78.090728) (xy 338.185087 -78.150672)
			(xy 338.177263 -78.210104) (xy 338.161748 -78.268006) (xy 338.138808 -78.323387) (xy 338.108836 -78.375301)
			(xy 338.072344 -78.422858) (xy 338.029957 -78.465245) (xy 337.982399 -78.501737) (xy 337.930486 -78.531709)
			(xy 337.875104 -78.554649) (xy 337.817202 -78.570163) (xy 337.75777 -78.577987) (xy 337.727798 -78.578456)
			(xy 336.864198 -78.578456) (xy 336.834234 -78.57787) (xy 336.774817 -78.570047) (xy 336.716931 -78.554536)
			(xy 336.661564 -78.531603) (xy 336.609664 -78.501638) (xy 336.562119 -78.465155) (xy 336.519743 -78.422779)
			(xy 336.483261 -78.375234) (xy 336.453297 -78.323334) (xy 336.430363 -78.267967) (xy 336.414852 -78.210081)
			(xy 336.40703 -78.150664) (xy 228.83413 -78.150664) (xy 228.846354 -78.171838) (xy 228.86929 -78.227211)
			(xy 228.884803 -78.285104) (xy 228.892626 -78.344526) (xy 228.893116 -78.374494) (xy 228.893116 -79.238094)
			(xy 228.892626 -79.268062) (xy 228.884803 -79.327484) (xy 228.86929 -79.385377) (xy 228.846354 -79.44075)
			(xy 228.816387 -79.492656) (xy 228.7799 -79.540206) (xy 228.73752 -79.582586) (xy 228.68997 -79.619073)
			(xy 228.638064 -79.64904) (xy 228.582691 -79.671976) (xy 228.524798 -79.687489) (xy 228.465376 -79.695312)
			(xy 228.40544 -79.695312) (xy 228.346018 -79.687489) (xy 228.288125 -79.671976) (xy 228.232752 -79.64904)
			(xy 228.180846 -79.619073) (xy 228.133296 -79.582586) (xy 228.090916 -79.540206) (xy 228.054429 -79.492656)
			(xy 228.024462 -79.44075) (xy 228.001526 -79.385377) (xy 227.986013 -79.327484) (xy 227.97819 -79.268062)
			(xy 227.9777 -79.238094) (xy 0.508 -79.238094) (xy 0.508 -80.183482) (xy 237.540292 -80.183482) (xy 237.540292 -79.319882)
			(xy 237.540782 -79.289914) (xy 237.548605 -79.230492) (xy 237.564118 -79.172599) (xy 237.587054 -79.117226)
			(xy 237.617021 -79.06532) (xy 237.653508 -79.01777) (xy 237.695888 -78.97539) (xy 237.743438 -78.938903)
			(xy 237.795344 -78.908936) (xy 237.850717 -78.886) (xy 237.90861 -78.870487) (xy 237.968032 -78.862664)
			(xy 238.027968 -78.862664) (xy 238.08739 -78.870487) (xy 238.145283 -78.886) (xy 238.200656 -78.908936)
			(xy 238.207117 -78.912666) (xy 334.407009 -78.912666) (xy 334.407009 -78.852734) (xy 334.414832 -78.793315)
			(xy 334.430343 -78.735425) (xy 334.453278 -78.680055) (xy 334.483244 -78.628153) (xy 334.519729 -78.580606)
			(xy 334.562107 -78.538227) (xy 334.609654 -78.501743) (xy 334.661557 -78.471777) (xy 334.716927 -78.448843)
			(xy 334.774817 -78.433331) (xy 334.834236 -78.425509) (xy 334.864202 -78.42504) (xy 335.727802 -78.42504)
			(xy 335.757773 -78.425434) (xy 335.817201 -78.433258) (xy 335.8751 -78.448773) (xy 335.930479 -78.471711)
			(xy 335.982389 -78.501682) (xy 336.029944 -78.538172) (xy 336.072329 -78.580557) (xy 336.108819 -78.628112)
			(xy 336.13879 -78.680023) (xy 336.161728 -78.735402) (xy 336.177242 -78.793301) (xy 336.185066 -78.852729)
			(xy 336.185066 -78.912664) (xy 338.40703 -78.912664) (xy 338.40703 -78.852736) (xy 338.414852 -78.79332)
			(xy 338.430363 -78.735433) (xy 338.453296 -78.680067) (xy 338.48326 -78.628167) (xy 338.519742 -78.580622)
			(xy 338.562118 -78.538246) (xy 338.609662 -78.501763) (xy 338.661561 -78.471799) (xy 338.716928 -78.448865)
			(xy 338.774814 -78.433353) (xy 338.83423 -78.42553) (xy 338.864194 -78.42504) (xy 339.727794 -78.42504)
			(xy 339.757766 -78.425412) (xy 339.817199 -78.433236) (xy 339.875101 -78.44875) (xy 339.930483 -78.47169)
			(xy 339.982397 -78.501662) (xy 340.029955 -78.538153) (xy 340.072343 -78.580541) (xy 340.108835 -78.628098)
			(xy 340.138808 -78.680011) (xy 340.161748 -78.735393) (xy 340.177263 -78.793296) (xy 340.185087 -78.852728)
			(xy 340.185087 -78.912672) (xy 340.177263 -78.972104) (xy 340.161748 -79.030007) (xy 340.138808 -79.085389)
			(xy 340.108835 -79.137302) (xy 340.072343 -79.184859) (xy 340.029955 -79.227247) (xy 339.982397 -79.263738)
			(xy 339.930483 -79.29371) (xy 339.875101 -79.31665) (xy 339.817199 -79.332164) (xy 339.757766 -79.339988)
			(xy 339.727794 -79.340456) (xy 338.864194 -79.340456) (xy 338.83423 -79.33987) (xy 338.774814 -79.332047)
			(xy 338.716928 -79.316535) (xy 338.661561 -79.293601) (xy 338.609662 -79.263637) (xy 338.562118 -79.227154)
			(xy 338.519742 -79.184778) (xy 338.48326 -79.137233) (xy 338.453296 -79.085333) (xy 338.430363 -79.029967)
			(xy 338.414852 -78.97208) (xy 338.40703 -78.912664) (xy 336.185066 -78.912664) (xy 336.185066 -78.912671)
			(xy 336.177242 -78.972099) (xy 336.161728 -79.029998) (xy 336.13879 -79.085377) (xy 336.108819 -79.137288)
			(xy 336.072329 -79.184843) (xy 336.029944 -79.227228) (xy 335.982389 -79.263718) (xy 335.930479 -79.293689)
			(xy 335.8751 -79.316627) (xy 335.817201 -79.332142) (xy 335.757773 -79.339966) (xy 335.727802 -79.340456)
			(xy 334.864202 -79.340456) (xy 334.834236 -79.339891) (xy 334.774817 -79.332069) (xy 334.716927 -79.316557)
			(xy 334.661557 -79.293623) (xy 334.609654 -79.263657) (xy 334.562107 -79.227173) (xy 334.519729 -79.184794)
			(xy 334.483244 -79.137247) (xy 334.453278 -79.085345) (xy 334.430343 -79.029975) (xy 334.414832 -78.972085)
			(xy 334.407009 -78.912666) (xy 238.207117 -78.912666) (xy 238.252562 -78.938903) (xy 238.300112 -78.97539)
			(xy 238.342492 -79.01777) (xy 238.378979 -79.06532) (xy 238.408946 -79.117226) (xy 238.431882 -79.172599)
			(xy 238.447395 -79.230492) (xy 238.455218 -79.289914) (xy 238.455708 -79.319882) (xy 238.455708 -80.183482)
			(xy 238.455218 -80.21345) (xy 238.447395 -80.272872) (xy 238.431882 -80.330765) (xy 238.408946 -80.386138)
			(xy 238.378979 -80.438044) (xy 238.342492 -80.485594) (xy 238.300112 -80.527974) (xy 238.252562 -80.564461)
			(xy 238.200656 -80.594428) (xy 238.145283 -80.617364) (xy 238.08739 -80.632877) (xy 238.027968 -80.6407)
			(xy 237.968032 -80.6407) (xy 237.90861 -80.632877) (xy 237.850717 -80.617364) (xy 237.795344 -80.594428)
			(xy 237.743438 -80.564461) (xy 237.695888 -80.527974) (xy 237.653508 -80.485594) (xy 237.617021 -80.438044)
			(xy 237.587054 -80.386138) (xy 237.564118 -80.330765) (xy 237.548605 -80.272872) (xy 237.540782 -80.21345)
			(xy 237.540292 -80.183482) (xy 0.508 -80.183482) (xy 0.508 -82.131916) (xy 0.508487 -82.185165) (xy 0.516104 -82.291392)
			(xy 0.531277 -82.396804) (xy 0.553928 -82.500867) (xy 0.583941 -82.603049) (xy 0.621164 -82.702831)
			(xy 0.665407 -82.799705) (xy 0.716446 -82.893178) (xy 0.774019 -82.982773) (xy 0.837835 -83.068035)
			(xy 0.907568 -83.14853) (xy 0.94488 -83.186524) (xy 2.783716 -85.025538) (xy 44.856389 -85.025538)
			(xy 44.856389 -84.896398) (xy 44.864339 -84.767503) (xy 44.880209 -84.639343) (xy 44.903938 -84.512402)
			(xy 44.935437 -84.387163) (xy 44.974586 -84.2641) (xy 45.021237 -84.143681) (xy 45.075212 -84.026362)
			(xy 45.136307 -83.912588) (xy 45.20429 -83.802791) (xy 45.278904 -83.697388) (xy 45.359865 -83.596778)
			(xy 45.446865 -83.501343) (xy 45.539576 -83.411444) (xy 45.637646 -83.327423) (xy 45.740701 -83.249599)
			(xy 45.848352 -83.178267) (xy 45.960191 -83.113697) (xy 46.075792 -83.056135) (xy 46.194717 -83.005798)
			(xy 46.316516 -82.962878) (xy 46.440726 -82.927537) (xy 46.566875 -82.89991) (xy 46.694487 -82.880101)
			(xy 46.823076 -82.868185) (xy 46.952154 -82.864209) (xy 47.081232 -82.868185) (xy 47.209821 -82.880101)
			(xy 47.337433 -82.89991) (xy 47.463582 -82.927537) (xy 47.587792 -82.962878) (xy 47.709591 -83.005798)
			(xy 47.828516 -83.056135) (xy 47.944117 -83.113697) (xy 48.055956 -83.178267) (xy 48.163607 -83.249599)
			(xy 48.266662 -83.327423) (xy 48.303507 -83.35899) (xy 116.623592 -83.35899) (xy 116.623592 -82.49539)
			(xy 116.624082 -82.465422) (xy 116.631905 -82.406) (xy 116.647418 -82.348107) (xy 116.670354 -82.292734)
			(xy 116.700321 -82.240828) (xy 116.736808 -82.193278) (xy 116.779188 -82.150898) (xy 116.826738 -82.114411)
			(xy 116.878644 -82.084444) (xy 116.934017 -82.061508) (xy 116.99191 -82.045995) (xy 117.051332 -82.038172)
			(xy 117.111268 -82.038172) (xy 117.17069 -82.045995) (xy 117.228583 -82.061508) (xy 117.283956 -82.084444)
			(xy 117.335862 -82.114411) (xy 117.383412 -82.150898) (xy 117.425792 -82.193278) (xy 117.462279 -82.240828)
			(xy 117.492246 -82.292734) (xy 117.515182 -82.348107) (xy 117.530695 -82.406) (xy 117.538518 -82.465422)
			(xy 117.539008 -82.49539) (xy 117.539008 -83.35899) (xy 117.538875 -83.367118) (xy 232.68432 -83.367118)
			(xy 232.68432 -82.503518) (xy 232.68481 -82.47355) (xy 232.692633 -82.414128) (xy 232.708146 -82.356235)
			(xy 232.731082 -82.300862) (xy 232.761049 -82.248956) (xy 232.797536 -82.201406) (xy 232.839916 -82.159026)
			(xy 232.887466 -82.122539) (xy 232.939372 -82.092572) (xy 232.994745 -82.069636) (xy 233.052638 -82.054123)
			(xy 233.11206 -82.0463) (xy 233.171996 -82.0463) (xy 233.231418 -82.054123) (xy 233.289311 -82.069636)
			(xy 233.344684 -82.092572) (xy 233.39659 -82.122539) (xy 233.44414 -82.159026) (xy 233.48652 -82.201406)
			(xy 233.523007 -82.248956) (xy 233.552974 -82.300862) (xy 233.568014 -82.337171) (xy 238.132537 -82.337171)
			(xy 238.132537 -82.277229) (xy 238.140362 -82.217799) (xy 238.155876 -82.159898) (xy 238.178816 -82.104519)
			(xy 238.208788 -82.052607) (xy 238.24528 -82.005052) (xy 238.287667 -81.962667) (xy 238.335224 -81.926177)
			(xy 238.387137 -81.896207) (xy 238.442517 -81.87327) (xy 238.500418 -81.857758) (xy 238.559849 -81.849936)
			(xy 238.58982 -81.849468) (xy 239.45342 -81.849468) (xy 239.483385 -81.850007) (xy 239.542803 -81.857832)
			(xy 239.600691 -81.873345) (xy 239.656058 -81.896282) (xy 239.707959 -81.926248) (xy 239.755504 -81.962733)
			(xy 239.769238 -81.976468) (xy 273.798284 -81.976468) (xy 273.798284 -81.112868) (xy 273.798774 -81.0829)
			(xy 273.806597 -81.023478) (xy 273.82211 -80.965585) (xy 273.845046 -80.910212) (xy 273.875013 -80.858306)
			(xy 273.9115 -80.810756) (xy 273.95388 -80.768376) (xy 274.00143 -80.731889) (xy 274.053336 -80.701922)
			(xy 274.108709 -80.678986) (xy 274.166602 -80.663473) (xy 274.226024 -80.65565) (xy 274.28596 -80.65565)
			(xy 274.345382 -80.663473) (xy 274.403275 -80.678986) (xy 274.458648 -80.701922) (xy 274.510554 -80.731889)
			(xy 274.558104 -80.768376) (xy 274.600484 -80.810756) (xy 274.636971 -80.858306) (xy 274.666938 -80.910212)
			(xy 274.689874 -80.965585) (xy 274.705387 -81.023478) (xy 274.71321 -81.0829) (xy 274.7137 -81.112868)
			(xy 274.7137 -81.976468) (xy 274.71321 -82.006436) (xy 274.705387 -82.065858) (xy 274.689874 -82.123751)
			(xy 274.666938 -82.179124) (xy 274.636971 -82.23103) (xy 274.600484 -82.27858) (xy 274.558104 -82.32096)
			(xy 274.510554 -82.357447) (xy 274.458648 -82.387414) (xy 274.403275 -82.41035) (xy 274.345382 -82.425863)
			(xy 274.28596 -82.433686) (xy 274.226024 -82.433686) (xy 274.166602 -82.425863) (xy 274.108709 -82.41035)
			(xy 274.053336 -82.387414) (xy 274.00143 -82.357447) (xy 273.95388 -82.32096) (xy 273.9115 -82.27858)
			(xy 273.875013 -82.23103) (xy 273.845046 -82.179124) (xy 273.82211 -82.123751) (xy 273.806597 -82.065858)
			(xy 273.798774 -82.006436) (xy 273.798284 -81.976468) (xy 239.769238 -81.976468) (xy 239.79788 -82.005111)
			(xy 239.834363 -82.052658) (xy 239.864327 -82.10456) (xy 239.887261 -82.159928) (xy 239.902772 -82.217817)
			(xy 239.910594 -82.277235) (xy 239.910594 -82.337165) (xy 239.902772 -82.396583) (xy 239.887261 -82.454472)
			(xy 239.864327 -82.50984) (xy 239.834363 -82.561742) (xy 239.79788 -82.609289) (xy 239.755504 -82.651667)
			(xy 239.707959 -82.688152) (xy 239.656058 -82.718118) (xy 239.600691 -82.741055) (xy 239.542803 -82.756568)
			(xy 239.483385 -82.764393) (xy 239.45342 -82.764884) (xy 238.58982 -82.764884) (xy 238.559849 -82.764464)
			(xy 238.500418 -82.756642) (xy 238.442517 -82.74113) (xy 238.387137 -82.718193) (xy 238.335224 -82.688223)
			(xy 238.287667 -82.651733) (xy 238.24528 -82.609348) (xy 238.208788 -82.561793) (xy 238.178816 -82.509881)
			(xy 238.155876 -82.454502) (xy 238.140362 -82.396601) (xy 238.132537 -82.337171) (xy 233.568014 -82.337171)
			(xy 233.57591 -82.356235) (xy 233.591423 -82.414128) (xy 233.599246 -82.47355) (xy 233.599736 -82.503518)
			(xy 233.599736 -83.367118) (xy 233.599246 -83.397086) (xy 233.591423 -83.456508) (xy 233.57591 -83.514401)
			(xy 233.552974 -83.569774) (xy 233.523007 -83.62168) (xy 233.48652 -83.66923) (xy 233.44414 -83.71161)
			(xy 233.39659 -83.748097) (xy 233.344684 -83.778064) (xy 233.289311 -83.801) (xy 233.231418 -83.816513)
			(xy 233.171996 -83.824336) (xy 233.11206 -83.824336) (xy 233.052638 -83.816513) (xy 232.994745 -83.801)
			(xy 232.939372 -83.778064) (xy 232.887466 -83.748097) (xy 232.839916 -83.71161) (xy 232.797536 -83.66923)
			(xy 232.761049 -83.62168) (xy 232.731082 -83.569774) (xy 232.708146 -83.514401) (xy 232.692633 -83.456508)
			(xy 232.68481 -83.397086) (xy 232.68432 -83.367118) (xy 117.538875 -83.367118) (xy 117.538518 -83.388958)
			(xy 117.530695 -83.44838) (xy 117.515182 -83.506273) (xy 117.492246 -83.561646) (xy 117.462279 -83.613552)
			(xy 117.425792 -83.661102) (xy 117.383412 -83.703482) (xy 117.335862 -83.739969) (xy 117.283956 -83.769936)
			(xy 117.228583 -83.792872) (xy 117.17069 -83.808385) (xy 117.111268 -83.816208) (xy 117.051332 -83.816208)
			(xy 116.99191 -83.808385) (xy 116.934017 -83.792872) (xy 116.878644 -83.769936) (xy 116.826738 -83.739969)
			(xy 116.779188 -83.703482) (xy 116.736808 -83.661102) (xy 116.700321 -83.613552) (xy 116.670354 -83.561646)
			(xy 116.647418 -83.506273) (xy 116.631905 -83.44838) (xy 116.624082 -83.388958) (xy 116.623592 -83.35899)
			(xy 48.303507 -83.35899) (xy 48.364732 -83.411444) (xy 48.457443 -83.501343) (xy 48.544443 -83.596778)
			(xy 48.625404 -83.697388) (xy 48.700018 -83.802791) (xy 48.768001 -83.912588) (xy 48.829096 -84.026362)
			(xy 48.883071 -84.143681) (xy 48.929722 -84.2641) (xy 48.968871 -84.387163) (xy 49.00037 -84.512402)
			(xy 49.024099 -84.639343) (xy 49.039969 -84.767503) (xy 49.047919 -84.896398) (xy 49.048416 -84.960968)
			(xy 49.047919 -85.025538) (xy 49.039969 -85.154433) (xy 49.024099 -85.282593) (xy 49.009819 -85.358986)
			(xy 117.385592 -85.358986) (xy 117.385592 -84.495386) (xy 117.386082 -84.465418) (xy 117.393905 -84.405996)
			(xy 117.409418 -84.348103) (xy 117.432354 -84.29273) (xy 117.462321 -84.240824) (xy 117.498808 -84.193274)
			(xy 117.541188 -84.150894) (xy 117.588738 -84.114407) (xy 117.640644 -84.08444) (xy 117.696017 -84.061504)
			(xy 117.75391 -84.045991) (xy 117.813332 -84.038168) (xy 117.873268 -84.038168) (xy 117.93269 -84.045991)
			(xy 117.990583 -84.061504) (xy 118.045956 -84.08444) (xy 118.097862 -84.114407) (xy 118.145412 -84.150894)
			(xy 118.187792 -84.193274) (xy 118.224279 -84.240824) (xy 118.254246 -84.29273) (xy 118.277182 -84.348103)
			(xy 118.292695 -84.405996) (xy 118.300518 -84.465418) (xy 118.301008 -84.495386) (xy 118.301008 -85.358986)
			(xy 118.300518 -85.388954) (xy 118.292695 -85.448376) (xy 118.289959 -85.458587) (xy 232.264389 -85.458587)
			(xy 232.264389 -85.398613) (xy 232.272218 -85.339151) (xy 232.28774 -85.28122) (xy 232.310692 -85.225811)
			(xy 232.34068 -85.173871) (xy 232.377191 -85.126291) (xy 232.4196 -85.083883) (xy 232.467181 -85.047373)
			(xy 232.519122 -85.017387) (xy 232.574531 -84.994437) (xy 232.632463 -84.978915) (xy 232.691925 -84.971088)
			(xy 232.721912 -84.97062) (xy 233.585512 -84.97062) (xy 233.615495 -84.971147) (xy 233.674947 -84.978975)
			(xy 233.732868 -84.994497) (xy 233.788268 -85.017445) (xy 233.840199 -85.047429) (xy 233.887772 -85.083934)
			(xy 233.930174 -85.126337) (xy 233.963295 -85.169502) (xy 238.555276 -85.169502) (xy 238.555276 -84.305902)
			(xy 238.555766 -84.275918) (xy 238.563594 -84.216462) (xy 238.579115 -84.158537) (xy 238.602064 -84.103133)
			(xy 238.632048 -84.051199) (xy 238.668554 -84.003623) (xy 238.710959 -83.961218) (xy 238.758535 -83.924712)
			(xy 238.810469 -83.894728) (xy 238.865873 -83.871779) (xy 238.923798 -83.856258) (xy 238.983254 -83.84843)
			(xy 239.043222 -83.84843) (xy 239.102678 -83.856258) (xy 239.160603 -83.871779) (xy 239.216007 -83.894728)
			(xy 239.267941 -83.924712) (xy 239.315517 -83.961218) (xy 239.357922 -84.003623) (xy 239.394428 -84.051199)
			(xy 239.424412 -84.103133) (xy 239.447361 -84.158537) (xy 239.462882 -84.216462) (xy 239.46603 -84.24037)
			(xy 273.951192 -84.24037) (xy 273.951192 -83.37677) (xy 273.951682 -83.346786) (xy 273.95951 -83.28733)
			(xy 273.975031 -83.229405) (xy 273.99798 -83.174001) (xy 274.027964 -83.122067) (xy 274.06447 -83.074491)
			(xy 274.106875 -83.032086) (xy 274.154451 -82.99558) (xy 274.206385 -82.965596) (xy 274.261789 -82.942647)
			(xy 274.319714 -82.927126) (xy 274.37917 -82.919298) (xy 274.439138 -82.919298) (xy 274.498594 -82.927126)
			(xy 274.556519 -82.942647) (xy 274.611923 -82.965596) (xy 274.663857 -82.99558) (xy 274.711433 -83.032086)
			(xy 274.753838 -83.074491) (xy 274.790344 -83.122067) (xy 274.820328 -83.174001) (xy 274.843277 -83.229405)
			(xy 274.858798 -83.28733) (xy 274.866626 -83.346786) (xy 274.867116 -83.37677) (xy 274.867116 -84.144612)
			(xy 345.879928 -84.144612) (xy 345.879928 -83.281012) (xy 345.880418 -83.251028) (xy 345.888246 -83.191572)
			(xy 345.903767 -83.133647) (xy 345.926716 -83.078243) (xy 345.9567 -83.026309) (xy 345.993206 -82.978733)
			(xy 346.035611 -82.936328) (xy 346.083187 -82.899822) (xy 346.135121 -82.869838) (xy 346.190525 -82.846889)
			(xy 346.24845 -82.831368) (xy 346.307906 -82.82354) (xy 346.367874 -82.82354) (xy 346.42733 -82.831368)
			(xy 346.485255 -82.846889) (xy 346.540659 -82.869838) (xy 346.592593 -82.899822) (xy 346.640169 -82.936328)
			(xy 346.682574 -82.978733) (xy 346.71908 -83.026309) (xy 346.749064 -83.078243) (xy 346.772013 -83.133647)
			(xy 346.787534 -83.191572) (xy 346.795362 -83.251028) (xy 346.795852 -83.281012) (xy 346.795852 -84.144612)
			(xy 346.795362 -84.174596) (xy 346.787534 -84.234052) (xy 346.772013 -84.291977) (xy 346.749064 -84.347381)
			(xy 346.71908 -84.399315) (xy 346.682574 -84.446891) (xy 346.640169 -84.489296) (xy 346.592593 -84.525802)
			(xy 346.540659 -84.555786) (xy 346.485255 -84.578735) (xy 346.42733 -84.594256) (xy 346.367874 -84.602084)
			(xy 346.307906 -84.602084) (xy 346.24845 -84.594256) (xy 346.190525 -84.578735) (xy 346.135121 -84.555786)
			(xy 346.083187 -84.525802) (xy 346.035611 -84.489296) (xy 345.993206 -84.446891) (xy 345.9567 -84.399315)
			(xy 345.926716 -84.347381) (xy 345.903767 -84.291977) (xy 345.888246 -84.234052) (xy 345.880418 -84.174596)
			(xy 345.879928 -84.144612) (xy 274.867116 -84.144612) (xy 274.867116 -84.24037) (xy 274.866626 -84.270354)
			(xy 274.858798 -84.32981) (xy 274.843277 -84.387735) (xy 274.820328 -84.443139) (xy 274.790344 -84.495073)
			(xy 274.753838 -84.542649) (xy 274.711433 -84.585054) (xy 274.663857 -84.62156) (xy 274.611923 -84.651544)
			(xy 274.556519 -84.674493) (xy 274.498594 -84.690014) (xy 274.439138 -84.697842) (xy 274.37917 -84.697842)
			(xy 274.319714 -84.690014) (xy 274.261789 -84.674493) (xy 274.206385 -84.651544) (xy 274.154451 -84.62156)
			(xy 274.106875 -84.585054) (xy 274.06447 -84.542649) (xy 274.027964 -84.495073) (xy 273.99798 -84.443139)
			(xy 273.975031 -84.387735) (xy 273.95951 -84.32981) (xy 273.951682 -84.270354) (xy 273.951192 -84.24037)
			(xy 239.46603 -84.24037) (xy 239.47071 -84.275918) (xy 239.4712 -84.305902) (xy 239.4712 -85.169502)
			(xy 239.47071 -85.199486) (xy 239.462882 -85.258942) (xy 239.447361 -85.316867) (xy 239.424412 -85.372271)
			(xy 239.394428 -85.424205) (xy 239.357922 -85.471781) (xy 239.315517 -85.514186) (xy 239.267941 -85.550692)
			(xy 239.216007 -85.580676) (xy 239.160603 -85.603625) (xy 239.102678 -85.619146) (xy 239.043222 -85.626974)
			(xy 238.983254 -85.626974) (xy 238.923798 -85.619146) (xy 238.865873 -85.603625) (xy 238.810469 -85.580676)
			(xy 238.758535 -85.550692) (xy 238.710959 -85.514186) (xy 238.668554 -85.471781) (xy 238.632048 -85.424205)
			(xy 238.602064 -85.372271) (xy 238.579115 -85.316867) (xy 238.563594 -85.258942) (xy 238.555766 -85.199486)
			(xy 238.555276 -85.169502) (xy 233.963295 -85.169502) (xy 233.966678 -85.173911) (xy 233.99666 -85.225842)
			(xy 234.019607 -85.281243) (xy 234.035127 -85.339165) (xy 234.042954 -85.398617) (xy 234.042954 -85.458583)
			(xy 234.035127 -85.518035) (xy 234.019607 -85.575957) (xy 233.99666 -85.631358) (xy 233.966678 -85.683289)
			(xy 233.930174 -85.730863) (xy 233.887772 -85.773266) (xy 233.840199 -85.809771) (xy 233.788268 -85.839755)
			(xy 233.732868 -85.862703) (xy 233.674947 -85.878225) (xy 233.615495 -85.886053) (xy 233.585512 -85.886544)
			(xy 232.721912 -85.886544) (xy 232.691925 -85.886112) (xy 232.632463 -85.878285) (xy 232.574531 -85.862763)
			(xy 232.519122 -85.839813) (xy 232.467181 -85.809827) (xy 232.4196 -85.773317) (xy 232.377191 -85.730909)
			(xy 232.34068 -85.683329) (xy 232.310692 -85.631389) (xy 232.28774 -85.57598) (xy 232.272218 -85.518049)
			(xy 232.264389 -85.458587) (xy 118.289959 -85.458587) (xy 118.277182 -85.506269) (xy 118.254246 -85.561642)
			(xy 118.224279 -85.613548) (xy 118.187792 -85.661098) (xy 118.145412 -85.703478) (xy 118.097862 -85.739965)
			(xy 118.045956 -85.769932) (xy 117.990583 -85.792868) (xy 117.93269 -85.808381) (xy 117.873268 -85.816204)
			(xy 117.813332 -85.816204) (xy 117.75391 -85.808381) (xy 117.696017 -85.792868) (xy 117.640644 -85.769932)
			(xy 117.588738 -85.739965) (xy 117.541188 -85.703478) (xy 117.498808 -85.661098) (xy 117.462321 -85.613548)
			(xy 117.432354 -85.561642) (xy 117.409418 -85.506269) (xy 117.393905 -85.448376) (xy 117.386082 -85.388954)
			(xy 117.385592 -85.358986) (xy 49.009819 -85.358986) (xy 49.00037 -85.409534) (xy 48.968871 -85.534773)
			(xy 48.929722 -85.657836) (xy 48.883071 -85.778255) (xy 48.829096 -85.895574) (xy 48.768001 -86.009348)
			(xy 48.700018 -86.119145) (xy 48.625404 -86.224548) (xy 48.544443 -86.325158) (xy 48.457443 -86.420593)
			(xy 48.364732 -86.510492) (xy 48.266662 -86.594513) (xy 48.163607 -86.672337) (xy 48.055956 -86.743669)
			(xy 47.944117 -86.808239) (xy 47.937853 -86.811358) (xy 99.84232 -86.811358) (xy 99.84232 -85.947758)
			(xy 99.84281 -85.917774) (xy 99.850638 -85.858318) (xy 99.866159 -85.800393) (xy 99.889108 -85.744989)
			(xy 99.919092 -85.693055) (xy 99.955598 -85.645479) (xy 99.998003 -85.603074) (xy 100.045579 -85.566568)
			(xy 100.097513 -85.536584) (xy 100.152917 -85.513635) (xy 100.210842 -85.498114) (xy 100.270298 -85.490286)
			(xy 100.330266 -85.490286) (xy 100.389722 -85.498114) (xy 100.447647 -85.513635) (xy 100.503051 -85.536584)
			(xy 100.554985 -85.566568) (xy 100.602561 -85.603074) (xy 100.644966 -85.645479) (xy 100.681472 -85.693055)
			(xy 100.711456 -85.744989) (xy 100.734405 -85.800393) (xy 100.749926 -85.858318) (xy 100.757754 -85.917774)
			(xy 100.758244 -85.947758) (xy 100.758244 -86.811358) (xy 100.757754 -86.841342) (xy 100.749926 -86.900798)
			(xy 100.734405 -86.958723) (xy 100.711456 -87.014127) (xy 100.681472 -87.066061) (xy 100.644966 -87.113637)
			(xy 100.602561 -87.156042) (xy 100.554985 -87.192548) (xy 100.503051 -87.222532) (xy 100.447647 -87.245481)
			(xy 100.389722 -87.261002) (xy 100.330266 -87.26883) (xy 100.270298 -87.26883) (xy 100.210842 -87.261002)
			(xy 100.152917 -87.245481) (xy 100.097513 -87.222532) (xy 100.045579 -87.192548) (xy 99.998003 -87.156042)
			(xy 99.955598 -87.113637) (xy 99.919092 -87.066061) (xy 99.889108 -87.014127) (xy 99.866159 -86.958723)
			(xy 99.850638 -86.900798) (xy 99.84281 -86.841342) (xy 99.84232 -86.811358) (xy 47.937853 -86.811358)
			(xy 47.828516 -86.865801) (xy 47.709591 -86.916138) (xy 47.587792 -86.959058) (xy 47.463582 -86.994399)
			(xy 47.337433 -87.022026) (xy 47.209821 -87.041835) (xy 47.081232 -87.053751) (xy 46.952154 -87.057728)
			(xy 46.823076 -87.053751) (xy 46.694487 -87.041835) (xy 46.566875 -87.022026) (xy 46.440726 -86.994399)
			(xy 46.316516 -86.959058) (xy 46.194717 -86.916138) (xy 46.075792 -86.865801) (xy 45.960191 -86.808239)
			(xy 45.848352 -86.743669) (xy 45.740701 -86.672337) (xy 45.637646 -86.594513) (xy 45.539576 -86.510492)
			(xy 45.446865 -86.420593) (xy 45.359865 -86.325158) (xy 45.278904 -86.224548) (xy 45.20429 -86.119145)
			(xy 45.136307 -86.009348) (xy 45.075212 -85.895574) (xy 45.021237 -85.778255) (xy 44.974586 -85.657836)
			(xy 44.935437 -85.534773) (xy 44.903938 -85.409534) (xy 44.880209 -85.282593) (xy 44.864339 -85.154433)
			(xy 44.856389 -85.025538) (xy 2.783716 -85.025538) (xy 3.573272 -85.81517) (xy 3.622687 -85.865245)
			(xy 3.716468 -85.970133) (xy 3.804219 -86.080117) (xy 3.885663 -86.194848) (xy 3.960544 -86.313966)
			(xy 4.028628 -86.437097) (xy 4.089698 -86.563852) (xy 4.143563 -86.693833) (xy 4.190054 -86.82663)
			(xy 4.229024 -86.961825) (xy 4.260351 -87.098994) (xy 4.283935 -87.237703) (xy 4.297613 -87.358982)
			(xy 116.623592 -87.358982) (xy 116.623592 -86.495382) (xy 116.624082 -86.465414) (xy 116.631905 -86.405992)
			(xy 116.647418 -86.348099) (xy 116.670354 -86.292726) (xy 116.700321 -86.24082) (xy 116.736808 -86.19327)
			(xy 116.779188 -86.15089) (xy 116.826738 -86.114403) (xy 116.878644 -86.084436) (xy 116.934017 -86.0615)
			(xy 116.99191 -86.045987) (xy 117.051332 -86.038164) (xy 117.111268 -86.038164) (xy 117.17069 -86.045987)
			(xy 117.228583 -86.0615) (xy 117.283956 -86.084436) (xy 117.335862 -86.114403) (xy 117.383412 -86.15089)
			(xy 117.425792 -86.19327) (xy 117.462279 -86.24082) (xy 117.492246 -86.292726) (xy 117.515182 -86.348099)
			(xy 117.530695 -86.405992) (xy 117.538518 -86.465414) (xy 117.539008 -86.495382) (xy 117.539008 -87.358982)
			(xy 117.538518 -87.38895) (xy 117.531262 -87.444066) (xy 232.194882 -87.444066) (xy 232.194882 -87.384134)
			(xy 232.202704 -87.324714) (xy 232.218215 -87.266824) (xy 232.241149 -87.211454) (xy 232.271114 -87.15955)
			(xy 232.307596 -87.112002) (xy 232.349973 -87.069621) (xy 232.397519 -87.033135) (xy 232.44942 -87.003166)
			(xy 232.504788 -86.980227) (xy 232.562677 -86.964712) (xy 232.622096 -86.956884) (xy 232.652062 -86.956392)
			(xy 233.515662 -86.956392) (xy 233.545633 -86.956859) (xy 233.605062 -86.964678) (xy 233.662961 -86.980188)
			(xy 233.718341 -87.003123) (xy 233.770254 -87.033091) (xy 233.81781 -87.069578) (xy 233.860197 -87.111961)
			(xy 233.896688 -87.159515) (xy 233.92666 -87.211425) (xy 233.9496 -87.266803) (xy 233.965115 -87.324701)
			(xy 233.972939 -87.384129) (xy 233.972939 -87.416385) (xy 234.381521 -87.416385) (xy 234.381521 -87.356415)
			(xy 234.389349 -87.296959) (xy 234.40487 -87.239032) (xy 234.42782 -87.183628) (xy 234.457804 -87.131692)
			(xy 234.494312 -87.084115) (xy 234.536717 -87.04171) (xy 234.584294 -87.005203) (xy 234.636229 -86.975219)
			(xy 234.691634 -86.952269) (xy 234.749561 -86.936748) (xy 234.809017 -86.928921) (xy 234.839002 -86.928452)
			(xy 235.702602 -86.928452) (xy 235.732587 -86.928914) (xy 235.792044 -86.936742) (xy 235.849971 -86.952264)
			(xy 235.905376 -86.975214) (xy 235.957312 -87.005199) (xy 236.004889 -87.041707) (xy 236.047295 -87.084112)
			(xy 236.083802 -87.13169) (xy 236.113787 -87.183626) (xy 236.136737 -87.239031) (xy 236.152258 -87.296958)
			(xy 236.155843 -87.324184) (xy 330.477876 -87.324184) (xy 330.477876 -86.460584) (xy 330.478366 -86.430616)
			(xy 330.486189 -86.371194) (xy 330.501702 -86.313301) (xy 330.524638 -86.257928) (xy 330.554605 -86.206022)
			(xy 330.591092 -86.158472) (xy 330.633472 -86.116092) (xy 330.681022 -86.079605) (xy 330.732928 -86.049638)
			(xy 330.788301 -86.026702) (xy 330.846194 -86.011189) (xy 330.905616 -86.003366) (xy 330.965552 -86.003366)
			(xy 331.024974 -86.011189) (xy 331.082867 -86.026702) (xy 331.13824 -86.049638) (xy 331.190146 -86.079605)
			(xy 331.237696 -86.116092) (xy 331.266212 -86.144608) (xy 346.641928 -86.144608) (xy 346.641928 -85.281008)
			(xy 346.642418 -85.251024) (xy 346.650246 -85.191568) (xy 346.665767 -85.133643) (xy 346.688716 -85.078239)
			(xy 346.7187 -85.026305) (xy 346.755206 -84.978729) (xy 346.797611 -84.936324) (xy 346.845187 -84.899818)
			(xy 346.897121 -84.869834) (xy 346.952525 -84.846885) (xy 347.01045 -84.831364) (xy 347.069906 -84.823536)
			(xy 347.129874 -84.823536) (xy 347.18933 -84.831364) (xy 347.247255 -84.846885) (xy 347.302659 -84.869834)
			(xy 347.354593 -84.899818) (xy 347.402169 -84.936324) (xy 347.444574 -84.978729) (xy 347.48108 -85.026305)
			(xy 347.511064 -85.078239) (xy 347.534013 -85.133643) (xy 347.549534 -85.191568) (xy 347.557362 -85.251024)
			(xy 347.557852 -85.281008) (xy 347.557852 -86.144608) (xy 347.557362 -86.174592) (xy 347.549534 -86.234048)
			(xy 347.534013 -86.291973) (xy 347.511064 -86.347377) (xy 347.48108 -86.399311) (xy 347.444574 -86.446887)
			(xy 347.402169 -86.489292) (xy 347.354593 -86.525798) (xy 347.302659 -86.555782) (xy 347.247255 -86.578731)
			(xy 347.18933 -86.594252) (xy 347.129874 -86.60208) (xy 347.069906 -86.60208) (xy 347.01045 -86.594252)
			(xy 346.952525 -86.578731) (xy 346.897121 -86.555782) (xy 346.845187 -86.525798) (xy 346.797611 -86.489292)
			(xy 346.755206 -86.446887) (xy 346.7187 -86.399311) (xy 346.688716 -86.347377) (xy 346.665767 -86.291973)
			(xy 346.650246 -86.234048) (xy 346.642418 -86.174592) (xy 346.641928 -86.144608) (xy 331.266212 -86.144608)
			(xy 331.280076 -86.158472) (xy 331.316563 -86.206022) (xy 331.34653 -86.257928) (xy 331.369466 -86.313301)
			(xy 331.384979 -86.371194) (xy 331.392802 -86.430616) (xy 331.393292 -86.460584) (xy 331.393292 -87.324184)
			(xy 331.392802 -87.354152) (xy 331.384979 -87.413574) (xy 331.369466 -87.471467) (xy 331.34653 -87.52684)
			(xy 331.316563 -87.578746) (xy 331.280076 -87.626296) (xy 331.237696 -87.668676) (xy 331.190146 -87.705163)
			(xy 331.13824 -87.73513) (xy 331.082867 -87.758066) (xy 331.024974 -87.773579) (xy 330.965552 -87.781402)
			(xy 330.905616 -87.781402) (xy 330.846194 -87.773579) (xy 330.788301 -87.758066) (xy 330.732928 -87.73513)
			(xy 330.681022 -87.705163) (xy 330.633472 -87.668676) (xy 330.591092 -87.626296) (xy 330.554605 -87.578746)
			(xy 330.524638 -87.52684) (xy 330.501702 -87.471467) (xy 330.486189 -87.413574) (xy 330.478366 -87.354152)
			(xy 330.477876 -87.324184) (xy 236.155843 -87.324184) (xy 236.160086 -87.356415) (xy 236.160086 -87.416385)
			(xy 236.152258 -87.475842) (xy 236.136737 -87.533769) (xy 236.113787 -87.589174) (xy 236.083802 -87.64111)
			(xy 236.047295 -87.688688) (xy 236.004889 -87.731093) (xy 235.957312 -87.767601) (xy 235.905376 -87.797586)
			(xy 235.849971 -87.820536) (xy 235.792044 -87.836058) (xy 235.732587 -87.843886) (xy 235.702602 -87.844376)
			(xy 234.839002 -87.844376) (xy 234.809017 -87.843879) (xy 234.749561 -87.836052) (xy 234.691634 -87.820531)
			(xy 234.636229 -87.797581) (xy 234.584294 -87.767597) (xy 234.536717 -87.73109) (xy 234.494312 -87.688685)
			(xy 234.457804 -87.641108) (xy 234.42782 -87.589172) (xy 234.40487 -87.533768) (xy 234.389349 -87.475841)
			(xy 234.381521 -87.416385) (xy 233.972939 -87.416385) (xy 233.972939 -87.444071) (xy 233.965115 -87.503499)
			(xy 233.9496 -87.561397) (xy 233.92666 -87.616775) (xy 233.896688 -87.668685) (xy 233.860197 -87.716239)
			(xy 233.81781 -87.758622) (xy 233.770254 -87.795109) (xy 233.718341 -87.825077) (xy 233.662961 -87.848012)
			(xy 233.605062 -87.863522) (xy 233.545633 -87.871341) (xy 233.515662 -87.871808) (xy 232.652062 -87.871808)
			(xy 232.622096 -87.871316) (xy 232.562677 -87.863488) (xy 232.504788 -87.847973) (xy 232.44942 -87.825034)
			(xy 232.397519 -87.795065) (xy 232.349973 -87.758579) (xy 232.307596 -87.716198) (xy 232.271114 -87.66865)
			(xy 232.241149 -87.616746) (xy 232.218215 -87.561376) (xy 232.202704 -87.503486) (xy 232.194882 -87.444066)
			(xy 117.531262 -87.444066) (xy 117.530695 -87.448372) (xy 117.515182 -87.506265) (xy 117.492246 -87.561638)
			(xy 117.462279 -87.613544) (xy 117.425792 -87.661094) (xy 117.383412 -87.703474) (xy 117.335862 -87.739961)
			(xy 117.283956 -87.769928) (xy 117.228583 -87.792864) (xy 117.17069 -87.808377) (xy 117.111268 -87.8162)
			(xy 117.051332 -87.8162) (xy 116.99191 -87.808377) (xy 116.934017 -87.792864) (xy 116.878644 -87.769928)
			(xy 116.826738 -87.739961) (xy 116.779188 -87.703474) (xy 116.736808 -87.661094) (xy 116.700321 -87.613544)
			(xy 116.670354 -87.561638) (xy 116.647418 -87.506265) (xy 116.631905 -87.448372) (xy 116.624082 -87.38895)
			(xy 116.623592 -87.358982) (xy 4.297613 -87.358982) (xy 4.299703 -87.377516) (xy 4.307605 -87.517994)
			(xy 4.308094 -87.588344) (xy 4.308094 -88.006187) (xy 238.124409 -88.006187) (xy 238.124409 -87.946213)
			(xy 238.132238 -87.886751) (xy 238.147762 -87.82882) (xy 238.170714 -87.773411) (xy 238.200704 -87.721472)
			(xy 238.237216 -87.673892) (xy 238.279627 -87.631486) (xy 238.32721 -87.594978) (xy 238.379152 -87.564994)
			(xy 238.434563 -87.542047) (xy 238.492496 -87.526529) (xy 238.551959 -87.518706) (xy 238.581946 -87.51824)
			(xy 239.445546 -87.51824) (xy 239.475528 -87.518729) (xy 239.53498 -87.526561) (xy 239.5929 -87.542086)
			(xy 239.648299 -87.565038) (xy 239.700228 -87.595024) (xy 239.747799 -87.631531) (xy 239.790199 -87.673935)
			(xy 239.826701 -87.72151) (xy 239.856682 -87.773442) (xy 239.879628 -87.828843) (xy 239.895148 -87.886765)
			(xy 239.902974 -87.946217) (xy 239.902974 -88.006183) (xy 239.895148 -88.065635) (xy 239.879628 -88.123557)
			(xy 239.870911 -88.144604) (xy 345.879928 -88.144604) (xy 345.879928 -87.281004) (xy 345.880418 -87.25102)
			(xy 345.888246 -87.191564) (xy 345.903767 -87.133639) (xy 345.926716 -87.078235) (xy 345.9567 -87.026301)
			(xy 345.993206 -86.978725) (xy 346.035611 -86.93632) (xy 346.083187 -86.899814) (xy 346.135121 -86.86983)
			(xy 346.190525 -86.846881) (xy 346.24845 -86.83136) (xy 346.307906 -86.823532) (xy 346.367874 -86.823532)
			(xy 346.42733 -86.83136) (xy 346.485255 -86.846881) (xy 346.540659 -86.86983) (xy 346.592593 -86.899814)
			(xy 346.640169 -86.93632) (xy 346.682574 -86.978725) (xy 346.71908 -87.026301) (xy 346.749064 -87.078235)
			(xy 346.772013 -87.133639) (xy 346.787534 -87.191564) (xy 346.795362 -87.25102) (xy 346.795852 -87.281004)
			(xy 346.795852 -88.144604) (xy 346.795362 -88.174588) (xy 346.787534 -88.234044) (xy 346.772013 -88.291969)
			(xy 346.749064 -88.347373) (xy 346.71908 -88.399307) (xy 346.682574 -88.446883) (xy 346.640169 -88.489288)
			(xy 346.592593 -88.525794) (xy 346.540659 -88.555778) (xy 346.485255 -88.578727) (xy 346.42733 -88.594248)
			(xy 346.367874 -88.602076) (xy 346.307906 -88.602076) (xy 346.24845 -88.594248) (xy 346.190525 -88.578727)
			(xy 346.135121 -88.555778) (xy 346.083187 -88.525794) (xy 346.035611 -88.489288) (xy 345.993206 -88.446883)
			(xy 345.9567 -88.399307) (xy 345.926716 -88.347373) (xy 345.903767 -88.291969) (xy 345.888246 -88.234044)
			(xy 345.880418 -88.174588) (xy 345.879928 -88.144604) (xy 239.870911 -88.144604) (xy 239.856682 -88.178958)
			(xy 239.826701 -88.23089) (xy 239.790199 -88.278465) (xy 239.747799 -88.320869) (xy 239.700228 -88.357376)
			(xy 239.648299 -88.387362) (xy 239.5929 -88.410314) (xy 239.53498 -88.425839) (xy 239.475528 -88.433671)
			(xy 239.445546 -88.434164) (xy 238.581946 -88.434164) (xy 238.551959 -88.433694) (xy 238.492496 -88.425871)
			(xy 238.434563 -88.410353) (xy 238.379152 -88.387406) (xy 238.32721 -88.357422) (xy 238.279627 -88.320914)
			(xy 238.237216 -88.278508) (xy 238.200704 -88.230928) (xy 238.170714 -88.178989) (xy 238.147762 -88.12358)
			(xy 238.132238 -88.065649) (xy 238.124409 -88.006187) (xy 4.308094 -88.006187) (xy 4.308094 -89.358978)
			(xy 117.385592 -89.358978) (xy 117.385592 -88.495378) (xy 117.386082 -88.46541) (xy 117.393905 -88.405988)
			(xy 117.409418 -88.348095) (xy 117.432354 -88.292722) (xy 117.462321 -88.240816) (xy 117.498808 -88.193266)
			(xy 117.541188 -88.150886) (xy 117.588738 -88.114399) (xy 117.640644 -88.084432) (xy 117.696017 -88.061496)
			(xy 117.75391 -88.045983) (xy 117.813332 -88.03816) (xy 117.873268 -88.03816) (xy 117.93269 -88.045983)
			(xy 117.990583 -88.061496) (xy 118.045956 -88.084432) (xy 118.097862 -88.114399) (xy 118.145412 -88.150886)
			(xy 118.187792 -88.193266) (xy 118.224279 -88.240816) (xy 118.254246 -88.292722) (xy 118.277182 -88.348095)
			(xy 118.292695 -88.405988) (xy 118.300518 -88.46541) (xy 118.301008 -88.495378) (xy 118.301008 -89.358978)
			(xy 118.300518 -89.388946) (xy 118.292695 -89.448368) (xy 118.277182 -89.506261) (xy 118.254246 -89.561634)
			(xy 118.224279 -89.61354) (xy 118.187792 -89.66109) (xy 118.145412 -89.70347) (xy 118.097862 -89.739957)
			(xy 118.045956 -89.769924) (xy 117.990583 -89.79286) (xy 117.93269 -89.808373) (xy 117.873268 -89.816196)
			(xy 117.813332 -89.816196) (xy 117.75391 -89.808373) (xy 117.696017 -89.79286) (xy 117.640644 -89.769924)
			(xy 117.588738 -89.739957) (xy 117.541188 -89.70347) (xy 117.498808 -89.66109) (xy 117.462321 -89.61354)
			(xy 117.432354 -89.561634) (xy 117.409418 -89.506261) (xy 117.393905 -89.448368) (xy 117.386082 -89.388946)
			(xy 117.385592 -89.358978) (xy 4.308094 -89.358978) (xy 4.308094 -90.1446) (xy 346.641928 -90.1446)
			(xy 346.641928 -89.281) (xy 346.642418 -89.251016) (xy 346.650246 -89.19156) (xy 346.665767 -89.133635)
			(xy 346.688716 -89.078231) (xy 346.7187 -89.026297) (xy 346.755206 -88.978721) (xy 346.797611 -88.936316)
			(xy 346.845187 -88.89981) (xy 346.897121 -88.869826) (xy 346.952525 -88.846877) (xy 347.01045 -88.831356)
			(xy 347.069906 -88.823528) (xy 347.129874 -88.823528) (xy 347.18933 -88.831356) (xy 347.247255 -88.846877)
			(xy 347.302659 -88.869826) (xy 347.354593 -88.89981) (xy 347.402169 -88.936316) (xy 347.444574 -88.978721)
			(xy 347.48108 -89.026297) (xy 347.511064 -89.078231) (xy 347.534013 -89.133635) (xy 347.549534 -89.19156)
			(xy 347.557362 -89.251016) (xy 347.557852 -89.281) (xy 347.557852 -90.1446) (xy 347.557362 -90.174584)
			(xy 347.549534 -90.23404) (xy 347.534013 -90.291965) (xy 347.511064 -90.347369) (xy 347.48108 -90.399303)
			(xy 347.444574 -90.446879) (xy 347.402169 -90.489284) (xy 347.354593 -90.52579) (xy 347.302659 -90.555774)
			(xy 347.247255 -90.578723) (xy 347.18933 -90.594244) (xy 347.129874 -90.602072) (xy 347.069906 -90.602072)
			(xy 347.01045 -90.594244) (xy 346.952525 -90.578723) (xy 346.897121 -90.555774) (xy 346.845187 -90.52579)
			(xy 346.797611 -90.489284) (xy 346.755206 -90.446879) (xy 346.7187 -90.399303) (xy 346.688716 -90.347369)
			(xy 346.665767 -90.291965) (xy 346.650246 -90.23404) (xy 346.642418 -90.174584) (xy 346.641928 -90.1446)
			(xy 4.308094 -90.1446) (xy 4.308094 -94.088485) (xy 109.149614 -94.088485) (xy 109.149614 -94.028515)
			(xy 109.157442 -93.969058) (xy 109.172963 -93.911131) (xy 109.195912 -93.855726) (xy 109.225897 -93.80379)
			(xy 109.262405 -93.756213) (xy 109.30481 -93.713807) (xy 109.352387 -93.6773) (xy 109.404322 -93.647314)
			(xy 109.459727 -93.624364) (xy 109.517654 -93.608843) (xy 109.577111 -93.601014) (xy 109.607096 -93.600524)
			(xy 110.470696 -93.600524) (xy 110.500681 -93.601021) (xy 110.560138 -93.608848) (xy 110.618064 -93.624369)
			(xy 110.673469 -93.647318) (xy 110.725405 -93.677303) (xy 110.772982 -93.71381) (xy 110.815388 -93.756215)
			(xy 110.851895 -93.803792) (xy 110.88188 -93.855727) (xy 110.90483 -93.911132) (xy 110.920351 -93.969058)
			(xy 110.928179 -94.028515) (xy 110.928179 -94.088485) (xy 110.920351 -94.147942) (xy 110.90483 -94.205868)
			(xy 110.88188 -94.261273) (xy 110.851895 -94.313208) (xy 110.815388 -94.360785) (xy 110.772982 -94.40319)
			(xy 110.725405 -94.439697) (xy 110.673469 -94.469682) (xy 110.618064 -94.492631) (xy 110.560138 -94.508152)
			(xy 110.500681 -94.515979) (xy 110.470696 -94.516448) (xy 109.607096 -94.516448) (xy 109.577111 -94.515986)
			(xy 109.517654 -94.508157) (xy 109.459727 -94.492636) (xy 109.404322 -94.469686) (xy 109.352387 -94.4397)
			(xy 109.30481 -94.403193) (xy 109.262405 -94.360787) (xy 109.225897 -94.31321) (xy 109.195912 -94.261274)
			(xy 109.172963 -94.205869) (xy 109.157442 -94.147942) (xy 109.149614 -94.088485) (xy 4.308094 -94.088485)
			(xy 4.308094 -95.214948) (xy 47.274239 -95.214948) (xy 47.278194 -95.123111) (xy 47.290029 -95.031954)
			(xy 47.309656 -94.942151) (xy 47.33693 -94.854369) (xy 47.37165 -94.769255) (xy 47.413558 -94.687442)
			(xy 47.462344 -94.609534) (xy 47.517647 -94.536109) (xy 47.579057 -94.467709) (xy 47.646119 -94.404842)
			(xy 47.718338 -94.347972) (xy 47.795178 -94.297521) (xy 47.876071 -94.253862) (xy 47.960417 -94.217319)
			(xy 48.047593 -94.188162) (xy 48.136952 -94.166608) (xy 48.227833 -94.152814) (xy 48.319564 -94.146884)
			(xy 48.411465 -94.148862) (xy 48.502856 -94.158733) (xy 48.59306 -94.176423) (xy 48.681409 -94.201803)
			(xy 48.767249 -94.234683) (xy 48.849945 -94.274821) (xy 48.928885 -94.32192) (xy 49.003483 -94.37563)
			(xy 49.073189 -94.435554) (xy 49.137484 -94.501248) (xy 49.195895 -94.572226) (xy 49.247987 -94.647963)
			(xy 49.293376 -94.727898) (xy 49.331726 -94.811438) (xy 49.362751 -94.897966) (xy 49.386224 -94.986841)
			(xy 49.40197 -95.077405) (xy 49.409872 -95.168987) (xy 49.410366 -95.214948) (xy 71.639189 -95.214948)
			(xy 71.643144 -95.123111) (xy 71.654979 -95.031954) (xy 71.674606 -94.942151) (xy 71.70188 -94.854369)
			(xy 71.7366 -94.769255) (xy 71.778508 -94.687442) (xy 71.827294 -94.609534) (xy 71.882597 -94.536109)
			(xy 71.944007 -94.467709) (xy 72.011069 -94.404842) (xy 72.083288 -94.347972) (xy 72.160128 -94.297521)
			(xy 72.241021 -94.253862) (xy 72.325367 -94.217319) (xy 72.412543 -94.188162) (xy 72.501902 -94.166608)
			(xy 72.592783 -94.152814) (xy 72.684514 -94.146884) (xy 72.776415 -94.148862) (xy 72.867806 -94.158733)
			(xy 72.95801 -94.176423) (xy 73.046359 -94.201803) (xy 73.132199 -94.234683) (xy 73.214895 -94.274821)
			(xy 73.293835 -94.32192) (xy 73.368433 -94.37563) (xy 73.438139 -94.435554) (xy 73.502434 -94.501248)
			(xy 73.560845 -94.572226) (xy 73.612937 -94.647963) (xy 73.658326 -94.727898) (xy 73.696676 -94.811438)
			(xy 73.727701 -94.897966) (xy 73.751174 -94.986841) (xy 73.76692 -95.077405) (xy 73.774822 -95.168987)
			(xy 73.775316 -95.214948) (xy 73.774822 -95.260909) (xy 73.774772 -95.261486) (xy 163.375394 -95.261486)
			(xy 163.375394 -95.168314) (xy 163.383515 -95.075496) (xy 163.399694 -94.983738) (xy 163.423808 -94.893741)
			(xy 163.455675 -94.806187) (xy 163.495052 -94.721744) (xy 163.541638 -94.641054) (xy 163.595079 -94.564731)
			(xy 163.654969 -94.493357) (xy 163.720852 -94.427473) (xy 163.792226 -94.367583) (xy 163.868549 -94.314141)
			(xy 163.949238 -94.267554) (xy 164.033681 -94.228178) (xy 164.121235 -94.19631) (xy 164.211233 -94.172195)
			(xy 164.30299 -94.156015) (xy 164.395808 -94.147894) (xy 164.442394 -94.147386) (xy 164.442648 -94.147386)
			(xy 164.489237 -94.1478) (xy 164.582061 -94.155925) (xy 164.673824 -94.172109) (xy 164.763826 -94.196229)
			(xy 164.851385 -94.228101) (xy 164.935832 -94.267483) (xy 165.016526 -94.314074) (xy 165.092852 -94.367522)
			(xy 165.164229 -94.427418) (xy 165.230115 -94.493306) (xy 165.290008 -94.564687) (xy 165.343451 -94.641015)
			(xy 165.390039 -94.721711) (xy 165.429417 -94.80616) (xy 165.461286 -94.893719) (xy 165.485401 -94.983723)
			(xy 165.501581 -95.075487) (xy 165.509702 -95.168311) (xy 165.509702 -95.214948) (xy 187.739796 -95.214948)
			(xy 187.743748 -95.123155) (xy 187.755578 -95.032041) (xy 187.775195 -94.942281) (xy 187.802457 -94.85454)
			(xy 187.83716 -94.769468) (xy 187.879048 -94.687693) (xy 187.927811 -94.609822) (xy 187.983087 -94.536432)
			(xy 188.044468 -94.468065) (xy 188.111499 -94.405227) (xy 188.183683 -94.348385) (xy 188.260487 -94.297958)
			(xy 188.341341 -94.25432) (xy 188.425647 -94.217794) (xy 188.512781 -94.188651) (xy 188.602098 -94.167106)
			(xy 188.692936 -94.15332) (xy 188.784623 -94.147393) (xy 188.87648 -94.14937) (xy 188.967828 -94.159236)
			(xy 189.057988 -94.176918) (xy 189.146296 -94.202285) (xy 189.232095 -94.23515) (xy 189.314752 -94.275269)
			(xy 189.393654 -94.322345) (xy 189.468217 -94.376029) (xy 189.537889 -94.435925) (xy 189.602154 -94.501588)
			(xy 189.660537 -94.572532) (xy 189.712604 -94.648233) (xy 189.757972 -94.72813) (xy 189.796303 -94.81163)
			(xy 189.827314 -94.898117) (xy 189.850775 -94.98695) (xy 189.866514 -95.07747) (xy 189.874412 -95.169009)
			(xy 189.874906 -95.214948) (xy 279.474181 -95.214948) (xy 279.478136 -95.123111) (xy 279.489971 -95.031954)
			(xy 279.509598 -94.942151) (xy 279.536872 -94.854369) (xy 279.571592 -94.769255) (xy 279.6135 -94.687442)
			(xy 279.662286 -94.609534) (xy 279.717589 -94.536109) (xy 279.778999 -94.467709) (xy 279.846061 -94.404842)
			(xy 279.91828 -94.347972) (xy 279.99512 -94.297521) (xy 280.076013 -94.253862) (xy 280.160359 -94.217319)
			(xy 280.247535 -94.188162) (xy 280.336894 -94.166608) (xy 280.427775 -94.152814) (xy 280.519506 -94.146884)
			(xy 280.611407 -94.148862) (xy 280.702798 -94.158733) (xy 280.793002 -94.176423) (xy 280.881351 -94.201803)
			(xy 280.967191 -94.234683) (xy 281.049887 -94.274821) (xy 281.128827 -94.32192) (xy 281.203425 -94.37563)
			(xy 281.273131 -94.435554) (xy 281.337426 -94.501248) (xy 281.395837 -94.572226) (xy 281.447929 -94.647963)
			(xy 281.493318 -94.727898) (xy 281.531668 -94.811438) (xy 281.562693 -94.897966) (xy 281.586166 -94.986841)
			(xy 281.601912 -95.077405) (xy 281.609814 -95.168987) (xy 281.610308 -95.214948) (xy 303.839131 -95.214948)
			(xy 303.843086 -95.123111) (xy 303.854921 -95.031954) (xy 303.874548 -94.942151) (xy 303.901822 -94.854369)
			(xy 303.936542 -94.769255) (xy 303.97845 -94.687442) (xy 304.027236 -94.609534) (xy 304.082539 -94.536109)
			(xy 304.143949 -94.467709) (xy 304.211011 -94.404842) (xy 304.28323 -94.347972) (xy 304.36007 -94.297521)
			(xy 304.440963 -94.253862) (xy 304.525309 -94.217319) (xy 304.612485 -94.188162) (xy 304.701844 -94.166608)
			(xy 304.792725 -94.152814) (xy 304.884456 -94.146884) (xy 304.976357 -94.148862) (xy 305.067748 -94.158733)
			(xy 305.157952 -94.176423) (xy 305.246301 -94.201803) (xy 305.332141 -94.234683) (xy 305.414837 -94.274821)
			(xy 305.493777 -94.32192) (xy 305.568375 -94.37563) (xy 305.638081 -94.435554) (xy 305.702376 -94.501248)
			(xy 305.760787 -94.572226) (xy 305.812879 -94.647963) (xy 305.858268 -94.727898) (xy 305.896618 -94.811438)
			(xy 305.91901 -94.87389) (xy 338.405861 -94.87389) (xy 338.405861 -94.81391) (xy 338.413691 -94.754443)
			(xy 338.429215 -94.696507) (xy 338.45217 -94.641093) (xy 338.482161 -94.58915) (xy 338.518676 -94.541565)
			(xy 338.561089 -94.499155) (xy 338.608676 -94.462643) (xy 338.660622 -94.432655) (xy 338.716037 -94.409705)
			(xy 338.773975 -94.394184) (xy 338.833442 -94.386359) (xy 338.863432 -94.385892) (xy 339.727032 -94.385892)
			(xy 339.757012 -94.386476) (xy 339.816458 -94.394306) (xy 339.874374 -94.409828) (xy 339.929769 -94.432777)
			(xy 339.981694 -94.462759) (xy 340.029262 -94.499262) (xy 340.071659 -94.541662) (xy 340.108159 -94.589232)
			(xy 340.138137 -94.64116) (xy 340.161082 -94.696556) (xy 340.1766 -94.754473) (xy 340.184426 -94.81392)
			(xy 340.184426 -94.87388) (xy 340.1766 -94.933327) (xy 340.161082 -94.991244) (xy 340.138137 -95.04664)
			(xy 340.108159 -95.098568) (xy 340.071659 -95.146138) (xy 340.029262 -95.188538) (xy 339.994846 -95.214948)
			(xy 395.574279 -95.214948) (xy 395.578234 -95.123111) (xy 395.590069 -95.031954) (xy 395.609696 -94.942151)
			(xy 395.63697 -94.854369) (xy 395.67169 -94.769255) (xy 395.713598 -94.687442) (xy 395.762384 -94.609534)
			(xy 395.817687 -94.536109) (xy 395.879097 -94.467709) (xy 395.946159 -94.404842) (xy 396.018378 -94.347972)
			(xy 396.095218 -94.297521) (xy 396.176111 -94.253862) (xy 396.260457 -94.217319) (xy 396.347633 -94.188162)
			(xy 396.436992 -94.166608) (xy 396.527873 -94.152814) (xy 396.619604 -94.146884) (xy 396.711505 -94.148862)
			(xy 396.802896 -94.158733) (xy 396.8931 -94.176423) (xy 396.981449 -94.201803) (xy 397.067289 -94.234683)
			(xy 397.149985 -94.274821) (xy 397.228925 -94.32192) (xy 397.303523 -94.37563) (xy 397.373229 -94.435554)
			(xy 397.437524 -94.501248) (xy 397.495935 -94.572226) (xy 397.548027 -94.647963) (xy 397.593416 -94.727898)
			(xy 397.631766 -94.811438) (xy 397.662791 -94.897966) (xy 397.686264 -94.986841) (xy 397.70201 -95.077405)
			(xy 397.709912 -95.168987) (xy 397.710406 -95.214948) (xy 419.939229 -95.214948) (xy 419.943184 -95.123111)
			(xy 419.955019 -95.031954) (xy 419.974646 -94.942151) (xy 420.00192 -94.854369) (xy 420.03664 -94.769255)
			(xy 420.078548 -94.687442) (xy 420.127334 -94.609534) (xy 420.182637 -94.536109) (xy 420.244047 -94.467709)
			(xy 420.311109 -94.404842) (xy 420.383328 -94.347972) (xy 420.460168 -94.297521) (xy 420.541061 -94.253862)
			(xy 420.625407 -94.217319) (xy 420.712583 -94.188162) (xy 420.801942 -94.166608) (xy 420.892823 -94.152814)
			(xy 420.984554 -94.146884) (xy 421.076455 -94.148862) (xy 421.167846 -94.158733) (xy 421.25805 -94.176423)
			(xy 421.346399 -94.201803) (xy 421.432239 -94.234683) (xy 421.514935 -94.274821) (xy 421.593875 -94.32192)
			(xy 421.668473 -94.37563) (xy 421.738179 -94.435554) (xy 421.802474 -94.501248) (xy 421.860885 -94.572226)
			(xy 421.912977 -94.647963) (xy 421.958366 -94.727898) (xy 421.996716 -94.811438) (xy 422.027741 -94.897966)
			(xy 422.051214 -94.986841) (xy 422.06696 -95.077405) (xy 422.074862 -95.168987) (xy 422.075356 -95.214948)
			(xy 422.074862 -95.260909) (xy 422.06696 -95.352491) (xy 422.051214 -95.443055) (xy 422.027741 -95.53193)
			(xy 421.996716 -95.618458) (xy 421.958366 -95.701998) (xy 421.912977 -95.781933) (xy 421.860885 -95.85767)
			(xy 421.802474 -95.928648) (xy 421.738179 -95.994342) (xy 421.668473 -96.054266) (xy 421.593875 -96.107976)
			(xy 421.514935 -96.155075) (xy 421.432239 -96.195213) (xy 421.346399 -96.228093) (xy 421.25805 -96.253473)
			(xy 421.167846 -96.271163) (xy 421.076455 -96.281034) (xy 420.984554 -96.283012) (xy 420.892823 -96.277082)
			(xy 420.801942 -96.263288) (xy 420.712583 -96.241734) (xy 420.625407 -96.212577) (xy 420.541061 -96.176034)
			(xy 420.460168 -96.132375) (xy 420.383328 -96.081924) (xy 420.311109 -96.025054) (xy 420.244047 -95.962187)
			(xy 420.182637 -95.893787) (xy 420.127334 -95.820362) (xy 420.078548 -95.742454) (xy 420.03664 -95.660641)
			(xy 420.00192 -95.575527) (xy 419.974646 -95.487745) (xy 419.955019 -95.397942) (xy 419.943184 -95.306785)
			(xy 419.939229 -95.214948) (xy 397.710406 -95.214948) (xy 397.709912 -95.260909) (xy 397.70201 -95.352491)
			(xy 397.686264 -95.443055) (xy 397.662791 -95.53193) (xy 397.631766 -95.618458) (xy 397.593416 -95.701998)
			(xy 397.548027 -95.781933) (xy 397.495935 -95.85767) (xy 397.437524 -95.928648) (xy 397.373229 -95.994342)
			(xy 397.303523 -96.054266) (xy 397.228925 -96.107976) (xy 397.149985 -96.155075) (xy 397.067289 -96.195213)
			(xy 396.981449 -96.228093) (xy 396.8931 -96.253473) (xy 396.802896 -96.271163) (xy 396.711505 -96.281034)
			(xy 396.619604 -96.283012) (xy 396.527873 -96.277082) (xy 396.436992 -96.263288) (xy 396.347633 -96.241734)
			(xy 396.260457 -96.212577) (xy 396.176111 -96.176034) (xy 396.095218 -96.132375) (xy 396.018378 -96.081924)
			(xy 395.946159 -96.025054) (xy 395.879097 -95.962187) (xy 395.817687 -95.893787) (xy 395.762384 -95.820362)
			(xy 395.713598 -95.742454) (xy 395.67169 -95.660641) (xy 395.63697 -95.575527) (xy 395.609696 -95.487745)
			(xy 395.590069 -95.397942) (xy 395.578234 -95.306785) (xy 395.574279 -95.214948) (xy 339.994846 -95.214948)
			(xy 339.981694 -95.225041) (xy 339.929769 -95.255023) (xy 339.874374 -95.277972) (xy 339.816458 -95.293494)
			(xy 339.757012 -95.301324) (xy 339.727032 -95.301816) (xy 338.863432 -95.301816) (xy 338.833442 -95.301441)
			(xy 338.773975 -95.293616) (xy 338.716037 -95.278095) (xy 338.660622 -95.255145) (xy 338.608676 -95.225157)
			(xy 338.561089 -95.188645) (xy 338.518676 -95.146235) (xy 338.482161 -95.09865) (xy 338.45217 -95.046707)
			(xy 338.429215 -94.991293) (xy 338.413691 -94.933357) (xy 338.405861 -94.87389) (xy 305.91901 -94.87389)
			(xy 305.927643 -94.897966) (xy 305.951116 -94.986841) (xy 305.966862 -95.077405) (xy 305.974764 -95.168987)
			(xy 305.975258 -95.214948) (xy 305.974764 -95.260909) (xy 305.966862 -95.352491) (xy 305.951116 -95.443055)
			(xy 305.927643 -95.53193) (xy 305.896618 -95.618458) (xy 305.858268 -95.701998) (xy 305.812879 -95.781933)
			(xy 305.760787 -95.85767) (xy 305.702376 -95.928648) (xy 305.638081 -95.994342) (xy 305.568375 -96.054266)
			(xy 305.493777 -96.107976) (xy 305.414837 -96.155075) (xy 305.332141 -96.195213) (xy 305.246301 -96.228093)
			(xy 305.157952 -96.253473) (xy 305.067748 -96.271163) (xy 304.976357 -96.281034) (xy 304.884456 -96.283012)
			(xy 304.792725 -96.277082) (xy 304.701844 -96.263288) (xy 304.612485 -96.241734) (xy 304.525309 -96.212577)
			(xy 304.440963 -96.176034) (xy 304.36007 -96.132375) (xy 304.28323 -96.081924) (xy 304.211011 -96.025054)
			(xy 304.143949 -95.962187) (xy 304.082539 -95.893787) (xy 304.027236 -95.820362) (xy 303.97845 -95.742454)
			(xy 303.936542 -95.660641) (xy 303.901822 -95.575527) (xy 303.874548 -95.487745) (xy 303.854921 -95.397942)
			(xy 303.843086 -95.306785) (xy 303.839131 -95.214948) (xy 281.610308 -95.214948) (xy 281.609814 -95.260909)
			(xy 281.601912 -95.352491) (xy 281.586166 -95.443055) (xy 281.562693 -95.53193) (xy 281.531668 -95.618458)
			(xy 281.493318 -95.701998) (xy 281.447929 -95.781933) (xy 281.395837 -95.85767) (xy 281.337426 -95.928648)
			(xy 281.273131 -95.994342) (xy 281.203425 -96.054266) (xy 281.128827 -96.107976) (xy 281.049887 -96.155075)
			(xy 280.967191 -96.195213) (xy 280.881351 -96.228093) (xy 280.793002 -96.253473) (xy 280.702798 -96.271163)
			(xy 280.611407 -96.281034) (xy 280.519506 -96.283012) (xy 280.427775 -96.277082) (xy 280.336894 -96.263288)
			(xy 280.247535 -96.241734) (xy 280.160359 -96.212577) (xy 280.076013 -96.176034) (xy 279.99512 -96.132375)
			(xy 279.91828 -96.081924) (xy 279.846061 -96.025054) (xy 279.778999 -95.962187) (xy 279.717589 -95.893787)
			(xy 279.662286 -95.820362) (xy 279.6135 -95.742454) (xy 279.571592 -95.660641) (xy 279.536872 -95.575527)
			(xy 279.509598 -95.487745) (xy 279.489971 -95.397942) (xy 279.478136 -95.306785) (xy 279.474181 -95.214948)
			(xy 189.874906 -95.214948) (xy 189.874412 -95.260887) (xy 189.866514 -95.352426) (xy 189.850775 -95.442946)
			(xy 189.827314 -95.531779) (xy 189.796303 -95.618266) (xy 189.757972 -95.701766) (xy 189.712604 -95.781663)
			(xy 189.660537 -95.857364) (xy 189.602154 -95.928308) (xy 189.537889 -95.993971) (xy 189.468217 -96.053867)
			(xy 189.393654 -96.107551) (xy 189.314752 -96.154627) (xy 189.232095 -96.194746) (xy 189.146296 -96.227611)
			(xy 189.057988 -96.252978) (xy 188.967828 -96.27066) (xy 188.87648 -96.280526) (xy 188.784623 -96.282503)
			(xy 188.692936 -96.276576) (xy 188.602098 -96.26279) (xy 188.512781 -96.241245) (xy 188.425647 -96.212102)
			(xy 188.341341 -96.175576) (xy 188.260487 -96.131938) (xy 188.183683 -96.081511) (xy 188.111499 -96.024669)
			(xy 188.044468 -95.961831) (xy 187.983087 -95.893464) (xy 187.927811 -95.820074) (xy 187.879048 -95.742203)
			(xy 187.83716 -95.660428) (xy 187.802457 -95.575356) (xy 187.775195 -95.487615) (xy 187.755578 -95.397855)
			(xy 187.743748 -95.306741) (xy 187.739796 -95.214948) (xy 165.509702 -95.214948) (xy 165.509702 -95.261489)
			(xy 165.501581 -95.354313) (xy 165.485401 -95.446077) (xy 165.461286 -95.536081) (xy 165.429417 -95.62364)
			(xy 165.390039 -95.708089) (xy 165.343451 -95.788785) (xy 165.290008 -95.865113) (xy 165.230115 -95.936494)
			(xy 165.164229 -96.002382) (xy 165.092852 -96.062278) (xy 165.016526 -96.115726) (xy 164.935832 -96.162317)
			(xy 164.851385 -96.201699) (xy 164.763826 -96.233571) (xy 164.673824 -96.257691) (xy 164.582061 -96.273875)
			(xy 164.489237 -96.282) (xy 164.442648 -96.28251) (xy 164.442394 -96.28251) (xy 164.395808 -96.281906)
			(xy 164.30299 -96.273785) (xy 164.211233 -96.257605) (xy 164.121235 -96.23349) (xy 164.033681 -96.201622)
			(xy 163.949238 -96.162246) (xy 163.868549 -96.115659) (xy 163.792226 -96.062217) (xy 163.720852 -96.002327)
			(xy 163.654969 -95.936443) (xy 163.595079 -95.865069) (xy 163.541638 -95.788746) (xy 163.495052 -95.708056)
			(xy 163.455675 -95.623613) (xy 163.423808 -95.536059) (xy 163.399694 -95.446062) (xy 163.383515 -95.354304)
			(xy 163.375394 -95.261486) (xy 73.774772 -95.261486) (xy 73.76692 -95.352491) (xy 73.751174 -95.443055)
			(xy 73.727701 -95.53193) (xy 73.696676 -95.618458) (xy 73.658326 -95.701998) (xy 73.612937 -95.781933)
			(xy 73.560845 -95.85767) (xy 73.502434 -95.928648) (xy 73.438139 -95.994342) (xy 73.368433 -96.054266)
			(xy 73.293835 -96.107976) (xy 73.214895 -96.155075) (xy 73.132199 -96.195213) (xy 73.046359 -96.228093)
			(xy 72.95801 -96.253473) (xy 72.867806 -96.271163) (xy 72.776415 -96.281034) (xy 72.684514 -96.283012)
			(xy 72.592783 -96.277082) (xy 72.501902 -96.263288) (xy 72.412543 -96.241734) (xy 72.325367 -96.212577)
			(xy 72.241021 -96.176034) (xy 72.160128 -96.132375) (xy 72.083288 -96.081924) (xy 72.011069 -96.025054)
			(xy 71.944007 -95.962187) (xy 71.882597 -95.893787) (xy 71.827294 -95.820362) (xy 71.778508 -95.742454)
			(xy 71.7366 -95.660641) (xy 71.70188 -95.575527) (xy 71.674606 -95.487745) (xy 71.654979 -95.397942)
			(xy 71.643144 -95.306785) (xy 71.639189 -95.214948) (xy 49.410366 -95.214948) (xy 49.409872 -95.260909)
			(xy 49.40197 -95.352491) (xy 49.386224 -95.443055) (xy 49.362751 -95.53193) (xy 49.331726 -95.618458)
			(xy 49.293376 -95.701998) (xy 49.247987 -95.781933) (xy 49.195895 -95.85767) (xy 49.137484 -95.928648)
			(xy 49.073189 -95.994342) (xy 49.003483 -96.054266) (xy 48.928885 -96.107976) (xy 48.849945 -96.155075)
			(xy 48.767249 -96.195213) (xy 48.681409 -96.228093) (xy 48.59306 -96.253473) (xy 48.502856 -96.271163)
			(xy 48.411465 -96.281034) (xy 48.319564 -96.283012) (xy 48.227833 -96.277082) (xy 48.136952 -96.263288)
			(xy 48.047593 -96.241734) (xy 47.960417 -96.212577) (xy 47.876071 -96.176034) (xy 47.795178 -96.132375)
			(xy 47.718338 -96.081924) (xy 47.646119 -96.025054) (xy 47.579057 -95.962187) (xy 47.517647 -95.893787)
			(xy 47.462344 -95.820362) (xy 47.413558 -95.742454) (xy 47.37165 -95.660641) (xy 47.33693 -95.575527)
			(xy 47.309656 -95.487745) (xy 47.290029 -95.397942) (xy 47.278194 -95.306785) (xy 47.274239 -95.214948)
			(xy 4.308094 -95.214948) (xy 4.308094 -98.766863) (xy 206.090008 -98.766863) (xy 206.090008 -98.633301)
			(xy 206.098072 -98.499983) (xy 206.114172 -98.367395) (xy 206.138247 -98.236021) (xy 206.17021 -98.10634)
			(xy 206.209945 -97.978826) (xy 206.257307 -97.853943) (xy 206.312122 -97.732148) (xy 206.374192 -97.613885)
			(xy 206.443288 -97.499586) (xy 206.51916 -97.389666) (xy 206.60153 -97.284529) (xy 206.690098 -97.184556)
			(xy 206.78454 -97.090114) (xy 206.884513 -97.001546) (xy 206.98965 -96.919176) (xy 207.09957 -96.843304)
			(xy 207.213869 -96.774208) (xy 207.332132 -96.712138) (xy 207.453927 -96.657323) (xy 207.57881 -96.609961)
			(xy 207.706324 -96.570226) (xy 207.836005 -96.538263) (xy 207.967379 -96.514188) (xy 208.099967 -96.498088)
			(xy 208.233285 -96.490024) (xy 208.366847 -96.490024) (xy 208.500165 -96.498088) (xy 208.632753 -96.514188)
			(xy 208.764127 -96.538263) (xy 208.893808 -96.570226) (xy 209.021322 -96.609961) (xy 209.146205 -96.657323)
			(xy 209.268 -96.712138) (xy 209.386263 -96.774208) (xy 209.500562 -96.843304) (xy 209.610482 -96.919176)
			(xy 209.715619 -97.001546) (xy 209.815592 -97.090114) (xy 209.910034 -97.184556) (xy 209.998602 -97.284529)
			(xy 210.080972 -97.389666) (xy 210.156844 -97.499586) (xy 210.22594 -97.613885) (xy 210.28801 -97.732148)
			(xy 210.342825 -97.853943) (xy 210.390187 -97.978826) (xy 210.429922 -98.10634) (xy 210.461885 -98.236021)
			(xy 210.48596 -98.367395) (xy 210.50206 -98.499983) (xy 210.510124 -98.633301) (xy 210.510628 -98.700082)
			(xy 210.510124 -98.766863) (xy 257.089906 -98.766863) (xy 257.089906 -98.633301) (xy 257.09797 -98.499983)
			(xy 257.11407 -98.367395) (xy 257.138145 -98.236021) (xy 257.170108 -98.10634) (xy 257.209843 -97.978826)
			(xy 257.257205 -97.853943) (xy 257.31202 -97.732148) (xy 257.37409 -97.613885) (xy 257.443186 -97.499586)
			(xy 257.519058 -97.389666) (xy 257.601428 -97.284529) (xy 257.689996 -97.184556) (xy 257.784438 -97.090114)
			(xy 257.884411 -97.001546) (xy 257.989548 -96.919176) (xy 258.099468 -96.843304) (xy 258.213767 -96.774208)
			(xy 258.33203 -96.712138) (xy 258.453825 -96.657323) (xy 258.578708 -96.609961) (xy 258.706222 -96.570226)
			(xy 258.835903 -96.538263) (xy 258.967277 -96.514188) (xy 259.099865 -96.498088) (xy 259.233183 -96.490024)
			(xy 259.366745 -96.490024) (xy 259.500063 -96.498088) (xy 259.632651 -96.514188) (xy 259.764025 -96.538263)
			(xy 259.893706 -96.570226) (xy 260.02122 -96.609961) (xy 260.146103 -96.657323) (xy 260.267898 -96.712138)
			(xy 260.386161 -96.774208) (xy 260.50046 -96.843304) (xy 260.61038 -96.919176) (xy 260.715517 -97.001546)
			(xy 260.81549 -97.090114) (xy 260.909932 -97.184556) (xy 260.9985 -97.284529) (xy 261.08087 -97.389666)
			(xy 261.156742 -97.499586) (xy 261.225838 -97.613885) (xy 261.287908 -97.732148) (xy 261.342723 -97.853943)
			(xy 261.390085 -97.978826) (xy 261.42982 -98.10634) (xy 261.461783 -98.236021) (xy 261.485858 -98.367395)
			(xy 261.501958 -98.499983) (xy 261.510022 -98.633301) (xy 261.510526 -98.700082) (xy 261.510022 -98.766863)
			(xy 261.501958 -98.900181) (xy 261.485858 -99.032769) (xy 261.461783 -99.164143) (xy 261.42982 -99.293824)
			(xy 261.390085 -99.421338) (xy 261.342723 -99.546221) (xy 261.287908 -99.668016) (xy 261.225838 -99.786279)
			(xy 261.156742 -99.900578) (xy 261.08087 -100.010498) (xy 260.9985 -100.115635) (xy 260.943379 -100.177854)
			(xy 269.509748 -100.177854) (xy 269.509748 -99.314254) (xy 269.510238 -99.28427) (xy 269.518066 -99.224814)
			(xy 269.533587 -99.166889) (xy 269.556536 -99.111485) (xy 269.58652 -99.059551) (xy 269.623026 -99.011975)
			(xy 269.665431 -98.96957) (xy 269.713007 -98.933064) (xy 269.764941 -98.90308) (xy 269.820345 -98.880131)
			(xy 269.87827 -98.86461) (xy 269.937726 -98.856782) (xy 269.997694 -98.856782) (xy 270.05715 -98.86461)
			(xy 270.115075 -98.880131) (xy 270.170479 -98.90308) (xy 270.222413 -98.933064) (xy 270.269989 -98.96957)
			(xy 270.312394 -99.011975) (xy 270.3489 -99.059551) (xy 270.378884 -99.111485) (xy 270.401833 -99.166889)
			(xy 270.417354 -99.224814) (xy 270.425182 -99.28427) (xy 270.425672 -99.314254) (xy 270.425672 -100.17633)
			(xy 285.8389 -100.17633) (xy 285.8389 -99.31273) (xy 285.83939 -99.282746) (xy 285.847218 -99.22329)
			(xy 285.862739 -99.165365) (xy 285.885688 -99.109961) (xy 285.915672 -99.058027) (xy 285.952178 -99.010451)
			(xy 285.994583 -98.968046) (xy 286.042159 -98.93154) (xy 286.094093 -98.901556) (xy 286.149497 -98.878607)
			(xy 286.207422 -98.863086) (xy 286.266878 -98.855258) (xy 286.326846 -98.855258) (xy 286.386302 -98.863086)
			(xy 286.444227 -98.878607) (xy 286.499631 -98.901556) (xy 286.551565 -98.93154) (xy 286.599141 -98.968046)
			(xy 286.641546 -99.010451) (xy 286.678052 -99.058027) (xy 286.708036 -99.109961) (xy 286.730985 -99.165365)
			(xy 286.746506 -99.22329) (xy 286.754334 -99.282746) (xy 286.754824 -99.31273) (xy 286.754824 -100.17633)
			(xy 286.754799 -100.177854) (xy 385.6101 -100.177854) (xy 385.6101 -99.314254) (xy 385.61059 -99.284286)
			(xy 385.618413 -99.224864) (xy 385.633926 -99.166971) (xy 385.656862 -99.111598) (xy 385.686829 -99.059692)
			(xy 385.723316 -99.012142) (xy 385.765696 -98.969762) (xy 385.813246 -98.933275) (xy 385.865152 -98.903308)
			(xy 385.920525 -98.880372) (xy 385.978418 -98.864859) (xy 386.03784 -98.857036) (xy 386.097776 -98.857036)
			(xy 386.157198 -98.864859) (xy 386.215091 -98.880372) (xy 386.270464 -98.903308) (xy 386.32237 -98.933275)
			(xy 386.36992 -98.969762) (xy 386.4123 -99.012142) (xy 386.448787 -99.059692) (xy 386.478754 -99.111598)
			(xy 386.50169 -99.166971) (xy 386.517203 -99.224864) (xy 386.525026 -99.284286) (xy 386.525516 -99.314254)
			(xy 386.525516 -100.17633) (xy 401.939252 -100.17633) (xy 401.939252 -99.31273) (xy 401.939742 -99.282762)
			(xy 401.947565 -99.22334) (xy 401.963078 -99.165447) (xy 401.986014 -99.110074) (xy 402.015981 -99.058168)
			(xy 402.052468 -99.010618) (xy 402.094848 -98.968238) (xy 402.142398 -98.931751) (xy 402.194304 -98.901784)
			(xy 402.249677 -98.878848) (xy 402.30757 -98.863335) (xy 402.366992 -98.855512) (xy 402.426928 -98.855512)
			(xy 402.48635 -98.863335) (xy 402.544243 -98.878848) (xy 402.599616 -98.901784) (xy 402.651522 -98.931751)
			(xy 402.699072 -98.968238) (xy 402.741452 -99.010618) (xy 402.777939 -99.058168) (xy 402.807906 -99.110074)
			(xy 402.830842 -99.165447) (xy 402.846355 -99.22334) (xy 402.854178 -99.282762) (xy 402.854668 -99.31273)
			(xy 402.854668 -100.17633) (xy 402.854178 -100.206298) (xy 402.846355 -100.26572) (xy 402.830842 -100.323613)
			(xy 402.807906 -100.378986) (xy 402.777939 -100.430892) (xy 402.741452 -100.478442) (xy 402.699072 -100.520822)
			(xy 402.651522 -100.557309) (xy 402.599616 -100.587276) (xy 402.544243 -100.610212) (xy 402.48635 -100.625725)
			(xy 402.426928 -100.633548) (xy 402.366992 -100.633548) (xy 402.30757 -100.625725) (xy 402.249677 -100.610212)
			(xy 402.194304 -100.587276) (xy 402.142398 -100.557309) (xy 402.094848 -100.520822) (xy 402.052468 -100.478442)
			(xy 402.015981 -100.430892) (xy 401.986014 -100.378986) (xy 401.963078 -100.323613) (xy 401.947565 -100.26572)
			(xy 401.939742 -100.206298) (xy 401.939252 -100.17633) (xy 386.525516 -100.17633) (xy 386.525516 -100.177854)
			(xy 386.525026 -100.207822) (xy 386.517203 -100.267244) (xy 386.50169 -100.325137) (xy 386.478754 -100.38051)
			(xy 386.448787 -100.432416) (xy 386.4123 -100.479966) (xy 386.36992 -100.522346) (xy 386.32237 -100.558833)
			(xy 386.270464 -100.5888) (xy 386.215091 -100.611736) (xy 386.157198 -100.627249) (xy 386.097776 -100.635072)
			(xy 386.03784 -100.635072) (xy 385.978418 -100.627249) (xy 385.920525 -100.611736) (xy 385.865152 -100.5888)
			(xy 385.813246 -100.558833) (xy 385.765696 -100.522346) (xy 385.723316 -100.479966) (xy 385.686829 -100.432416)
			(xy 385.656862 -100.38051) (xy 385.633926 -100.325137) (xy 385.618413 -100.267244) (xy 385.61059 -100.207822)
			(xy 385.6101 -100.177854) (xy 286.754799 -100.177854) (xy 286.754334 -100.206314) (xy 286.746506 -100.26577)
			(xy 286.730985 -100.323695) (xy 286.708036 -100.379099) (xy 286.678052 -100.431033) (xy 286.641546 -100.478609)
			(xy 286.599141 -100.521014) (xy 286.551565 -100.55752) (xy 286.499631 -100.587504) (xy 286.444227 -100.610453)
			(xy 286.386302 -100.625974) (xy 286.326846 -100.633802) (xy 286.266878 -100.633802) (xy 286.207422 -100.625974)
			(xy 286.149497 -100.610453) (xy 286.094093 -100.587504) (xy 286.042159 -100.55752) (xy 285.994583 -100.521014)
			(xy 285.952178 -100.478609) (xy 285.915672 -100.431033) (xy 285.885688 -100.379099) (xy 285.862739 -100.323695)
			(xy 285.847218 -100.26577) (xy 285.83939 -100.206314) (xy 285.8389 -100.17633) (xy 270.425672 -100.17633)
			(xy 270.425672 -100.177854) (xy 270.425182 -100.207838) (xy 270.417354 -100.267294) (xy 270.401833 -100.325219)
			(xy 270.378884 -100.380623) (xy 270.3489 -100.432557) (xy 270.312394 -100.480133) (xy 270.269989 -100.522538)
			(xy 270.222413 -100.559044) (xy 270.170479 -100.589028) (xy 270.115075 -100.611977) (xy 270.05715 -100.627498)
			(xy 269.997694 -100.635326) (xy 269.937726 -100.635326) (xy 269.87827 -100.627498) (xy 269.820345 -100.611977)
			(xy 269.764941 -100.589028) (xy 269.713007 -100.559044) (xy 269.665431 -100.522538) (xy 269.623026 -100.480133)
			(xy 269.58652 -100.432557) (xy 269.556536 -100.380623) (xy 269.533587 -100.325219) (xy 269.518066 -100.267294)
			(xy 269.510238 -100.207838) (xy 269.509748 -100.177854) (xy 260.943379 -100.177854) (xy 260.909932 -100.215608)
			(xy 260.81549 -100.31005) (xy 260.715517 -100.398618) (xy 260.61038 -100.480988) (xy 260.50046 -100.55686)
			(xy 260.386161 -100.625956) (xy 260.267898 -100.688026) (xy 260.146103 -100.742841) (xy 260.02122 -100.790203)
			(xy 259.893706 -100.829938) (xy 259.764025 -100.861901) (xy 259.632651 -100.885976) (xy 259.500063 -100.902076)
			(xy 259.366745 -100.91014) (xy 259.233183 -100.91014) (xy 259.099865 -100.902076) (xy 258.967277 -100.885976)
			(xy 258.835903 -100.861901) (xy 258.706222 -100.829938) (xy 258.578708 -100.790203) (xy 258.453825 -100.742841)
			(xy 258.33203 -100.688026) (xy 258.213767 -100.625956) (xy 258.099468 -100.55686) (xy 257.989548 -100.480988)
			(xy 257.884411 -100.398618) (xy 257.784438 -100.31005) (xy 257.689996 -100.215608) (xy 257.601428 -100.115635)
			(xy 257.519058 -100.010498) (xy 257.443186 -99.900578) (xy 257.37409 -99.786279) (xy 257.31202 -99.668016)
			(xy 257.257205 -99.546221) (xy 257.209843 -99.421338) (xy 257.170108 -99.293824) (xy 257.138145 -99.164143)
			(xy 257.11407 -99.032769) (xy 257.09797 -98.900181) (xy 257.089906 -98.766863) (xy 210.510124 -98.766863)
			(xy 210.50206 -98.900181) (xy 210.48596 -99.032769) (xy 210.461885 -99.164143) (xy 210.429922 -99.293824)
			(xy 210.390187 -99.421338) (xy 210.342825 -99.546221) (xy 210.28801 -99.668016) (xy 210.22594 -99.786279)
			(xy 210.156844 -99.900578) (xy 210.080972 -100.010498) (xy 209.998602 -100.115635) (xy 209.910034 -100.215608)
			(xy 209.815592 -100.31005) (xy 209.715619 -100.398618) (xy 209.610482 -100.480988) (xy 209.500562 -100.55686)
			(xy 209.386263 -100.625956) (xy 209.268 -100.688026) (xy 209.146205 -100.742841) (xy 209.021322 -100.790203)
			(xy 208.893808 -100.829938) (xy 208.764127 -100.861901) (xy 208.632753 -100.885976) (xy 208.500165 -100.902076)
			(xy 208.366847 -100.91014) (xy 208.233285 -100.91014) (xy 208.099967 -100.902076) (xy 207.967379 -100.885976)
			(xy 207.836005 -100.861901) (xy 207.706324 -100.829938) (xy 207.57881 -100.790203) (xy 207.453927 -100.742841)
			(xy 207.332132 -100.688026) (xy 207.213869 -100.625956) (xy 207.09957 -100.55686) (xy 206.98965 -100.480988)
			(xy 206.884513 -100.398618) (xy 206.78454 -100.31005) (xy 206.690098 -100.215608) (xy 206.60153 -100.115635)
			(xy 206.51916 -100.010498) (xy 206.443288 -99.900578) (xy 206.374192 -99.786279) (xy 206.312122 -99.668016)
			(xy 206.257307 -99.546221) (xy 206.209945 -99.421338) (xy 206.17021 -99.293824) (xy 206.138247 -99.164143)
			(xy 206.114172 -99.032769) (xy 206.098072 -98.900181) (xy 206.090008 -98.766863) (xy 4.308094 -98.766863)
			(xy 4.308094 -100.177854) (xy 37.31006 -100.177854) (xy 37.31006 -99.314254) (xy 37.31055 -99.284286)
			(xy 37.318373 -99.224864) (xy 37.333886 -99.166971) (xy 37.356822 -99.111598) (xy 37.386789 -99.059692)
			(xy 37.423276 -99.012142) (xy 37.465656 -98.969762) (xy 37.513206 -98.933275) (xy 37.565112 -98.903308)
			(xy 37.620485 -98.880372) (xy 37.678378 -98.864859) (xy 37.7378 -98.857036) (xy 37.797736 -98.857036)
			(xy 37.857158 -98.864859) (xy 37.915051 -98.880372) (xy 37.970424 -98.903308) (xy 38.02233 -98.933275)
			(xy 38.06988 -98.969762) (xy 38.11226 -99.012142) (xy 38.148747 -99.059692) (xy 38.178714 -99.111598)
			(xy 38.20165 -99.166971) (xy 38.217163 -99.224864) (xy 38.224986 -99.284286) (xy 38.225476 -99.314254)
			(xy 38.225476 -100.17633) (xy 53.639212 -100.17633) (xy 53.639212 -99.31273) (xy 53.639702 -99.282762)
			(xy 53.647525 -99.22334) (xy 53.663038 -99.165447) (xy 53.685974 -99.110074) (xy 53.715941 -99.058168)
			(xy 53.752428 -99.010618) (xy 53.794808 -98.968238) (xy 53.842358 -98.931751) (xy 53.894264 -98.901784)
			(xy 53.949637 -98.878848) (xy 54.00753 -98.863335) (xy 54.066952 -98.855512) (xy 54.126888 -98.855512)
			(xy 54.18631 -98.863335) (xy 54.244203 -98.878848) (xy 54.299576 -98.901784) (xy 54.351482 -98.931751)
			(xy 54.399032 -98.968238) (xy 54.441412 -99.010618) (xy 54.477899 -99.058168) (xy 54.507866 -99.110074)
			(xy 54.530802 -99.165447) (xy 54.546315 -99.22334) (xy 54.554138 -99.282762) (xy 54.554628 -99.31273)
			(xy 54.554628 -100.17633) (xy 54.554603 -100.177854) (xy 153.409904 -100.177854) (xy 153.409904 -99.314254)
			(xy 153.410394 -99.28427) (xy 153.418222 -99.224814) (xy 153.433743 -99.166889) (xy 153.456692 -99.111485)
			(xy 153.486676 -99.059551) (xy 153.523182 -99.011975) (xy 153.565587 -98.96957) (xy 153.613163 -98.933064)
			(xy 153.665097 -98.90308) (xy 153.720501 -98.880131) (xy 153.778426 -98.86461) (xy 153.837882 -98.856782)
			(xy 153.89785 -98.856782) (xy 153.957306 -98.86461) (xy 154.015231 -98.880131) (xy 154.070635 -98.90308)
			(xy 154.122569 -98.933064) (xy 154.170145 -98.96957) (xy 154.21255 -99.011975) (xy 154.249056 -99.059551)
			(xy 154.27904 -99.111485) (xy 154.301989 -99.166889) (xy 154.31751 -99.224814) (xy 154.325338 -99.28427)
			(xy 154.325828 -99.314254) (xy 154.325828 -100.17633) (xy 169.739056 -100.17633) (xy 169.739056 -99.31273)
			(xy 169.739546 -99.282746) (xy 169.747374 -99.22329) (xy 169.762895 -99.165365) (xy 169.785844 -99.109961)
			(xy 169.815828 -99.058027) (xy 169.852334 -99.010451) (xy 169.894739 -98.968046) (xy 169.942315 -98.93154)
			(xy 169.994249 -98.901556) (xy 170.049653 -98.878607) (xy 170.107578 -98.863086) (xy 170.167034 -98.855258)
			(xy 170.227002 -98.855258) (xy 170.286458 -98.863086) (xy 170.344383 -98.878607) (xy 170.399787 -98.901556)
			(xy 170.451721 -98.93154) (xy 170.499297 -98.968046) (xy 170.541702 -99.010451) (xy 170.578208 -99.058027)
			(xy 170.608192 -99.109961) (xy 170.631141 -99.165365) (xy 170.646662 -99.22329) (xy 170.65449 -99.282746)
			(xy 170.65498 -99.31273) (xy 170.65498 -100.17633) (xy 170.65449 -100.206314) (xy 170.646662 -100.26577)
			(xy 170.631141 -100.323695) (xy 170.608192 -100.379099) (xy 170.578208 -100.431033) (xy 170.541702 -100.478609)
			(xy 170.499297 -100.521014) (xy 170.451721 -100.55752) (xy 170.399787 -100.587504) (xy 170.344383 -100.610453)
			(xy 170.286458 -100.625974) (xy 170.227002 -100.633802) (xy 170.167034 -100.633802) (xy 170.107578 -100.625974)
			(xy 170.049653 -100.610453) (xy 169.994249 -100.587504) (xy 169.942315 -100.55752) (xy 169.894739 -100.521014)
			(xy 169.852334 -100.478609) (xy 169.815828 -100.431033) (xy 169.785844 -100.379099) (xy 169.762895 -100.323695)
			(xy 169.747374 -100.26577) (xy 169.739546 -100.206314) (xy 169.739056 -100.17633) (xy 154.325828 -100.17633)
			(xy 154.325828 -100.177854) (xy 154.325338 -100.207838) (xy 154.31751 -100.267294) (xy 154.301989 -100.325219)
			(xy 154.27904 -100.380623) (xy 154.249056 -100.432557) (xy 154.21255 -100.480133) (xy 154.170145 -100.522538)
			(xy 154.122569 -100.559044) (xy 154.070635 -100.589028) (xy 154.015231 -100.611977) (xy 153.957306 -100.627498)
			(xy 153.89785 -100.635326) (xy 153.837882 -100.635326) (xy 153.778426 -100.627498) (xy 153.720501 -100.611977)
			(xy 153.665097 -100.589028) (xy 153.613163 -100.559044) (xy 153.565587 -100.522538) (xy 153.523182 -100.480133)
			(xy 153.486676 -100.432557) (xy 153.456692 -100.380623) (xy 153.433743 -100.325219) (xy 153.418222 -100.267294)
			(xy 153.410394 -100.207838) (xy 153.409904 -100.177854) (xy 54.554603 -100.177854) (xy 54.554138 -100.206298)
			(xy 54.546315 -100.26572) (xy 54.530802 -100.323613) (xy 54.507866 -100.378986) (xy 54.477899 -100.430892)
			(xy 54.441412 -100.478442) (xy 54.399032 -100.520822) (xy 54.351482 -100.557309) (xy 54.299576 -100.587276)
			(xy 54.244203 -100.610212) (xy 54.18631 -100.625725) (xy 54.126888 -100.633548) (xy 54.066952 -100.633548)
			(xy 54.00753 -100.625725) (xy 53.949637 -100.610212) (xy 53.894264 -100.587276) (xy 53.842358 -100.557309)
			(xy 53.794808 -100.520822) (xy 53.752428 -100.478442) (xy 53.715941 -100.430892) (xy 53.685974 -100.378986)
			(xy 53.663038 -100.323613) (xy 53.647525 -100.26572) (xy 53.639702 -100.206298) (xy 53.639212 -100.17633)
			(xy 38.225476 -100.17633) (xy 38.225476 -100.177854) (xy 38.224986 -100.207822) (xy 38.217163 -100.267244)
			(xy 38.20165 -100.325137) (xy 38.178714 -100.38051) (xy 38.148747 -100.432416) (xy 38.11226 -100.479966)
			(xy 38.06988 -100.522346) (xy 38.02233 -100.558833) (xy 37.970424 -100.5888) (xy 37.915051 -100.611736)
			(xy 37.857158 -100.627249) (xy 37.797736 -100.635072) (xy 37.7378 -100.635072) (xy 37.678378 -100.627249)
			(xy 37.620485 -100.611736) (xy 37.565112 -100.5888) (xy 37.513206 -100.558833) (xy 37.465656 -100.522346)
			(xy 37.423276 -100.479966) (xy 37.386789 -100.432416) (xy 37.356822 -100.38051) (xy 37.333886 -100.325137)
			(xy 37.318373 -100.267244) (xy 37.31055 -100.207822) (xy 37.31006 -100.177854) (xy 4.308094 -100.177854)
			(xy 4.308094 -101.984302) (xy 35.277552 -101.984302) (xy 35.277552 -101.120702) (xy 35.278042 -101.090734)
			(xy 35.285865 -101.031312) (xy 35.301378 -100.973419) (xy 35.324314 -100.918046) (xy 35.354281 -100.86614)
			(xy 35.390768 -100.81859) (xy 35.433148 -100.77621) (xy 35.480698 -100.739723) (xy 35.532604 -100.709756)
			(xy 35.587977 -100.68682) (xy 35.64587 -100.671307) (xy 35.705292 -100.663484) (xy 35.765228 -100.663484)
			(xy 35.82465 -100.671307) (xy 35.882543 -100.68682) (xy 35.937916 -100.709756) (xy 35.989822 -100.739723)
			(xy 36.037372 -100.77621) (xy 36.079752 -100.81859) (xy 36.116239 -100.86614) (xy 36.146206 -100.918046)
			(xy 36.169142 -100.973419) (xy 36.184655 -101.031312) (xy 36.192478 -101.090734) (xy 36.192968 -101.120702)
			(xy 36.192968 -101.976428) (xy 51.785012 -101.976428) (xy 51.785012 -101.112828) (xy 51.785502 -101.08286)
			(xy 51.793325 -101.023438) (xy 51.808838 -100.965545) (xy 51.831774 -100.910172) (xy 51.861741 -100.858266)
			(xy 51.898228 -100.810716) (xy 51.940608 -100.768336) (xy 51.988158 -100.731849) (xy 52.040064 -100.701882)
			(xy 52.095437 -100.678946) (xy 52.15333 -100.663433) (xy 52.212752 -100.65561) (xy 52.272688 -100.65561)
			(xy 52.33211 -100.663433) (xy 52.390003 -100.678946) (xy 52.445376 -100.701882) (xy 52.497282 -100.731849)
			(xy 52.544832 -100.768336) (xy 52.587212 -100.810716) (xy 52.623699 -100.858266) (xy 52.653666 -100.910172)
			(xy 52.676602 -100.965545) (xy 52.692115 -101.023438) (xy 52.699938 -101.08286) (xy 52.700428 -101.112828)
			(xy 52.700428 -101.976428) (xy 52.700299 -101.984302) (xy 151.377396 -101.984302) (xy 151.377396 -101.120702)
			(xy 151.377886 -101.090718) (xy 151.385714 -101.031262) (xy 151.401235 -100.973337) (xy 151.424184 -100.917933)
			(xy 151.454168 -100.865999) (xy 151.490674 -100.818423) (xy 151.533079 -100.776018) (xy 151.580655 -100.739512)
			(xy 151.632589 -100.709528) (xy 151.687993 -100.686579) (xy 151.745918 -100.671058) (xy 151.805374 -100.66323)
			(xy 151.865342 -100.66323) (xy 151.924798 -100.671058) (xy 151.982723 -100.686579) (xy 152.038127 -100.709528)
			(xy 152.090061 -100.739512) (xy 152.137637 -100.776018) (xy 152.180042 -100.818423) (xy 152.216548 -100.865999)
			(xy 152.246532 -100.917933) (xy 152.269481 -100.973337) (xy 152.285002 -101.031262) (xy 152.29283 -101.090718)
			(xy 152.29332 -101.120702) (xy 152.29332 -101.976428) (xy 167.884856 -101.976428) (xy 167.884856 -101.112828)
			(xy 167.885346 -101.082844) (xy 167.893174 -101.023388) (xy 167.908695 -100.965463) (xy 167.931644 -100.910059)
			(xy 167.961628 -100.858125) (xy 167.998134 -100.810549) (xy 168.040539 -100.768144) (xy 168.088115 -100.731638)
			(xy 168.140049 -100.701654) (xy 168.195453 -100.678705) (xy 168.253378 -100.663184) (xy 168.312834 -100.655356)
			(xy 168.372802 -100.655356) (xy 168.432258 -100.663184) (xy 168.490183 -100.678705) (xy 168.545587 -100.701654)
			(xy 168.597521 -100.731638) (xy 168.645097 -100.768144) (xy 168.687502 -100.810549) (xy 168.724008 -100.858125)
			(xy 168.753992 -100.910059) (xy 168.776941 -100.965463) (xy 168.792462 -101.023388) (xy 168.80029 -101.082844)
			(xy 168.80078 -101.112828) (xy 168.80078 -101.976428) (xy 168.800651 -101.984302) (xy 267.47724 -101.984302)
			(xy 267.47724 -101.120702) (xy 267.47773 -101.090718) (xy 267.485558 -101.031262) (xy 267.501079 -100.973337)
			(xy 267.524028 -100.917933) (xy 267.554012 -100.865999) (xy 267.590518 -100.818423) (xy 267.632923 -100.776018)
			(xy 267.680499 -100.739512) (xy 267.732433 -100.709528) (xy 267.787837 -100.686579) (xy 267.845762 -100.671058)
			(xy 267.905218 -100.66323) (xy 267.965186 -100.66323) (xy 268.024642 -100.671058) (xy 268.082567 -100.686579)
			(xy 268.137971 -100.709528) (xy 268.189905 -100.739512) (xy 268.237481 -100.776018) (xy 268.279886 -100.818423)
			(xy 268.316392 -100.865999) (xy 268.346376 -100.917933) (xy 268.369325 -100.973337) (xy 268.384846 -101.031262)
			(xy 268.392674 -101.090718) (xy 268.393164 -101.120702) (xy 268.393164 -101.976428) (xy 283.9847 -101.976428)
			(xy 283.9847 -101.112828) (xy 283.98519 -101.082844) (xy 283.993018 -101.023388) (xy 284.008539 -100.965463)
			(xy 284.031488 -100.910059) (xy 284.061472 -100.858125) (xy 284.097978 -100.810549) (xy 284.140383 -100.768144)
			(xy 284.187959 -100.731638) (xy 284.239893 -100.701654) (xy 284.295297 -100.678705) (xy 284.353222 -100.663184)
			(xy 284.412678 -100.655356) (xy 284.472646 -100.655356) (xy 284.532102 -100.663184) (xy 284.590027 -100.678705)
			(xy 284.645431 -100.701654) (xy 284.697365 -100.731638) (xy 284.744941 -100.768144) (xy 284.787346 -100.810549)
			(xy 284.823852 -100.858125) (xy 284.853836 -100.910059) (xy 284.876785 -100.965463) (xy 284.892306 -101.023388)
			(xy 284.900134 -101.082844) (xy 284.900624 -101.112828) (xy 284.900624 -101.976428) (xy 284.900495 -101.984302)
			(xy 383.577592 -101.984302) (xy 383.577592 -101.120702) (xy 383.578082 -101.090734) (xy 383.585905 -101.031312)
			(xy 383.601418 -100.973419) (xy 383.624354 -100.918046) (xy 383.654321 -100.86614) (xy 383.690808 -100.81859)
			(xy 383.733188 -100.77621) (xy 383.780738 -100.739723) (xy 383.832644 -100.709756) (xy 383.888017 -100.68682)
			(xy 383.94591 -100.671307) (xy 384.005332 -100.663484) (xy 384.065268 -100.663484) (xy 384.12469 -100.671307)
			(xy 384.182583 -100.68682) (xy 384.237956 -100.709756) (xy 384.289862 -100.739723) (xy 384.337412 -100.77621)
			(xy 384.379792 -100.81859) (xy 384.416279 -100.86614) (xy 384.446246 -100.918046) (xy 384.469182 -100.973419)
			(xy 384.484695 -101.031312) (xy 384.492518 -101.090734) (xy 384.493008 -101.120702) (xy 384.493008 -101.976428)
			(xy 400.085052 -101.976428) (xy 400.085052 -101.112828) (xy 400.085542 -101.08286) (xy 400.093365 -101.023438)
			(xy 400.108878 -100.965545) (xy 400.131814 -100.910172) (xy 400.161781 -100.858266) (xy 400.198268 -100.810716)
			(xy 400.240648 -100.768336) (xy 400.288198 -100.731849) (xy 400.340104 -100.701882) (xy 400.395477 -100.678946)
			(xy 400.45337 -100.663433) (xy 400.512792 -100.65561) (xy 400.572728 -100.65561) (xy 400.63215 -100.663433)
			(xy 400.690043 -100.678946) (xy 400.745416 -100.701882) (xy 400.797322 -100.731849) (xy 400.844872 -100.768336)
			(xy 400.887252 -100.810716) (xy 400.923739 -100.858266) (xy 400.953706 -100.910172) (xy 400.976642 -100.965545)
			(xy 400.992155 -101.023438) (xy 400.999978 -101.08286) (xy 401.000468 -101.112828) (xy 401.000468 -101.976428)
			(xy 400.999978 -102.006396) (xy 400.992155 -102.065818) (xy 400.976642 -102.123711) (xy 400.953706 -102.179084)
			(xy 400.923739 -102.23099) (xy 400.887252 -102.27854) (xy 400.844872 -102.32092) (xy 400.797322 -102.357407)
			(xy 400.745416 -102.387374) (xy 400.690043 -102.41031) (xy 400.63215 -102.425823) (xy 400.572728 -102.433646)
			(xy 400.512792 -102.433646) (xy 400.45337 -102.425823) (xy 400.395477 -102.41031) (xy 400.340104 -102.387374)
			(xy 400.288198 -102.357407) (xy 400.240648 -102.32092) (xy 400.198268 -102.27854) (xy 400.161781 -102.23099)
			(xy 400.131814 -102.179084) (xy 400.108878 -102.123711) (xy 400.093365 -102.065818) (xy 400.085542 -102.006396)
			(xy 400.085052 -101.976428) (xy 384.493008 -101.976428) (xy 384.493008 -101.984302) (xy 384.492518 -102.01427)
			(xy 384.484695 -102.073692) (xy 384.469182 -102.131585) (xy 384.446246 -102.186958) (xy 384.416279 -102.238864)
			(xy 384.379792 -102.286414) (xy 384.337412 -102.328794) (xy 384.289862 -102.365281) (xy 384.237956 -102.395248)
			(xy 384.182583 -102.418184) (xy 384.12469 -102.433697) (xy 384.065268 -102.44152) (xy 384.005332 -102.44152)
			(xy 383.94591 -102.433697) (xy 383.888017 -102.418184) (xy 383.832644 -102.395248) (xy 383.780738 -102.365281)
			(xy 383.733188 -102.328794) (xy 383.690808 -102.286414) (xy 383.654321 -102.238864) (xy 383.624354 -102.186958)
			(xy 383.601418 -102.131585) (xy 383.585905 -102.073692) (xy 383.578082 -102.01427) (xy 383.577592 -101.984302)
			(xy 284.900495 -101.984302) (xy 284.900134 -102.006412) (xy 284.892306 -102.065868) (xy 284.876785 -102.123793)
			(xy 284.853836 -102.179197) (xy 284.823852 -102.231131) (xy 284.787346 -102.278707) (xy 284.744941 -102.321112)
			(xy 284.697365 -102.357618) (xy 284.645431 -102.387602) (xy 284.590027 -102.410551) (xy 284.532102 -102.426072)
			(xy 284.472646 -102.4339) (xy 284.412678 -102.4339) (xy 284.353222 -102.426072) (xy 284.295297 -102.410551)
			(xy 284.239893 -102.387602) (xy 284.187959 -102.357618) (xy 284.140383 -102.321112) (xy 284.097978 -102.278707)
			(xy 284.061472 -102.231131) (xy 284.031488 -102.179197) (xy 284.008539 -102.123793) (xy 283.993018 -102.065868)
			(xy 283.98519 -102.006412) (xy 283.9847 -101.976428) (xy 268.393164 -101.976428) (xy 268.393164 -101.984302)
			(xy 268.392674 -102.014286) (xy 268.384846 -102.073742) (xy 268.369325 -102.131667) (xy 268.346376 -102.187071)
			(xy 268.316392 -102.239005) (xy 268.279886 -102.286581) (xy 268.237481 -102.328986) (xy 268.189905 -102.365492)
			(xy 268.137971 -102.395476) (xy 268.082567 -102.418425) (xy 268.024642 -102.433946) (xy 267.965186 -102.441774)
			(xy 267.905218 -102.441774) (xy 267.845762 -102.433946) (xy 267.787837 -102.418425) (xy 267.732433 -102.395476)
			(xy 267.680499 -102.365492) (xy 267.632923 -102.328986) (xy 267.590518 -102.286581) (xy 267.554012 -102.239005)
			(xy 267.524028 -102.187071) (xy 267.501079 -102.131667) (xy 267.485558 -102.073742) (xy 267.47773 -102.014286)
			(xy 267.47724 -101.984302) (xy 168.800651 -101.984302) (xy 168.80029 -102.006412) (xy 168.792462 -102.065868)
			(xy 168.776941 -102.123793) (xy 168.753992 -102.179197) (xy 168.724008 -102.231131) (xy 168.687502 -102.278707)
			(xy 168.645097 -102.321112) (xy 168.597521 -102.357618) (xy 168.545587 -102.387602) (xy 168.490183 -102.410551)
			(xy 168.432258 -102.426072) (xy 168.372802 -102.4339) (xy 168.312834 -102.4339) (xy 168.253378 -102.426072)
			(xy 168.195453 -102.410551) (xy 168.140049 -102.387602) (xy 168.088115 -102.357618) (xy 168.040539 -102.321112)
			(xy 167.998134 -102.278707) (xy 167.961628 -102.231131) (xy 167.931644 -102.179197) (xy 167.908695 -102.123793)
			(xy 167.893174 -102.065868) (xy 167.885346 -102.006412) (xy 167.884856 -101.976428) (xy 152.29332 -101.976428)
			(xy 152.29332 -101.984302) (xy 152.29283 -102.014286) (xy 152.285002 -102.073742) (xy 152.269481 -102.131667)
			(xy 152.246532 -102.187071) (xy 152.216548 -102.239005) (xy 152.180042 -102.286581) (xy 152.137637 -102.328986)
			(xy 152.090061 -102.365492) (xy 152.038127 -102.395476) (xy 151.982723 -102.418425) (xy 151.924798 -102.433946)
			(xy 151.865342 -102.441774) (xy 151.805374 -102.441774) (xy 151.745918 -102.433946) (xy 151.687993 -102.418425)
			(xy 151.632589 -102.395476) (xy 151.580655 -102.365492) (xy 151.533079 -102.328986) (xy 151.490674 -102.286581)
			(xy 151.454168 -102.239005) (xy 151.424184 -102.187071) (xy 151.401235 -102.131667) (xy 151.385714 -102.073742)
			(xy 151.377886 -102.014286) (xy 151.377396 -101.984302) (xy 52.700299 -101.984302) (xy 52.699938 -102.006396)
			(xy 52.692115 -102.065818) (xy 52.676602 -102.123711) (xy 52.653666 -102.179084) (xy 52.623699 -102.23099)
			(xy 52.587212 -102.27854) (xy 52.544832 -102.32092) (xy 52.497282 -102.357407) (xy 52.445376 -102.387374)
			(xy 52.390003 -102.41031) (xy 52.33211 -102.425823) (xy 52.272688 -102.433646) (xy 52.212752 -102.433646)
			(xy 52.15333 -102.425823) (xy 52.095437 -102.41031) (xy 52.040064 -102.387374) (xy 51.988158 -102.357407)
			(xy 51.940608 -102.32092) (xy 51.898228 -102.27854) (xy 51.861741 -102.23099) (xy 51.831774 -102.179084)
			(xy 51.808838 -102.123711) (xy 51.793325 -102.065818) (xy 51.785502 -102.006396) (xy 51.785012 -101.976428)
			(xy 36.192968 -101.976428) (xy 36.192968 -101.984302) (xy 36.192478 -102.01427) (xy 36.184655 -102.073692)
			(xy 36.169142 -102.131585) (xy 36.146206 -102.186958) (xy 36.116239 -102.238864) (xy 36.079752 -102.286414)
			(xy 36.037372 -102.328794) (xy 35.989822 -102.365281) (xy 35.937916 -102.395248) (xy 35.882543 -102.418184)
			(xy 35.82465 -102.433697) (xy 35.765228 -102.44152) (xy 35.705292 -102.44152) (xy 35.64587 -102.433697)
			(xy 35.587977 -102.418184) (xy 35.532604 -102.395248) (xy 35.480698 -102.365281) (xy 35.433148 -102.328794)
			(xy 35.390768 -102.286414) (xy 35.354281 -102.238864) (xy 35.324314 -102.186958) (xy 35.301378 -102.131585)
			(xy 35.285865 -102.073692) (xy 35.278042 -102.01427) (xy 35.277552 -101.984302) (xy 4.308094 -101.984302)
			(xy 4.308094 -103.777796) (xy 37.31006 -103.777796) (xy 37.31006 -102.914196) (xy 37.31055 -102.884228)
			(xy 37.318373 -102.824806) (xy 37.333886 -102.766913) (xy 37.356822 -102.71154) (xy 37.386789 -102.659634)
			(xy 37.423276 -102.612084) (xy 37.465656 -102.569704) (xy 37.513206 -102.533217) (xy 37.565112 -102.50325)
			(xy 37.620485 -102.480314) (xy 37.678378 -102.464801) (xy 37.7378 -102.456978) (xy 37.797736 -102.456978)
			(xy 37.857158 -102.464801) (xy 37.915051 -102.480314) (xy 37.970424 -102.50325) (xy 38.02233 -102.533217)
			(xy 38.06988 -102.569704) (xy 38.11226 -102.612084) (xy 38.148747 -102.659634) (xy 38.178714 -102.71154)
			(xy 38.20165 -102.766913) (xy 38.217163 -102.824806) (xy 38.224986 -102.884228) (xy 38.225476 -102.914196)
			(xy 38.225476 -103.776272) (xy 53.639212 -103.776272) (xy 53.639212 -102.912672) (xy 53.639702 -102.882704)
			(xy 53.647525 -102.823282) (xy 53.663038 -102.765389) (xy 53.685974 -102.710016) (xy 53.715941 -102.65811)
			(xy 53.752428 -102.61056) (xy 53.794808 -102.56818) (xy 53.842358 -102.531693) (xy 53.894264 -102.501726)
			(xy 53.949637 -102.47879) (xy 54.00753 -102.463277) (xy 54.066952 -102.455454) (xy 54.126888 -102.455454)
			(xy 54.18631 -102.463277) (xy 54.244203 -102.47879) (xy 54.299576 -102.501726) (xy 54.351482 -102.531693)
			(xy 54.399032 -102.56818) (xy 54.441412 -102.61056) (xy 54.477899 -102.65811) (xy 54.507866 -102.710016)
			(xy 54.530802 -102.765389) (xy 54.546315 -102.823282) (xy 54.554138 -102.882704) (xy 54.554628 -102.912672)
			(xy 54.554628 -103.776272) (xy 54.554603 -103.777796) (xy 153.409904 -103.777796) (xy 153.409904 -102.914196)
			(xy 153.410394 -102.884212) (xy 153.418222 -102.824756) (xy 153.433743 -102.766831) (xy 153.456692 -102.711427)
			(xy 153.486676 -102.659493) (xy 153.523182 -102.611917) (xy 153.565587 -102.569512) (xy 153.613163 -102.533006)
			(xy 153.665097 -102.503022) (xy 153.720501 -102.480073) (xy 153.778426 -102.464552) (xy 153.837882 -102.456724)
			(xy 153.89785 -102.456724) (xy 153.957306 -102.464552) (xy 154.015231 -102.480073) (xy 154.070635 -102.503022)
			(xy 154.122569 -102.533006) (xy 154.170145 -102.569512) (xy 154.21255 -102.611917) (xy 154.249056 -102.659493)
			(xy 154.27904 -102.711427) (xy 154.301989 -102.766831) (xy 154.31751 -102.824756) (xy 154.325338 -102.884212)
			(xy 154.325828 -102.914196) (xy 154.325828 -103.776272) (xy 169.739056 -103.776272) (xy 169.739056 -102.912672)
			(xy 169.739546 -102.882688) (xy 169.747374 -102.823232) (xy 169.762895 -102.765307) (xy 169.785844 -102.709903)
			(xy 169.815828 -102.657969) (xy 169.852334 -102.610393) (xy 169.894739 -102.567988) (xy 169.942315 -102.531482)
			(xy 169.994249 -102.501498) (xy 170.049653 -102.478549) (xy 170.107578 -102.463028) (xy 170.167034 -102.4552)
			(xy 170.227002 -102.4552) (xy 170.286458 -102.463028) (xy 170.344383 -102.478549) (xy 170.399787 -102.501498)
			(xy 170.451721 -102.531482) (xy 170.499297 -102.567988) (xy 170.541702 -102.610393) (xy 170.578208 -102.657969)
			(xy 170.608192 -102.709903) (xy 170.631141 -102.765307) (xy 170.646662 -102.823232) (xy 170.65449 -102.882688)
			(xy 170.65498 -102.912672) (xy 170.65498 -103.776272) (xy 170.654955 -103.777796) (xy 269.509748 -103.777796)
			(xy 269.509748 -102.914196) (xy 269.510238 -102.884212) (xy 269.518066 -102.824756) (xy 269.533587 -102.766831)
			(xy 269.556536 -102.711427) (xy 269.58652 -102.659493) (xy 269.623026 -102.611917) (xy 269.665431 -102.569512)
			(xy 269.713007 -102.533006) (xy 269.764941 -102.503022) (xy 269.820345 -102.480073) (xy 269.87827 -102.464552)
			(xy 269.937726 -102.456724) (xy 269.997694 -102.456724) (xy 270.05715 -102.464552) (xy 270.115075 -102.480073)
			(xy 270.170479 -102.503022) (xy 270.222413 -102.533006) (xy 270.269989 -102.569512) (xy 270.312394 -102.611917)
			(xy 270.3489 -102.659493) (xy 270.378884 -102.711427) (xy 270.401833 -102.766831) (xy 270.417354 -102.824756)
			(xy 270.425182 -102.884212) (xy 270.425672 -102.914196) (xy 270.425672 -103.776272) (xy 285.8389 -103.776272)
			(xy 285.8389 -102.912672) (xy 285.83939 -102.882688) (xy 285.847218 -102.823232) (xy 285.862739 -102.765307)
			(xy 285.885688 -102.709903) (xy 285.915672 -102.657969) (xy 285.952178 -102.610393) (xy 285.994583 -102.567988)
			(xy 286.042159 -102.531482) (xy 286.094093 -102.501498) (xy 286.149497 -102.478549) (xy 286.207422 -102.463028)
			(xy 286.266878 -102.4552) (xy 286.326846 -102.4552) (xy 286.386302 -102.463028) (xy 286.444227 -102.478549)
			(xy 286.499631 -102.501498) (xy 286.551565 -102.531482) (xy 286.599141 -102.567988) (xy 286.641546 -102.610393)
			(xy 286.678052 -102.657969) (xy 286.708036 -102.709903) (xy 286.730985 -102.765307) (xy 286.746506 -102.823232)
			(xy 286.754334 -102.882688) (xy 286.754824 -102.912672) (xy 286.754824 -103.776272) (xy 286.754799 -103.777796)
			(xy 385.6101 -103.777796) (xy 385.6101 -102.914196) (xy 385.61059 -102.884228) (xy 385.618413 -102.824806)
			(xy 385.633926 -102.766913) (xy 385.656862 -102.71154) (xy 385.686829 -102.659634) (xy 385.723316 -102.612084)
			(xy 385.765696 -102.569704) (xy 385.813246 -102.533217) (xy 385.865152 -102.50325) (xy 385.920525 -102.480314)
			(xy 385.978418 -102.464801) (xy 386.03784 -102.456978) (xy 386.097776 -102.456978) (xy 386.157198 -102.464801)
			(xy 386.215091 -102.480314) (xy 386.270464 -102.50325) (xy 386.32237 -102.533217) (xy 386.36992 -102.569704)
			(xy 386.4123 -102.612084) (xy 386.448787 -102.659634) (xy 386.478754 -102.71154) (xy 386.50169 -102.766913)
			(xy 386.517203 -102.824806) (xy 386.525026 -102.884228) (xy 386.525516 -102.914196) (xy 386.525516 -103.776272)
			(xy 401.939252 -103.776272) (xy 401.939252 -102.912672) (xy 401.939742 -102.882704) (xy 401.947565 -102.823282)
			(xy 401.963078 -102.765389) (xy 401.986014 -102.710016) (xy 402.015981 -102.65811) (xy 402.052468 -102.61056)
			(xy 402.094848 -102.56818) (xy 402.142398 -102.531693) (xy 402.194304 -102.501726) (xy 402.249677 -102.47879)
			(xy 402.30757 -102.463277) (xy 402.366992 -102.455454) (xy 402.426928 -102.455454) (xy 402.48635 -102.463277)
			(xy 402.544243 -102.47879) (xy 402.599616 -102.501726) (xy 402.651522 -102.531693) (xy 402.699072 -102.56818)
			(xy 402.741452 -102.61056) (xy 402.777939 -102.65811) (xy 402.807906 -102.710016) (xy 402.830842 -102.765389)
			(xy 402.846355 -102.823282) (xy 402.854178 -102.882704) (xy 402.854668 -102.912672) (xy 402.854668 -103.776272)
			(xy 402.854178 -103.80624) (xy 402.846355 -103.865662) (xy 402.830842 -103.923555) (xy 402.807906 -103.978928)
			(xy 402.777939 -104.030834) (xy 402.741452 -104.078384) (xy 402.699072 -104.120764) (xy 402.651522 -104.157251)
			(xy 402.599616 -104.187218) (xy 402.544243 -104.210154) (xy 402.48635 -104.225667) (xy 402.426928 -104.23349)
			(xy 402.366992 -104.23349) (xy 402.30757 -104.225667) (xy 402.249677 -104.210154) (xy 402.194304 -104.187218)
			(xy 402.142398 -104.157251) (xy 402.094848 -104.120764) (xy 402.052468 -104.078384) (xy 402.015981 -104.030834)
			(xy 401.986014 -103.978928) (xy 401.963078 -103.923555) (xy 401.947565 -103.865662) (xy 401.939742 -103.80624)
			(xy 401.939252 -103.776272) (xy 386.525516 -103.776272) (xy 386.525516 -103.777796) (xy 386.525026 -103.807764)
			(xy 386.517203 -103.867186) (xy 386.50169 -103.925079) (xy 386.478754 -103.980452) (xy 386.448787 -104.032358)
			(xy 386.4123 -104.079908) (xy 386.36992 -104.122288) (xy 386.32237 -104.158775) (xy 386.270464 -104.188742)
			(xy 386.215091 -104.211678) (xy 386.157198 -104.227191) (xy 386.097776 -104.235014) (xy 386.03784 -104.235014)
			(xy 385.978418 -104.227191) (xy 385.920525 -104.211678) (xy 385.865152 -104.188742) (xy 385.813246 -104.158775)
			(xy 385.765696 -104.122288) (xy 385.723316 -104.079908) (xy 385.686829 -104.032358) (xy 385.656862 -103.980452)
			(xy 385.633926 -103.925079) (xy 385.618413 -103.867186) (xy 385.61059 -103.807764) (xy 385.6101 -103.777796)
			(xy 286.754799 -103.777796) (xy 286.754334 -103.806256) (xy 286.746506 -103.865712) (xy 286.730985 -103.923637)
			(xy 286.708036 -103.979041) (xy 286.678052 -104.030975) (xy 286.641546 -104.078551) (xy 286.599141 -104.120956)
			(xy 286.551565 -104.157462) (xy 286.499631 -104.187446) (xy 286.444227 -104.210395) (xy 286.386302 -104.225916)
			(xy 286.326846 -104.233744) (xy 286.266878 -104.233744) (xy 286.207422 -104.225916) (xy 286.149497 -104.210395)
			(xy 286.094093 -104.187446) (xy 286.042159 -104.157462) (xy 285.994583 -104.120956) (xy 285.952178 -104.078551)
			(xy 285.915672 -104.030975) (xy 285.885688 -103.979041) (xy 285.862739 -103.923637) (xy 285.847218 -103.865712)
			(xy 285.83939 -103.806256) (xy 285.8389 -103.776272) (xy 270.425672 -103.776272) (xy 270.425672 -103.777796)
			(xy 270.425182 -103.80778) (xy 270.417354 -103.867236) (xy 270.401833 -103.925161) (xy 270.378884 -103.980565)
			(xy 270.3489 -104.032499) (xy 270.312394 -104.080075) (xy 270.269989 -104.12248) (xy 270.222413 -104.158986)
			(xy 270.170479 -104.18897) (xy 270.115075 -104.211919) (xy 270.05715 -104.22744) (xy 269.997694 -104.235268)
			(xy 269.937726 -104.235268) (xy 269.87827 -104.22744) (xy 269.820345 -104.211919) (xy 269.764941 -104.18897)
			(xy 269.713007 -104.158986) (xy 269.665431 -104.12248) (xy 269.623026 -104.080075) (xy 269.58652 -104.032499)
			(xy 269.556536 -103.980565) (xy 269.533587 -103.925161) (xy 269.518066 -103.867236) (xy 269.510238 -103.80778)
			(xy 269.509748 -103.777796) (xy 170.654955 -103.777796) (xy 170.65449 -103.806256) (xy 170.646662 -103.865712)
			(xy 170.631141 -103.923637) (xy 170.608192 -103.979041) (xy 170.578208 -104.030975) (xy 170.541702 -104.078551)
			(xy 170.499297 -104.120956) (xy 170.451721 -104.157462) (xy 170.399787 -104.187446) (xy 170.344383 -104.210395)
			(xy 170.286458 -104.225916) (xy 170.227002 -104.233744) (xy 170.167034 -104.233744) (xy 170.107578 -104.225916)
			(xy 170.049653 -104.210395) (xy 169.994249 -104.187446) (xy 169.942315 -104.157462) (xy 169.894739 -104.120956)
			(xy 169.852334 -104.078551) (xy 169.815828 -104.030975) (xy 169.785844 -103.979041) (xy 169.762895 -103.923637)
			(xy 169.747374 -103.865712) (xy 169.739546 -103.806256) (xy 169.739056 -103.776272) (xy 154.325828 -103.776272)
			(xy 154.325828 -103.777796) (xy 154.325338 -103.80778) (xy 154.31751 -103.867236) (xy 154.301989 -103.925161)
			(xy 154.27904 -103.980565) (xy 154.249056 -104.032499) (xy 154.21255 -104.080075) (xy 154.170145 -104.12248)
			(xy 154.122569 -104.158986) (xy 154.070635 -104.18897) (xy 154.015231 -104.211919) (xy 153.957306 -104.22744)
			(xy 153.89785 -104.235268) (xy 153.837882 -104.235268) (xy 153.778426 -104.22744) (xy 153.720501 -104.211919)
			(xy 153.665097 -104.18897) (xy 153.613163 -104.158986) (xy 153.565587 -104.12248) (xy 153.523182 -104.080075)
			(xy 153.486676 -104.032499) (xy 153.456692 -103.980565) (xy 153.433743 -103.925161) (xy 153.418222 -103.867236)
			(xy 153.410394 -103.80778) (xy 153.409904 -103.777796) (xy 54.554603 -103.777796) (xy 54.554138 -103.80624)
			(xy 54.546315 -103.865662) (xy 54.530802 -103.923555) (xy 54.507866 -103.978928) (xy 54.477899 -104.030834)
			(xy 54.441412 -104.078384) (xy 54.399032 -104.120764) (xy 54.351482 -104.157251) (xy 54.299576 -104.187218)
			(xy 54.244203 -104.210154) (xy 54.18631 -104.225667) (xy 54.126888 -104.23349) (xy 54.066952 -104.23349)
			(xy 54.00753 -104.225667) (xy 53.949637 -104.210154) (xy 53.894264 -104.187218) (xy 53.842358 -104.157251)
			(xy 53.794808 -104.120764) (xy 53.752428 -104.078384) (xy 53.715941 -104.030834) (xy 53.685974 -103.978928)
			(xy 53.663038 -103.923555) (xy 53.647525 -103.865662) (xy 53.639702 -103.80624) (xy 53.639212 -103.776272)
			(xy 38.225476 -103.776272) (xy 38.225476 -103.777796) (xy 38.224986 -103.807764) (xy 38.217163 -103.867186)
			(xy 38.20165 -103.925079) (xy 38.178714 -103.980452) (xy 38.148747 -104.032358) (xy 38.11226 -104.079908)
			(xy 38.06988 -104.122288) (xy 38.02233 -104.158775) (xy 37.970424 -104.188742) (xy 37.915051 -104.211678)
			(xy 37.857158 -104.227191) (xy 37.797736 -104.235014) (xy 37.7378 -104.235014) (xy 37.678378 -104.227191)
			(xy 37.620485 -104.211678) (xy 37.565112 -104.188742) (xy 37.513206 -104.158775) (xy 37.465656 -104.122288)
			(xy 37.423276 -104.079908) (xy 37.386789 -104.032358) (xy 37.356822 -103.980452) (xy 37.333886 -103.925079)
			(xy 37.318373 -103.867186) (xy 37.31055 -103.807764) (xy 37.31006 -103.777796) (xy 4.308094 -103.777796)
			(xy 4.308094 -105.584498) (xy 34.667952 -105.584498) (xy 34.667952 -104.720898) (xy 34.668442 -104.69093)
			(xy 34.676265 -104.631508) (xy 34.691778 -104.573615) (xy 34.714714 -104.518242) (xy 34.744681 -104.466336)
			(xy 34.781168 -104.418786) (xy 34.823548 -104.376406) (xy 34.871098 -104.339919) (xy 34.923004 -104.309952)
			(xy 34.978377 -104.287016) (xy 35.03627 -104.271503) (xy 35.095692 -104.26368) (xy 35.155628 -104.26368)
			(xy 35.21505 -104.271503) (xy 35.272943 -104.287016) (xy 35.328316 -104.309952) (xy 35.380222 -104.339919)
			(xy 35.427772 -104.376406) (xy 35.470152 -104.418786) (xy 35.506639 -104.466336) (xy 35.536606 -104.518242)
			(xy 35.559542 -104.573615) (xy 35.575055 -104.631508) (xy 35.582878 -104.69093) (xy 35.583368 -104.720898)
			(xy 35.583368 -105.57637) (xy 51.785012 -105.57637) (xy 51.785012 -104.71277) (xy 51.785502 -104.682802)
			(xy 51.793325 -104.62338) (xy 51.808838 -104.565487) (xy 51.831774 -104.510114) (xy 51.861741 -104.458208)
			(xy 51.898228 -104.410658) (xy 51.940608 -104.368278) (xy 51.988158 -104.331791) (xy 52.040064 -104.301824)
			(xy 52.095437 -104.278888) (xy 52.15333 -104.263375) (xy 52.212752 -104.255552) (xy 52.272688 -104.255552)
			(xy 52.33211 -104.263375) (xy 52.390003 -104.278888) (xy 52.445376 -104.301824) (xy 52.497282 -104.331791)
			(xy 52.544832 -104.368278) (xy 52.587212 -104.410658) (xy 52.623699 -104.458208) (xy 52.653666 -104.510114)
			(xy 52.676602 -104.565487) (xy 52.692115 -104.62338) (xy 52.699938 -104.682802) (xy 52.700428 -104.71277)
			(xy 52.700428 -105.57637) (xy 52.700295 -105.584498) (xy 150.767796 -105.584498) (xy 150.767796 -104.720898)
			(xy 150.768286 -104.690914) (xy 150.776114 -104.631458) (xy 150.791635 -104.573533) (xy 150.814584 -104.518129)
			(xy 150.844568 -104.466195) (xy 150.881074 -104.418619) (xy 150.923479 -104.376214) (xy 150.971055 -104.339708)
			(xy 151.022989 -104.309724) (xy 151.078393 -104.286775) (xy 151.136318 -104.271254) (xy 151.195774 -104.263426)
			(xy 151.255742 -104.263426) (xy 151.315198 -104.271254) (xy 151.373123 -104.286775) (xy 151.428527 -104.309724)
			(xy 151.480461 -104.339708) (xy 151.528037 -104.376214) (xy 151.570442 -104.418619) (xy 151.606948 -104.466195)
			(xy 151.636932 -104.518129) (xy 151.659881 -104.573533) (xy 151.675402 -104.631458) (xy 151.68323 -104.690914)
			(xy 151.68372 -104.720898) (xy 151.68372 -105.57637) (xy 167.884856 -105.57637) (xy 167.884856 -104.71277)
			(xy 167.885346 -104.682786) (xy 167.893174 -104.62333) (xy 167.908695 -104.565405) (xy 167.931644 -104.510001)
			(xy 167.961628 -104.458067) (xy 167.998134 -104.410491) (xy 168.040539 -104.368086) (xy 168.088115 -104.33158)
			(xy 168.140049 -104.301596) (xy 168.195453 -104.278647) (xy 168.253378 -104.263126) (xy 168.312834 -104.255298)
			(xy 168.372802 -104.255298) (xy 168.432258 -104.263126) (xy 168.490183 -104.278647) (xy 168.545587 -104.301596)
			(xy 168.597521 -104.33158) (xy 168.645097 -104.368086) (xy 168.687502 -104.410491) (xy 168.724008 -104.458067)
			(xy 168.753992 -104.510001) (xy 168.776941 -104.565405) (xy 168.792462 -104.62333) (xy 168.80029 -104.682786)
			(xy 168.80078 -104.71277) (xy 168.80078 -105.57637) (xy 168.800647 -105.584498) (xy 266.86764 -105.584498)
			(xy 266.86764 -104.720898) (xy 266.86813 -104.690914) (xy 266.875958 -104.631458) (xy 266.891479 -104.573533)
			(xy 266.914428 -104.518129) (xy 266.944412 -104.466195) (xy 266.980918 -104.418619) (xy 267.023323 -104.376214)
			(xy 267.070899 -104.339708) (xy 267.122833 -104.309724) (xy 267.178237 -104.286775) (xy 267.236162 -104.271254)
			(xy 267.295618 -104.263426) (xy 267.355586 -104.263426) (xy 267.415042 -104.271254) (xy 267.472967 -104.286775)
			(xy 267.528371 -104.309724) (xy 267.580305 -104.339708) (xy 267.627881 -104.376214) (xy 267.670286 -104.418619)
			(xy 267.706792 -104.466195) (xy 267.736776 -104.518129) (xy 267.759725 -104.573533) (xy 267.775246 -104.631458)
			(xy 267.783074 -104.690914) (xy 267.783564 -104.720898) (xy 267.783564 -105.57637) (xy 283.9847 -105.57637)
			(xy 283.9847 -104.71277) (xy 283.98519 -104.682786) (xy 283.993018 -104.62333) (xy 284.008539 -104.565405)
			(xy 284.031488 -104.510001) (xy 284.061472 -104.458067) (xy 284.097978 -104.410491) (xy 284.140383 -104.368086)
			(xy 284.187959 -104.33158) (xy 284.239893 -104.301596) (xy 284.295297 -104.278647) (xy 284.353222 -104.263126)
			(xy 284.412678 -104.255298) (xy 284.472646 -104.255298) (xy 284.532102 -104.263126) (xy 284.590027 -104.278647)
			(xy 284.645431 -104.301596) (xy 284.697365 -104.33158) (xy 284.744941 -104.368086) (xy 284.787346 -104.410491)
			(xy 284.823852 -104.458067) (xy 284.853836 -104.510001) (xy 284.876785 -104.565405) (xy 284.892306 -104.62333)
			(xy 284.900134 -104.682786) (xy 284.900624 -104.71277) (xy 284.900624 -105.57637) (xy 284.900491 -105.584498)
			(xy 382.967992 -105.584498) (xy 382.967992 -104.720898) (xy 382.968482 -104.69093) (xy 382.976305 -104.631508)
			(xy 382.991818 -104.573615) (xy 383.014754 -104.518242) (xy 383.044721 -104.466336) (xy 383.081208 -104.418786)
			(xy 383.123588 -104.376406) (xy 383.171138 -104.339919) (xy 383.223044 -104.309952) (xy 383.278417 -104.287016)
			(xy 383.33631 -104.271503) (xy 383.395732 -104.26368) (xy 383.455668 -104.26368) (xy 383.51509 -104.271503)
			(xy 383.572983 -104.287016) (xy 383.628356 -104.309952) (xy 383.680262 -104.339919) (xy 383.727812 -104.376406)
			(xy 383.770192 -104.418786) (xy 383.806679 -104.466336) (xy 383.836646 -104.518242) (xy 383.859582 -104.573615)
			(xy 383.875095 -104.631508) (xy 383.882918 -104.69093) (xy 383.883408 -104.720898) (xy 383.883408 -105.57637)
			(xy 400.085052 -105.57637) (xy 400.085052 -104.71277) (xy 400.085542 -104.682802) (xy 400.093365 -104.62338)
			(xy 400.108878 -104.565487) (xy 400.131814 -104.510114) (xy 400.161781 -104.458208) (xy 400.198268 -104.410658)
			(xy 400.240648 -104.368278) (xy 400.288198 -104.331791) (xy 400.340104 -104.301824) (xy 400.395477 -104.278888)
			(xy 400.45337 -104.263375) (xy 400.512792 -104.255552) (xy 400.572728 -104.255552) (xy 400.63215 -104.263375)
			(xy 400.690043 -104.278888) (xy 400.745416 -104.301824) (xy 400.797322 -104.331791) (xy 400.844872 -104.368278)
			(xy 400.887252 -104.410658) (xy 400.923739 -104.458208) (xy 400.953706 -104.510114) (xy 400.976642 -104.565487)
			(xy 400.992155 -104.62338) (xy 400.999978 -104.682802) (xy 401.000468 -104.71277) (xy 401.000468 -105.57637)
			(xy 400.999978 -105.606338) (xy 400.992155 -105.66576) (xy 400.976642 -105.723653) (xy 400.953706 -105.779026)
			(xy 400.923739 -105.830932) (xy 400.887252 -105.878482) (xy 400.844872 -105.920862) (xy 400.797322 -105.957349)
			(xy 400.745416 -105.987316) (xy 400.690043 -106.010252) (xy 400.63215 -106.025765) (xy 400.572728 -106.033588)
			(xy 400.512792 -106.033588) (xy 400.45337 -106.025765) (xy 400.395477 -106.010252) (xy 400.340104 -105.987316)
			(xy 400.288198 -105.957349) (xy 400.240648 -105.920862) (xy 400.198268 -105.878482) (xy 400.161781 -105.830932)
			(xy 400.131814 -105.779026) (xy 400.108878 -105.723653) (xy 400.093365 -105.66576) (xy 400.085542 -105.606338)
			(xy 400.085052 -105.57637) (xy 383.883408 -105.57637) (xy 383.883408 -105.584498) (xy 383.882918 -105.614466)
			(xy 383.875095 -105.673888) (xy 383.859582 -105.731781) (xy 383.836646 -105.787154) (xy 383.806679 -105.83906)
			(xy 383.770192 -105.88661) (xy 383.727812 -105.92899) (xy 383.680262 -105.965477) (xy 383.628356 -105.995444)
			(xy 383.572983 -106.01838) (xy 383.51509 -106.033893) (xy 383.455668 -106.041716) (xy 383.395732 -106.041716)
			(xy 383.33631 -106.033893) (xy 383.278417 -106.01838) (xy 383.223044 -105.995444) (xy 383.171138 -105.965477)
			(xy 383.123588 -105.92899) (xy 383.081208 -105.88661) (xy 383.044721 -105.83906) (xy 383.014754 -105.787154)
			(xy 382.991818 -105.731781) (xy 382.976305 -105.673888) (xy 382.968482 -105.614466) (xy 382.967992 -105.584498)
			(xy 284.900491 -105.584498) (xy 284.900134 -105.606354) (xy 284.892306 -105.66581) (xy 284.876785 -105.723735)
			(xy 284.853836 -105.779139) (xy 284.823852 -105.831073) (xy 284.787346 -105.878649) (xy 284.744941 -105.921054)
			(xy 284.697365 -105.95756) (xy 284.645431 -105.987544) (xy 284.590027 -106.010493) (xy 284.532102 -106.026014)
			(xy 284.472646 -106.033842) (xy 284.412678 -106.033842) (xy 284.353222 -106.026014) (xy 284.295297 -106.010493)
			(xy 284.239893 -105.987544) (xy 284.187959 -105.95756) (xy 284.140383 -105.921054) (xy 284.097978 -105.878649)
			(xy 284.061472 -105.831073) (xy 284.031488 -105.779139) (xy 284.008539 -105.723735) (xy 283.993018 -105.66581)
			(xy 283.98519 -105.606354) (xy 283.9847 -105.57637) (xy 267.783564 -105.57637) (xy 267.783564 -105.584498)
			(xy 267.783074 -105.614482) (xy 267.775246 -105.673938) (xy 267.759725 -105.731863) (xy 267.736776 -105.787267)
			(xy 267.706792 -105.839201) (xy 267.670286 -105.886777) (xy 267.627881 -105.929182) (xy 267.580305 -105.965688)
			(xy 267.528371 -105.995672) (xy 267.472967 -106.018621) (xy 267.415042 -106.034142) (xy 267.355586 -106.04197)
			(xy 267.295618 -106.04197) (xy 267.236162 -106.034142) (xy 267.178237 -106.018621) (xy 267.122833 -105.995672)
			(xy 267.070899 -105.965688) (xy 267.023323 -105.929182) (xy 266.980918 -105.886777) (xy 266.944412 -105.839201)
			(xy 266.914428 -105.787267) (xy 266.891479 -105.731863) (xy 266.875958 -105.673938) (xy 266.86813 -105.614482)
			(xy 266.86764 -105.584498) (xy 168.800647 -105.584498) (xy 168.80029 -105.606354) (xy 168.792462 -105.66581)
			(xy 168.776941 -105.723735) (xy 168.753992 -105.779139) (xy 168.724008 -105.831073) (xy 168.687502 -105.878649)
			(xy 168.645097 -105.921054) (xy 168.597521 -105.95756) (xy 168.545587 -105.987544) (xy 168.490183 -106.010493)
			(xy 168.432258 -106.026014) (xy 168.372802 -106.033842) (xy 168.312834 -106.033842) (xy 168.253378 -106.026014)
			(xy 168.195453 -106.010493) (xy 168.140049 -105.987544) (xy 168.088115 -105.95756) (xy 168.040539 -105.921054)
			(xy 167.998134 -105.878649) (xy 167.961628 -105.831073) (xy 167.931644 -105.779139) (xy 167.908695 -105.723735)
			(xy 167.893174 -105.66581) (xy 167.885346 -105.606354) (xy 167.884856 -105.57637) (xy 151.68372 -105.57637)
			(xy 151.68372 -105.584498) (xy 151.68323 -105.614482) (xy 151.675402 -105.673938) (xy 151.659881 -105.731863)
			(xy 151.636932 -105.787267) (xy 151.606948 -105.839201) (xy 151.570442 -105.886777) (xy 151.528037 -105.929182)
			(xy 151.480461 -105.965688) (xy 151.428527 -105.995672) (xy 151.373123 -106.018621) (xy 151.315198 -106.034142)
			(xy 151.255742 -106.04197) (xy 151.195774 -106.04197) (xy 151.136318 -106.034142) (xy 151.078393 -106.018621)
			(xy 151.022989 -105.995672) (xy 150.971055 -105.965688) (xy 150.923479 -105.929182) (xy 150.881074 -105.886777)
			(xy 150.844568 -105.839201) (xy 150.814584 -105.787267) (xy 150.791635 -105.731863) (xy 150.776114 -105.673938)
			(xy 150.768286 -105.614482) (xy 150.767796 -105.584498) (xy 52.700295 -105.584498) (xy 52.699938 -105.606338)
			(xy 52.692115 -105.66576) (xy 52.676602 -105.723653) (xy 52.653666 -105.779026) (xy 52.623699 -105.830932)
			(xy 52.587212 -105.878482) (xy 52.544832 -105.920862) (xy 52.497282 -105.957349) (xy 52.445376 -105.987316)
			(xy 52.390003 -106.010252) (xy 52.33211 -106.025765) (xy 52.272688 -106.033588) (xy 52.212752 -106.033588)
			(xy 52.15333 -106.025765) (xy 52.095437 -106.010252) (xy 52.040064 -105.987316) (xy 51.988158 -105.957349)
			(xy 51.940608 -105.920862) (xy 51.898228 -105.878482) (xy 51.861741 -105.830932) (xy 51.831774 -105.779026)
			(xy 51.808838 -105.723653) (xy 51.793325 -105.66576) (xy 51.785502 -105.606338) (xy 51.785012 -105.57637)
			(xy 35.583368 -105.57637) (xy 35.583368 -105.584498) (xy 35.582878 -105.614466) (xy 35.575055 -105.673888)
			(xy 35.559542 -105.731781) (xy 35.536606 -105.787154) (xy 35.506639 -105.83906) (xy 35.470152 -105.88661)
			(xy 35.427772 -105.92899) (xy 35.380222 -105.965477) (xy 35.328316 -105.995444) (xy 35.272943 -106.01838)
			(xy 35.21505 -106.033893) (xy 35.155628 -106.041716) (xy 35.095692 -106.041716) (xy 35.03627 -106.033893)
			(xy 34.978377 -106.01838) (xy 34.923004 -105.995444) (xy 34.871098 -105.965477) (xy 34.823548 -105.92899)
			(xy 34.781168 -105.88661) (xy 34.744681 -105.83906) (xy 34.714714 -105.787154) (xy 34.691778 -105.731781)
			(xy 34.676265 -105.673888) (xy 34.668442 -105.614466) (xy 34.667952 -105.584498) (xy 4.308094 -105.584498)
			(xy 4.308094 -107.377738) (xy 37.31006 -107.377738) (xy 37.31006 -106.514138) (xy 37.31055 -106.48417)
			(xy 37.318373 -106.424748) (xy 37.333886 -106.366855) (xy 37.356822 -106.311482) (xy 37.386789 -106.259576)
			(xy 37.423276 -106.212026) (xy 37.465656 -106.169646) (xy 37.513206 -106.133159) (xy 37.565112 -106.103192)
			(xy 37.620485 -106.080256) (xy 37.678378 -106.064743) (xy 37.7378 -106.05692) (xy 37.797736 -106.05692)
			(xy 37.857158 -106.064743) (xy 37.915051 -106.080256) (xy 37.970424 -106.103192) (xy 38.02233 -106.133159)
			(xy 38.06988 -106.169646) (xy 38.11226 -106.212026) (xy 38.148747 -106.259576) (xy 38.178714 -106.311482)
			(xy 38.20165 -106.366855) (xy 38.217163 -106.424748) (xy 38.224986 -106.48417) (xy 38.225476 -106.514138)
			(xy 38.225476 -107.376214) (xy 53.639212 -107.376214) (xy 53.639212 -106.512614) (xy 53.639702 -106.482646)
			(xy 53.647525 -106.423224) (xy 53.663038 -106.365331) (xy 53.685974 -106.309958) (xy 53.715941 -106.258052)
			(xy 53.752428 -106.210502) (xy 53.794808 -106.168122) (xy 53.842358 -106.131635) (xy 53.894264 -106.101668)
			(xy 53.949637 -106.078732) (xy 54.00753 -106.063219) (xy 54.066952 -106.055396) (xy 54.126888 -106.055396)
			(xy 54.18631 -106.063219) (xy 54.244203 -106.078732) (xy 54.299576 -106.101668) (xy 54.351482 -106.131635)
			(xy 54.399032 -106.168122) (xy 54.441412 -106.210502) (xy 54.477899 -106.258052) (xy 54.507866 -106.309958)
			(xy 54.530802 -106.365331) (xy 54.546315 -106.423224) (xy 54.554138 -106.482646) (xy 54.554628 -106.512614)
			(xy 54.554628 -107.376214) (xy 54.554603 -107.377738) (xy 153.409904 -107.377738) (xy 153.409904 -106.514138)
			(xy 153.410394 -106.484154) (xy 153.418222 -106.424698) (xy 153.433743 -106.366773) (xy 153.456692 -106.311369)
			(xy 153.486676 -106.259435) (xy 153.523182 -106.211859) (xy 153.565587 -106.169454) (xy 153.613163 -106.132948)
			(xy 153.665097 -106.102964) (xy 153.720501 -106.080015) (xy 153.778426 -106.064494) (xy 153.837882 -106.056666)
			(xy 153.89785 -106.056666) (xy 153.957306 -106.064494) (xy 154.015231 -106.080015) (xy 154.070635 -106.102964)
			(xy 154.122569 -106.132948) (xy 154.170145 -106.169454) (xy 154.21255 -106.211859) (xy 154.249056 -106.259435)
			(xy 154.27904 -106.311369) (xy 154.301989 -106.366773) (xy 154.31751 -106.424698) (xy 154.325338 -106.484154)
			(xy 154.325828 -106.514138) (xy 154.325828 -107.376214) (xy 169.739056 -107.376214) (xy 169.739056 -106.512614)
			(xy 169.739546 -106.48263) (xy 169.747374 -106.423174) (xy 169.762895 -106.365249) (xy 169.785844 -106.309845)
			(xy 169.815828 -106.257911) (xy 169.852334 -106.210335) (xy 169.894739 -106.16793) (xy 169.942315 -106.131424)
			(xy 169.994249 -106.10144) (xy 170.049653 -106.078491) (xy 170.107578 -106.06297) (xy 170.167034 -106.055142)
			(xy 170.227002 -106.055142) (xy 170.286458 -106.06297) (xy 170.344383 -106.078491) (xy 170.399787 -106.10144)
			(xy 170.451721 -106.131424) (xy 170.499297 -106.16793) (xy 170.541702 -106.210335) (xy 170.578208 -106.257911)
			(xy 170.608192 -106.309845) (xy 170.631141 -106.365249) (xy 170.646662 -106.423174) (xy 170.65449 -106.48263)
			(xy 170.65498 -106.512614) (xy 170.65498 -107.376214) (xy 170.654955 -107.377738) (xy 269.509748 -107.377738)
			(xy 269.509748 -106.514138) (xy 269.510238 -106.484154) (xy 269.518066 -106.424698) (xy 269.533587 -106.366773)
			(xy 269.556536 -106.311369) (xy 269.58652 -106.259435) (xy 269.623026 -106.211859) (xy 269.665431 -106.169454)
			(xy 269.713007 -106.132948) (xy 269.764941 -106.102964) (xy 269.820345 -106.080015) (xy 269.87827 -106.064494)
			(xy 269.937726 -106.056666) (xy 269.997694 -106.056666) (xy 270.05715 -106.064494) (xy 270.115075 -106.080015)
			(xy 270.170479 -106.102964) (xy 270.222413 -106.132948) (xy 270.269989 -106.169454) (xy 270.312394 -106.211859)
			(xy 270.3489 -106.259435) (xy 270.378884 -106.311369) (xy 270.401833 -106.366773) (xy 270.417354 -106.424698)
			(xy 270.425182 -106.484154) (xy 270.425672 -106.514138) (xy 270.425672 -107.376214) (xy 285.8389 -107.376214)
			(xy 285.8389 -106.512614) (xy 285.83939 -106.48263) (xy 285.847218 -106.423174) (xy 285.862739 -106.365249)
			(xy 285.885688 -106.309845) (xy 285.915672 -106.257911) (xy 285.952178 -106.210335) (xy 285.994583 -106.16793)
			(xy 286.042159 -106.131424) (xy 286.094093 -106.10144) (xy 286.149497 -106.078491) (xy 286.207422 -106.06297)
			(xy 286.266878 -106.055142) (xy 286.326846 -106.055142) (xy 286.386302 -106.06297) (xy 286.444227 -106.078491)
			(xy 286.499631 -106.10144) (xy 286.551565 -106.131424) (xy 286.599141 -106.16793) (xy 286.641546 -106.210335)
			(xy 286.678052 -106.257911) (xy 286.708036 -106.309845) (xy 286.730985 -106.365249) (xy 286.746506 -106.423174)
			(xy 286.754334 -106.48263) (xy 286.754824 -106.512614) (xy 286.754824 -107.376214) (xy 286.754799 -107.377738)
			(xy 385.6101 -107.377738) (xy 385.6101 -106.514138) (xy 385.61059 -106.48417) (xy 385.618413 -106.424748)
			(xy 385.633926 -106.366855) (xy 385.656862 -106.311482) (xy 385.686829 -106.259576) (xy 385.723316 -106.212026)
			(xy 385.765696 -106.169646) (xy 385.813246 -106.133159) (xy 385.865152 -106.103192) (xy 385.920525 -106.080256)
			(xy 385.978418 -106.064743) (xy 386.03784 -106.05692) (xy 386.097776 -106.05692) (xy 386.157198 -106.064743)
			(xy 386.215091 -106.080256) (xy 386.270464 -106.103192) (xy 386.32237 -106.133159) (xy 386.36992 -106.169646)
			(xy 386.4123 -106.212026) (xy 386.448787 -106.259576) (xy 386.478754 -106.311482) (xy 386.50169 -106.366855)
			(xy 386.517203 -106.424748) (xy 386.525026 -106.48417) (xy 386.525516 -106.514138) (xy 386.525516 -107.376214)
			(xy 401.939252 -107.376214) (xy 401.939252 -106.512614) (xy 401.939742 -106.482646) (xy 401.947565 -106.423224)
			(xy 401.963078 -106.365331) (xy 401.986014 -106.309958) (xy 402.015981 -106.258052) (xy 402.052468 -106.210502)
			(xy 402.094848 -106.168122) (xy 402.142398 -106.131635) (xy 402.194304 -106.101668) (xy 402.249677 -106.078732)
			(xy 402.30757 -106.063219) (xy 402.366992 -106.055396) (xy 402.426928 -106.055396) (xy 402.48635 -106.063219)
			(xy 402.544243 -106.078732) (xy 402.599616 -106.101668) (xy 402.651522 -106.131635) (xy 402.699072 -106.168122)
			(xy 402.741452 -106.210502) (xy 402.777939 -106.258052) (xy 402.807906 -106.309958) (xy 402.830842 -106.365331)
			(xy 402.846355 -106.423224) (xy 402.854178 -106.482646) (xy 402.854668 -106.512614) (xy 402.854668 -107.376214)
			(xy 402.854178 -107.406182) (xy 402.846355 -107.465604) (xy 402.830842 -107.523497) (xy 402.807906 -107.57887)
			(xy 402.777939 -107.630776) (xy 402.741452 -107.678326) (xy 402.699072 -107.720706) (xy 402.651522 -107.757193)
			(xy 402.599616 -107.78716) (xy 402.544243 -107.810096) (xy 402.48635 -107.825609) (xy 402.426928 -107.833432)
			(xy 402.366992 -107.833432) (xy 402.30757 -107.825609) (xy 402.249677 -107.810096) (xy 402.194304 -107.78716)
			(xy 402.142398 -107.757193) (xy 402.094848 -107.720706) (xy 402.052468 -107.678326) (xy 402.015981 -107.630776)
			(xy 401.986014 -107.57887) (xy 401.963078 -107.523497) (xy 401.947565 -107.465604) (xy 401.939742 -107.406182)
			(xy 401.939252 -107.376214) (xy 386.525516 -107.376214) (xy 386.525516 -107.377738) (xy 386.525026 -107.407706)
			(xy 386.517203 -107.467128) (xy 386.50169 -107.525021) (xy 386.478754 -107.580394) (xy 386.448787 -107.6323)
			(xy 386.4123 -107.67985) (xy 386.36992 -107.72223) (xy 386.32237 -107.758717) (xy 386.270464 -107.788684)
			(xy 386.215091 -107.81162) (xy 386.157198 -107.827133) (xy 386.097776 -107.834956) (xy 386.03784 -107.834956)
			(xy 385.978418 -107.827133) (xy 385.920525 -107.81162) (xy 385.865152 -107.788684) (xy 385.813246 -107.758717)
			(xy 385.765696 -107.72223) (xy 385.723316 -107.67985) (xy 385.686829 -107.6323) (xy 385.656862 -107.580394)
			(xy 385.633926 -107.525021) (xy 385.618413 -107.467128) (xy 385.61059 -107.407706) (xy 385.6101 -107.377738)
			(xy 286.754799 -107.377738) (xy 286.754334 -107.406198) (xy 286.746506 -107.465654) (xy 286.730985 -107.523579)
			(xy 286.708036 -107.578983) (xy 286.678052 -107.630917) (xy 286.641546 -107.678493) (xy 286.599141 -107.720898)
			(xy 286.551565 -107.757404) (xy 286.499631 -107.787388) (xy 286.444227 -107.810337) (xy 286.386302 -107.825858)
			(xy 286.326846 -107.833686) (xy 286.266878 -107.833686) (xy 286.207422 -107.825858) (xy 286.149497 -107.810337)
			(xy 286.094093 -107.787388) (xy 286.042159 -107.757404) (xy 285.994583 -107.720898) (xy 285.952178 -107.678493)
			(xy 285.915672 -107.630917) (xy 285.885688 -107.578983) (xy 285.862739 -107.523579) (xy 285.847218 -107.465654)
			(xy 285.83939 -107.406198) (xy 285.8389 -107.376214) (xy 270.425672 -107.376214) (xy 270.425672 -107.377738)
			(xy 270.425182 -107.407722) (xy 270.417354 -107.467178) (xy 270.401833 -107.525103) (xy 270.378884 -107.580507)
			(xy 270.3489 -107.632441) (xy 270.312394 -107.680017) (xy 270.269989 -107.722422) (xy 270.222413 -107.758928)
			(xy 270.170479 -107.788912) (xy 270.115075 -107.811861) (xy 270.05715 -107.827382) (xy 269.997694 -107.83521)
			(xy 269.937726 -107.83521) (xy 269.87827 -107.827382) (xy 269.820345 -107.811861) (xy 269.764941 -107.788912)
			(xy 269.713007 -107.758928) (xy 269.665431 -107.722422) (xy 269.623026 -107.680017) (xy 269.58652 -107.632441)
			(xy 269.556536 -107.580507) (xy 269.533587 -107.525103) (xy 269.518066 -107.467178) (xy 269.510238 -107.407722)
			(xy 269.509748 -107.377738) (xy 170.654955 -107.377738) (xy 170.65449 -107.406198) (xy 170.646662 -107.465654)
			(xy 170.631141 -107.523579) (xy 170.608192 -107.578983) (xy 170.578208 -107.630917) (xy 170.541702 -107.678493)
			(xy 170.499297 -107.720898) (xy 170.451721 -107.757404) (xy 170.399787 -107.787388) (xy 170.344383 -107.810337)
			(xy 170.286458 -107.825858) (xy 170.227002 -107.833686) (xy 170.167034 -107.833686) (xy 170.107578 -107.825858)
			(xy 170.049653 -107.810337) (xy 169.994249 -107.787388) (xy 169.942315 -107.757404) (xy 169.894739 -107.720898)
			(xy 169.852334 -107.678493) (xy 169.815828 -107.630917) (xy 169.785844 -107.578983) (xy 169.762895 -107.523579)
			(xy 169.747374 -107.465654) (xy 169.739546 -107.406198) (xy 169.739056 -107.376214) (xy 154.325828 -107.376214)
			(xy 154.325828 -107.377738) (xy 154.325338 -107.407722) (xy 154.31751 -107.467178) (xy 154.301989 -107.525103)
			(xy 154.27904 -107.580507) (xy 154.249056 -107.632441) (xy 154.21255 -107.680017) (xy 154.170145 -107.722422)
			(xy 154.122569 -107.758928) (xy 154.070635 -107.788912) (xy 154.015231 -107.811861) (xy 153.957306 -107.827382)
			(xy 153.89785 -107.83521) (xy 153.837882 -107.83521) (xy 153.778426 -107.827382) (xy 153.720501 -107.811861)
			(xy 153.665097 -107.788912) (xy 153.613163 -107.758928) (xy 153.565587 -107.722422) (xy 153.523182 -107.680017)
			(xy 153.486676 -107.632441) (xy 153.456692 -107.580507) (xy 153.433743 -107.525103) (xy 153.418222 -107.467178)
			(xy 153.410394 -107.407722) (xy 153.409904 -107.377738) (xy 54.554603 -107.377738) (xy 54.554138 -107.406182)
			(xy 54.546315 -107.465604) (xy 54.530802 -107.523497) (xy 54.507866 -107.57887) (xy 54.477899 -107.630776)
			(xy 54.441412 -107.678326) (xy 54.399032 -107.720706) (xy 54.351482 -107.757193) (xy 54.299576 -107.78716)
			(xy 54.244203 -107.810096) (xy 54.18631 -107.825609) (xy 54.126888 -107.833432) (xy 54.066952 -107.833432)
			(xy 54.00753 -107.825609) (xy 53.949637 -107.810096) (xy 53.894264 -107.78716) (xy 53.842358 -107.757193)
			(xy 53.794808 -107.720706) (xy 53.752428 -107.678326) (xy 53.715941 -107.630776) (xy 53.685974 -107.57887)
			(xy 53.663038 -107.523497) (xy 53.647525 -107.465604) (xy 53.639702 -107.406182) (xy 53.639212 -107.376214)
			(xy 38.225476 -107.376214) (xy 38.225476 -107.377738) (xy 38.224986 -107.407706) (xy 38.217163 -107.467128)
			(xy 38.20165 -107.525021) (xy 38.178714 -107.580394) (xy 38.148747 -107.6323) (xy 38.11226 -107.67985)
			(xy 38.06988 -107.72223) (xy 38.02233 -107.758717) (xy 37.970424 -107.788684) (xy 37.915051 -107.81162)
			(xy 37.857158 -107.827133) (xy 37.797736 -107.834956) (xy 37.7378 -107.834956) (xy 37.678378 -107.827133)
			(xy 37.620485 -107.81162) (xy 37.565112 -107.788684) (xy 37.513206 -107.758717) (xy 37.465656 -107.72223)
			(xy 37.423276 -107.67985) (xy 37.386789 -107.6323) (xy 37.356822 -107.580394) (xy 37.333886 -107.525021)
			(xy 37.318373 -107.467128) (xy 37.31055 -107.407706) (xy 37.31006 -107.377738) (xy 4.308094 -107.377738)
			(xy 4.308094 -109.18444) (xy 34.667952 -109.18444) (xy 34.667952 -108.32084) (xy 34.668442 -108.290872)
			(xy 34.676265 -108.23145) (xy 34.691778 -108.173557) (xy 34.714714 -108.118184) (xy 34.744681 -108.066278)
			(xy 34.781168 -108.018728) (xy 34.823548 -107.976348) (xy 34.871098 -107.939861) (xy 34.923004 -107.909894)
			(xy 34.978377 -107.886958) (xy 35.03627 -107.871445) (xy 35.095692 -107.863622) (xy 35.155628 -107.863622)
			(xy 35.21505 -107.871445) (xy 35.272943 -107.886958) (xy 35.328316 -107.909894) (xy 35.380222 -107.939861)
			(xy 35.427772 -107.976348) (xy 35.470152 -108.018728) (xy 35.506639 -108.066278) (xy 35.536606 -108.118184)
			(xy 35.559542 -108.173557) (xy 35.575055 -108.23145) (xy 35.582878 -108.290872) (xy 35.583368 -108.32084)
			(xy 35.583368 -109.176312) (xy 51.785012 -109.176312) (xy 51.785012 -108.312712) (xy 51.785502 -108.282744)
			(xy 51.793325 -108.223322) (xy 51.808838 -108.165429) (xy 51.831774 -108.110056) (xy 51.861741 -108.05815)
			(xy 51.898228 -108.0106) (xy 51.940608 -107.96822) (xy 51.988158 -107.931733) (xy 52.040064 -107.901766)
			(xy 52.095437 -107.87883) (xy 52.15333 -107.863317) (xy 52.212752 -107.855494) (xy 52.272688 -107.855494)
			(xy 52.33211 -107.863317) (xy 52.390003 -107.87883) (xy 52.445376 -107.901766) (xy 52.497282 -107.931733)
			(xy 52.544832 -107.96822) (xy 52.587212 -108.0106) (xy 52.623699 -108.05815) (xy 52.653666 -108.110056)
			(xy 52.676602 -108.165429) (xy 52.692115 -108.223322) (xy 52.699938 -108.282744) (xy 52.700428 -108.312712)
			(xy 52.700428 -109.176312) (xy 52.700295 -109.18444) (xy 150.767796 -109.18444) (xy 150.767796 -108.32084)
			(xy 150.768286 -108.290856) (xy 150.776114 -108.2314) (xy 150.791635 -108.173475) (xy 150.814584 -108.118071)
			(xy 150.844568 -108.066137) (xy 150.881074 -108.018561) (xy 150.923479 -107.976156) (xy 150.971055 -107.93965)
			(xy 151.022989 -107.909666) (xy 151.078393 -107.886717) (xy 151.136318 -107.871196) (xy 151.195774 -107.863368)
			(xy 151.255742 -107.863368) (xy 151.315198 -107.871196) (xy 151.373123 -107.886717) (xy 151.428527 -107.909666)
			(xy 151.480461 -107.93965) (xy 151.528037 -107.976156) (xy 151.570442 -108.018561) (xy 151.606948 -108.066137)
			(xy 151.636932 -108.118071) (xy 151.659881 -108.173475) (xy 151.675402 -108.2314) (xy 151.68323 -108.290856)
			(xy 151.68372 -108.32084) (xy 151.68372 -109.176312) (xy 167.884856 -109.176312) (xy 167.884856 -108.312712)
			(xy 167.885346 -108.282728) (xy 167.893174 -108.223272) (xy 167.908695 -108.165347) (xy 167.931644 -108.109943)
			(xy 167.961628 -108.058009) (xy 167.998134 -108.010433) (xy 168.040539 -107.968028) (xy 168.088115 -107.931522)
			(xy 168.140049 -107.901538) (xy 168.195453 -107.878589) (xy 168.253378 -107.863068) (xy 168.312834 -107.85524)
			(xy 168.372802 -107.85524) (xy 168.432258 -107.863068) (xy 168.490183 -107.878589) (xy 168.545587 -107.901538)
			(xy 168.597521 -107.931522) (xy 168.645097 -107.968028) (xy 168.687502 -108.010433) (xy 168.724008 -108.058009)
			(xy 168.753992 -108.109943) (xy 168.776941 -108.165347) (xy 168.792462 -108.223272) (xy 168.80029 -108.282728)
			(xy 168.80078 -108.312712) (xy 168.80078 -109.176312) (xy 168.800647 -109.18444) (xy 266.86764 -109.18444)
			(xy 266.86764 -108.32084) (xy 266.86813 -108.290856) (xy 266.875958 -108.2314) (xy 266.891479 -108.173475)
			(xy 266.914428 -108.118071) (xy 266.944412 -108.066137) (xy 266.980918 -108.018561) (xy 267.023323 -107.976156)
			(xy 267.070899 -107.93965) (xy 267.122833 -107.909666) (xy 267.178237 -107.886717) (xy 267.236162 -107.871196)
			(xy 267.295618 -107.863368) (xy 267.355586 -107.863368) (xy 267.415042 -107.871196) (xy 267.472967 -107.886717)
			(xy 267.528371 -107.909666) (xy 267.580305 -107.93965) (xy 267.627881 -107.976156) (xy 267.670286 -108.018561)
			(xy 267.706792 -108.066137) (xy 267.736776 -108.118071) (xy 267.759725 -108.173475) (xy 267.775246 -108.2314)
			(xy 267.783074 -108.290856) (xy 267.783564 -108.32084) (xy 267.783564 -109.176312) (xy 283.9847 -109.176312)
			(xy 283.9847 -108.312712) (xy 283.98519 -108.282728) (xy 283.993018 -108.223272) (xy 284.008539 -108.165347)
			(xy 284.031488 -108.109943) (xy 284.061472 -108.058009) (xy 284.097978 -108.010433) (xy 284.140383 -107.968028)
			(xy 284.187959 -107.931522) (xy 284.239893 -107.901538) (xy 284.295297 -107.878589) (xy 284.353222 -107.863068)
			(xy 284.412678 -107.85524) (xy 284.472646 -107.85524) (xy 284.532102 -107.863068) (xy 284.590027 -107.878589)
			(xy 284.645431 -107.901538) (xy 284.697365 -107.931522) (xy 284.744941 -107.968028) (xy 284.787346 -108.010433)
			(xy 284.823852 -108.058009) (xy 284.853836 -108.109943) (xy 284.876785 -108.165347) (xy 284.892306 -108.223272)
			(xy 284.900134 -108.282728) (xy 284.900624 -108.312712) (xy 284.900624 -109.176312) (xy 284.900491 -109.18444)
			(xy 382.967992 -109.18444) (xy 382.967992 -108.32084) (xy 382.968482 -108.290872) (xy 382.976305 -108.23145)
			(xy 382.991818 -108.173557) (xy 383.014754 -108.118184) (xy 383.044721 -108.066278) (xy 383.081208 -108.018728)
			(xy 383.123588 -107.976348) (xy 383.171138 -107.939861) (xy 383.223044 -107.909894) (xy 383.278417 -107.886958)
			(xy 383.33631 -107.871445) (xy 383.395732 -107.863622) (xy 383.455668 -107.863622) (xy 383.51509 -107.871445)
			(xy 383.572983 -107.886958) (xy 383.628356 -107.909894) (xy 383.680262 -107.939861) (xy 383.727812 -107.976348)
			(xy 383.770192 -108.018728) (xy 383.806679 -108.066278) (xy 383.836646 -108.118184) (xy 383.859582 -108.173557)
			(xy 383.875095 -108.23145) (xy 383.882918 -108.290872) (xy 383.883408 -108.32084) (xy 383.883408 -109.176312)
			(xy 400.085052 -109.176312) (xy 400.085052 -108.312712) (xy 400.085542 -108.282744) (xy 400.093365 -108.223322)
			(xy 400.108878 -108.165429) (xy 400.131814 -108.110056) (xy 400.161781 -108.05815) (xy 400.198268 -108.0106)
			(xy 400.240648 -107.96822) (xy 400.288198 -107.931733) (xy 400.340104 -107.901766) (xy 400.395477 -107.87883)
			(xy 400.45337 -107.863317) (xy 400.512792 -107.855494) (xy 400.572728 -107.855494) (xy 400.63215 -107.863317)
			(xy 400.690043 -107.87883) (xy 400.745416 -107.901766) (xy 400.797322 -107.931733) (xy 400.844872 -107.96822)
			(xy 400.887252 -108.0106) (xy 400.923739 -108.05815) (xy 400.953706 -108.110056) (xy 400.976642 -108.165429)
			(xy 400.992155 -108.223322) (xy 400.999978 -108.282744) (xy 401.000468 -108.312712) (xy 401.000468 -109.176312)
			(xy 400.999978 -109.20628) (xy 400.992155 -109.265702) (xy 400.976642 -109.323595) (xy 400.953706 -109.378968)
			(xy 400.923739 -109.430874) (xy 400.887252 -109.478424) (xy 400.844872 -109.520804) (xy 400.797322 -109.557291)
			(xy 400.745416 -109.587258) (xy 400.690043 -109.610194) (xy 400.63215 -109.625707) (xy 400.572728 -109.63353)
			(xy 400.512792 -109.63353) (xy 400.45337 -109.625707) (xy 400.395477 -109.610194) (xy 400.340104 -109.587258)
			(xy 400.288198 -109.557291) (xy 400.240648 -109.520804) (xy 400.198268 -109.478424) (xy 400.161781 -109.430874)
			(xy 400.131814 -109.378968) (xy 400.108878 -109.323595) (xy 400.093365 -109.265702) (xy 400.085542 -109.20628)
			(xy 400.085052 -109.176312) (xy 383.883408 -109.176312) (xy 383.883408 -109.18444) (xy 383.882918 -109.214408)
			(xy 383.875095 -109.27383) (xy 383.859582 -109.331723) (xy 383.836646 -109.387096) (xy 383.806679 -109.439002)
			(xy 383.770192 -109.486552) (xy 383.727812 -109.528932) (xy 383.680262 -109.565419) (xy 383.628356 -109.595386)
			(xy 383.572983 -109.618322) (xy 383.51509 -109.633835) (xy 383.455668 -109.641658) (xy 383.395732 -109.641658)
			(xy 383.33631 -109.633835) (xy 383.278417 -109.618322) (xy 383.223044 -109.595386) (xy 383.171138 -109.565419)
			(xy 383.123588 -109.528932) (xy 383.081208 -109.486552) (xy 383.044721 -109.439002) (xy 383.014754 -109.387096)
			(xy 382.991818 -109.331723) (xy 382.976305 -109.27383) (xy 382.968482 -109.214408) (xy 382.967992 -109.18444)
			(xy 284.900491 -109.18444) (xy 284.900134 -109.206296) (xy 284.892306 -109.265752) (xy 284.876785 -109.323677)
			(xy 284.853836 -109.379081) (xy 284.823852 -109.431015) (xy 284.787346 -109.478591) (xy 284.744941 -109.520996)
			(xy 284.697365 -109.557502) (xy 284.645431 -109.587486) (xy 284.590027 -109.610435) (xy 284.532102 -109.625956)
			(xy 284.472646 -109.633784) (xy 284.412678 -109.633784) (xy 284.353222 -109.625956) (xy 284.295297 -109.610435)
			(xy 284.239893 -109.587486) (xy 284.187959 -109.557502) (xy 284.140383 -109.520996) (xy 284.097978 -109.478591)
			(xy 284.061472 -109.431015) (xy 284.031488 -109.379081) (xy 284.008539 -109.323677) (xy 283.993018 -109.265752)
			(xy 283.98519 -109.206296) (xy 283.9847 -109.176312) (xy 267.783564 -109.176312) (xy 267.783564 -109.18444)
			(xy 267.783074 -109.214424) (xy 267.775246 -109.27388) (xy 267.759725 -109.331805) (xy 267.736776 -109.387209)
			(xy 267.706792 -109.439143) (xy 267.670286 -109.486719) (xy 267.627881 -109.529124) (xy 267.580305 -109.56563)
			(xy 267.528371 -109.595614) (xy 267.472967 -109.618563) (xy 267.415042 -109.634084) (xy 267.355586 -109.641912)
			(xy 267.295618 -109.641912) (xy 267.236162 -109.634084) (xy 267.178237 -109.618563) (xy 267.122833 -109.595614)
			(xy 267.070899 -109.56563) (xy 267.023323 -109.529124) (xy 266.980918 -109.486719) (xy 266.944412 -109.439143)
			(xy 266.914428 -109.387209) (xy 266.891479 -109.331805) (xy 266.875958 -109.27388) (xy 266.86813 -109.214424)
			(xy 266.86764 -109.18444) (xy 168.800647 -109.18444) (xy 168.80029 -109.206296) (xy 168.792462 -109.265752)
			(xy 168.776941 -109.323677) (xy 168.753992 -109.379081) (xy 168.724008 -109.431015) (xy 168.687502 -109.478591)
			(xy 168.645097 -109.520996) (xy 168.597521 -109.557502) (xy 168.545587 -109.587486) (xy 168.490183 -109.610435)
			(xy 168.432258 -109.625956) (xy 168.372802 -109.633784) (xy 168.312834 -109.633784) (xy 168.253378 -109.625956)
			(xy 168.195453 -109.610435) (xy 168.140049 -109.587486) (xy 168.088115 -109.557502) (xy 168.040539 -109.520996)
			(xy 167.998134 -109.478591) (xy 167.961628 -109.431015) (xy 167.931644 -109.379081) (xy 167.908695 -109.323677)
			(xy 167.893174 -109.265752) (xy 167.885346 -109.206296) (xy 167.884856 -109.176312) (xy 151.68372 -109.176312)
			(xy 151.68372 -109.18444) (xy 151.68323 -109.214424) (xy 151.675402 -109.27388) (xy 151.659881 -109.331805)
			(xy 151.636932 -109.387209) (xy 151.606948 -109.439143) (xy 151.570442 -109.486719) (xy 151.528037 -109.529124)
			(xy 151.480461 -109.56563) (xy 151.428527 -109.595614) (xy 151.373123 -109.618563) (xy 151.315198 -109.634084)
			(xy 151.255742 -109.641912) (xy 151.195774 -109.641912) (xy 151.136318 -109.634084) (xy 151.078393 -109.618563)
			(xy 151.022989 -109.595614) (xy 150.971055 -109.56563) (xy 150.923479 -109.529124) (xy 150.881074 -109.486719)
			(xy 150.844568 -109.439143) (xy 150.814584 -109.387209) (xy 150.791635 -109.331805) (xy 150.776114 -109.27388)
			(xy 150.768286 -109.214424) (xy 150.767796 -109.18444) (xy 52.700295 -109.18444) (xy 52.699938 -109.20628)
			(xy 52.692115 -109.265702) (xy 52.676602 -109.323595) (xy 52.653666 -109.378968) (xy 52.623699 -109.430874)
			(xy 52.587212 -109.478424) (xy 52.544832 -109.520804) (xy 52.497282 -109.557291) (xy 52.445376 -109.587258)
			(xy 52.390003 -109.610194) (xy 52.33211 -109.625707) (xy 52.272688 -109.63353) (xy 52.212752 -109.63353)
			(xy 52.15333 -109.625707) (xy 52.095437 -109.610194) (xy 52.040064 -109.587258) (xy 51.988158 -109.557291)
			(xy 51.940608 -109.520804) (xy 51.898228 -109.478424) (xy 51.861741 -109.430874) (xy 51.831774 -109.378968)
			(xy 51.808838 -109.323595) (xy 51.793325 -109.265702) (xy 51.785502 -109.20628) (xy 51.785012 -109.176312)
			(xy 35.583368 -109.176312) (xy 35.583368 -109.18444) (xy 35.582878 -109.214408) (xy 35.575055 -109.27383)
			(xy 35.559542 -109.331723) (xy 35.536606 -109.387096) (xy 35.506639 -109.439002) (xy 35.470152 -109.486552)
			(xy 35.427772 -109.528932) (xy 35.380222 -109.565419) (xy 35.328316 -109.595386) (xy 35.272943 -109.618322)
			(xy 35.21505 -109.633835) (xy 35.155628 -109.641658) (xy 35.095692 -109.641658) (xy 35.03627 -109.633835)
			(xy 34.978377 -109.618322) (xy 34.923004 -109.595386) (xy 34.871098 -109.565419) (xy 34.823548 -109.528932)
			(xy 34.781168 -109.486552) (xy 34.744681 -109.439002) (xy 34.714714 -109.387096) (xy 34.691778 -109.331723)
			(xy 34.676265 -109.27383) (xy 34.668442 -109.214408) (xy 34.667952 -109.18444) (xy 4.308094 -109.18444)
			(xy 4.308094 -110.977934) (xy 37.31006 -110.977934) (xy 37.31006 -110.114334) (xy 37.31055 -110.084366)
			(xy 37.318373 -110.024944) (xy 37.333886 -109.967051) (xy 37.356822 -109.911678) (xy 37.386789 -109.859772)
			(xy 37.423276 -109.812222) (xy 37.465656 -109.769842) (xy 37.513206 -109.733355) (xy 37.565112 -109.703388)
			(xy 37.620485 -109.680452) (xy 37.678378 -109.664939) (xy 37.7378 -109.657116) (xy 37.797736 -109.657116)
			(xy 37.857158 -109.664939) (xy 37.915051 -109.680452) (xy 37.970424 -109.703388) (xy 38.02233 -109.733355)
			(xy 38.06988 -109.769842) (xy 38.11226 -109.812222) (xy 38.148747 -109.859772) (xy 38.178714 -109.911678)
			(xy 38.20165 -109.967051) (xy 38.217163 -110.024944) (xy 38.224986 -110.084366) (xy 38.225476 -110.114334)
			(xy 38.225476 -110.97641) (xy 53.639212 -110.97641) (xy 53.639212 -110.11281) (xy 53.639702 -110.082842)
			(xy 53.647525 -110.02342) (xy 53.663038 -109.965527) (xy 53.685974 -109.910154) (xy 53.715941 -109.858248)
			(xy 53.752428 -109.810698) (xy 53.794808 -109.768318) (xy 53.842358 -109.731831) (xy 53.894264 -109.701864)
			(xy 53.949637 -109.678928) (xy 54.00753 -109.663415) (xy 54.066952 -109.655592) (xy 54.126888 -109.655592)
			(xy 54.18631 -109.663415) (xy 54.244203 -109.678928) (xy 54.299576 -109.701864) (xy 54.351482 -109.731831)
			(xy 54.399032 -109.768318) (xy 54.441412 -109.810698) (xy 54.477899 -109.858248) (xy 54.507866 -109.910154)
			(xy 54.530802 -109.965527) (xy 54.546315 -110.02342) (xy 54.554138 -110.082842) (xy 54.554628 -110.11281)
			(xy 54.554628 -110.97641) (xy 54.554603 -110.977934) (xy 153.409904 -110.977934) (xy 153.409904 -110.114334)
			(xy 153.410394 -110.08435) (xy 153.418222 -110.024894) (xy 153.433743 -109.966969) (xy 153.456692 -109.911565)
			(xy 153.486676 -109.859631) (xy 153.523182 -109.812055) (xy 153.565587 -109.76965) (xy 153.613163 -109.733144)
			(xy 153.665097 -109.70316) (xy 153.720501 -109.680211) (xy 153.778426 -109.66469) (xy 153.837882 -109.656862)
			(xy 153.89785 -109.656862) (xy 153.957306 -109.66469) (xy 154.015231 -109.680211) (xy 154.070635 -109.70316)
			(xy 154.122569 -109.733144) (xy 154.170145 -109.76965) (xy 154.21255 -109.812055) (xy 154.249056 -109.859631)
			(xy 154.27904 -109.911565) (xy 154.301989 -109.966969) (xy 154.31751 -110.024894) (xy 154.325338 -110.08435)
			(xy 154.325828 -110.114334) (xy 154.325828 -110.97641) (xy 169.739056 -110.97641) (xy 169.739056 -110.11281)
			(xy 169.739546 -110.082826) (xy 169.747374 -110.02337) (xy 169.762895 -109.965445) (xy 169.785844 -109.910041)
			(xy 169.815828 -109.858107) (xy 169.852334 -109.810531) (xy 169.894739 -109.768126) (xy 169.942315 -109.73162)
			(xy 169.994249 -109.701636) (xy 170.049653 -109.678687) (xy 170.107578 -109.663166) (xy 170.167034 -109.655338)
			(xy 170.227002 -109.655338) (xy 170.286458 -109.663166) (xy 170.344383 -109.678687) (xy 170.399787 -109.701636)
			(xy 170.451721 -109.73162) (xy 170.499297 -109.768126) (xy 170.541702 -109.810531) (xy 170.578208 -109.858107)
			(xy 170.608192 -109.910041) (xy 170.631141 -109.965445) (xy 170.646662 -110.02337) (xy 170.65449 -110.082826)
			(xy 170.65498 -110.11281) (xy 170.65498 -110.97641) (xy 170.654955 -110.977934) (xy 269.509748 -110.977934)
			(xy 269.509748 -110.114334) (xy 269.510238 -110.08435) (xy 269.518066 -110.024894) (xy 269.533587 -109.966969)
			(xy 269.556536 -109.911565) (xy 269.58652 -109.859631) (xy 269.623026 -109.812055) (xy 269.665431 -109.76965)
			(xy 269.713007 -109.733144) (xy 269.764941 -109.70316) (xy 269.820345 -109.680211) (xy 269.87827 -109.66469)
			(xy 269.937726 -109.656862) (xy 269.997694 -109.656862) (xy 270.05715 -109.66469) (xy 270.115075 -109.680211)
			(xy 270.170479 -109.70316) (xy 270.222413 -109.733144) (xy 270.269989 -109.76965) (xy 270.312394 -109.812055)
			(xy 270.3489 -109.859631) (xy 270.378884 -109.911565) (xy 270.401833 -109.966969) (xy 270.417354 -110.024894)
			(xy 270.425182 -110.08435) (xy 270.425672 -110.114334) (xy 270.425672 -110.97641) (xy 285.8389 -110.97641)
			(xy 285.8389 -110.11281) (xy 285.83939 -110.082826) (xy 285.847218 -110.02337) (xy 285.862739 -109.965445)
			(xy 285.885688 -109.910041) (xy 285.915672 -109.858107) (xy 285.952178 -109.810531) (xy 285.994583 -109.768126)
			(xy 286.042159 -109.73162) (xy 286.094093 -109.701636) (xy 286.149497 -109.678687) (xy 286.207422 -109.663166)
			(xy 286.266878 -109.655338) (xy 286.326846 -109.655338) (xy 286.386302 -109.663166) (xy 286.444227 -109.678687)
			(xy 286.499631 -109.701636) (xy 286.551565 -109.73162) (xy 286.599141 -109.768126) (xy 286.641546 -109.810531)
			(xy 286.678052 -109.858107) (xy 286.708036 -109.910041) (xy 286.730985 -109.965445) (xy 286.746506 -110.02337)
			(xy 286.754334 -110.082826) (xy 286.754824 -110.11281) (xy 286.754824 -110.97641) (xy 286.754799 -110.977934)
			(xy 385.6101 -110.977934) (xy 385.6101 -110.114334) (xy 385.61059 -110.084366) (xy 385.618413 -110.024944)
			(xy 385.633926 -109.967051) (xy 385.656862 -109.911678) (xy 385.686829 -109.859772) (xy 385.723316 -109.812222)
			(xy 385.765696 -109.769842) (xy 385.813246 -109.733355) (xy 385.865152 -109.703388) (xy 385.920525 -109.680452)
			(xy 385.978418 -109.664939) (xy 386.03784 -109.657116) (xy 386.097776 -109.657116) (xy 386.157198 -109.664939)
			(xy 386.215091 -109.680452) (xy 386.270464 -109.703388) (xy 386.32237 -109.733355) (xy 386.36992 -109.769842)
			(xy 386.4123 -109.812222) (xy 386.448787 -109.859772) (xy 386.478754 -109.911678) (xy 386.50169 -109.967051)
			(xy 386.517203 -110.024944) (xy 386.525026 -110.084366) (xy 386.525516 -110.114334) (xy 386.525516 -110.97641)
			(xy 401.939252 -110.97641) (xy 401.939252 -110.11281) (xy 401.939742 -110.082842) (xy 401.947565 -110.02342)
			(xy 401.963078 -109.965527) (xy 401.986014 -109.910154) (xy 402.015981 -109.858248) (xy 402.052468 -109.810698)
			(xy 402.094848 -109.768318) (xy 402.142398 -109.731831) (xy 402.194304 -109.701864) (xy 402.249677 -109.678928)
			(xy 402.30757 -109.663415) (xy 402.366992 -109.655592) (xy 402.426928 -109.655592) (xy 402.48635 -109.663415)
			(xy 402.544243 -109.678928) (xy 402.599616 -109.701864) (xy 402.651522 -109.731831) (xy 402.699072 -109.768318)
			(xy 402.741452 -109.810698) (xy 402.777939 -109.858248) (xy 402.807906 -109.910154) (xy 402.830842 -109.965527)
			(xy 402.846355 -110.02342) (xy 402.854178 -110.082842) (xy 402.854668 -110.11281) (xy 402.854668 -110.97641)
			(xy 402.854178 -111.006378) (xy 402.846355 -111.0658) (xy 402.830842 -111.123693) (xy 402.807906 -111.179066)
			(xy 402.777939 -111.230972) (xy 402.741452 -111.278522) (xy 402.699072 -111.320902) (xy 402.651522 -111.357389)
			(xy 402.599616 -111.387356) (xy 402.544243 -111.410292) (xy 402.48635 -111.425805) (xy 402.426928 -111.433628)
			(xy 402.366992 -111.433628) (xy 402.30757 -111.425805) (xy 402.249677 -111.410292) (xy 402.194304 -111.387356)
			(xy 402.142398 -111.357389) (xy 402.094848 -111.320902) (xy 402.052468 -111.278522) (xy 402.015981 -111.230972)
			(xy 401.986014 -111.179066) (xy 401.963078 -111.123693) (xy 401.947565 -111.0658) (xy 401.939742 -111.006378)
			(xy 401.939252 -110.97641) (xy 386.525516 -110.97641) (xy 386.525516 -110.977934) (xy 386.525026 -111.007902)
			(xy 386.517203 -111.067324) (xy 386.50169 -111.125217) (xy 386.478754 -111.18059) (xy 386.448787 -111.232496)
			(xy 386.4123 -111.280046) (xy 386.36992 -111.322426) (xy 386.32237 -111.358913) (xy 386.270464 -111.38888)
			(xy 386.215091 -111.411816) (xy 386.157198 -111.427329) (xy 386.097776 -111.435152) (xy 386.03784 -111.435152)
			(xy 385.978418 -111.427329) (xy 385.920525 -111.411816) (xy 385.865152 -111.38888) (xy 385.813246 -111.358913)
			(xy 385.765696 -111.322426) (xy 385.723316 -111.280046) (xy 385.686829 -111.232496) (xy 385.656862 -111.18059)
			(xy 385.633926 -111.125217) (xy 385.618413 -111.067324) (xy 385.61059 -111.007902) (xy 385.6101 -110.977934)
			(xy 286.754799 -110.977934) (xy 286.754334 -111.006394) (xy 286.746506 -111.06585) (xy 286.730985 -111.123775)
			(xy 286.708036 -111.179179) (xy 286.678052 -111.231113) (xy 286.641546 -111.278689) (xy 286.599141 -111.321094)
			(xy 286.551565 -111.3576) (xy 286.499631 -111.387584) (xy 286.444227 -111.410533) (xy 286.386302 -111.426054)
			(xy 286.326846 -111.433882) (xy 286.266878 -111.433882) (xy 286.207422 -111.426054) (xy 286.149497 -111.410533)
			(xy 286.094093 -111.387584) (xy 286.042159 -111.3576) (xy 285.994583 -111.321094) (xy 285.952178 -111.278689)
			(xy 285.915672 -111.231113) (xy 285.885688 -111.179179) (xy 285.862739 -111.123775) (xy 285.847218 -111.06585)
			(xy 285.83939 -111.006394) (xy 285.8389 -110.97641) (xy 270.425672 -110.97641) (xy 270.425672 -110.977934)
			(xy 270.425182 -111.007918) (xy 270.417354 -111.067374) (xy 270.401833 -111.125299) (xy 270.378884 -111.180703)
			(xy 270.3489 -111.232637) (xy 270.312394 -111.280213) (xy 270.269989 -111.322618) (xy 270.222413 -111.359124)
			(xy 270.170479 -111.389108) (xy 270.115075 -111.412057) (xy 270.05715 -111.427578) (xy 269.997694 -111.435406)
			(xy 269.937726 -111.435406) (xy 269.87827 -111.427578) (xy 269.820345 -111.412057) (xy 269.764941 -111.389108)
			(xy 269.713007 -111.359124) (xy 269.665431 -111.322618) (xy 269.623026 -111.280213) (xy 269.58652 -111.232637)
			(xy 269.556536 -111.180703) (xy 269.533587 -111.125299) (xy 269.518066 -111.067374) (xy 269.510238 -111.007918)
			(xy 269.509748 -110.977934) (xy 170.654955 -110.977934) (xy 170.65449 -111.006394) (xy 170.646662 -111.06585)
			(xy 170.631141 -111.123775) (xy 170.608192 -111.179179) (xy 170.578208 -111.231113) (xy 170.541702 -111.278689)
			(xy 170.499297 -111.321094) (xy 170.451721 -111.3576) (xy 170.399787 -111.387584) (xy 170.344383 -111.410533)
			(xy 170.286458 -111.426054) (xy 170.227002 -111.433882) (xy 170.167034 -111.433882) (xy 170.107578 -111.426054)
			(xy 170.049653 -111.410533) (xy 169.994249 -111.387584) (xy 169.942315 -111.3576) (xy 169.894739 -111.321094)
			(xy 169.852334 -111.278689) (xy 169.815828 -111.231113) (xy 169.785844 -111.179179) (xy 169.762895 -111.123775)
			(xy 169.747374 -111.06585) (xy 169.739546 -111.006394) (xy 169.739056 -110.97641) (xy 154.325828 -110.97641)
			(xy 154.325828 -110.977934) (xy 154.325338 -111.007918) (xy 154.31751 -111.067374) (xy 154.301989 -111.125299)
			(xy 154.27904 -111.180703) (xy 154.249056 -111.232637) (xy 154.21255 -111.280213) (xy 154.170145 -111.322618)
			(xy 154.122569 -111.359124) (xy 154.070635 -111.389108) (xy 154.015231 -111.412057) (xy 153.957306 -111.427578)
			(xy 153.89785 -111.435406) (xy 153.837882 -111.435406) (xy 153.778426 -111.427578) (xy 153.720501 -111.412057)
			(xy 153.665097 -111.389108) (xy 153.613163 -111.359124) (xy 153.565587 -111.322618) (xy 153.523182 -111.280213)
			(xy 153.486676 -111.232637) (xy 153.456692 -111.180703) (xy 153.433743 -111.125299) (xy 153.418222 -111.067374)
			(xy 153.410394 -111.007918) (xy 153.409904 -110.977934) (xy 54.554603 -110.977934) (xy 54.554138 -111.006378)
			(xy 54.546315 -111.0658) (xy 54.530802 -111.123693) (xy 54.507866 -111.179066) (xy 54.477899 -111.230972)
			(xy 54.441412 -111.278522) (xy 54.399032 -111.320902) (xy 54.351482 -111.357389) (xy 54.299576 -111.387356)
			(xy 54.244203 -111.410292) (xy 54.18631 -111.425805) (xy 54.126888 -111.433628) (xy 54.066952 -111.433628)
			(xy 54.00753 -111.425805) (xy 53.949637 -111.410292) (xy 53.894264 -111.387356) (xy 53.842358 -111.357389)
			(xy 53.794808 -111.320902) (xy 53.752428 -111.278522) (xy 53.715941 -111.230972) (xy 53.685974 -111.179066)
			(xy 53.663038 -111.123693) (xy 53.647525 -111.0658) (xy 53.639702 -111.006378) (xy 53.639212 -110.97641)
			(xy 38.225476 -110.97641) (xy 38.225476 -110.977934) (xy 38.224986 -111.007902) (xy 38.217163 -111.067324)
			(xy 38.20165 -111.125217) (xy 38.178714 -111.18059) (xy 38.148747 -111.232496) (xy 38.11226 -111.280046)
			(xy 38.06988 -111.322426) (xy 38.02233 -111.358913) (xy 37.970424 -111.38888) (xy 37.915051 -111.411816)
			(xy 37.857158 -111.427329) (xy 37.797736 -111.435152) (xy 37.7378 -111.435152) (xy 37.678378 -111.427329)
			(xy 37.620485 -111.411816) (xy 37.565112 -111.38888) (xy 37.513206 -111.358913) (xy 37.465656 -111.322426)
			(xy 37.423276 -111.280046) (xy 37.386789 -111.232496) (xy 37.356822 -111.18059) (xy 37.333886 -111.125217)
			(xy 37.318373 -111.067324) (xy 37.31055 -111.007902) (xy 37.31006 -110.977934) (xy 4.308094 -110.977934)
			(xy 4.308094 -112.784382) (xy 34.667952 -112.784382) (xy 34.667952 -111.920782) (xy 34.668442 -111.890814)
			(xy 34.676265 -111.831392) (xy 34.691778 -111.773499) (xy 34.714714 -111.718126) (xy 34.744681 -111.66622)
			(xy 34.781168 -111.61867) (xy 34.823548 -111.57629) (xy 34.871098 -111.539803) (xy 34.923004 -111.509836)
			(xy 34.978377 -111.4869) (xy 35.03627 -111.471387) (xy 35.095692 -111.463564) (xy 35.155628 -111.463564)
			(xy 35.21505 -111.471387) (xy 35.272943 -111.4869) (xy 35.328316 -111.509836) (xy 35.380222 -111.539803)
			(xy 35.427772 -111.57629) (xy 35.470152 -111.61867) (xy 35.506639 -111.66622) (xy 35.536606 -111.718126)
			(xy 35.559542 -111.773499) (xy 35.575055 -111.831392) (xy 35.582878 -111.890814) (xy 35.583368 -111.920782)
			(xy 35.583368 -112.776508) (xy 51.785012 -112.776508) (xy 51.785012 -111.912908) (xy 51.785502 -111.88294)
			(xy 51.793325 -111.823518) (xy 51.808838 -111.765625) (xy 51.831774 -111.710252) (xy 51.861741 -111.658346)
			(xy 51.898228 -111.610796) (xy 51.940608 -111.568416) (xy 51.988158 -111.531929) (xy 52.040064 -111.501962)
			(xy 52.095437 -111.479026) (xy 52.15333 -111.463513) (xy 52.212752 -111.45569) (xy 52.272688 -111.45569)
			(xy 52.33211 -111.463513) (xy 52.390003 -111.479026) (xy 52.445376 -111.501962) (xy 52.497282 -111.531929)
			(xy 52.544832 -111.568416) (xy 52.587212 -111.610796) (xy 52.623699 -111.658346) (xy 52.653666 -111.710252)
			(xy 52.676602 -111.765625) (xy 52.692115 -111.823518) (xy 52.699938 -111.88294) (xy 52.700428 -111.912908)
			(xy 52.700428 -112.776508) (xy 52.700299 -112.784382) (xy 150.767796 -112.784382) (xy 150.767796 -111.920782)
			(xy 150.768286 -111.890798) (xy 150.776114 -111.831342) (xy 150.791635 -111.773417) (xy 150.814584 -111.718013)
			(xy 150.844568 -111.666079) (xy 150.881074 -111.618503) (xy 150.923479 -111.576098) (xy 150.971055 -111.539592)
			(xy 151.022989 -111.509608) (xy 151.078393 -111.486659) (xy 151.136318 -111.471138) (xy 151.195774 -111.46331)
			(xy 151.255742 -111.46331) (xy 151.315198 -111.471138) (xy 151.373123 -111.486659) (xy 151.428527 -111.509608)
			(xy 151.480461 -111.539592) (xy 151.528037 -111.576098) (xy 151.570442 -111.618503) (xy 151.606948 -111.666079)
			(xy 151.636932 -111.718013) (xy 151.659881 -111.773417) (xy 151.675402 -111.831342) (xy 151.68323 -111.890798)
			(xy 151.68372 -111.920782) (xy 151.68372 -112.776508) (xy 167.884856 -112.776508) (xy 167.884856 -111.912908)
			(xy 167.885346 -111.882924) (xy 167.893174 -111.823468) (xy 167.908695 -111.765543) (xy 167.931644 -111.710139)
			(xy 167.961628 -111.658205) (xy 167.998134 -111.610629) (xy 168.040539 -111.568224) (xy 168.088115 -111.531718)
			(xy 168.140049 -111.501734) (xy 168.195453 -111.478785) (xy 168.253378 -111.463264) (xy 168.312834 -111.455436)
			(xy 168.372802 -111.455436) (xy 168.432258 -111.463264) (xy 168.490183 -111.478785) (xy 168.545587 -111.501734)
			(xy 168.597521 -111.531718) (xy 168.645097 -111.568224) (xy 168.687502 -111.610629) (xy 168.724008 -111.658205)
			(xy 168.753992 -111.710139) (xy 168.776941 -111.765543) (xy 168.792462 -111.823468) (xy 168.80029 -111.882924)
			(xy 168.80078 -111.912908) (xy 168.80078 -112.776508) (xy 168.800651 -112.784382) (xy 266.86764 -112.784382)
			(xy 266.86764 -111.920782) (xy 266.86813 -111.890798) (xy 266.875958 -111.831342) (xy 266.891479 -111.773417)
			(xy 266.914428 -111.718013) (xy 266.944412 -111.666079) (xy 266.980918 -111.618503) (xy 267.023323 -111.576098)
			(xy 267.070899 -111.539592) (xy 267.122833 -111.509608) (xy 267.178237 -111.486659) (xy 267.236162 -111.471138)
			(xy 267.295618 -111.46331) (xy 267.355586 -111.46331) (xy 267.415042 -111.471138) (xy 267.472967 -111.486659)
			(xy 267.528371 -111.509608) (xy 267.580305 -111.539592) (xy 267.627881 -111.576098) (xy 267.670286 -111.618503)
			(xy 267.706792 -111.666079) (xy 267.736776 -111.718013) (xy 267.759725 -111.773417) (xy 267.775246 -111.831342)
			(xy 267.783074 -111.890798) (xy 267.783564 -111.920782) (xy 267.783564 -112.776508) (xy 283.9847 -112.776508)
			(xy 283.9847 -111.912908) (xy 283.98519 -111.882924) (xy 283.993018 -111.823468) (xy 284.008539 -111.765543)
			(xy 284.031488 -111.710139) (xy 284.061472 -111.658205) (xy 284.097978 -111.610629) (xy 284.140383 -111.568224)
			(xy 284.187959 -111.531718) (xy 284.239893 -111.501734) (xy 284.295297 -111.478785) (xy 284.353222 -111.463264)
			(xy 284.412678 -111.455436) (xy 284.472646 -111.455436) (xy 284.532102 -111.463264) (xy 284.590027 -111.478785)
			(xy 284.645431 -111.501734) (xy 284.697365 -111.531718) (xy 284.744941 -111.568224) (xy 284.787346 -111.610629)
			(xy 284.823852 -111.658205) (xy 284.853836 -111.710139) (xy 284.876785 -111.765543) (xy 284.892306 -111.823468)
			(xy 284.900134 -111.882924) (xy 284.900624 -111.912908) (xy 284.900624 -112.776508) (xy 284.900495 -112.784382)
			(xy 382.967992 -112.784382) (xy 382.967992 -111.920782) (xy 382.968482 -111.890814) (xy 382.976305 -111.831392)
			(xy 382.991818 -111.773499) (xy 383.014754 -111.718126) (xy 383.044721 -111.66622) (xy 383.081208 -111.61867)
			(xy 383.123588 -111.57629) (xy 383.171138 -111.539803) (xy 383.223044 -111.509836) (xy 383.278417 -111.4869)
			(xy 383.33631 -111.471387) (xy 383.395732 -111.463564) (xy 383.455668 -111.463564) (xy 383.51509 -111.471387)
			(xy 383.572983 -111.4869) (xy 383.628356 -111.509836) (xy 383.680262 -111.539803) (xy 383.727812 -111.57629)
			(xy 383.770192 -111.61867) (xy 383.806679 -111.66622) (xy 383.836646 -111.718126) (xy 383.859582 -111.773499)
			(xy 383.875095 -111.831392) (xy 383.882918 -111.890814) (xy 383.883408 -111.920782) (xy 383.883408 -112.776508)
			(xy 400.085052 -112.776508) (xy 400.085052 -111.912908) (xy 400.085542 -111.88294) (xy 400.093365 -111.823518)
			(xy 400.108878 -111.765625) (xy 400.131814 -111.710252) (xy 400.161781 -111.658346) (xy 400.198268 -111.610796)
			(xy 400.240648 -111.568416) (xy 400.288198 -111.531929) (xy 400.340104 -111.501962) (xy 400.395477 -111.479026)
			(xy 400.45337 -111.463513) (xy 400.512792 -111.45569) (xy 400.572728 -111.45569) (xy 400.63215 -111.463513)
			(xy 400.690043 -111.479026) (xy 400.745416 -111.501962) (xy 400.797322 -111.531929) (xy 400.844872 -111.568416)
			(xy 400.887252 -111.610796) (xy 400.923739 -111.658346) (xy 400.953706 -111.710252) (xy 400.976642 -111.765625)
			(xy 400.992155 -111.823518) (xy 400.999978 -111.88294) (xy 401.000468 -111.912908) (xy 401.000468 -112.776508)
			(xy 400.999978 -112.806476) (xy 400.992155 -112.865898) (xy 400.976642 -112.923791) (xy 400.953706 -112.979164)
			(xy 400.923739 -113.03107) (xy 400.887252 -113.07862) (xy 400.844872 -113.121) (xy 400.797322 -113.157487)
			(xy 400.745416 -113.187454) (xy 400.690043 -113.21039) (xy 400.63215 -113.225903) (xy 400.572728 -113.233726)
			(xy 400.512792 -113.233726) (xy 400.45337 -113.225903) (xy 400.395477 -113.21039) (xy 400.340104 -113.187454)
			(xy 400.288198 -113.157487) (xy 400.240648 -113.121) (xy 400.198268 -113.07862) (xy 400.161781 -113.03107)
			(xy 400.131814 -112.979164) (xy 400.108878 -112.923791) (xy 400.093365 -112.865898) (xy 400.085542 -112.806476)
			(xy 400.085052 -112.776508) (xy 383.883408 -112.776508) (xy 383.883408 -112.784382) (xy 383.882918 -112.81435)
			(xy 383.875095 -112.873772) (xy 383.859582 -112.931665) (xy 383.836646 -112.987038) (xy 383.806679 -113.038944)
			(xy 383.770192 -113.086494) (xy 383.727812 -113.128874) (xy 383.680262 -113.165361) (xy 383.628356 -113.195328)
			(xy 383.572983 -113.218264) (xy 383.51509 -113.233777) (xy 383.455668 -113.2416) (xy 383.395732 -113.2416)
			(xy 383.33631 -113.233777) (xy 383.278417 -113.218264) (xy 383.223044 -113.195328) (xy 383.171138 -113.165361)
			(xy 383.123588 -113.128874) (xy 383.081208 -113.086494) (xy 383.044721 -113.038944) (xy 383.014754 -112.987038)
			(xy 382.991818 -112.931665) (xy 382.976305 -112.873772) (xy 382.968482 -112.81435) (xy 382.967992 -112.784382)
			(xy 284.900495 -112.784382) (xy 284.900134 -112.806492) (xy 284.892306 -112.865948) (xy 284.876785 -112.923873)
			(xy 284.853836 -112.979277) (xy 284.823852 -113.031211) (xy 284.787346 -113.078787) (xy 284.744941 -113.121192)
			(xy 284.697365 -113.157698) (xy 284.645431 -113.187682) (xy 284.590027 -113.210631) (xy 284.532102 -113.226152)
			(xy 284.472646 -113.23398) (xy 284.412678 -113.23398) (xy 284.353222 -113.226152) (xy 284.295297 -113.210631)
			(xy 284.239893 -113.187682) (xy 284.187959 -113.157698) (xy 284.140383 -113.121192) (xy 284.097978 -113.078787)
			(xy 284.061472 -113.031211) (xy 284.031488 -112.979277) (xy 284.008539 -112.923873) (xy 283.993018 -112.865948)
			(xy 283.98519 -112.806492) (xy 283.9847 -112.776508) (xy 267.783564 -112.776508) (xy 267.783564 -112.784382)
			(xy 267.783074 -112.814366) (xy 267.775246 -112.873822) (xy 267.759725 -112.931747) (xy 267.736776 -112.987151)
			(xy 267.706792 -113.039085) (xy 267.670286 -113.086661) (xy 267.627881 -113.129066) (xy 267.580305 -113.165572)
			(xy 267.528371 -113.195556) (xy 267.472967 -113.218505) (xy 267.415042 -113.234026) (xy 267.355586 -113.241854)
			(xy 267.295618 -113.241854) (xy 267.236162 -113.234026) (xy 267.178237 -113.218505) (xy 267.122833 -113.195556)
			(xy 267.070899 -113.165572) (xy 267.023323 -113.129066) (xy 266.980918 -113.086661) (xy 266.944412 -113.039085)
			(xy 266.914428 -112.987151) (xy 266.891479 -112.931747) (xy 266.875958 -112.873822) (xy 266.86813 -112.814366)
			(xy 266.86764 -112.784382) (xy 168.800651 -112.784382) (xy 168.80029 -112.806492) (xy 168.792462 -112.865948)
			(xy 168.776941 -112.923873) (xy 168.753992 -112.979277) (xy 168.724008 -113.031211) (xy 168.687502 -113.078787)
			(xy 168.645097 -113.121192) (xy 168.597521 -113.157698) (xy 168.545587 -113.187682) (xy 168.490183 -113.210631)
			(xy 168.432258 -113.226152) (xy 168.372802 -113.23398) (xy 168.312834 -113.23398) (xy 168.253378 -113.226152)
			(xy 168.195453 -113.210631) (xy 168.140049 -113.187682) (xy 168.088115 -113.157698) (xy 168.040539 -113.121192)
			(xy 167.998134 -113.078787) (xy 167.961628 -113.031211) (xy 167.931644 -112.979277) (xy 167.908695 -112.923873)
			(xy 167.893174 -112.865948) (xy 167.885346 -112.806492) (xy 167.884856 -112.776508) (xy 151.68372 -112.776508)
			(xy 151.68372 -112.784382) (xy 151.68323 -112.814366) (xy 151.675402 -112.873822) (xy 151.659881 -112.931747)
			(xy 151.636932 -112.987151) (xy 151.606948 -113.039085) (xy 151.570442 -113.086661) (xy 151.528037 -113.129066)
			(xy 151.480461 -113.165572) (xy 151.428527 -113.195556) (xy 151.373123 -113.218505) (xy 151.315198 -113.234026)
			(xy 151.255742 -113.241854) (xy 151.195774 -113.241854) (xy 151.136318 -113.234026) (xy 151.078393 -113.218505)
			(xy 151.022989 -113.195556) (xy 150.971055 -113.165572) (xy 150.923479 -113.129066) (xy 150.881074 -113.086661)
			(xy 150.844568 -113.039085) (xy 150.814584 -112.987151) (xy 150.791635 -112.931747) (xy 150.776114 -112.873822)
			(xy 150.768286 -112.814366) (xy 150.767796 -112.784382) (xy 52.700299 -112.784382) (xy 52.699938 -112.806476)
			(xy 52.692115 -112.865898) (xy 52.676602 -112.923791) (xy 52.653666 -112.979164) (xy 52.623699 -113.03107)
			(xy 52.587212 -113.07862) (xy 52.544832 -113.121) (xy 52.497282 -113.157487) (xy 52.445376 -113.187454)
			(xy 52.390003 -113.21039) (xy 52.33211 -113.225903) (xy 52.272688 -113.233726) (xy 52.212752 -113.233726)
			(xy 52.15333 -113.225903) (xy 52.095437 -113.21039) (xy 52.040064 -113.187454) (xy 51.988158 -113.157487)
			(xy 51.940608 -113.121) (xy 51.898228 -113.07862) (xy 51.861741 -113.03107) (xy 51.831774 -112.979164)
			(xy 51.808838 -112.923791) (xy 51.793325 -112.865898) (xy 51.785502 -112.806476) (xy 51.785012 -112.776508)
			(xy 35.583368 -112.776508) (xy 35.583368 -112.784382) (xy 35.582878 -112.81435) (xy 35.575055 -112.873772)
			(xy 35.559542 -112.931665) (xy 35.536606 -112.987038) (xy 35.506639 -113.038944) (xy 35.470152 -113.086494)
			(xy 35.427772 -113.128874) (xy 35.380222 -113.165361) (xy 35.328316 -113.195328) (xy 35.272943 -113.218264)
			(xy 35.21505 -113.233777) (xy 35.155628 -113.2416) (xy 35.095692 -113.2416) (xy 35.03627 -113.233777)
			(xy 34.978377 -113.218264) (xy 34.923004 -113.195328) (xy 34.871098 -113.165361) (xy 34.823548 -113.128874)
			(xy 34.781168 -113.086494) (xy 34.744681 -113.038944) (xy 34.714714 -112.987038) (xy 34.691778 -112.931665)
			(xy 34.676265 -112.873772) (xy 34.668442 -112.81435) (xy 34.667952 -112.784382) (xy 4.308094 -112.784382)
			(xy 4.308094 -117.758718) (xy 74.474832 -117.758718) (xy 74.474832 -116.895118) (xy 74.475322 -116.865134)
			(xy 74.48315 -116.805678) (xy 74.498671 -116.747753) (xy 74.52162 -116.692349) (xy 74.551604 -116.640415)
			(xy 74.58811 -116.592839) (xy 74.630515 -116.550434) (xy 74.678091 -116.513928) (xy 74.730025 -116.483944)
			(xy 74.785429 -116.460995) (xy 74.843354 -116.445474) (xy 74.90281 -116.437646) (xy 74.962778 -116.437646)
			(xy 75.022234 -116.445474) (xy 75.080159 -116.460995) (xy 75.135563 -116.483944) (xy 75.187497 -116.513928)
			(xy 75.235073 -116.550434) (xy 75.277478 -116.592839) (xy 75.313984 -116.640415) (xy 75.343968 -116.692349)
			(xy 75.366917 -116.747753) (xy 75.382438 -116.805678) (xy 75.390266 -116.865134) (xy 75.390756 -116.895118)
			(xy 75.390756 -117.758718) (xy 190.574676 -117.758718) (xy 190.574676 -116.895118) (xy 190.575166 -116.865134)
			(xy 190.582994 -116.805678) (xy 190.598515 -116.747753) (xy 190.621464 -116.692349) (xy 190.651448 -116.640415)
			(xy 190.687954 -116.592839) (xy 190.730359 -116.550434) (xy 190.777935 -116.513928) (xy 190.829869 -116.483944)
			(xy 190.885273 -116.460995) (xy 190.943198 -116.445474) (xy 191.002654 -116.437646) (xy 191.062622 -116.437646)
			(xy 191.122078 -116.445474) (xy 191.180003 -116.460995) (xy 191.235407 -116.483944) (xy 191.287341 -116.513928)
			(xy 191.334917 -116.550434) (xy 191.377322 -116.592839) (xy 191.413828 -116.640415) (xy 191.443812 -116.692349)
			(xy 191.466761 -116.747753) (xy 191.482282 -116.805678) (xy 191.49011 -116.865134) (xy 191.4906 -116.895118)
			(xy 191.4906 -117.758718) (xy 306.675028 -117.758718) (xy 306.675028 -116.895118) (xy 306.675518 -116.86515)
			(xy 306.683341 -116.805728) (xy 306.698854 -116.747835) (xy 306.72179 -116.692462) (xy 306.751757 -116.640556)
			(xy 306.788244 -116.593006) (xy 306.830624 -116.550626) (xy 306.878174 -116.514139) (xy 306.93008 -116.484172)
			(xy 306.985453 -116.461236) (xy 307.043346 -116.445723) (xy 307.102768 -116.4379) (xy 307.162704 -116.4379)
			(xy 307.222126 -116.445723) (xy 307.280019 -116.461236) (xy 307.335392 -116.484172) (xy 307.387298 -116.514139)
			(xy 307.434848 -116.550626) (xy 307.477228 -116.593006) (xy 307.513715 -116.640556) (xy 307.543682 -116.692462)
			(xy 307.566618 -116.747835) (xy 307.582131 -116.805728) (xy 307.589954 -116.86515) (xy 307.590444 -116.895118)
			(xy 307.590444 -117.758718) (xy 307.590436 -117.759226) (xy 422.774872 -117.759226) (xy 422.774872 -116.895626)
			(xy 422.775362 -116.865642) (xy 422.78319 -116.806186) (xy 422.798711 -116.748261) (xy 422.82166 -116.692857)
			(xy 422.851644 -116.640923) (xy 422.88815 -116.593347) (xy 422.930555 -116.550942) (xy 422.978131 -116.514436)
			(xy 423.030065 -116.484452) (xy 423.085469 -116.461503) (xy 423.143394 -116.445982) (xy 423.20285 -116.438154)
			(xy 423.262818 -116.438154) (xy 423.322274 -116.445982) (xy 423.380199 -116.461503) (xy 423.435603 -116.484452)
			(xy 423.487537 -116.514436) (xy 423.535113 -116.550942) (xy 423.577518 -116.593347) (xy 423.614024 -116.640923)
			(xy 423.644008 -116.692857) (xy 423.666957 -116.748261) (xy 423.682478 -116.806186) (xy 423.690306 -116.865642)
			(xy 423.690796 -116.895626) (xy 423.690796 -117.759226) (xy 423.690306 -117.78921) (xy 423.682478 -117.848666)
			(xy 423.666957 -117.906591) (xy 423.644008 -117.961995) (xy 423.614024 -118.013929) (xy 423.577518 -118.061505)
			(xy 423.535113 -118.10391) (xy 423.487537 -118.140416) (xy 423.435603 -118.1704) (xy 423.380199 -118.193349)
			(xy 423.322274 -118.20887) (xy 423.262818 -118.216698) (xy 423.20285 -118.216698) (xy 423.143394 -118.20887)
			(xy 423.085469 -118.193349) (xy 423.030065 -118.1704) (xy 422.978131 -118.140416) (xy 422.930555 -118.10391)
			(xy 422.88815 -118.061505) (xy 422.851644 -118.013929) (xy 422.82166 -117.961995) (xy 422.798711 -117.906591)
			(xy 422.78319 -117.848666) (xy 422.775362 -117.78921) (xy 422.774872 -117.759226) (xy 307.590436 -117.759226)
			(xy 307.589954 -117.788686) (xy 307.582131 -117.848108) (xy 307.566618 -117.906001) (xy 307.543682 -117.961374)
			(xy 307.513715 -118.01328) (xy 307.477228 -118.06083) (xy 307.434848 -118.10321) (xy 307.387298 -118.139697)
			(xy 307.335392 -118.169664) (xy 307.280019 -118.1926) (xy 307.222126 -118.208113) (xy 307.162704 -118.215936)
			(xy 307.102768 -118.215936) (xy 307.043346 -118.208113) (xy 306.985453 -118.1926) (xy 306.93008 -118.169664)
			(xy 306.878174 -118.139697) (xy 306.830624 -118.10321) (xy 306.788244 -118.06083) (xy 306.751757 -118.01328)
			(xy 306.72179 -117.961374) (xy 306.698854 -117.906001) (xy 306.683341 -117.848108) (xy 306.675518 -117.788686)
			(xy 306.675028 -117.758718) (xy 191.4906 -117.758718) (xy 191.49011 -117.788702) (xy 191.482282 -117.848158)
			(xy 191.466761 -117.906083) (xy 191.443812 -117.961487) (xy 191.413828 -118.013421) (xy 191.377322 -118.060997)
			(xy 191.334917 -118.103402) (xy 191.287341 -118.139908) (xy 191.235407 -118.169892) (xy 191.180003 -118.192841)
			(xy 191.122078 -118.208362) (xy 191.062622 -118.21619) (xy 191.002654 -118.21619) (xy 190.943198 -118.208362)
			(xy 190.885273 -118.192841) (xy 190.829869 -118.169892) (xy 190.777935 -118.139908) (xy 190.730359 -118.103402)
			(xy 190.687954 -118.060997) (xy 190.651448 -118.013421) (xy 190.621464 -117.961487) (xy 190.598515 -117.906083)
			(xy 190.582994 -117.848158) (xy 190.575166 -117.788702) (xy 190.574676 -117.758718) (xy 75.390756 -117.758718)
			(xy 75.390266 -117.788702) (xy 75.382438 -117.848158) (xy 75.366917 -117.906083) (xy 75.343968 -117.961487)
			(xy 75.313984 -118.013421) (xy 75.277478 -118.060997) (xy 75.235073 -118.103402) (xy 75.187497 -118.139908)
			(xy 75.135563 -118.169892) (xy 75.080159 -118.192841) (xy 75.022234 -118.208362) (xy 74.962778 -118.21619)
			(xy 74.90281 -118.21619) (xy 74.843354 -118.208362) (xy 74.785429 -118.192841) (xy 74.730025 -118.169892)
			(xy 74.678091 -118.139908) (xy 74.630515 -118.103402) (xy 74.58811 -118.060997) (xy 74.551604 -118.013421)
			(xy 74.52162 -117.961487) (xy 74.498671 -117.906083) (xy 74.48315 -117.848158) (xy 74.475322 -117.788702)
			(xy 74.474832 -117.758718) (xy 4.308094 -117.758718) (xy 4.308094 -120.087898) (xy 34.667952 -120.087898)
			(xy 34.667952 -119.224298) (xy 34.668442 -119.19433) (xy 34.676265 -119.134908) (xy 34.691778 -119.077015)
			(xy 34.714714 -119.021642) (xy 34.744681 -118.969736) (xy 34.781168 -118.922186) (xy 34.823548 -118.879806)
			(xy 34.871098 -118.843319) (xy 34.923004 -118.813352) (xy 34.978377 -118.790416) (xy 35.03627 -118.774903)
			(xy 35.095692 -118.76708) (xy 35.155628 -118.76708) (xy 35.21505 -118.774903) (xy 35.272943 -118.790416)
			(xy 35.328316 -118.813352) (xy 35.380222 -118.843319) (xy 35.427772 -118.879806) (xy 35.470152 -118.922186)
			(xy 35.506639 -118.969736) (xy 35.536606 -119.021642) (xy 35.559542 -119.077015) (xy 35.575055 -119.134908)
			(xy 35.582878 -119.19433) (xy 35.583368 -119.224298) (xy 35.583368 -120.086374) (xy 53.639212 -120.086374)
			(xy 53.639212 -119.222774) (xy 53.639702 -119.192806) (xy 53.647525 -119.133384) (xy 53.663038 -119.075491)
			(xy 53.685974 -119.020118) (xy 53.715941 -118.968212) (xy 53.752428 -118.920662) (xy 53.794808 -118.878282)
			(xy 53.842358 -118.841795) (xy 53.894264 -118.811828) (xy 53.949637 -118.788892) (xy 54.00753 -118.773379)
			(xy 54.066952 -118.765556) (xy 54.126888 -118.765556) (xy 54.18631 -118.773379) (xy 54.244203 -118.788892)
			(xy 54.299576 -118.811828) (xy 54.351482 -118.841795) (xy 54.399032 -118.878282) (xy 54.441412 -118.920662)
			(xy 54.477899 -118.968212) (xy 54.507866 -119.020118) (xy 54.530802 -119.075491) (xy 54.546315 -119.133384)
			(xy 54.554138 -119.192806) (xy 54.554628 -119.222774) (xy 54.554628 -119.567198) (xy 66.599308 -119.567198)
			(xy 66.599308 -118.703598) (xy 66.599798 -118.673614) (xy 66.607626 -118.614158) (xy 66.623147 -118.556233)
			(xy 66.646096 -118.500829) (xy 66.67608 -118.448895) (xy 66.712586 -118.401319) (xy 66.754991 -118.358914)
			(xy 66.802567 -118.322408) (xy 66.854501 -118.292424) (xy 66.909905 -118.269475) (xy 66.96783 -118.253954)
			(xy 67.027286 -118.246126) (xy 67.087254 -118.246126) (xy 67.14671 -118.253954) (xy 67.204635 -118.269475)
			(xy 67.260039 -118.292424) (xy 67.311973 -118.322408) (xy 67.359549 -118.358914) (xy 67.401954 -118.401319)
			(xy 67.43846 -118.448895) (xy 67.468444 -118.500829) (xy 67.491393 -118.556233) (xy 67.506914 -118.614158)
			(xy 67.514742 -118.673614) (xy 67.515232 -118.703598) (xy 67.515232 -119.55907) (xy 81.07426 -119.55907)
			(xy 81.07426 -118.69547) (xy 81.07475 -118.665486) (xy 81.082578 -118.60603) (xy 81.098099 -118.548105)
			(xy 81.121048 -118.492701) (xy 81.151032 -118.440767) (xy 81.187538 -118.393191) (xy 81.229943 -118.350786)
			(xy 81.277519 -118.31428) (xy 81.329453 -118.284296) (xy 81.384857 -118.261347) (xy 81.442782 -118.245826)
			(xy 81.502238 -118.237998) (xy 81.562206 -118.237998) (xy 81.621662 -118.245826) (xy 81.679587 -118.261347)
			(xy 81.734991 -118.284296) (xy 81.786925 -118.31428) (xy 81.834501 -118.350786) (xy 81.876906 -118.393191)
			(xy 81.913412 -118.440767) (xy 81.943396 -118.492701) (xy 81.966345 -118.548105) (xy 81.981866 -118.60603)
			(xy 81.989694 -118.665486) (xy 81.990184 -118.69547) (xy 81.990184 -119.55907) (xy 81.989694 -119.589054)
			(xy 81.981866 -119.64851) (xy 81.966345 -119.706435) (xy 81.943396 -119.761839) (xy 81.913412 -119.813773)
			(xy 81.876906 -119.861349) (xy 81.834501 -119.903754) (xy 81.786925 -119.94026) (xy 81.734991 -119.970244)
			(xy 81.679587 -119.993193) (xy 81.621662 -120.008714) (xy 81.562206 -120.016542) (xy 81.502238 -120.016542)
			(xy 81.442782 -120.008714) (xy 81.384857 -119.993193) (xy 81.329453 -119.970244) (xy 81.277519 -119.94026)
			(xy 81.229943 -119.903754) (xy 81.187538 -119.861349) (xy 81.151032 -119.813773) (xy 81.121048 -119.761839)
			(xy 81.098099 -119.706435) (xy 81.082578 -119.64851) (xy 81.07475 -119.589054) (xy 81.07426 -119.55907)
			(xy 67.515232 -119.55907) (xy 67.515232 -119.567198) (xy 67.514742 -119.597182) (xy 67.506914 -119.656638)
			(xy 67.491393 -119.714563) (xy 67.468444 -119.769967) (xy 67.43846 -119.821901) (xy 67.401954 -119.869477)
			(xy 67.359549 -119.911882) (xy 67.311973 -119.948388) (xy 67.260039 -119.978372) (xy 67.204635 -120.001321)
			(xy 67.14671 -120.016842) (xy 67.087254 -120.02467) (xy 67.027286 -120.02467) (xy 66.96783 -120.016842)
			(xy 66.909905 -120.001321) (xy 66.854501 -119.978372) (xy 66.802567 -119.948388) (xy 66.754991 -119.911882)
			(xy 66.712586 -119.869477) (xy 66.67608 -119.821901) (xy 66.646096 -119.769967) (xy 66.623147 -119.714563)
			(xy 66.607626 -119.656638) (xy 66.599798 -119.597182) (xy 66.599308 -119.567198) (xy 54.554628 -119.567198)
			(xy 54.554628 -120.086374) (xy 54.554138 -120.116342) (xy 54.546315 -120.175764) (xy 54.530802 -120.233657)
			(xy 54.507866 -120.28903) (xy 54.477899 -120.340936) (xy 54.441412 -120.388486) (xy 54.399032 -120.430866)
			(xy 54.351482 -120.467353) (xy 54.299576 -120.49732) (xy 54.244203 -120.520256) (xy 54.18631 -120.535769)
			(xy 54.126888 -120.543592) (xy 54.066952 -120.543592) (xy 54.00753 -120.535769) (xy 53.949637 -120.520256)
			(xy 53.894264 -120.49732) (xy 53.842358 -120.467353) (xy 53.794808 -120.430866) (xy 53.752428 -120.388486)
			(xy 53.715941 -120.340936) (xy 53.685974 -120.28903) (xy 53.663038 -120.233657) (xy 53.647525 -120.175764)
			(xy 53.639702 -120.116342) (xy 53.639212 -120.086374) (xy 35.583368 -120.086374) (xy 35.583368 -120.087898)
			(xy 35.582878 -120.117866) (xy 35.575055 -120.177288) (xy 35.559542 -120.235181) (xy 35.536606 -120.290554)
			(xy 35.506639 -120.34246) (xy 35.470152 -120.39001) (xy 35.427772 -120.43239) (xy 35.380222 -120.468877)
			(xy 35.328316 -120.498844) (xy 35.272943 -120.52178) (xy 35.21505 -120.537293) (xy 35.155628 -120.545116)
			(xy 35.095692 -120.545116) (xy 35.03627 -120.537293) (xy 34.978377 -120.52178) (xy 34.923004 -120.498844)
			(xy 34.871098 -120.468877) (xy 34.823548 -120.43239) (xy 34.781168 -120.39001) (xy 34.744681 -120.34246)
			(xy 34.714714 -120.290554) (xy 34.691778 -120.235181) (xy 34.676265 -120.177288) (xy 34.668442 -120.117866)
			(xy 34.667952 -120.087898) (xy 4.308094 -120.087898) (xy 4.308094 -121.894346) (xy 37.31006 -121.894346)
			(xy 37.31006 -121.030746) (xy 37.31055 -121.000778) (xy 37.318373 -120.941356) (xy 37.333886 -120.883463)
			(xy 37.356822 -120.82809) (xy 37.386789 -120.776184) (xy 37.423276 -120.728634) (xy 37.465656 -120.686254)
			(xy 37.513206 -120.649767) (xy 37.565112 -120.6198) (xy 37.620485 -120.596864) (xy 37.678378 -120.581351)
			(xy 37.7378 -120.573528) (xy 37.797736 -120.573528) (xy 37.857158 -120.581351) (xy 37.915051 -120.596864)
			(xy 37.970424 -120.6198) (xy 38.02233 -120.649767) (xy 38.06988 -120.686254) (xy 38.11226 -120.728634)
			(xy 38.148747 -120.776184) (xy 38.178714 -120.82809) (xy 38.20165 -120.883463) (xy 38.217163 -120.941356)
			(xy 38.224986 -121.000778) (xy 38.225476 -121.030746) (xy 38.225476 -121.886472) (xy 51.785012 -121.886472)
			(xy 51.785012 -121.022872) (xy 51.785502 -120.992904) (xy 51.793325 -120.933482) (xy 51.808838 -120.875589)
			(xy 51.831774 -120.820216) (xy 51.861741 -120.76831) (xy 51.898228 -120.72076) (xy 51.940608 -120.67838)
			(xy 51.988158 -120.641893) (xy 52.040064 -120.611926) (xy 52.095437 -120.58899) (xy 52.15333 -120.573477)
			(xy 52.212752 -120.565654) (xy 52.272688 -120.565654) (xy 52.33211 -120.573477) (xy 52.390003 -120.58899)
			(xy 52.445376 -120.611926) (xy 52.497282 -120.641893) (xy 52.544832 -120.67838) (xy 52.587212 -120.72076)
			(xy 52.623699 -120.76831) (xy 52.653666 -120.820216) (xy 52.676602 -120.875589) (xy 52.692115 -120.933482)
			(xy 52.699938 -120.992904) (xy 52.700428 -121.022872) (xy 52.700428 -121.367296) (xy 64.745108 -121.367296)
			(xy 64.745108 -120.503696) (xy 64.745598 -120.473712) (xy 64.753426 -120.414256) (xy 64.768947 -120.356331)
			(xy 64.791896 -120.300927) (xy 64.82188 -120.248993) (xy 64.858386 -120.201417) (xy 64.900791 -120.159012)
			(xy 64.948367 -120.122506) (xy 65.000301 -120.092522) (xy 65.055705 -120.069573) (xy 65.11363 -120.054052)
			(xy 65.173086 -120.046224) (xy 65.233054 -120.046224) (xy 65.29251 -120.054052) (xy 65.350435 -120.069573)
			(xy 65.405839 -120.092522) (xy 65.457773 -120.122506) (xy 65.505349 -120.159012) (xy 65.547754 -120.201417)
			(xy 65.58426 -120.248993) (xy 65.614244 -120.300927) (xy 65.637193 -120.356331) (xy 65.652714 -120.414256)
			(xy 65.660542 -120.473712) (xy 65.661032 -120.503696) (xy 65.661032 -121.365772) (xy 83.716368 -121.365772)
			(xy 83.716368 -120.502172) (xy 83.716858 -120.472188) (xy 83.724686 -120.412732) (xy 83.740207 -120.354807)
			(xy 83.763156 -120.299403) (xy 83.79314 -120.247469) (xy 83.829646 -120.199893) (xy 83.872051 -120.157488)
			(xy 83.919627 -120.120982) (xy 83.971561 -120.090998) (xy 84.026965 -120.068049) (xy 84.08489 -120.052528)
			(xy 84.144346 -120.0447) (xy 84.204314 -120.0447) (xy 84.26377 -120.052528) (xy 84.321695 -120.068049)
			(xy 84.369615 -120.087898) (xy 150.767796 -120.087898) (xy 150.767796 -119.224298) (xy 150.768286 -119.194314)
			(xy 150.776114 -119.134858) (xy 150.791635 -119.076933) (xy 150.814584 -119.021529) (xy 150.844568 -118.969595)
			(xy 150.881074 -118.922019) (xy 150.923479 -118.879614) (xy 150.971055 -118.843108) (xy 151.022989 -118.813124)
			(xy 151.078393 -118.790175) (xy 151.136318 -118.774654) (xy 151.195774 -118.766826) (xy 151.255742 -118.766826)
			(xy 151.315198 -118.774654) (xy 151.373123 -118.790175) (xy 151.428527 -118.813124) (xy 151.480461 -118.843108)
			(xy 151.528037 -118.879614) (xy 151.570442 -118.922019) (xy 151.606948 -118.969595) (xy 151.636932 -119.021529)
			(xy 151.659881 -119.076933) (xy 151.675402 -119.134858) (xy 151.68323 -119.194314) (xy 151.68372 -119.224298)
			(xy 151.68372 -120.086374) (xy 169.739056 -120.086374) (xy 169.739056 -119.222774) (xy 169.739546 -119.19279)
			(xy 169.747374 -119.133334) (xy 169.762895 -119.075409) (xy 169.785844 -119.020005) (xy 169.815828 -118.968071)
			(xy 169.852334 -118.920495) (xy 169.894739 -118.87809) (xy 169.942315 -118.841584) (xy 169.994249 -118.8116)
			(xy 170.049653 -118.788651) (xy 170.107578 -118.77313) (xy 170.167034 -118.765302) (xy 170.227002 -118.765302)
			(xy 170.286458 -118.77313) (xy 170.344383 -118.788651) (xy 170.399787 -118.8116) (xy 170.451721 -118.841584)
			(xy 170.499297 -118.87809) (xy 170.541702 -118.920495) (xy 170.578208 -118.968071) (xy 170.608192 -119.020005)
			(xy 170.631141 -119.075409) (xy 170.646662 -119.133334) (xy 170.65449 -119.19279) (xy 170.65498 -119.222774)
			(xy 170.65498 -119.567198) (xy 182.69966 -119.567198) (xy 182.69966 -118.703598) (xy 182.70015 -118.67363)
			(xy 182.707973 -118.614208) (xy 182.723486 -118.556315) (xy 182.746422 -118.500942) (xy 182.776389 -118.449036)
			(xy 182.812876 -118.401486) (xy 182.855256 -118.359106) (xy 182.902806 -118.322619) (xy 182.954712 -118.292652)
			(xy 183.010085 -118.269716) (xy 183.067978 -118.254203) (xy 183.1274 -118.24638) (xy 183.187336 -118.24638)
			(xy 183.246758 -118.254203) (xy 183.304651 -118.269716) (xy 183.360024 -118.292652) (xy 183.41193 -118.322619)
			(xy 183.45948 -118.359106) (xy 183.50186 -118.401486) (xy 183.538347 -118.449036) (xy 183.568314 -118.500942)
			(xy 183.59125 -118.556315) (xy 183.606763 -118.614208) (xy 183.614586 -118.67363) (xy 183.615076 -118.703598)
			(xy 183.615076 -119.559324) (xy 197.174612 -119.559324) (xy 197.174612 -118.695724) (xy 197.175102 -118.665756)
			(xy 197.182925 -118.606334) (xy 197.198438 -118.548441) (xy 197.221374 -118.493068) (xy 197.251341 -118.441162)
			(xy 197.287828 -118.393612) (xy 197.330208 -118.351232) (xy 197.377758 -118.314745) (xy 197.429664 -118.284778)
			(xy 197.485037 -118.261842) (xy 197.54293 -118.246329) (xy 197.602352 -118.238506) (xy 197.662288 -118.238506)
			(xy 197.72171 -118.246329) (xy 197.779603 -118.261842) (xy 197.834976 -118.284778) (xy 197.886882 -118.314745)
			(xy 197.934432 -118.351232) (xy 197.976812 -118.393612) (xy 198.013299 -118.441162) (xy 198.043266 -118.493068)
			(xy 198.066202 -118.548441) (xy 198.081715 -118.606334) (xy 198.089538 -118.665756) (xy 198.090028 -118.695724)
			(xy 198.090028 -119.559324) (xy 198.089538 -119.589292) (xy 198.081715 -119.648714) (xy 198.066202 -119.706607)
			(xy 198.043266 -119.76198) (xy 198.013299 -119.813886) (xy 197.976812 -119.861436) (xy 197.934432 -119.903816)
			(xy 197.886882 -119.940303) (xy 197.834976 -119.97027) (xy 197.779603 -119.993206) (xy 197.72171 -120.008719)
			(xy 197.662288 -120.016542) (xy 197.602352 -120.016542) (xy 197.54293 -120.008719) (xy 197.485037 -119.993206)
			(xy 197.429664 -119.97027) (xy 197.377758 -119.940303) (xy 197.330208 -119.903816) (xy 197.287828 -119.861436)
			(xy 197.251341 -119.813886) (xy 197.221374 -119.76198) (xy 197.198438 -119.706607) (xy 197.182925 -119.648714)
			(xy 197.175102 -119.589292) (xy 197.174612 -119.559324) (xy 183.615076 -119.559324) (xy 183.615076 -119.567198)
			(xy 183.614586 -119.597166) (xy 183.606763 -119.656588) (xy 183.59125 -119.714481) (xy 183.568314 -119.769854)
			(xy 183.538347 -119.82176) (xy 183.50186 -119.86931) (xy 183.45948 -119.91169) (xy 183.41193 -119.948177)
			(xy 183.360024 -119.978144) (xy 183.304651 -120.00108) (xy 183.246758 -120.016593) (xy 183.187336 -120.024416)
			(xy 183.1274 -120.024416) (xy 183.067978 -120.016593) (xy 183.010085 -120.00108) (xy 182.954712 -119.978144)
			(xy 182.902806 -119.948177) (xy 182.855256 -119.91169) (xy 182.812876 -119.86931) (xy 182.776389 -119.82176)
			(xy 182.746422 -119.769854) (xy 182.723486 -119.714481) (xy 182.707973 -119.656588) (xy 182.70015 -119.597166)
			(xy 182.69966 -119.567198) (xy 170.65498 -119.567198) (xy 170.65498 -120.086374) (xy 170.65449 -120.116358)
			(xy 170.646662 -120.175814) (xy 170.631141 -120.233739) (xy 170.608192 -120.289143) (xy 170.578208 -120.341077)
			(xy 170.541702 -120.388653) (xy 170.499297 -120.431058) (xy 170.451721 -120.467564) (xy 170.399787 -120.497548)
			(xy 170.344383 -120.520497) (xy 170.286458 -120.536018) (xy 170.227002 -120.543846) (xy 170.167034 -120.543846)
			(xy 170.107578 -120.536018) (xy 170.049653 -120.520497) (xy 169.994249 -120.497548) (xy 169.942315 -120.467564)
			(xy 169.894739 -120.431058) (xy 169.852334 -120.388653) (xy 169.815828 -120.341077) (xy 169.785844 -120.289143)
			(xy 169.762895 -120.233739) (xy 169.747374 -120.175814) (xy 169.739546 -120.116358) (xy 169.739056 -120.086374)
			(xy 151.68372 -120.086374) (xy 151.68372 -120.087898) (xy 151.68323 -120.117882) (xy 151.675402 -120.177338)
			(xy 151.659881 -120.235263) (xy 151.636932 -120.290667) (xy 151.606948 -120.342601) (xy 151.570442 -120.390177)
			(xy 151.528037 -120.432582) (xy 151.480461 -120.469088) (xy 151.428527 -120.499072) (xy 151.373123 -120.522021)
			(xy 151.315198 -120.537542) (xy 151.255742 -120.54537) (xy 151.195774 -120.54537) (xy 151.136318 -120.537542)
			(xy 151.078393 -120.522021) (xy 151.022989 -120.499072) (xy 150.971055 -120.469088) (xy 150.923479 -120.432582)
			(xy 150.881074 -120.390177) (xy 150.844568 -120.342601) (xy 150.814584 -120.290667) (xy 150.791635 -120.235263)
			(xy 150.776114 -120.177338) (xy 150.768286 -120.117882) (xy 150.767796 -120.087898) (xy 84.369615 -120.087898)
			(xy 84.377099 -120.090998) (xy 84.429033 -120.120982) (xy 84.476609 -120.157488) (xy 84.519014 -120.199893)
			(xy 84.55552 -120.247469) (xy 84.585504 -120.299403) (xy 84.608453 -120.354807) (xy 84.623974 -120.412732)
			(xy 84.631802 -120.472188) (xy 84.632292 -120.502172) (xy 84.632292 -121.365772) (xy 84.631802 -121.395756)
			(xy 84.623974 -121.455212) (xy 84.608453 -121.513137) (xy 84.585504 -121.568541) (xy 84.55552 -121.620475)
			(xy 84.519014 -121.668051) (xy 84.476609 -121.710456) (xy 84.429033 -121.746962) (xy 84.377099 -121.776946)
			(xy 84.321695 -121.799895) (xy 84.26377 -121.815416) (xy 84.204314 -121.823244) (xy 84.144346 -121.823244)
			(xy 84.08489 -121.815416) (xy 84.026965 -121.799895) (xy 83.971561 -121.776946) (xy 83.919627 -121.746962)
			(xy 83.872051 -121.710456) (xy 83.829646 -121.668051) (xy 83.79314 -121.620475) (xy 83.763156 -121.568541)
			(xy 83.740207 -121.513137) (xy 83.724686 -121.455212) (xy 83.716858 -121.395756) (xy 83.716368 -121.365772)
			(xy 65.661032 -121.365772) (xy 65.661032 -121.367296) (xy 65.660542 -121.39728) (xy 65.652714 -121.456736)
			(xy 65.637193 -121.514661) (xy 65.614244 -121.570065) (xy 65.58426 -121.621999) (xy 65.547754 -121.669575)
			(xy 65.505349 -121.71198) (xy 65.457773 -121.748486) (xy 65.405839 -121.77847) (xy 65.350435 -121.801419)
			(xy 65.29251 -121.81694) (xy 65.233054 -121.824768) (xy 65.173086 -121.824768) (xy 65.11363 -121.81694)
			(xy 65.055705 -121.801419) (xy 65.000301 -121.77847) (xy 64.948367 -121.748486) (xy 64.900791 -121.71198)
			(xy 64.858386 -121.669575) (xy 64.82188 -121.621999) (xy 64.791896 -121.570065) (xy 64.768947 -121.514661)
			(xy 64.753426 -121.456736) (xy 64.745598 -121.39728) (xy 64.745108 -121.367296) (xy 52.700428 -121.367296)
			(xy 52.700428 -121.886472) (xy 52.699938 -121.91644) (xy 52.692115 -121.975862) (xy 52.676602 -122.033755)
			(xy 52.653666 -122.089128) (xy 52.623699 -122.141034) (xy 52.587212 -122.188584) (xy 52.544832 -122.230964)
			(xy 52.497282 -122.267451) (xy 52.445376 -122.297418) (xy 52.390003 -122.320354) (xy 52.33211 -122.335867)
			(xy 52.272688 -122.34369) (xy 52.212752 -122.34369) (xy 52.15333 -122.335867) (xy 52.095437 -122.320354)
			(xy 52.040064 -122.297418) (xy 51.988158 -122.267451) (xy 51.940608 -122.230964) (xy 51.898228 -122.188584)
			(xy 51.861741 -122.141034) (xy 51.831774 -122.089128) (xy 51.808838 -122.033755) (xy 51.793325 -121.975862)
			(xy 51.785502 -121.91644) (xy 51.785012 -121.886472) (xy 38.225476 -121.886472) (xy 38.225476 -121.894346)
			(xy 38.224986 -121.924314) (xy 38.217163 -121.983736) (xy 38.20165 -122.041629) (xy 38.178714 -122.097002)
			(xy 38.148747 -122.148908) (xy 38.11226 -122.196458) (xy 38.06988 -122.238838) (xy 38.02233 -122.275325)
			(xy 37.970424 -122.305292) (xy 37.915051 -122.328228) (xy 37.857158 -122.343741) (xy 37.797736 -122.351564)
			(xy 37.7378 -122.351564) (xy 37.678378 -122.343741) (xy 37.620485 -122.328228) (xy 37.565112 -122.305292)
			(xy 37.513206 -122.275325) (xy 37.465656 -122.238838) (xy 37.423276 -122.196458) (xy 37.386789 -122.148908)
			(xy 37.356822 -122.097002) (xy 37.333886 -122.041629) (xy 37.318373 -121.983736) (xy 37.31055 -121.924314)
			(xy 37.31006 -121.894346) (xy 4.308094 -121.894346) (xy 4.308094 -123.68784) (xy 34.667952 -123.68784)
			(xy 34.667952 -122.82424) (xy 34.668442 -122.794272) (xy 34.676265 -122.73485) (xy 34.691778 -122.676957)
			(xy 34.714714 -122.621584) (xy 34.744681 -122.569678) (xy 34.781168 -122.522128) (xy 34.823548 -122.479748)
			(xy 34.871098 -122.443261) (xy 34.923004 -122.413294) (xy 34.978377 -122.390358) (xy 35.03627 -122.374845)
			(xy 35.095692 -122.367022) (xy 35.155628 -122.367022) (xy 35.21505 -122.374845) (xy 35.272943 -122.390358)
			(xy 35.328316 -122.413294) (xy 35.380222 -122.443261) (xy 35.427772 -122.479748) (xy 35.470152 -122.522128)
			(xy 35.506639 -122.569678) (xy 35.536606 -122.621584) (xy 35.559542 -122.676957) (xy 35.575055 -122.73485)
			(xy 35.582878 -122.794272) (xy 35.583368 -122.82424) (xy 35.583368 -123.686316) (xy 53.639212 -123.686316)
			(xy 53.639212 -122.822716) (xy 53.639702 -122.792748) (xy 53.647525 -122.733326) (xy 53.663038 -122.675433)
			(xy 53.685974 -122.62006) (xy 53.715941 -122.568154) (xy 53.752428 -122.520604) (xy 53.794808 -122.478224)
			(xy 53.842358 -122.441737) (xy 53.894264 -122.41177) (xy 53.949637 -122.388834) (xy 54.00753 -122.373321)
			(xy 54.066952 -122.365498) (xy 54.126888 -122.365498) (xy 54.18631 -122.373321) (xy 54.244203 -122.388834)
			(xy 54.299576 -122.41177) (xy 54.351482 -122.441737) (xy 54.399032 -122.478224) (xy 54.441412 -122.520604)
			(xy 54.477899 -122.568154) (xy 54.507866 -122.62006) (xy 54.530802 -122.675433) (xy 54.546315 -122.733326)
			(xy 54.554138 -122.792748) (xy 54.554628 -122.822716) (xy 54.554628 -123.16714) (xy 66.599308 -123.16714)
			(xy 66.599308 -122.30354) (xy 66.599798 -122.273556) (xy 66.607626 -122.2141) (xy 66.623147 -122.156175)
			(xy 66.646096 -122.100771) (xy 66.67608 -122.048837) (xy 66.712586 -122.001261) (xy 66.754991 -121.958856)
			(xy 66.802567 -121.92235) (xy 66.854501 -121.892366) (xy 66.909905 -121.869417) (xy 66.96783 -121.853896)
			(xy 67.027286 -121.846068) (xy 67.087254 -121.846068) (xy 67.14671 -121.853896) (xy 67.204635 -121.869417)
			(xy 67.260039 -121.892366) (xy 67.311973 -121.92235) (xy 67.359549 -121.958856) (xy 67.401954 -122.001261)
			(xy 67.43846 -122.048837) (xy 67.468444 -122.100771) (xy 67.491393 -122.156175) (xy 67.506914 -122.2141)
			(xy 67.514742 -122.273556) (xy 67.515232 -122.30354) (xy 67.515232 -123.159266) (xy 81.07426 -123.159266)
			(xy 81.07426 -122.295666) (xy 81.07475 -122.265682) (xy 81.082578 -122.206226) (xy 81.098099 -122.148301)
			(xy 81.121048 -122.092897) (xy 81.151032 -122.040963) (xy 81.187538 -121.993387) (xy 81.229943 -121.950982)
			(xy 81.277519 -121.914476) (xy 81.329453 -121.884492) (xy 81.384857 -121.861543) (xy 81.442782 -121.846022)
			(xy 81.502238 -121.838194) (xy 81.562206 -121.838194) (xy 81.621662 -121.846022) (xy 81.679587 -121.861543)
			(xy 81.734991 -121.884492) (xy 81.752059 -121.894346) (xy 153.409904 -121.894346) (xy 153.409904 -121.030746)
			(xy 153.410394 -121.000762) (xy 153.418222 -120.941306) (xy 153.433743 -120.883381) (xy 153.456692 -120.827977)
			(xy 153.486676 -120.776043) (xy 153.523182 -120.728467) (xy 153.565587 -120.686062) (xy 153.613163 -120.649556)
			(xy 153.665097 -120.619572) (xy 153.720501 -120.596623) (xy 153.778426 -120.581102) (xy 153.837882 -120.573274)
			(xy 153.89785 -120.573274) (xy 153.957306 -120.581102) (xy 154.015231 -120.596623) (xy 154.070635 -120.619572)
			(xy 154.122569 -120.649556) (xy 154.170145 -120.686062) (xy 154.21255 -120.728467) (xy 154.249056 -120.776043)
			(xy 154.27904 -120.827977) (xy 154.301989 -120.883381) (xy 154.31751 -120.941306) (xy 154.325338 -121.000762)
			(xy 154.325828 -121.030746) (xy 154.325828 -121.886472) (xy 167.884856 -121.886472) (xy 167.884856 -121.022872)
			(xy 167.885346 -120.992888) (xy 167.893174 -120.933432) (xy 167.908695 -120.875507) (xy 167.931644 -120.820103)
			(xy 167.961628 -120.768169) (xy 167.998134 -120.720593) (xy 168.040539 -120.678188) (xy 168.088115 -120.641682)
			(xy 168.140049 -120.611698) (xy 168.195453 -120.588749) (xy 168.253378 -120.573228) (xy 168.312834 -120.5654)
			(xy 168.372802 -120.5654) (xy 168.432258 -120.573228) (xy 168.490183 -120.588749) (xy 168.545587 -120.611698)
			(xy 168.597521 -120.641682) (xy 168.645097 -120.678188) (xy 168.687502 -120.720593) (xy 168.724008 -120.768169)
			(xy 168.753992 -120.820103) (xy 168.776941 -120.875507) (xy 168.792462 -120.933432) (xy 168.80029 -120.992888)
			(xy 168.80078 -121.022872) (xy 168.80078 -121.367296) (xy 180.84546 -121.367296) (xy 180.84546 -120.503696)
			(xy 180.84595 -120.473728) (xy 180.853773 -120.414306) (xy 180.869286 -120.356413) (xy 180.892222 -120.30104)
			(xy 180.922189 -120.249134) (xy 180.958676 -120.201584) (xy 181.001056 -120.159204) (xy 181.048606 -120.122717)
			(xy 181.100512 -120.09275) (xy 181.155885 -120.069814) (xy 181.213778 -120.054301) (xy 181.2732 -120.046478)
			(xy 181.333136 -120.046478) (xy 181.392558 -120.054301) (xy 181.450451 -120.069814) (xy 181.505824 -120.09275)
			(xy 181.55773 -120.122717) (xy 181.60528 -120.159204) (xy 181.64766 -120.201584) (xy 181.684147 -120.249134)
			(xy 181.714114 -120.30104) (xy 181.73705 -120.356413) (xy 181.752563 -120.414306) (xy 181.760386 -120.473728)
			(xy 181.760876 -120.503696) (xy 181.760876 -121.365772) (xy 199.81672 -121.365772) (xy 199.81672 -120.502172)
			(xy 199.81721 -120.472204) (xy 199.825033 -120.412782) (xy 199.840546 -120.354889) (xy 199.863482 -120.299516)
			(xy 199.893449 -120.24761) (xy 199.929936 -120.20006) (xy 199.972316 -120.15768) (xy 200.019866 -120.121193)
			(xy 200.071772 -120.091226) (xy 200.127145 -120.06829) (xy 200.185038 -120.052777) (xy 200.24446 -120.044954)
			(xy 200.304396 -120.044954) (xy 200.363818 -120.052777) (xy 200.421711 -120.06829) (xy 200.469049 -120.087898)
			(xy 266.86764 -120.087898) (xy 266.86764 -119.224298) (xy 266.86813 -119.194314) (xy 266.875958 -119.134858)
			(xy 266.891479 -119.076933) (xy 266.914428 -119.021529) (xy 266.944412 -118.969595) (xy 266.980918 -118.922019)
			(xy 267.023323 -118.879614) (xy 267.070899 -118.843108) (xy 267.122833 -118.813124) (xy 267.178237 -118.790175)
			(xy 267.236162 -118.774654) (xy 267.295618 -118.766826) (xy 267.355586 -118.766826) (xy 267.415042 -118.774654)
			(xy 267.472967 -118.790175) (xy 267.528371 -118.813124) (xy 267.580305 -118.843108) (xy 267.627881 -118.879614)
			(xy 267.670286 -118.922019) (xy 267.706792 -118.969595) (xy 267.736776 -119.021529) (xy 267.759725 -119.076933)
			(xy 267.775246 -119.134858) (xy 267.783074 -119.194314) (xy 267.783564 -119.224298) (xy 267.783564 -120.086374)
			(xy 285.8389 -120.086374) (xy 285.8389 -119.222774) (xy 285.83939 -119.19279) (xy 285.847218 -119.133334)
			(xy 285.862739 -119.075409) (xy 285.885688 -119.020005) (xy 285.915672 -118.968071) (xy 285.952178 -118.920495)
			(xy 285.994583 -118.87809) (xy 286.042159 -118.841584) (xy 286.094093 -118.8116) (xy 286.149497 -118.788651)
			(xy 286.207422 -118.77313) (xy 286.266878 -118.765302) (xy 286.326846 -118.765302) (xy 286.386302 -118.77313)
			(xy 286.444227 -118.788651) (xy 286.499631 -118.8116) (xy 286.551565 -118.841584) (xy 286.599141 -118.87809)
			(xy 286.641546 -118.920495) (xy 286.678052 -118.968071) (xy 286.708036 -119.020005) (xy 286.730985 -119.075409)
			(xy 286.746506 -119.133334) (xy 286.754334 -119.19279) (xy 286.754824 -119.222774) (xy 286.754824 -119.567198)
			(xy 298.799504 -119.567198) (xy 298.799504 -118.703598) (xy 298.799994 -118.67363) (xy 298.807817 -118.614208)
			(xy 298.82333 -118.556315) (xy 298.846266 -118.500942) (xy 298.876233 -118.449036) (xy 298.91272 -118.401486)
			(xy 298.9551 -118.359106) (xy 299.00265 -118.322619) (xy 299.054556 -118.292652) (xy 299.109929 -118.269716)
			(xy 299.167822 -118.254203) (xy 299.227244 -118.24638) (xy 299.28718 -118.24638) (xy 299.346602 -118.254203)
			(xy 299.404495 -118.269716) (xy 299.459868 -118.292652) (xy 299.511774 -118.322619) (xy 299.559324 -118.359106)
			(xy 299.601704 -118.401486) (xy 299.638191 -118.449036) (xy 299.668158 -118.500942) (xy 299.691094 -118.556315)
			(xy 299.706607 -118.614208) (xy 299.71443 -118.67363) (xy 299.71492 -118.703598) (xy 299.71492 -119.559324)
			(xy 313.274456 -119.559324) (xy 313.274456 -118.695724) (xy 313.274946 -118.665756) (xy 313.282769 -118.606334)
			(xy 313.298282 -118.548441) (xy 313.321218 -118.493068) (xy 313.351185 -118.441162) (xy 313.387672 -118.393612)
			(xy 313.430052 -118.351232) (xy 313.477602 -118.314745) (xy 313.529508 -118.284778) (xy 313.584881 -118.261842)
			(xy 313.642774 -118.246329) (xy 313.702196 -118.238506) (xy 313.762132 -118.238506) (xy 313.821554 -118.246329)
			(xy 313.879447 -118.261842) (xy 313.93482 -118.284778) (xy 313.986726 -118.314745) (xy 314.034276 -118.351232)
			(xy 314.076656 -118.393612) (xy 314.113143 -118.441162) (xy 314.14311 -118.493068) (xy 314.166046 -118.548441)
			(xy 314.181559 -118.606334) (xy 314.189382 -118.665756) (xy 314.189872 -118.695724) (xy 314.189872 -119.559324)
			(xy 314.189382 -119.589292) (xy 314.181559 -119.648714) (xy 314.166046 -119.706607) (xy 314.14311 -119.76198)
			(xy 314.113143 -119.813886) (xy 314.076656 -119.861436) (xy 314.034276 -119.903816) (xy 313.986726 -119.940303)
			(xy 313.93482 -119.97027) (xy 313.879447 -119.993206) (xy 313.821554 -120.008719) (xy 313.762132 -120.016542)
			(xy 313.702196 -120.016542) (xy 313.642774 -120.008719) (xy 313.584881 -119.993206) (xy 313.529508 -119.97027)
			(xy 313.477602 -119.940303) (xy 313.430052 -119.903816) (xy 313.387672 -119.861436) (xy 313.351185 -119.813886)
			(xy 313.321218 -119.76198) (xy 313.298282 -119.706607) (xy 313.282769 -119.648714) (xy 313.274946 -119.589292)
			(xy 313.274456 -119.559324) (xy 299.71492 -119.559324) (xy 299.71492 -119.567198) (xy 299.71443 -119.597166)
			(xy 299.706607 -119.656588) (xy 299.691094 -119.714481) (xy 299.668158 -119.769854) (xy 299.638191 -119.82176)
			(xy 299.601704 -119.86931) (xy 299.559324 -119.91169) (xy 299.511774 -119.948177) (xy 299.459868 -119.978144)
			(xy 299.404495 -120.00108) (xy 299.346602 -120.016593) (xy 299.28718 -120.024416) (xy 299.227244 -120.024416)
			(xy 299.167822 -120.016593) (xy 299.109929 -120.00108) (xy 299.054556 -119.978144) (xy 299.00265 -119.948177)
			(xy 298.9551 -119.91169) (xy 298.91272 -119.86931) (xy 298.876233 -119.82176) (xy 298.846266 -119.769854)
			(xy 298.82333 -119.714481) (xy 298.807817 -119.656588) (xy 298.799994 -119.597166) (xy 298.799504 -119.567198)
			(xy 286.754824 -119.567198) (xy 286.754824 -120.086374) (xy 286.754334 -120.116358) (xy 286.746506 -120.175814)
			(xy 286.730985 -120.233739) (xy 286.708036 -120.289143) (xy 286.678052 -120.341077) (xy 286.641546 -120.388653)
			(xy 286.599141 -120.431058) (xy 286.551565 -120.467564) (xy 286.499631 -120.497548) (xy 286.444227 -120.520497)
			(xy 286.386302 -120.536018) (xy 286.326846 -120.543846) (xy 286.266878 -120.543846) (xy 286.207422 -120.536018)
			(xy 286.149497 -120.520497) (xy 286.094093 -120.497548) (xy 286.042159 -120.467564) (xy 285.994583 -120.431058)
			(xy 285.952178 -120.388653) (xy 285.915672 -120.341077) (xy 285.885688 -120.289143) (xy 285.862739 -120.233739)
			(xy 285.847218 -120.175814) (xy 285.83939 -120.116358) (xy 285.8389 -120.086374) (xy 267.783564 -120.086374)
			(xy 267.783564 -120.087898) (xy 267.783074 -120.117882) (xy 267.775246 -120.177338) (xy 267.759725 -120.235263)
			(xy 267.736776 -120.290667) (xy 267.706792 -120.342601) (xy 267.670286 -120.390177) (xy 267.627881 -120.432582)
			(xy 267.580305 -120.469088) (xy 267.528371 -120.499072) (xy 267.472967 -120.522021) (xy 267.415042 -120.537542)
			(xy 267.355586 -120.54537) (xy 267.295618 -120.54537) (xy 267.236162 -120.537542) (xy 267.178237 -120.522021)
			(xy 267.122833 -120.499072) (xy 267.070899 -120.469088) (xy 267.023323 -120.432582) (xy 266.980918 -120.390177)
			(xy 266.944412 -120.342601) (xy 266.914428 -120.290667) (xy 266.891479 -120.235263) (xy 266.875958 -120.177338)
			(xy 266.86813 -120.117882) (xy 266.86764 -120.087898) (xy 200.469049 -120.087898) (xy 200.477084 -120.091226)
			(xy 200.52899 -120.121193) (xy 200.57654 -120.15768) (xy 200.61892 -120.20006) (xy 200.655407 -120.24761)
			(xy 200.685374 -120.299516) (xy 200.70831 -120.354889) (xy 200.723823 -120.412782) (xy 200.731646 -120.472204)
			(xy 200.732136 -120.502172) (xy 200.732136 -121.365772) (xy 200.731646 -121.39574) (xy 200.723823 -121.455162)
			(xy 200.70831 -121.513055) (xy 200.685374 -121.568428) (xy 200.655407 -121.620334) (xy 200.61892 -121.667884)
			(xy 200.57654 -121.710264) (xy 200.52899 -121.746751) (xy 200.477084 -121.776718) (xy 200.421711 -121.799654)
			(xy 200.363818 -121.815167) (xy 200.304396 -121.82299) (xy 200.24446 -121.82299) (xy 200.185038 -121.815167)
			(xy 200.127145 -121.799654) (xy 200.071772 -121.776718) (xy 200.019866 -121.746751) (xy 199.972316 -121.710264)
			(xy 199.929936 -121.667884) (xy 199.893449 -121.620334) (xy 199.863482 -121.568428) (xy 199.840546 -121.513055)
			(xy 199.825033 -121.455162) (xy 199.81721 -121.39574) (xy 199.81672 -121.365772) (xy 181.760876 -121.365772)
			(xy 181.760876 -121.367296) (xy 181.760386 -121.397264) (xy 181.752563 -121.456686) (xy 181.73705 -121.514579)
			(xy 181.714114 -121.569952) (xy 181.684147 -121.621858) (xy 181.64766 -121.669408) (xy 181.60528 -121.711788)
			(xy 181.55773 -121.748275) (xy 181.505824 -121.778242) (xy 181.450451 -121.801178) (xy 181.392558 -121.816691)
			(xy 181.333136 -121.824514) (xy 181.2732 -121.824514) (xy 181.213778 -121.816691) (xy 181.155885 -121.801178)
			(xy 181.100512 -121.778242) (xy 181.048606 -121.748275) (xy 181.001056 -121.711788) (xy 180.958676 -121.669408)
			(xy 180.922189 -121.621858) (xy 180.892222 -121.569952) (xy 180.869286 -121.514579) (xy 180.853773 -121.456686)
			(xy 180.84595 -121.397264) (xy 180.84546 -121.367296) (xy 168.80078 -121.367296) (xy 168.80078 -121.886472)
			(xy 168.80029 -121.916456) (xy 168.792462 -121.975912) (xy 168.776941 -122.033837) (xy 168.753992 -122.089241)
			(xy 168.724008 -122.141175) (xy 168.687502 -122.188751) (xy 168.645097 -122.231156) (xy 168.597521 -122.267662)
			(xy 168.545587 -122.297646) (xy 168.490183 -122.320595) (xy 168.432258 -122.336116) (xy 168.372802 -122.343944)
			(xy 168.312834 -122.343944) (xy 168.253378 -122.336116) (xy 168.195453 -122.320595) (xy 168.140049 -122.297646)
			(xy 168.088115 -122.267662) (xy 168.040539 -122.231156) (xy 167.998134 -122.188751) (xy 167.961628 -122.141175)
			(xy 167.931644 -122.089241) (xy 167.908695 -122.033837) (xy 167.893174 -121.975912) (xy 167.885346 -121.916456)
			(xy 167.884856 -121.886472) (xy 154.325828 -121.886472) (xy 154.325828 -121.894346) (xy 154.325338 -121.92433)
			(xy 154.31751 -121.983786) (xy 154.301989 -122.041711) (xy 154.27904 -122.097115) (xy 154.249056 -122.149049)
			(xy 154.21255 -122.196625) (xy 154.170145 -122.23903) (xy 154.122569 -122.275536) (xy 154.070635 -122.30552)
			(xy 154.015231 -122.328469) (xy 153.957306 -122.34399) (xy 153.89785 -122.351818) (xy 153.837882 -122.351818)
			(xy 153.778426 -122.34399) (xy 153.720501 -122.328469) (xy 153.665097 -122.30552) (xy 153.613163 -122.275536)
			(xy 153.565587 -122.23903) (xy 153.523182 -122.196625) (xy 153.486676 -122.149049) (xy 153.456692 -122.097115)
			(xy 153.433743 -122.041711) (xy 153.418222 -121.983786) (xy 153.410394 -121.92433) (xy 153.409904 -121.894346)
			(xy 81.752059 -121.894346) (xy 81.786925 -121.914476) (xy 81.834501 -121.950982) (xy 81.876906 -121.993387)
			(xy 81.913412 -122.040963) (xy 81.943396 -122.092897) (xy 81.966345 -122.148301) (xy 81.981866 -122.206226)
			(xy 81.989694 -122.265682) (xy 81.990184 -122.295666) (xy 81.990184 -123.159266) (xy 81.989694 -123.18925)
			(xy 81.981866 -123.248706) (xy 81.966345 -123.306631) (xy 81.943396 -123.362035) (xy 81.913412 -123.413969)
			(xy 81.876906 -123.461545) (xy 81.834501 -123.50395) (xy 81.786925 -123.540456) (xy 81.734991 -123.57044)
			(xy 81.679587 -123.593389) (xy 81.621662 -123.60891) (xy 81.562206 -123.616738) (xy 81.502238 -123.616738)
			(xy 81.442782 -123.60891) (xy 81.384857 -123.593389) (xy 81.329453 -123.57044) (xy 81.277519 -123.540456)
			(xy 81.229943 -123.50395) (xy 81.187538 -123.461545) (xy 81.151032 -123.413969) (xy 81.121048 -123.362035)
			(xy 81.098099 -123.306631) (xy 81.082578 -123.248706) (xy 81.07475 -123.18925) (xy 81.07426 -123.159266)
			(xy 67.515232 -123.159266) (xy 67.515232 -123.16714) (xy 67.514742 -123.197124) (xy 67.506914 -123.25658)
			(xy 67.491393 -123.314505) (xy 67.468444 -123.369909) (xy 67.43846 -123.421843) (xy 67.401954 -123.469419)
			(xy 67.359549 -123.511824) (xy 67.311973 -123.54833) (xy 67.260039 -123.578314) (xy 67.204635 -123.601263)
			(xy 67.14671 -123.616784) (xy 67.087254 -123.624612) (xy 67.027286 -123.624612) (xy 66.96783 -123.616784)
			(xy 66.909905 -123.601263) (xy 66.854501 -123.578314) (xy 66.802567 -123.54833) (xy 66.754991 -123.511824)
			(xy 66.712586 -123.469419) (xy 66.67608 -123.421843) (xy 66.646096 -123.369909) (xy 66.623147 -123.314505)
			(xy 66.607626 -123.25658) (xy 66.599798 -123.197124) (xy 66.599308 -123.16714) (xy 54.554628 -123.16714)
			(xy 54.554628 -123.686316) (xy 54.554138 -123.716284) (xy 54.546315 -123.775706) (xy 54.530802 -123.833599)
			(xy 54.507866 -123.888972) (xy 54.477899 -123.940878) (xy 54.441412 -123.988428) (xy 54.399032 -124.030808)
			(xy 54.351482 -124.067295) (xy 54.299576 -124.097262) (xy 54.244203 -124.120198) (xy 54.18631 -124.135711)
			(xy 54.126888 -124.143534) (xy 54.066952 -124.143534) (xy 54.00753 -124.135711) (xy 53.949637 -124.120198)
			(xy 53.894264 -124.097262) (xy 53.842358 -124.067295) (xy 53.794808 -124.030808) (xy 53.752428 -123.988428)
			(xy 53.715941 -123.940878) (xy 53.685974 -123.888972) (xy 53.663038 -123.833599) (xy 53.647525 -123.775706)
			(xy 53.639702 -123.716284) (xy 53.639212 -123.686316) (xy 35.583368 -123.686316) (xy 35.583368 -123.68784)
			(xy 35.582878 -123.717808) (xy 35.575055 -123.77723) (xy 35.559542 -123.835123) (xy 35.536606 -123.890496)
			(xy 35.506639 -123.942402) (xy 35.470152 -123.989952) (xy 35.427772 -124.032332) (xy 35.380222 -124.068819)
			(xy 35.328316 -124.098786) (xy 35.272943 -124.121722) (xy 35.21505 -124.137235) (xy 35.155628 -124.145058)
			(xy 35.095692 -124.145058) (xy 35.03627 -124.137235) (xy 34.978377 -124.121722) (xy 34.923004 -124.098786)
			(xy 34.871098 -124.068819) (xy 34.823548 -124.032332) (xy 34.781168 -123.989952) (xy 34.744681 -123.942402)
			(xy 34.714714 -123.890496) (xy 34.691778 -123.835123) (xy 34.676265 -123.77723) (xy 34.668442 -123.717808)
			(xy 34.667952 -123.68784) (xy 4.308094 -123.68784) (xy 4.308094 -125.494542) (xy 37.31006 -125.494542)
			(xy 37.31006 -124.630942) (xy 37.31055 -124.600974) (xy 37.318373 -124.541552) (xy 37.333886 -124.483659)
			(xy 37.356822 -124.428286) (xy 37.386789 -124.37638) (xy 37.423276 -124.32883) (xy 37.465656 -124.28645)
			(xy 37.513206 -124.249963) (xy 37.565112 -124.219996) (xy 37.620485 -124.19706) (xy 37.678378 -124.181547)
			(xy 37.7378 -124.173724) (xy 37.797736 -124.173724) (xy 37.857158 -124.181547) (xy 37.915051 -124.19706)
			(xy 37.970424 -124.219996) (xy 38.02233 -124.249963) (xy 38.06988 -124.28645) (xy 38.11226 -124.32883)
			(xy 38.148747 -124.37638) (xy 38.178714 -124.428286) (xy 38.20165 -124.483659) (xy 38.217163 -124.541552)
			(xy 38.224986 -124.600974) (xy 38.225476 -124.630942) (xy 38.225476 -125.486414) (xy 51.785012 -125.486414)
			(xy 51.785012 -124.622814) (xy 51.785502 -124.592846) (xy 51.793325 -124.533424) (xy 51.808838 -124.475531)
			(xy 51.831774 -124.420158) (xy 51.861741 -124.368252) (xy 51.898228 -124.320702) (xy 51.940608 -124.278322)
			(xy 51.988158 -124.241835) (xy 52.040064 -124.211868) (xy 52.095437 -124.188932) (xy 52.15333 -124.173419)
			(xy 52.212752 -124.165596) (xy 52.272688 -124.165596) (xy 52.33211 -124.173419) (xy 52.390003 -124.188932)
			(xy 52.445376 -124.211868) (xy 52.497282 -124.241835) (xy 52.544832 -124.278322) (xy 52.587212 -124.320702)
			(xy 52.623699 -124.368252) (xy 52.653666 -124.420158) (xy 52.676602 -124.475531) (xy 52.692115 -124.533424)
			(xy 52.699938 -124.592846) (xy 52.700428 -124.622814) (xy 52.700428 -124.967238) (xy 64.745108 -124.967238)
			(xy 64.745108 -124.103638) (xy 64.745598 -124.073654) (xy 64.753426 -124.014198) (xy 64.768947 -123.956273)
			(xy 64.791896 -123.900869) (xy 64.82188 -123.848935) (xy 64.858386 -123.801359) (xy 64.900791 -123.758954)
			(xy 64.948367 -123.722448) (xy 65.000301 -123.692464) (xy 65.055705 -123.669515) (xy 65.11363 -123.653994)
			(xy 65.173086 -123.646166) (xy 65.233054 -123.646166) (xy 65.29251 -123.653994) (xy 65.350435 -123.669515)
			(xy 65.405839 -123.692464) (xy 65.457773 -123.722448) (xy 65.505349 -123.758954) (xy 65.547754 -123.801359)
			(xy 65.58426 -123.848935) (xy 65.614244 -123.900869) (xy 65.637193 -123.956273) (xy 65.652714 -124.014198)
			(xy 65.660542 -124.073654) (xy 65.661032 -124.103638) (xy 65.661032 -124.965714) (xy 83.716368 -124.965714)
			(xy 83.716368 -124.102114) (xy 83.716858 -124.07213) (xy 83.724686 -124.012674) (xy 83.740207 -123.954749)
			(xy 83.763156 -123.899345) (xy 83.79314 -123.847411) (xy 83.829646 -123.799835) (xy 83.872051 -123.75743)
			(xy 83.919627 -123.720924) (xy 83.971561 -123.69094) (xy 84.026965 -123.667991) (xy 84.08489 -123.65247)
			(xy 84.144346 -123.644642) (xy 84.204314 -123.644642) (xy 84.26377 -123.65247) (xy 84.321695 -123.667991)
			(xy 84.369615 -123.68784) (xy 150.767796 -123.68784) (xy 150.767796 -122.82424) (xy 150.768286 -122.794256)
			(xy 150.776114 -122.7348) (xy 150.791635 -122.676875) (xy 150.814584 -122.621471) (xy 150.844568 -122.569537)
			(xy 150.881074 -122.521961) (xy 150.923479 -122.479556) (xy 150.971055 -122.44305) (xy 151.022989 -122.413066)
			(xy 151.078393 -122.390117) (xy 151.136318 -122.374596) (xy 151.195774 -122.366768) (xy 151.255742 -122.366768)
			(xy 151.315198 -122.374596) (xy 151.373123 -122.390117) (xy 151.428527 -122.413066) (xy 151.480461 -122.44305)
			(xy 151.528037 -122.479556) (xy 151.570442 -122.521961) (xy 151.606948 -122.569537) (xy 151.636932 -122.621471)
			(xy 151.659881 -122.676875) (xy 151.675402 -122.7348) (xy 151.68323 -122.794256) (xy 151.68372 -122.82424)
			(xy 151.68372 -123.686316) (xy 169.739056 -123.686316) (xy 169.739056 -122.822716) (xy 169.739546 -122.792732)
			(xy 169.747374 -122.733276) (xy 169.762895 -122.675351) (xy 169.785844 -122.619947) (xy 169.815828 -122.568013)
			(xy 169.852334 -122.520437) (xy 169.894739 -122.478032) (xy 169.942315 -122.441526) (xy 169.994249 -122.411542)
			(xy 170.049653 -122.388593) (xy 170.107578 -122.373072) (xy 170.167034 -122.365244) (xy 170.227002 -122.365244)
			(xy 170.286458 -122.373072) (xy 170.344383 -122.388593) (xy 170.399787 -122.411542) (xy 170.451721 -122.441526)
			(xy 170.499297 -122.478032) (xy 170.541702 -122.520437) (xy 170.578208 -122.568013) (xy 170.608192 -122.619947)
			(xy 170.631141 -122.675351) (xy 170.646662 -122.733276) (xy 170.65449 -122.792732) (xy 170.65498 -122.822716)
			(xy 170.65498 -123.16714) (xy 182.69966 -123.16714) (xy 182.69966 -122.30354) (xy 182.70015 -122.273572)
			(xy 182.707973 -122.21415) (xy 182.723486 -122.156257) (xy 182.746422 -122.100884) (xy 182.776389 -122.048978)
			(xy 182.812876 -122.001428) (xy 182.855256 -121.959048) (xy 182.902806 -121.922561) (xy 182.954712 -121.892594)
			(xy 183.010085 -121.869658) (xy 183.067978 -121.854145) (xy 183.1274 -121.846322) (xy 183.187336 -121.846322)
			(xy 183.246758 -121.854145) (xy 183.304651 -121.869658) (xy 183.360024 -121.892594) (xy 183.41193 -121.922561)
			(xy 183.45948 -121.959048) (xy 183.50186 -122.001428) (xy 183.538347 -122.048978) (xy 183.568314 -122.100884)
			(xy 183.59125 -122.156257) (xy 183.606763 -122.21415) (xy 183.614586 -122.273572) (xy 183.615076 -122.30354)
			(xy 183.615076 -123.159266) (xy 197.174612 -123.159266) (xy 197.174612 -122.295666) (xy 197.175102 -122.265698)
			(xy 197.182925 -122.206276) (xy 197.198438 -122.148383) (xy 197.221374 -122.09301) (xy 197.251341 -122.041104)
			(xy 197.287828 -121.993554) (xy 197.330208 -121.951174) (xy 197.377758 -121.914687) (xy 197.429664 -121.88472)
			(xy 197.485037 -121.861784) (xy 197.54293 -121.846271) (xy 197.602352 -121.838448) (xy 197.662288 -121.838448)
			(xy 197.72171 -121.846271) (xy 197.779603 -121.861784) (xy 197.834976 -121.88472) (xy 197.851649 -121.894346)
			(xy 269.509748 -121.894346) (xy 269.509748 -121.030746) (xy 269.510238 -121.000762) (xy 269.518066 -120.941306)
			(xy 269.533587 -120.883381) (xy 269.556536 -120.827977) (xy 269.58652 -120.776043) (xy 269.623026 -120.728467)
			(xy 269.665431 -120.686062) (xy 269.713007 -120.649556) (xy 269.764941 -120.619572) (xy 269.820345 -120.596623)
			(xy 269.87827 -120.581102) (xy 269.937726 -120.573274) (xy 269.997694 -120.573274) (xy 270.05715 -120.581102)
			(xy 270.115075 -120.596623) (xy 270.170479 -120.619572) (xy 270.222413 -120.649556) (xy 270.269989 -120.686062)
			(xy 270.312394 -120.728467) (xy 270.3489 -120.776043) (xy 270.378884 -120.827977) (xy 270.401833 -120.883381)
			(xy 270.417354 -120.941306) (xy 270.425182 -121.000762) (xy 270.425672 -121.030746) (xy 270.425672 -121.886472)
			(xy 283.9847 -121.886472) (xy 283.9847 -121.022872) (xy 283.98519 -120.992888) (xy 283.993018 -120.933432)
			(xy 284.008539 -120.875507) (xy 284.031488 -120.820103) (xy 284.061472 -120.768169) (xy 284.097978 -120.720593)
			(xy 284.140383 -120.678188) (xy 284.187959 -120.641682) (xy 284.239893 -120.611698) (xy 284.295297 -120.588749)
			(xy 284.353222 -120.573228) (xy 284.412678 -120.5654) (xy 284.472646 -120.5654) (xy 284.532102 -120.573228)
			(xy 284.590027 -120.588749) (xy 284.645431 -120.611698) (xy 284.697365 -120.641682) (xy 284.744941 -120.678188)
			(xy 284.787346 -120.720593) (xy 284.823852 -120.768169) (xy 284.853836 -120.820103) (xy 284.876785 -120.875507)
			(xy 284.892306 -120.933432) (xy 284.900134 -120.992888) (xy 284.900624 -121.022872) (xy 284.900624 -121.367296)
			(xy 296.945304 -121.367296) (xy 296.945304 -120.503696) (xy 296.945794 -120.473728) (xy 296.953617 -120.414306)
			(xy 296.96913 -120.356413) (xy 296.992066 -120.30104) (xy 297.022033 -120.249134) (xy 297.05852 -120.201584)
			(xy 297.1009 -120.159204) (xy 297.14845 -120.122717) (xy 297.200356 -120.09275) (xy 297.255729 -120.069814)
			(xy 297.313622 -120.054301) (xy 297.373044 -120.046478) (xy 297.43298 -120.046478) (xy 297.492402 -120.054301)
			(xy 297.550295 -120.069814) (xy 297.605668 -120.09275) (xy 297.657574 -120.122717) (xy 297.705124 -120.159204)
			(xy 297.747504 -120.201584) (xy 297.783991 -120.249134) (xy 297.813958 -120.30104) (xy 297.836894 -120.356413)
			(xy 297.852407 -120.414306) (xy 297.86023 -120.473728) (xy 297.86072 -120.503696) (xy 297.86072 -121.365772)
			(xy 315.916564 -121.365772) (xy 315.916564 -120.502172) (xy 315.917054 -120.472204) (xy 315.924877 -120.412782)
			(xy 315.94039 -120.354889) (xy 315.963326 -120.299516) (xy 315.993293 -120.24761) (xy 316.02978 -120.20006)
			(xy 316.07216 -120.15768) (xy 316.11971 -120.121193) (xy 316.171616 -120.091226) (xy 316.226989 -120.06829)
			(xy 316.284882 -120.052777) (xy 316.344304 -120.044954) (xy 316.40424 -120.044954) (xy 316.463662 -120.052777)
			(xy 316.521555 -120.06829) (xy 316.568893 -120.087898) (xy 382.967992 -120.087898) (xy 382.967992 -119.224298)
			(xy 382.968482 -119.19433) (xy 382.976305 -119.134908) (xy 382.991818 -119.077015) (xy 383.014754 -119.021642)
			(xy 383.044721 -118.969736) (xy 383.081208 -118.922186) (xy 383.123588 -118.879806) (xy 383.171138 -118.843319)
			(xy 383.223044 -118.813352) (xy 383.278417 -118.790416) (xy 383.33631 -118.774903) (xy 383.395732 -118.76708)
			(xy 383.455668 -118.76708) (xy 383.51509 -118.774903) (xy 383.572983 -118.790416) (xy 383.628356 -118.813352)
			(xy 383.680262 -118.843319) (xy 383.727812 -118.879806) (xy 383.770192 -118.922186) (xy 383.806679 -118.969736)
			(xy 383.836646 -119.021642) (xy 383.859582 -119.077015) (xy 383.875095 -119.134908) (xy 383.882918 -119.19433)
			(xy 383.883408 -119.224298) (xy 383.883408 -120.086374) (xy 401.939252 -120.086374) (xy 401.939252 -119.222774)
			(xy 401.939742 -119.192806) (xy 401.947565 -119.133384) (xy 401.963078 -119.075491) (xy 401.986014 -119.020118)
			(xy 402.015981 -118.968212) (xy 402.052468 -118.920662) (xy 402.094848 -118.878282) (xy 402.142398 -118.841795)
			(xy 402.194304 -118.811828) (xy 402.249677 -118.788892) (xy 402.30757 -118.773379) (xy 402.366992 -118.765556)
			(xy 402.426928 -118.765556) (xy 402.48635 -118.773379) (xy 402.544243 -118.788892) (xy 402.599616 -118.811828)
			(xy 402.651522 -118.841795) (xy 402.699072 -118.878282) (xy 402.741452 -118.920662) (xy 402.777939 -118.968212)
			(xy 402.807906 -119.020118) (xy 402.830842 -119.075491) (xy 402.846355 -119.133384) (xy 402.854178 -119.192806)
			(xy 402.854668 -119.222774) (xy 402.854668 -119.567198) (xy 414.899348 -119.567198) (xy 414.899348 -118.703598)
			(xy 414.899838 -118.673614) (xy 414.907666 -118.614158) (xy 414.923187 -118.556233) (xy 414.946136 -118.500829)
			(xy 414.97612 -118.448895) (xy 415.012626 -118.401319) (xy 415.055031 -118.358914) (xy 415.102607 -118.322408)
			(xy 415.154541 -118.292424) (xy 415.209945 -118.269475) (xy 415.26787 -118.253954) (xy 415.327326 -118.246126)
			(xy 415.387294 -118.246126) (xy 415.44675 -118.253954) (xy 415.504675 -118.269475) (xy 415.560079 -118.292424)
			(xy 415.612013 -118.322408) (xy 415.659589 -118.358914) (xy 415.701994 -118.401319) (xy 415.7385 -118.448895)
			(xy 415.768484 -118.500829) (xy 415.791433 -118.556233) (xy 415.806954 -118.614158) (xy 415.814782 -118.673614)
			(xy 415.815272 -118.703598) (xy 415.815272 -119.559324) (xy 429.3743 -119.559324) (xy 429.3743 -118.695724)
			(xy 429.37479 -118.66574) (xy 429.382618 -118.606284) (xy 429.398139 -118.548359) (xy 429.421088 -118.492955)
			(xy 429.451072 -118.441021) (xy 429.487578 -118.393445) (xy 429.529983 -118.35104) (xy 429.577559 -118.314534)
			(xy 429.629493 -118.28455) (xy 429.684897 -118.261601) (xy 429.742822 -118.24608) (xy 429.802278 -118.238252)
			(xy 429.862246 -118.238252) (xy 429.921702 -118.24608) (xy 429.979627 -118.261601) (xy 430.035031 -118.28455)
			(xy 430.086965 -118.314534) (xy 430.134541 -118.35104) (xy 430.176946 -118.393445) (xy 430.213452 -118.441021)
			(xy 430.243436 -118.492955) (xy 430.266385 -118.548359) (xy 430.281906 -118.606284) (xy 430.289734 -118.66574)
			(xy 430.290224 -118.695724) (xy 430.290224 -119.559324) (xy 430.289734 -119.589308) (xy 430.281906 -119.648764)
			(xy 430.266385 -119.706689) (xy 430.243436 -119.762093) (xy 430.213452 -119.814027) (xy 430.176946 -119.861603)
			(xy 430.134541 -119.904008) (xy 430.086965 -119.940514) (xy 430.035031 -119.970498) (xy 429.979627 -119.993447)
			(xy 429.921702 -120.008968) (xy 429.862246 -120.016796) (xy 429.802278 -120.016796) (xy 429.742822 -120.008968)
			(xy 429.684897 -119.993447) (xy 429.629493 -119.970498) (xy 429.577559 -119.940514) (xy 429.529983 -119.904008)
			(xy 429.487578 -119.861603) (xy 429.451072 -119.814027) (xy 429.421088 -119.762093) (xy 429.398139 -119.706689)
			(xy 429.382618 -119.648764) (xy 429.37479 -119.589308) (xy 429.3743 -119.559324) (xy 415.815272 -119.559324)
			(xy 415.815272 -119.567198) (xy 415.814782 -119.597182) (xy 415.806954 -119.656638) (xy 415.791433 -119.714563)
			(xy 415.768484 -119.769967) (xy 415.7385 -119.821901) (xy 415.701994 -119.869477) (xy 415.659589 -119.911882)
			(xy 415.612013 -119.948388) (xy 415.560079 -119.978372) (xy 415.504675 -120.001321) (xy 415.44675 -120.016842)
			(xy 415.387294 -120.02467) (xy 415.327326 -120.02467) (xy 415.26787 -120.016842) (xy 415.209945 -120.001321)
			(xy 415.154541 -119.978372) (xy 415.102607 -119.948388) (xy 415.055031 -119.911882) (xy 415.012626 -119.869477)
			(xy 414.97612 -119.821901) (xy 414.946136 -119.769967) (xy 414.923187 -119.714563) (xy 414.907666 -119.656638)
			(xy 414.899838 -119.597182) (xy 414.899348 -119.567198) (xy 402.854668 -119.567198) (xy 402.854668 -120.086374)
			(xy 402.854178 -120.116342) (xy 402.846355 -120.175764) (xy 402.830842 -120.233657) (xy 402.807906 -120.28903)
			(xy 402.777939 -120.340936) (xy 402.741452 -120.388486) (xy 402.699072 -120.430866) (xy 402.651522 -120.467353)
			(xy 402.599616 -120.49732) (xy 402.544243 -120.520256) (xy 402.48635 -120.535769) (xy 402.426928 -120.543592)
			(xy 402.366992 -120.543592) (xy 402.30757 -120.535769) (xy 402.249677 -120.520256) (xy 402.194304 -120.49732)
			(xy 402.142398 -120.467353) (xy 402.094848 -120.430866) (xy 402.052468 -120.388486) (xy 402.015981 -120.340936)
			(xy 401.986014 -120.28903) (xy 401.963078 -120.233657) (xy 401.947565 -120.175764) (xy 401.939742 -120.116342)
			(xy 401.939252 -120.086374) (xy 383.883408 -120.086374) (xy 383.883408 -120.087898) (xy 383.882918 -120.117866)
			(xy 383.875095 -120.177288) (xy 383.859582 -120.235181) (xy 383.836646 -120.290554) (xy 383.806679 -120.34246)
			(xy 383.770192 -120.39001) (xy 383.727812 -120.43239) (xy 383.680262 -120.468877) (xy 383.628356 -120.498844)
			(xy 383.572983 -120.52178) (xy 383.51509 -120.537293) (xy 383.455668 -120.545116) (xy 383.395732 -120.545116)
			(xy 383.33631 -120.537293) (xy 383.278417 -120.52178) (xy 383.223044 -120.498844) (xy 383.171138 -120.468877)
			(xy 383.123588 -120.43239) (xy 383.081208 -120.39001) (xy 383.044721 -120.34246) (xy 383.014754 -120.290554)
			(xy 382.991818 -120.235181) (xy 382.976305 -120.177288) (xy 382.968482 -120.117866) (xy 382.967992 -120.087898)
			(xy 316.568893 -120.087898) (xy 316.576928 -120.091226) (xy 316.628834 -120.121193) (xy 316.676384 -120.15768)
			(xy 316.718764 -120.20006) (xy 316.755251 -120.24761) (xy 316.785218 -120.299516) (xy 316.808154 -120.354889)
			(xy 316.823667 -120.412782) (xy 316.83149 -120.472204) (xy 316.83198 -120.502172) (xy 316.83198 -121.365772)
			(xy 316.83149 -121.39574) (xy 316.823667 -121.455162) (xy 316.808154 -121.513055) (xy 316.785218 -121.568428)
			(xy 316.755251 -121.620334) (xy 316.718764 -121.667884) (xy 316.676384 -121.710264) (xy 316.628834 -121.746751)
			(xy 316.576928 -121.776718) (xy 316.521555 -121.799654) (xy 316.463662 -121.815167) (xy 316.40424 -121.82299)
			(xy 316.344304 -121.82299) (xy 316.284882 -121.815167) (xy 316.226989 -121.799654) (xy 316.171616 -121.776718)
			(xy 316.11971 -121.746751) (xy 316.07216 -121.710264) (xy 316.02978 -121.667884) (xy 315.993293 -121.620334)
			(xy 315.963326 -121.568428) (xy 315.94039 -121.513055) (xy 315.924877 -121.455162) (xy 315.917054 -121.39574)
			(xy 315.916564 -121.365772) (xy 297.86072 -121.365772) (xy 297.86072 -121.367296) (xy 297.86023 -121.397264)
			(xy 297.852407 -121.456686) (xy 297.836894 -121.514579) (xy 297.813958 -121.569952) (xy 297.783991 -121.621858)
			(xy 297.747504 -121.669408) (xy 297.705124 -121.711788) (xy 297.657574 -121.748275) (xy 297.605668 -121.778242)
			(xy 297.550295 -121.801178) (xy 297.492402 -121.816691) (xy 297.43298 -121.824514) (xy 297.373044 -121.824514)
			(xy 297.313622 -121.816691) (xy 297.255729 -121.801178) (xy 297.200356 -121.778242) (xy 297.14845 -121.748275)
			(xy 297.1009 -121.711788) (xy 297.05852 -121.669408) (xy 297.022033 -121.621858) (xy 296.992066 -121.569952)
			(xy 296.96913 -121.514579) (xy 296.953617 -121.456686) (xy 296.945794 -121.397264) (xy 296.945304 -121.367296)
			(xy 284.900624 -121.367296) (xy 284.900624 -121.886472) (xy 284.900134 -121.916456) (xy 284.892306 -121.975912)
			(xy 284.876785 -122.033837) (xy 284.853836 -122.089241) (xy 284.823852 -122.141175) (xy 284.787346 -122.188751)
			(xy 284.744941 -122.231156) (xy 284.697365 -122.267662) (xy 284.645431 -122.297646) (xy 284.590027 -122.320595)
			(xy 284.532102 -122.336116) (xy 284.472646 -122.343944) (xy 284.412678 -122.343944) (xy 284.353222 -122.336116)
			(xy 284.295297 -122.320595) (xy 284.239893 -122.297646) (xy 284.187959 -122.267662) (xy 284.140383 -122.231156)
			(xy 284.097978 -122.188751) (xy 284.061472 -122.141175) (xy 284.031488 -122.089241) (xy 284.008539 -122.033837)
			(xy 283.993018 -121.975912) (xy 283.98519 -121.916456) (xy 283.9847 -121.886472) (xy 270.425672 -121.886472)
			(xy 270.425672 -121.894346) (xy 270.425182 -121.92433) (xy 270.417354 -121.983786) (xy 270.401833 -122.041711)
			(xy 270.378884 -122.097115) (xy 270.3489 -122.149049) (xy 270.312394 -122.196625) (xy 270.269989 -122.23903)
			(xy 270.222413 -122.275536) (xy 270.170479 -122.30552) (xy 270.115075 -122.328469) (xy 270.05715 -122.34399)
			(xy 269.997694 -122.351818) (xy 269.937726 -122.351818) (xy 269.87827 -122.34399) (xy 269.820345 -122.328469)
			(xy 269.764941 -122.30552) (xy 269.713007 -122.275536) (xy 269.665431 -122.23903) (xy 269.623026 -122.196625)
			(xy 269.58652 -122.149049) (xy 269.556536 -122.097115) (xy 269.533587 -122.041711) (xy 269.518066 -121.983786)
			(xy 269.510238 -121.92433) (xy 269.509748 -121.894346) (xy 197.851649 -121.894346) (xy 197.886882 -121.914687)
			(xy 197.934432 -121.951174) (xy 197.976812 -121.993554) (xy 198.013299 -122.041104) (xy 198.043266 -122.09301)
			(xy 198.066202 -122.148383) (xy 198.081715 -122.206276) (xy 198.089538 -122.265698) (xy 198.090028 -122.295666)
			(xy 198.090028 -123.159266) (xy 198.089538 -123.189234) (xy 198.081715 -123.248656) (xy 198.066202 -123.306549)
			(xy 198.043266 -123.361922) (xy 198.013299 -123.413828) (xy 197.976812 -123.461378) (xy 197.934432 -123.503758)
			(xy 197.886882 -123.540245) (xy 197.834976 -123.570212) (xy 197.779603 -123.593148) (xy 197.72171 -123.608661)
			(xy 197.662288 -123.616484) (xy 197.602352 -123.616484) (xy 197.54293 -123.608661) (xy 197.485037 -123.593148)
			(xy 197.429664 -123.570212) (xy 197.377758 -123.540245) (xy 197.330208 -123.503758) (xy 197.287828 -123.461378)
			(xy 197.251341 -123.413828) (xy 197.221374 -123.361922) (xy 197.198438 -123.306549) (xy 197.182925 -123.248656)
			(xy 197.175102 -123.189234) (xy 197.174612 -123.159266) (xy 183.615076 -123.159266) (xy 183.615076 -123.16714)
			(xy 183.614586 -123.197108) (xy 183.606763 -123.25653) (xy 183.59125 -123.314423) (xy 183.568314 -123.369796)
			(xy 183.538347 -123.421702) (xy 183.50186 -123.469252) (xy 183.45948 -123.511632) (xy 183.41193 -123.548119)
			(xy 183.360024 -123.578086) (xy 183.304651 -123.601022) (xy 183.246758 -123.616535) (xy 183.187336 -123.624358)
			(xy 183.1274 -123.624358) (xy 183.067978 -123.616535) (xy 183.010085 -123.601022) (xy 182.954712 -123.578086)
			(xy 182.902806 -123.548119) (xy 182.855256 -123.511632) (xy 182.812876 -123.469252) (xy 182.776389 -123.421702)
			(xy 182.746422 -123.369796) (xy 182.723486 -123.314423) (xy 182.707973 -123.25653) (xy 182.70015 -123.197108)
			(xy 182.69966 -123.16714) (xy 170.65498 -123.16714) (xy 170.65498 -123.686316) (xy 170.65449 -123.7163)
			(xy 170.646662 -123.775756) (xy 170.631141 -123.833681) (xy 170.608192 -123.889085) (xy 170.578208 -123.941019)
			(xy 170.541702 -123.988595) (xy 170.499297 -124.031) (xy 170.451721 -124.067506) (xy 170.399787 -124.09749)
			(xy 170.344383 -124.120439) (xy 170.286458 -124.13596) (xy 170.227002 -124.143788) (xy 170.167034 -124.143788)
			(xy 170.107578 -124.13596) (xy 170.049653 -124.120439) (xy 169.994249 -124.09749) (xy 169.942315 -124.067506)
			(xy 169.894739 -124.031) (xy 169.852334 -123.988595) (xy 169.815828 -123.941019) (xy 169.785844 -123.889085)
			(xy 169.762895 -123.833681) (xy 169.747374 -123.775756) (xy 169.739546 -123.7163) (xy 169.739056 -123.686316)
			(xy 151.68372 -123.686316) (xy 151.68372 -123.68784) (xy 151.68323 -123.717824) (xy 151.675402 -123.77728)
			(xy 151.659881 -123.835205) (xy 151.636932 -123.890609) (xy 151.606948 -123.942543) (xy 151.570442 -123.990119)
			(xy 151.528037 -124.032524) (xy 151.480461 -124.06903) (xy 151.428527 -124.099014) (xy 151.373123 -124.121963)
			(xy 151.315198 -124.137484) (xy 151.255742 -124.145312) (xy 151.195774 -124.145312) (xy 151.136318 -124.137484)
			(xy 151.078393 -124.121963) (xy 151.022989 -124.099014) (xy 150.971055 -124.06903) (xy 150.923479 -124.032524)
			(xy 150.881074 -123.990119) (xy 150.844568 -123.942543) (xy 150.814584 -123.890609) (xy 150.791635 -123.835205)
			(xy 150.776114 -123.77728) (xy 150.768286 -123.717824) (xy 150.767796 -123.68784) (xy 84.369615 -123.68784)
			(xy 84.377099 -123.69094) (xy 84.429033 -123.720924) (xy 84.476609 -123.75743) (xy 84.519014 -123.799835)
			(xy 84.55552 -123.847411) (xy 84.585504 -123.899345) (xy 84.608453 -123.954749) (xy 84.623974 -124.012674)
			(xy 84.631802 -124.07213) (xy 84.632292 -124.102114) (xy 84.632292 -124.965714) (xy 84.631802 -124.995698)
			(xy 84.623974 -125.055154) (xy 84.608453 -125.113079) (xy 84.585504 -125.168483) (xy 84.55552 -125.220417)
			(xy 84.519014 -125.267993) (xy 84.476609 -125.310398) (xy 84.429033 -125.346904) (xy 84.377099 -125.376888)
			(xy 84.321695 -125.399837) (xy 84.26377 -125.415358) (xy 84.204314 -125.423186) (xy 84.144346 -125.423186)
			(xy 84.08489 -125.415358) (xy 84.026965 -125.399837) (xy 83.971561 -125.376888) (xy 83.919627 -125.346904)
			(xy 83.872051 -125.310398) (xy 83.829646 -125.267993) (xy 83.79314 -125.220417) (xy 83.763156 -125.168483)
			(xy 83.740207 -125.113079) (xy 83.724686 -125.055154) (xy 83.716858 -124.995698) (xy 83.716368 -124.965714)
			(xy 65.661032 -124.965714) (xy 65.661032 -124.967238) (xy 65.660542 -124.997222) (xy 65.652714 -125.056678)
			(xy 65.637193 -125.114603) (xy 65.614244 -125.170007) (xy 65.58426 -125.221941) (xy 65.547754 -125.269517)
			(xy 65.505349 -125.311922) (xy 65.457773 -125.348428) (xy 65.405839 -125.378412) (xy 65.350435 -125.401361)
			(xy 65.29251 -125.416882) (xy 65.233054 -125.42471) (xy 65.173086 -125.42471) (xy 65.11363 -125.416882)
			(xy 65.055705 -125.401361) (xy 65.000301 -125.378412) (xy 64.948367 -125.348428) (xy 64.900791 -125.311922)
			(xy 64.858386 -125.269517) (xy 64.82188 -125.221941) (xy 64.791896 -125.170007) (xy 64.768947 -125.114603)
			(xy 64.753426 -125.056678) (xy 64.745598 -124.997222) (xy 64.745108 -124.967238) (xy 52.700428 -124.967238)
			(xy 52.700428 -125.486414) (xy 52.700295 -125.494542) (xy 153.409904 -125.494542) (xy 153.409904 -124.630942)
			(xy 153.410394 -124.600958) (xy 153.418222 -124.541502) (xy 153.433743 -124.483577) (xy 153.456692 -124.428173)
			(xy 153.486676 -124.376239) (xy 153.523182 -124.328663) (xy 153.565587 -124.286258) (xy 153.613163 -124.249752)
			(xy 153.665097 -124.219768) (xy 153.720501 -124.196819) (xy 153.778426 -124.181298) (xy 153.837882 -124.17347)
			(xy 153.89785 -124.17347) (xy 153.957306 -124.181298) (xy 154.015231 -124.196819) (xy 154.070635 -124.219768)
			(xy 154.122569 -124.249752) (xy 154.170145 -124.286258) (xy 154.21255 -124.328663) (xy 154.249056 -124.376239)
			(xy 154.27904 -124.428173) (xy 154.301989 -124.483577) (xy 154.31751 -124.541502) (xy 154.325338 -124.600958)
			(xy 154.325828 -124.630942) (xy 154.325828 -125.486414) (xy 167.884856 -125.486414) (xy 167.884856 -124.622814)
			(xy 167.885346 -124.59283) (xy 167.893174 -124.533374) (xy 167.908695 -124.475449) (xy 167.931644 -124.420045)
			(xy 167.961628 -124.368111) (xy 167.998134 -124.320535) (xy 168.040539 -124.27813) (xy 168.088115 -124.241624)
			(xy 168.140049 -124.21164) (xy 168.195453 -124.188691) (xy 168.253378 -124.17317) (xy 168.312834 -124.165342)
			(xy 168.372802 -124.165342) (xy 168.432258 -124.17317) (xy 168.490183 -124.188691) (xy 168.545587 -124.21164)
			(xy 168.597521 -124.241624) (xy 168.645097 -124.27813) (xy 168.687502 -124.320535) (xy 168.724008 -124.368111)
			(xy 168.753992 -124.420045) (xy 168.776941 -124.475449) (xy 168.792462 -124.533374) (xy 168.80029 -124.59283)
			(xy 168.80078 -124.622814) (xy 168.80078 -124.967238) (xy 180.84546 -124.967238) (xy 180.84546 -124.103638)
			(xy 180.84595 -124.07367) (xy 180.853773 -124.014248) (xy 180.869286 -123.956355) (xy 180.892222 -123.900982)
			(xy 180.922189 -123.849076) (xy 180.958676 -123.801526) (xy 181.001056 -123.759146) (xy 181.048606 -123.722659)
			(xy 181.100512 -123.692692) (xy 181.155885 -123.669756) (xy 181.213778 -123.654243) (xy 181.2732 -123.64642)
			(xy 181.333136 -123.64642) (xy 181.392558 -123.654243) (xy 181.450451 -123.669756) (xy 181.505824 -123.692692)
			(xy 181.55773 -123.722659) (xy 181.60528 -123.759146) (xy 181.64766 -123.801526) (xy 181.684147 -123.849076)
			(xy 181.714114 -123.900982) (xy 181.73705 -123.956355) (xy 181.752563 -124.014248) (xy 181.760386 -124.07367)
			(xy 181.760876 -124.103638) (xy 181.760876 -124.965714) (xy 199.81672 -124.965714) (xy 199.81672 -124.102114)
			(xy 199.81721 -124.072146) (xy 199.825033 -124.012724) (xy 199.840546 -123.954831) (xy 199.863482 -123.899458)
			(xy 199.893449 -123.847552) (xy 199.929936 -123.800002) (xy 199.972316 -123.757622) (xy 200.019866 -123.721135)
			(xy 200.071772 -123.691168) (xy 200.127145 -123.668232) (xy 200.185038 -123.652719) (xy 200.24446 -123.644896)
			(xy 200.304396 -123.644896) (xy 200.363818 -123.652719) (xy 200.421711 -123.668232) (xy 200.469049 -123.68784)
			(xy 266.86764 -123.68784) (xy 266.86764 -122.82424) (xy 266.86813 -122.794256) (xy 266.875958 -122.7348)
			(xy 266.891479 -122.676875) (xy 266.914428 -122.621471) (xy 266.944412 -122.569537) (xy 266.980918 -122.521961)
			(xy 267.023323 -122.479556) (xy 267.070899 -122.44305) (xy 267.122833 -122.413066) (xy 267.178237 -122.390117)
			(xy 267.236162 -122.374596) (xy 267.295618 -122.366768) (xy 267.355586 -122.366768) (xy 267.415042 -122.374596)
			(xy 267.472967 -122.390117) (xy 267.528371 -122.413066) (xy 267.580305 -122.44305) (xy 267.627881 -122.479556)
			(xy 267.670286 -122.521961) (xy 267.706792 -122.569537) (xy 267.736776 -122.621471) (xy 267.759725 -122.676875)
			(xy 267.775246 -122.7348) (xy 267.783074 -122.794256) (xy 267.783564 -122.82424) (xy 267.783564 -123.686316)
			(xy 285.8389 -123.686316) (xy 285.8389 -122.822716) (xy 285.83939 -122.792732) (xy 285.847218 -122.733276)
			(xy 285.862739 -122.675351) (xy 285.885688 -122.619947) (xy 285.915672 -122.568013) (xy 285.952178 -122.520437)
			(xy 285.994583 -122.478032) (xy 286.042159 -122.441526) (xy 286.094093 -122.411542) (xy 286.149497 -122.388593)
			(xy 286.207422 -122.373072) (xy 286.266878 -122.365244) (xy 286.326846 -122.365244) (xy 286.386302 -122.373072)
			(xy 286.444227 -122.388593) (xy 286.499631 -122.411542) (xy 286.551565 -122.441526) (xy 286.599141 -122.478032)
			(xy 286.641546 -122.520437) (xy 286.678052 -122.568013) (xy 286.708036 -122.619947) (xy 286.730985 -122.675351)
			(xy 286.746506 -122.733276) (xy 286.754334 -122.792732) (xy 286.754824 -122.822716) (xy 286.754824 -123.16714)
			(xy 298.799504 -123.16714) (xy 298.799504 -122.30354) (xy 298.799994 -122.273572) (xy 298.807817 -122.21415)
			(xy 298.82333 -122.156257) (xy 298.846266 -122.100884) (xy 298.876233 -122.048978) (xy 298.91272 -122.001428)
			(xy 298.9551 -121.959048) (xy 299.00265 -121.922561) (xy 299.054556 -121.892594) (xy 299.109929 -121.869658)
			(xy 299.167822 -121.854145) (xy 299.227244 -121.846322) (xy 299.28718 -121.846322) (xy 299.346602 -121.854145)
			(xy 299.404495 -121.869658) (xy 299.459868 -121.892594) (xy 299.511774 -121.922561) (xy 299.559324 -121.959048)
			(xy 299.601704 -122.001428) (xy 299.638191 -122.048978) (xy 299.668158 -122.100884) (xy 299.691094 -122.156257)
			(xy 299.706607 -122.21415) (xy 299.71443 -122.273572) (xy 299.71492 -122.30354) (xy 299.71492 -123.159266)
			(xy 313.274456 -123.159266) (xy 313.274456 -122.295666) (xy 313.274946 -122.265698) (xy 313.282769 -122.206276)
			(xy 313.298282 -122.148383) (xy 313.321218 -122.09301) (xy 313.351185 -122.041104) (xy 313.387672 -121.993554)
			(xy 313.430052 -121.951174) (xy 313.477602 -121.914687) (xy 313.529508 -121.88472) (xy 313.584881 -121.861784)
			(xy 313.642774 -121.846271) (xy 313.702196 -121.838448) (xy 313.762132 -121.838448) (xy 313.821554 -121.846271)
			(xy 313.879447 -121.861784) (xy 313.93482 -121.88472) (xy 313.951493 -121.894346) (xy 385.6101 -121.894346)
			(xy 385.6101 -121.030746) (xy 385.61059 -121.000778) (xy 385.618413 -120.941356) (xy 385.633926 -120.883463)
			(xy 385.656862 -120.82809) (xy 385.686829 -120.776184) (xy 385.723316 -120.728634) (xy 385.765696 -120.686254)
			(xy 385.813246 -120.649767) (xy 385.865152 -120.6198) (xy 385.920525 -120.596864) (xy 385.978418 -120.581351)
			(xy 386.03784 -120.573528) (xy 386.097776 -120.573528) (xy 386.157198 -120.581351) (xy 386.215091 -120.596864)
			(xy 386.270464 -120.6198) (xy 386.32237 -120.649767) (xy 386.36992 -120.686254) (xy 386.4123 -120.728634)
			(xy 386.448787 -120.776184) (xy 386.478754 -120.82809) (xy 386.50169 -120.883463) (xy 386.517203 -120.941356)
			(xy 386.525026 -121.000778) (xy 386.525516 -121.030746) (xy 386.525516 -121.886472) (xy 400.085052 -121.886472)
			(xy 400.085052 -121.022872) (xy 400.085542 -120.992904) (xy 400.093365 -120.933482) (xy 400.108878 -120.875589)
			(xy 400.131814 -120.820216) (xy 400.161781 -120.76831) (xy 400.198268 -120.72076) (xy 400.240648 -120.67838)
			(xy 400.288198 -120.641893) (xy 400.340104 -120.611926) (xy 400.395477 -120.58899) (xy 400.45337 -120.573477)
			(xy 400.512792 -120.565654) (xy 400.572728 -120.565654) (xy 400.63215 -120.573477) (xy 400.690043 -120.58899)
			(xy 400.745416 -120.611926) (xy 400.797322 -120.641893) (xy 400.844872 -120.67838) (xy 400.887252 -120.72076)
			(xy 400.923739 -120.76831) (xy 400.953706 -120.820216) (xy 400.976642 -120.875589) (xy 400.992155 -120.933482)
			(xy 400.999978 -120.992904) (xy 401.000468 -121.022872) (xy 401.000468 -121.367296) (xy 413.045148 -121.367296)
			(xy 413.045148 -120.503696) (xy 413.045638 -120.473712) (xy 413.053466 -120.414256) (xy 413.068987 -120.356331)
			(xy 413.091936 -120.300927) (xy 413.12192 -120.248993) (xy 413.158426 -120.201417) (xy 413.200831 -120.159012)
			(xy 413.248407 -120.122506) (xy 413.300341 -120.092522) (xy 413.355745 -120.069573) (xy 413.41367 -120.054052)
			(xy 413.473126 -120.046224) (xy 413.533094 -120.046224) (xy 413.59255 -120.054052) (xy 413.650475 -120.069573)
			(xy 413.705879 -120.092522) (xy 413.757813 -120.122506) (xy 413.805389 -120.159012) (xy 413.847794 -120.201417)
			(xy 413.8843 -120.248993) (xy 413.914284 -120.300927) (xy 413.937233 -120.356331) (xy 413.952754 -120.414256)
			(xy 413.960582 -120.473712) (xy 413.961072 -120.503696) (xy 413.961072 -121.365772) (xy 432.016408 -121.365772)
			(xy 432.016408 -120.502172) (xy 432.016898 -120.472188) (xy 432.024726 -120.412732) (xy 432.040247 -120.354807)
			(xy 432.063196 -120.299403) (xy 432.09318 -120.247469) (xy 432.129686 -120.199893) (xy 432.172091 -120.157488)
			(xy 432.219667 -120.120982) (xy 432.271601 -120.090998) (xy 432.327005 -120.068049) (xy 432.38493 -120.052528)
			(xy 432.444386 -120.0447) (xy 432.504354 -120.0447) (xy 432.56381 -120.052528) (xy 432.621735 -120.068049)
			(xy 432.677139 -120.090998) (xy 432.729073 -120.120982) (xy 432.776649 -120.157488) (xy 432.819054 -120.199893)
			(xy 432.85556 -120.247469) (xy 432.885544 -120.299403) (xy 432.908493 -120.354807) (xy 432.924014 -120.412732)
			(xy 432.931842 -120.472188) (xy 432.932332 -120.502172) (xy 432.932332 -121.365772) (xy 432.931842 -121.395756)
			(xy 432.924014 -121.455212) (xy 432.908493 -121.513137) (xy 432.885544 -121.568541) (xy 432.85556 -121.620475)
			(xy 432.819054 -121.668051) (xy 432.776649 -121.710456) (xy 432.729073 -121.746962) (xy 432.677139 -121.776946)
			(xy 432.621735 -121.799895) (xy 432.56381 -121.815416) (xy 432.504354 -121.823244) (xy 432.444386 -121.823244)
			(xy 432.38493 -121.815416) (xy 432.327005 -121.799895) (xy 432.271601 -121.776946) (xy 432.219667 -121.746962)
			(xy 432.172091 -121.710456) (xy 432.129686 -121.668051) (xy 432.09318 -121.620475) (xy 432.063196 -121.568541)
			(xy 432.040247 -121.513137) (xy 432.024726 -121.455212) (xy 432.016898 -121.395756) (xy 432.016408 -121.365772)
			(xy 413.961072 -121.365772) (xy 413.961072 -121.367296) (xy 413.960582 -121.39728) (xy 413.952754 -121.456736)
			(xy 413.937233 -121.514661) (xy 413.914284 -121.570065) (xy 413.8843 -121.621999) (xy 413.847794 -121.669575)
			(xy 413.805389 -121.71198) (xy 413.757813 -121.748486) (xy 413.705879 -121.77847) (xy 413.650475 -121.801419)
			(xy 413.59255 -121.81694) (xy 413.533094 -121.824768) (xy 413.473126 -121.824768) (xy 413.41367 -121.81694)
			(xy 413.355745 -121.801419) (xy 413.300341 -121.77847) (xy 413.248407 -121.748486) (xy 413.200831 -121.71198)
			(xy 413.158426 -121.669575) (xy 413.12192 -121.621999) (xy 413.091936 -121.570065) (xy 413.068987 -121.514661)
			(xy 413.053466 -121.456736) (xy 413.045638 -121.39728) (xy 413.045148 -121.367296) (xy 401.000468 -121.367296)
			(xy 401.000468 -121.886472) (xy 400.999978 -121.91644) (xy 400.992155 -121.975862) (xy 400.976642 -122.033755)
			(xy 400.953706 -122.089128) (xy 400.923739 -122.141034) (xy 400.887252 -122.188584) (xy 400.844872 -122.230964)
			(xy 400.797322 -122.267451) (xy 400.745416 -122.297418) (xy 400.690043 -122.320354) (xy 400.63215 -122.335867)
			(xy 400.572728 -122.34369) (xy 400.512792 -122.34369) (xy 400.45337 -122.335867) (xy 400.395477 -122.320354)
			(xy 400.340104 -122.297418) (xy 400.288198 -122.267451) (xy 400.240648 -122.230964) (xy 400.198268 -122.188584)
			(xy 400.161781 -122.141034) (xy 400.131814 -122.089128) (xy 400.108878 -122.033755) (xy 400.093365 -121.975862)
			(xy 400.085542 -121.91644) (xy 400.085052 -121.886472) (xy 386.525516 -121.886472) (xy 386.525516 -121.894346)
			(xy 386.525026 -121.924314) (xy 386.517203 -121.983736) (xy 386.50169 -122.041629) (xy 386.478754 -122.097002)
			(xy 386.448787 -122.148908) (xy 386.4123 -122.196458) (xy 386.36992 -122.238838) (xy 386.32237 -122.275325)
			(xy 386.270464 -122.305292) (xy 386.215091 -122.328228) (xy 386.157198 -122.343741) (xy 386.097776 -122.351564)
			(xy 386.03784 -122.351564) (xy 385.978418 -122.343741) (xy 385.920525 -122.328228) (xy 385.865152 -122.305292)
			(xy 385.813246 -122.275325) (xy 385.765696 -122.238838) (xy 385.723316 -122.196458) (xy 385.686829 -122.148908)
			(xy 385.656862 -122.097002) (xy 385.633926 -122.041629) (xy 385.618413 -121.983736) (xy 385.61059 -121.924314)
			(xy 385.6101 -121.894346) (xy 313.951493 -121.894346) (xy 313.986726 -121.914687) (xy 314.034276 -121.951174)
			(xy 314.076656 -121.993554) (xy 314.113143 -122.041104) (xy 314.14311 -122.09301) (xy 314.166046 -122.148383)
			(xy 314.181559 -122.206276) (xy 314.189382 -122.265698) (xy 314.189872 -122.295666) (xy 314.189872 -123.159266)
			(xy 314.189382 -123.189234) (xy 314.181559 -123.248656) (xy 314.166046 -123.306549) (xy 314.14311 -123.361922)
			(xy 314.113143 -123.413828) (xy 314.076656 -123.461378) (xy 314.034276 -123.503758) (xy 313.986726 -123.540245)
			(xy 313.93482 -123.570212) (xy 313.879447 -123.593148) (xy 313.821554 -123.608661) (xy 313.762132 -123.616484)
			(xy 313.702196 -123.616484) (xy 313.642774 -123.608661) (xy 313.584881 -123.593148) (xy 313.529508 -123.570212)
			(xy 313.477602 -123.540245) (xy 313.430052 -123.503758) (xy 313.387672 -123.461378) (xy 313.351185 -123.413828)
			(xy 313.321218 -123.361922) (xy 313.298282 -123.306549) (xy 313.282769 -123.248656) (xy 313.274946 -123.189234)
			(xy 313.274456 -123.159266) (xy 299.71492 -123.159266) (xy 299.71492 -123.16714) (xy 299.71443 -123.197108)
			(xy 299.706607 -123.25653) (xy 299.691094 -123.314423) (xy 299.668158 -123.369796) (xy 299.638191 -123.421702)
			(xy 299.601704 -123.469252) (xy 299.559324 -123.511632) (xy 299.511774 -123.548119) (xy 299.459868 -123.578086)
			(xy 299.404495 -123.601022) (xy 299.346602 -123.616535) (xy 299.28718 -123.624358) (xy 299.227244 -123.624358)
			(xy 299.167822 -123.616535) (xy 299.109929 -123.601022) (xy 299.054556 -123.578086) (xy 299.00265 -123.548119)
			(xy 298.9551 -123.511632) (xy 298.91272 -123.469252) (xy 298.876233 -123.421702) (xy 298.846266 -123.369796)
			(xy 298.82333 -123.314423) (xy 298.807817 -123.25653) (xy 298.799994 -123.197108) (xy 298.799504 -123.16714)
			(xy 286.754824 -123.16714) (xy 286.754824 -123.686316) (xy 286.754334 -123.7163) (xy 286.746506 -123.775756)
			(xy 286.730985 -123.833681) (xy 286.708036 -123.889085) (xy 286.678052 -123.941019) (xy 286.641546 -123.988595)
			(xy 286.599141 -124.031) (xy 286.551565 -124.067506) (xy 286.499631 -124.09749) (xy 286.444227 -124.120439)
			(xy 286.386302 -124.13596) (xy 286.326846 -124.143788) (xy 286.266878 -124.143788) (xy 286.207422 -124.13596)
			(xy 286.149497 -124.120439) (xy 286.094093 -124.09749) (xy 286.042159 -124.067506) (xy 285.994583 -124.031)
			(xy 285.952178 -123.988595) (xy 285.915672 -123.941019) (xy 285.885688 -123.889085) (xy 285.862739 -123.833681)
			(xy 285.847218 -123.775756) (xy 285.83939 -123.7163) (xy 285.8389 -123.686316) (xy 267.783564 -123.686316)
			(xy 267.783564 -123.68784) (xy 267.783074 -123.717824) (xy 267.775246 -123.77728) (xy 267.759725 -123.835205)
			(xy 267.736776 -123.890609) (xy 267.706792 -123.942543) (xy 267.670286 -123.990119) (xy 267.627881 -124.032524)
			(xy 267.580305 -124.06903) (xy 267.528371 -124.099014) (xy 267.472967 -124.121963) (xy 267.415042 -124.137484)
			(xy 267.355586 -124.145312) (xy 267.295618 -124.145312) (xy 267.236162 -124.137484) (xy 267.178237 -124.121963)
			(xy 267.122833 -124.099014) (xy 267.070899 -124.06903) (xy 267.023323 -124.032524) (xy 266.980918 -123.990119)
			(xy 266.944412 -123.942543) (xy 266.914428 -123.890609) (xy 266.891479 -123.835205) (xy 266.875958 -123.77728)
			(xy 266.86813 -123.717824) (xy 266.86764 -123.68784) (xy 200.469049 -123.68784) (xy 200.477084 -123.691168)
			(xy 200.52899 -123.721135) (xy 200.57654 -123.757622) (xy 200.61892 -123.800002) (xy 200.655407 -123.847552)
			(xy 200.685374 -123.899458) (xy 200.70831 -123.954831) (xy 200.723823 -124.012724) (xy 200.731646 -124.072146)
			(xy 200.732136 -124.102114) (xy 200.732136 -124.965714) (xy 200.731646 -124.995682) (xy 200.723823 -125.055104)
			(xy 200.70831 -125.112997) (xy 200.685374 -125.16837) (xy 200.655407 -125.220276) (xy 200.61892 -125.267826)
			(xy 200.57654 -125.310206) (xy 200.52899 -125.346693) (xy 200.477084 -125.37666) (xy 200.421711 -125.399596)
			(xy 200.363818 -125.415109) (xy 200.304396 -125.422932) (xy 200.24446 -125.422932) (xy 200.185038 -125.415109)
			(xy 200.127145 -125.399596) (xy 200.071772 -125.37666) (xy 200.019866 -125.346693) (xy 199.972316 -125.310206)
			(xy 199.929936 -125.267826) (xy 199.893449 -125.220276) (xy 199.863482 -125.16837) (xy 199.840546 -125.112997)
			(xy 199.825033 -125.055104) (xy 199.81721 -124.995682) (xy 199.81672 -124.965714) (xy 181.760876 -124.965714)
			(xy 181.760876 -124.967238) (xy 181.760386 -124.997206) (xy 181.752563 -125.056628) (xy 181.73705 -125.114521)
			(xy 181.714114 -125.169894) (xy 181.684147 -125.2218) (xy 181.64766 -125.26935) (xy 181.60528 -125.31173)
			(xy 181.55773 -125.348217) (xy 181.505824 -125.378184) (xy 181.450451 -125.40112) (xy 181.392558 -125.416633)
			(xy 181.333136 -125.424456) (xy 181.2732 -125.424456) (xy 181.213778 -125.416633) (xy 181.155885 -125.40112)
			(xy 181.100512 -125.378184) (xy 181.048606 -125.348217) (xy 181.001056 -125.31173) (xy 180.958676 -125.26935)
			(xy 180.922189 -125.2218) (xy 180.892222 -125.169894) (xy 180.869286 -125.114521) (xy 180.853773 -125.056628)
			(xy 180.84595 -124.997206) (xy 180.84546 -124.967238) (xy 168.80078 -124.967238) (xy 168.80078 -125.486414)
			(xy 168.800647 -125.494542) (xy 269.509748 -125.494542) (xy 269.509748 -124.630942) (xy 269.510238 -124.600958)
			(xy 269.518066 -124.541502) (xy 269.533587 -124.483577) (xy 269.556536 -124.428173) (xy 269.58652 -124.376239)
			(xy 269.623026 -124.328663) (xy 269.665431 -124.286258) (xy 269.713007 -124.249752) (xy 269.764941 -124.219768)
			(xy 269.820345 -124.196819) (xy 269.87827 -124.181298) (xy 269.937726 -124.17347) (xy 269.997694 -124.17347)
			(xy 270.05715 -124.181298) (xy 270.115075 -124.196819) (xy 270.170479 -124.219768) (xy 270.222413 -124.249752)
			(xy 270.269989 -124.286258) (xy 270.312394 -124.328663) (xy 270.3489 -124.376239) (xy 270.378884 -124.428173)
			(xy 270.401833 -124.483577) (xy 270.417354 -124.541502) (xy 270.425182 -124.600958) (xy 270.425672 -124.630942)
			(xy 270.425672 -125.486414) (xy 283.9847 -125.486414) (xy 283.9847 -124.622814) (xy 283.98519 -124.59283)
			(xy 283.993018 -124.533374) (xy 284.008539 -124.475449) (xy 284.031488 -124.420045) (xy 284.061472 -124.368111)
			(xy 284.097978 -124.320535) (xy 284.140383 -124.27813) (xy 284.187959 -124.241624) (xy 284.239893 -124.21164)
			(xy 284.295297 -124.188691) (xy 284.353222 -124.17317) (xy 284.412678 -124.165342) (xy 284.472646 -124.165342)
			(xy 284.532102 -124.17317) (xy 284.590027 -124.188691) (xy 284.645431 -124.21164) (xy 284.697365 -124.241624)
			(xy 284.744941 -124.27813) (xy 284.787346 -124.320535) (xy 284.823852 -124.368111) (xy 284.853836 -124.420045)
			(xy 284.876785 -124.475449) (xy 284.892306 -124.533374) (xy 284.900134 -124.59283) (xy 284.900624 -124.622814)
			(xy 284.900624 -124.967238) (xy 296.945304 -124.967238) (xy 296.945304 -124.103638) (xy 296.945794 -124.07367)
			(xy 296.953617 -124.014248) (xy 296.96913 -123.956355) (xy 296.992066 -123.900982) (xy 297.022033 -123.849076)
			(xy 297.05852 -123.801526) (xy 297.1009 -123.759146) (xy 297.14845 -123.722659) (xy 297.200356 -123.692692)
			(xy 297.255729 -123.669756) (xy 297.313622 -123.654243) (xy 297.373044 -123.64642) (xy 297.43298 -123.64642)
			(xy 297.492402 -123.654243) (xy 297.550295 -123.669756) (xy 297.605668 -123.692692) (xy 297.657574 -123.722659)
			(xy 297.705124 -123.759146) (xy 297.747504 -123.801526) (xy 297.783991 -123.849076) (xy 297.813958 -123.900982)
			(xy 297.836894 -123.956355) (xy 297.852407 -124.014248) (xy 297.86023 -124.07367) (xy 297.86072 -124.103638)
			(xy 297.86072 -124.965714) (xy 315.916564 -124.965714) (xy 315.916564 -124.102114) (xy 315.917054 -124.072146)
			(xy 315.924877 -124.012724) (xy 315.94039 -123.954831) (xy 315.963326 -123.899458) (xy 315.993293 -123.847552)
			(xy 316.02978 -123.800002) (xy 316.07216 -123.757622) (xy 316.11971 -123.721135) (xy 316.171616 -123.691168)
			(xy 316.226989 -123.668232) (xy 316.284882 -123.652719) (xy 316.344304 -123.644896) (xy 316.40424 -123.644896)
			(xy 316.463662 -123.652719) (xy 316.521555 -123.668232) (xy 316.568893 -123.68784) (xy 382.967992 -123.68784)
			(xy 382.967992 -122.82424) (xy 382.968482 -122.794272) (xy 382.976305 -122.73485) (xy 382.991818 -122.676957)
			(xy 383.014754 -122.621584) (xy 383.044721 -122.569678) (xy 383.081208 -122.522128) (xy 383.123588 -122.479748)
			(xy 383.171138 -122.443261) (xy 383.223044 -122.413294) (xy 383.278417 -122.390358) (xy 383.33631 -122.374845)
			(xy 383.395732 -122.367022) (xy 383.455668 -122.367022) (xy 383.51509 -122.374845) (xy 383.572983 -122.390358)
			(xy 383.628356 -122.413294) (xy 383.680262 -122.443261) (xy 383.727812 -122.479748) (xy 383.770192 -122.522128)
			(xy 383.806679 -122.569678) (xy 383.836646 -122.621584) (xy 383.859582 -122.676957) (xy 383.875095 -122.73485)
			(xy 383.882918 -122.794272) (xy 383.883408 -122.82424) (xy 383.883408 -123.686316) (xy 401.939252 -123.686316)
			(xy 401.939252 -122.822716) (xy 401.939742 -122.792748) (xy 401.947565 -122.733326) (xy 401.963078 -122.675433)
			(xy 401.986014 -122.62006) (xy 402.015981 -122.568154) (xy 402.052468 -122.520604) (xy 402.094848 -122.478224)
			(xy 402.142398 -122.441737) (xy 402.194304 -122.41177) (xy 402.249677 -122.388834) (xy 402.30757 -122.373321)
			(xy 402.366992 -122.365498) (xy 402.426928 -122.365498) (xy 402.48635 -122.373321) (xy 402.544243 -122.388834)
			(xy 402.599616 -122.41177) (xy 402.651522 -122.441737) (xy 402.699072 -122.478224) (xy 402.741452 -122.520604)
			(xy 402.777939 -122.568154) (xy 402.807906 -122.62006) (xy 402.830842 -122.675433) (xy 402.846355 -122.733326)
			(xy 402.854178 -122.792748) (xy 402.854668 -122.822716) (xy 402.854668 -123.16714) (xy 414.899348 -123.16714)
			(xy 414.899348 -122.30354) (xy 414.899838 -122.273556) (xy 414.907666 -122.2141) (xy 414.923187 -122.156175)
			(xy 414.946136 -122.100771) (xy 414.97612 -122.048837) (xy 415.012626 -122.001261) (xy 415.055031 -121.958856)
			(xy 415.102607 -121.92235) (xy 415.154541 -121.892366) (xy 415.209945 -121.869417) (xy 415.26787 -121.853896)
			(xy 415.327326 -121.846068) (xy 415.387294 -121.846068) (xy 415.44675 -121.853896) (xy 415.504675 -121.869417)
			(xy 415.560079 -121.892366) (xy 415.612013 -121.92235) (xy 415.659589 -121.958856) (xy 415.701994 -122.001261)
			(xy 415.7385 -122.048837) (xy 415.768484 -122.100771) (xy 415.791433 -122.156175) (xy 415.806954 -122.2141)
			(xy 415.814782 -122.273556) (xy 415.815272 -122.30354) (xy 415.815272 -123.159266) (xy 429.3743 -123.159266)
			(xy 429.3743 -122.295666) (xy 429.37479 -122.265682) (xy 429.382618 -122.206226) (xy 429.398139 -122.148301)
			(xy 429.421088 -122.092897) (xy 429.451072 -122.040963) (xy 429.487578 -121.993387) (xy 429.529983 -121.950982)
			(xy 429.577559 -121.914476) (xy 429.629493 -121.884492) (xy 429.684897 -121.861543) (xy 429.742822 -121.846022)
			(xy 429.802278 -121.838194) (xy 429.862246 -121.838194) (xy 429.921702 -121.846022) (xy 429.979627 -121.861543)
			(xy 430.035031 -121.884492) (xy 430.086965 -121.914476) (xy 430.134541 -121.950982) (xy 430.176946 -121.993387)
			(xy 430.213452 -122.040963) (xy 430.243436 -122.092897) (xy 430.266385 -122.148301) (xy 430.281906 -122.206226)
			(xy 430.289734 -122.265682) (xy 430.290224 -122.295666) (xy 430.290224 -123.159266) (xy 430.289734 -123.18925)
			(xy 430.281906 -123.248706) (xy 430.266385 -123.306631) (xy 430.243436 -123.362035) (xy 430.213452 -123.413969)
			(xy 430.176946 -123.461545) (xy 430.134541 -123.50395) (xy 430.086965 -123.540456) (xy 430.035031 -123.57044)
			(xy 429.979627 -123.593389) (xy 429.921702 -123.60891) (xy 429.862246 -123.616738) (xy 429.802278 -123.616738)
			(xy 429.742822 -123.60891) (xy 429.684897 -123.593389) (xy 429.629493 -123.57044) (xy 429.577559 -123.540456)
			(xy 429.529983 -123.50395) (xy 429.487578 -123.461545) (xy 429.451072 -123.413969) (xy 429.421088 -123.362035)
			(xy 429.398139 -123.306631) (xy 429.382618 -123.248706) (xy 429.37479 -123.18925) (xy 429.3743 -123.159266)
			(xy 415.815272 -123.159266) (xy 415.815272 -123.16714) (xy 415.814782 -123.197124) (xy 415.806954 -123.25658)
			(xy 415.791433 -123.314505) (xy 415.768484 -123.369909) (xy 415.7385 -123.421843) (xy 415.701994 -123.469419)
			(xy 415.659589 -123.511824) (xy 415.612013 -123.54833) (xy 415.560079 -123.578314) (xy 415.504675 -123.601263)
			(xy 415.44675 -123.616784) (xy 415.387294 -123.624612) (xy 415.327326 -123.624612) (xy 415.26787 -123.616784)
			(xy 415.209945 -123.601263) (xy 415.154541 -123.578314) (xy 415.102607 -123.54833) (xy 415.055031 -123.511824)
			(xy 415.012626 -123.469419) (xy 414.97612 -123.421843) (xy 414.946136 -123.369909) (xy 414.923187 -123.314505)
			(xy 414.907666 -123.25658) (xy 414.899838 -123.197124) (xy 414.899348 -123.16714) (xy 402.854668 -123.16714)
			(xy 402.854668 -123.686316) (xy 402.854178 -123.716284) (xy 402.846355 -123.775706) (xy 402.830842 -123.833599)
			(xy 402.807906 -123.888972) (xy 402.777939 -123.940878) (xy 402.741452 -123.988428) (xy 402.699072 -124.030808)
			(xy 402.651522 -124.067295) (xy 402.599616 -124.097262) (xy 402.544243 -124.120198) (xy 402.48635 -124.135711)
			(xy 402.426928 -124.143534) (xy 402.366992 -124.143534) (xy 402.30757 -124.135711) (xy 402.249677 -124.120198)
			(xy 402.194304 -124.097262) (xy 402.142398 -124.067295) (xy 402.094848 -124.030808) (xy 402.052468 -123.988428)
			(xy 402.015981 -123.940878) (xy 401.986014 -123.888972) (xy 401.963078 -123.833599) (xy 401.947565 -123.775706)
			(xy 401.939742 -123.716284) (xy 401.939252 -123.686316) (xy 383.883408 -123.686316) (xy 383.883408 -123.68784)
			(xy 383.882918 -123.717808) (xy 383.875095 -123.77723) (xy 383.859582 -123.835123) (xy 383.836646 -123.890496)
			(xy 383.806679 -123.942402) (xy 383.770192 -123.989952) (xy 383.727812 -124.032332) (xy 383.680262 -124.068819)
			(xy 383.628356 -124.098786) (xy 383.572983 -124.121722) (xy 383.51509 -124.137235) (xy 383.455668 -124.145058)
			(xy 383.395732 -124.145058) (xy 383.33631 -124.137235) (xy 383.278417 -124.121722) (xy 383.223044 -124.098786)
			(xy 383.171138 -124.068819) (xy 383.123588 -124.032332) (xy 383.081208 -123.989952) (xy 383.044721 -123.942402)
			(xy 383.014754 -123.890496) (xy 382.991818 -123.835123) (xy 382.976305 -123.77723) (xy 382.968482 -123.717808)
			(xy 382.967992 -123.68784) (xy 316.568893 -123.68784) (xy 316.576928 -123.691168) (xy 316.628834 -123.721135)
			(xy 316.676384 -123.757622) (xy 316.718764 -123.800002) (xy 316.755251 -123.847552) (xy 316.785218 -123.899458)
			(xy 316.808154 -123.954831) (xy 316.823667 -124.012724) (xy 316.83149 -124.072146) (xy 316.83198 -124.102114)
			(xy 316.83198 -124.965714) (xy 316.83149 -124.995682) (xy 316.823667 -125.055104) (xy 316.808154 -125.112997)
			(xy 316.785218 -125.16837) (xy 316.755251 -125.220276) (xy 316.718764 -125.267826) (xy 316.676384 -125.310206)
			(xy 316.628834 -125.346693) (xy 316.576928 -125.37666) (xy 316.521555 -125.399596) (xy 316.463662 -125.415109)
			(xy 316.40424 -125.422932) (xy 316.344304 -125.422932) (xy 316.284882 -125.415109) (xy 316.226989 -125.399596)
			(xy 316.171616 -125.37666) (xy 316.11971 -125.346693) (xy 316.07216 -125.310206) (xy 316.02978 -125.267826)
			(xy 315.993293 -125.220276) (xy 315.963326 -125.16837) (xy 315.94039 -125.112997) (xy 315.924877 -125.055104)
			(xy 315.917054 -124.995682) (xy 315.916564 -124.965714) (xy 297.86072 -124.965714) (xy 297.86072 -124.967238)
			(xy 297.86023 -124.997206) (xy 297.852407 -125.056628) (xy 297.836894 -125.114521) (xy 297.813958 -125.169894)
			(xy 297.783991 -125.2218) (xy 297.747504 -125.26935) (xy 297.705124 -125.31173) (xy 297.657574 -125.348217)
			(xy 297.605668 -125.378184) (xy 297.550295 -125.40112) (xy 297.492402 -125.416633) (xy 297.43298 -125.424456)
			(xy 297.373044 -125.424456) (xy 297.313622 -125.416633) (xy 297.255729 -125.40112) (xy 297.200356 -125.378184)
			(xy 297.14845 -125.348217) (xy 297.1009 -125.31173) (xy 297.05852 -125.26935) (xy 297.022033 -125.2218)
			(xy 296.992066 -125.169894) (xy 296.96913 -125.114521) (xy 296.953617 -125.056628) (xy 296.945794 -124.997206)
			(xy 296.945304 -124.967238) (xy 284.900624 -124.967238) (xy 284.900624 -125.486414) (xy 284.900491 -125.494542)
			(xy 385.6101 -125.494542) (xy 385.6101 -124.630942) (xy 385.61059 -124.600974) (xy 385.618413 -124.541552)
			(xy 385.633926 -124.483659) (xy 385.656862 -124.428286) (xy 385.686829 -124.37638) (xy 385.723316 -124.32883)
			(xy 385.765696 -124.28645) (xy 385.813246 -124.249963) (xy 385.865152 -124.219996) (xy 385.920525 -124.19706)
			(xy 385.978418 -124.181547) (xy 386.03784 -124.173724) (xy 386.097776 -124.173724) (xy 386.157198 -124.181547)
			(xy 386.215091 -124.19706) (xy 386.270464 -124.219996) (xy 386.32237 -124.249963) (xy 386.36992 -124.28645)
			(xy 386.4123 -124.32883) (xy 386.448787 -124.37638) (xy 386.478754 -124.428286) (xy 386.50169 -124.483659)
			(xy 386.517203 -124.541552) (xy 386.525026 -124.600974) (xy 386.525516 -124.630942) (xy 386.525516 -125.486414)
			(xy 400.085052 -125.486414) (xy 400.085052 -124.622814) (xy 400.085542 -124.592846) (xy 400.093365 -124.533424)
			(xy 400.108878 -124.475531) (xy 400.131814 -124.420158) (xy 400.161781 -124.368252) (xy 400.198268 -124.320702)
			(xy 400.240648 -124.278322) (xy 400.288198 -124.241835) (xy 400.340104 -124.211868) (xy 400.395477 -124.188932)
			(xy 400.45337 -124.173419) (xy 400.512792 -124.165596) (xy 400.572728 -124.165596) (xy 400.63215 -124.173419)
			(xy 400.690043 -124.188932) (xy 400.745416 -124.211868) (xy 400.797322 -124.241835) (xy 400.844872 -124.278322)
			(xy 400.887252 -124.320702) (xy 400.923739 -124.368252) (xy 400.953706 -124.420158) (xy 400.976642 -124.475531)
			(xy 400.992155 -124.533424) (xy 400.999978 -124.592846) (xy 401.000468 -124.622814) (xy 401.000468 -124.967238)
			(xy 413.045148 -124.967238) (xy 413.045148 -124.103638) (xy 413.045638 -124.073654) (xy 413.053466 -124.014198)
			(xy 413.068987 -123.956273) (xy 413.091936 -123.900869) (xy 413.12192 -123.848935) (xy 413.158426 -123.801359)
			(xy 413.200831 -123.758954) (xy 413.248407 -123.722448) (xy 413.300341 -123.692464) (xy 413.355745 -123.669515)
			(xy 413.41367 -123.653994) (xy 413.473126 -123.646166) (xy 413.533094 -123.646166) (xy 413.59255 -123.653994)
			(xy 413.650475 -123.669515) (xy 413.705879 -123.692464) (xy 413.757813 -123.722448) (xy 413.805389 -123.758954)
			(xy 413.847794 -123.801359) (xy 413.8843 -123.848935) (xy 413.914284 -123.900869) (xy 413.937233 -123.956273)
			(xy 413.952754 -124.014198) (xy 413.960582 -124.073654) (xy 413.961072 -124.103638) (xy 413.961072 -124.965714)
			(xy 432.016408 -124.965714) (xy 432.016408 -124.102114) (xy 432.016898 -124.07213) (xy 432.024726 -124.012674)
			(xy 432.040247 -123.954749) (xy 432.063196 -123.899345) (xy 432.09318 -123.847411) (xy 432.129686 -123.799835)
			(xy 432.172091 -123.75743) (xy 432.219667 -123.720924) (xy 432.271601 -123.69094) (xy 432.327005 -123.667991)
			(xy 432.38493 -123.65247) (xy 432.444386 -123.644642) (xy 432.504354 -123.644642) (xy 432.56381 -123.65247)
			(xy 432.621735 -123.667991) (xy 432.677139 -123.69094) (xy 432.729073 -123.720924) (xy 432.776649 -123.75743)
			(xy 432.819054 -123.799835) (xy 432.85556 -123.847411) (xy 432.885544 -123.899345) (xy 432.908493 -123.954749)
			(xy 432.924014 -124.012674) (xy 432.931842 -124.07213) (xy 432.932332 -124.102114) (xy 432.932332 -124.965714)
			(xy 432.931842 -124.995698) (xy 432.924014 -125.055154) (xy 432.908493 -125.113079) (xy 432.885544 -125.168483)
			(xy 432.85556 -125.220417) (xy 432.819054 -125.267993) (xy 432.776649 -125.310398) (xy 432.729073 -125.346904)
			(xy 432.677139 -125.376888) (xy 432.621735 -125.399837) (xy 432.56381 -125.415358) (xy 432.504354 -125.423186)
			(xy 432.444386 -125.423186) (xy 432.38493 -125.415358) (xy 432.327005 -125.399837) (xy 432.271601 -125.376888)
			(xy 432.219667 -125.346904) (xy 432.172091 -125.310398) (xy 432.129686 -125.267993) (xy 432.09318 -125.220417)
			(xy 432.063196 -125.168483) (xy 432.040247 -125.113079) (xy 432.024726 -125.055154) (xy 432.016898 -124.995698)
			(xy 432.016408 -124.965714) (xy 413.961072 -124.965714) (xy 413.961072 -124.967238) (xy 413.960582 -124.997222)
			(xy 413.952754 -125.056678) (xy 413.937233 -125.114603) (xy 413.914284 -125.170007) (xy 413.8843 -125.221941)
			(xy 413.847794 -125.269517) (xy 413.805389 -125.311922) (xy 413.757813 -125.348428) (xy 413.705879 -125.378412)
			(xy 413.650475 -125.401361) (xy 413.59255 -125.416882) (xy 413.533094 -125.42471) (xy 413.473126 -125.42471)
			(xy 413.41367 -125.416882) (xy 413.355745 -125.401361) (xy 413.300341 -125.378412) (xy 413.248407 -125.348428)
			(xy 413.200831 -125.311922) (xy 413.158426 -125.269517) (xy 413.12192 -125.221941) (xy 413.091936 -125.170007)
			(xy 413.068987 -125.114603) (xy 413.053466 -125.056678) (xy 413.045638 -124.997222) (xy 413.045148 -124.967238)
			(xy 401.000468 -124.967238) (xy 401.000468 -125.486414) (xy 400.999978 -125.516382) (xy 400.992155 -125.575804)
			(xy 400.976642 -125.633697) (xy 400.953706 -125.68907) (xy 400.923739 -125.740976) (xy 400.887252 -125.788526)
			(xy 400.844872 -125.830906) (xy 400.797322 -125.867393) (xy 400.745416 -125.89736) (xy 400.690043 -125.920296)
			(xy 400.63215 -125.935809) (xy 400.572728 -125.943632) (xy 400.512792 -125.943632) (xy 400.45337 -125.935809)
			(xy 400.395477 -125.920296) (xy 400.340104 -125.89736) (xy 400.288198 -125.867393) (xy 400.240648 -125.830906)
			(xy 400.198268 -125.788526) (xy 400.161781 -125.740976) (xy 400.131814 -125.68907) (xy 400.108878 -125.633697)
			(xy 400.093365 -125.575804) (xy 400.085542 -125.516382) (xy 400.085052 -125.486414) (xy 386.525516 -125.486414)
			(xy 386.525516 -125.494542) (xy 386.525026 -125.52451) (xy 386.517203 -125.583932) (xy 386.50169 -125.641825)
			(xy 386.478754 -125.697198) (xy 386.448787 -125.749104) (xy 386.4123 -125.796654) (xy 386.36992 -125.839034)
			(xy 386.32237 -125.875521) (xy 386.270464 -125.905488) (xy 386.215091 -125.928424) (xy 386.157198 -125.943937)
			(xy 386.097776 -125.95176) (xy 386.03784 -125.95176) (xy 385.978418 -125.943937) (xy 385.920525 -125.928424)
			(xy 385.865152 -125.905488) (xy 385.813246 -125.875521) (xy 385.765696 -125.839034) (xy 385.723316 -125.796654)
			(xy 385.686829 -125.749104) (xy 385.656862 -125.697198) (xy 385.633926 -125.641825) (xy 385.618413 -125.583932)
			(xy 385.61059 -125.52451) (xy 385.6101 -125.494542) (xy 284.900491 -125.494542) (xy 284.900134 -125.516398)
			(xy 284.892306 -125.575854) (xy 284.876785 -125.633779) (xy 284.853836 -125.689183) (xy 284.823852 -125.741117)
			(xy 284.787346 -125.788693) (xy 284.744941 -125.831098) (xy 284.697365 -125.867604) (xy 284.645431 -125.897588)
			(xy 284.590027 -125.920537) (xy 284.532102 -125.936058) (xy 284.472646 -125.943886) (xy 284.412678 -125.943886)
			(xy 284.353222 -125.936058) (xy 284.295297 -125.920537) (xy 284.239893 -125.897588) (xy 284.187959 -125.867604)
			(xy 284.140383 -125.831098) (xy 284.097978 -125.788693) (xy 284.061472 -125.741117) (xy 284.031488 -125.689183)
			(xy 284.008539 -125.633779) (xy 283.993018 -125.575854) (xy 283.98519 -125.516398) (xy 283.9847 -125.486414)
			(xy 270.425672 -125.486414) (xy 270.425672 -125.494542) (xy 270.425182 -125.524526) (xy 270.417354 -125.583982)
			(xy 270.401833 -125.641907) (xy 270.378884 -125.697311) (xy 270.3489 -125.749245) (xy 270.312394 -125.796821)
			(xy 270.269989 -125.839226) (xy 270.222413 -125.875732) (xy 270.170479 -125.905716) (xy 270.115075 -125.928665)
			(xy 270.05715 -125.944186) (xy 269.997694 -125.952014) (xy 269.937726 -125.952014) (xy 269.87827 -125.944186)
			(xy 269.820345 -125.928665) (xy 269.764941 -125.905716) (xy 269.713007 -125.875732) (xy 269.665431 -125.839226)
			(xy 269.623026 -125.796821) (xy 269.58652 -125.749245) (xy 269.556536 -125.697311) (xy 269.533587 -125.641907)
			(xy 269.518066 -125.583982) (xy 269.510238 -125.524526) (xy 269.509748 -125.494542) (xy 168.800647 -125.494542)
			(xy 168.80029 -125.516398) (xy 168.792462 -125.575854) (xy 168.776941 -125.633779) (xy 168.753992 -125.689183)
			(xy 168.724008 -125.741117) (xy 168.687502 -125.788693) (xy 168.645097 -125.831098) (xy 168.597521 -125.867604)
			(xy 168.545587 -125.897588) (xy 168.490183 -125.920537) (xy 168.432258 -125.936058) (xy 168.372802 -125.943886)
			(xy 168.312834 -125.943886) (xy 168.253378 -125.936058) (xy 168.195453 -125.920537) (xy 168.140049 -125.897588)
			(xy 168.088115 -125.867604) (xy 168.040539 -125.831098) (xy 167.998134 -125.788693) (xy 167.961628 -125.741117)
			(xy 167.931644 -125.689183) (xy 167.908695 -125.633779) (xy 167.893174 -125.575854) (xy 167.885346 -125.516398)
			(xy 167.884856 -125.486414) (xy 154.325828 -125.486414) (xy 154.325828 -125.494542) (xy 154.325338 -125.524526)
			(xy 154.31751 -125.583982) (xy 154.301989 -125.641907) (xy 154.27904 -125.697311) (xy 154.249056 -125.749245)
			(xy 154.21255 -125.796821) (xy 154.170145 -125.839226) (xy 154.122569 -125.875732) (xy 154.070635 -125.905716)
			(xy 154.015231 -125.928665) (xy 153.957306 -125.944186) (xy 153.89785 -125.952014) (xy 153.837882 -125.952014)
			(xy 153.778426 -125.944186) (xy 153.720501 -125.928665) (xy 153.665097 -125.905716) (xy 153.613163 -125.875732)
			(xy 153.565587 -125.839226) (xy 153.523182 -125.796821) (xy 153.486676 -125.749245) (xy 153.456692 -125.697311)
			(xy 153.433743 -125.641907) (xy 153.418222 -125.583982) (xy 153.410394 -125.524526) (xy 153.409904 -125.494542)
			(xy 52.700295 -125.494542) (xy 52.699938 -125.516382) (xy 52.692115 -125.575804) (xy 52.676602 -125.633697)
			(xy 52.653666 -125.68907) (xy 52.623699 -125.740976) (xy 52.587212 -125.788526) (xy 52.544832 -125.830906)
			(xy 52.497282 -125.867393) (xy 52.445376 -125.89736) (xy 52.390003 -125.920296) (xy 52.33211 -125.935809)
			(xy 52.272688 -125.943632) (xy 52.212752 -125.943632) (xy 52.15333 -125.935809) (xy 52.095437 -125.920296)
			(xy 52.040064 -125.89736) (xy 51.988158 -125.867393) (xy 51.940608 -125.830906) (xy 51.898228 -125.788526)
			(xy 51.861741 -125.740976) (xy 51.831774 -125.68907) (xy 51.808838 -125.633697) (xy 51.793325 -125.575804)
			(xy 51.785502 -125.516382) (xy 51.785012 -125.486414) (xy 38.225476 -125.486414) (xy 38.225476 -125.494542)
			(xy 38.224986 -125.52451) (xy 38.217163 -125.583932) (xy 38.20165 -125.641825) (xy 38.178714 -125.697198)
			(xy 38.148747 -125.749104) (xy 38.11226 -125.796654) (xy 38.06988 -125.839034) (xy 38.02233 -125.875521)
			(xy 37.970424 -125.905488) (xy 37.915051 -125.928424) (xy 37.857158 -125.943937) (xy 37.797736 -125.95176)
			(xy 37.7378 -125.95176) (xy 37.678378 -125.943937) (xy 37.620485 -125.928424) (xy 37.565112 -125.905488)
			(xy 37.513206 -125.875521) (xy 37.465656 -125.839034) (xy 37.423276 -125.796654) (xy 37.386789 -125.749104)
			(xy 37.356822 -125.697198) (xy 37.333886 -125.641825) (xy 37.318373 -125.583932) (xy 37.31055 -125.52451)
			(xy 37.31006 -125.494542) (xy 4.308094 -125.494542) (xy 4.308094 -131.297934) (xy 34.667952 -131.297934)
			(xy 34.667952 -130.434334) (xy 34.668442 -130.404366) (xy 34.676265 -130.344944) (xy 34.691778 -130.287051)
			(xy 34.714714 -130.231678) (xy 34.744681 -130.179772) (xy 34.781168 -130.132222) (xy 34.823548 -130.089842)
			(xy 34.871098 -130.053355) (xy 34.923004 -130.023388) (xy 34.978377 -130.000452) (xy 35.03627 -129.984939)
			(xy 35.095692 -129.977116) (xy 35.155628 -129.977116) (xy 35.21505 -129.984939) (xy 35.272943 -130.000452)
			(xy 35.328316 -130.023388) (xy 35.380222 -130.053355) (xy 35.427772 -130.089842) (xy 35.470152 -130.132222)
			(xy 35.506639 -130.179772) (xy 35.536606 -130.231678) (xy 35.559542 -130.287051) (xy 35.575055 -130.344944)
			(xy 35.582878 -130.404366) (xy 35.583368 -130.434334) (xy 35.583368 -131.29641) (xy 53.639212 -131.29641)
			(xy 53.639212 -130.43281) (xy 53.639702 -130.402842) (xy 53.647525 -130.34342) (xy 53.663038 -130.285527)
			(xy 53.685974 -130.230154) (xy 53.715941 -130.178248) (xy 53.752428 -130.130698) (xy 53.794808 -130.088318)
			(xy 53.842358 -130.051831) (xy 53.894264 -130.021864) (xy 53.949637 -129.998928) (xy 54.00753 -129.983415)
			(xy 54.066952 -129.975592) (xy 54.126888 -129.975592) (xy 54.18631 -129.983415) (xy 54.244203 -129.998928)
			(xy 54.299576 -130.021864) (xy 54.351482 -130.051831) (xy 54.399032 -130.088318) (xy 54.441412 -130.130698)
			(xy 54.477899 -130.178248) (xy 54.507866 -130.230154) (xy 54.530802 -130.285527) (xy 54.546315 -130.34342)
			(xy 54.554138 -130.402842) (xy 54.554628 -130.43281) (xy 54.554628 -130.777234) (xy 66.599308 -130.777234)
			(xy 66.599308 -129.913634) (xy 66.599798 -129.88365) (xy 66.607626 -129.824194) (xy 66.623147 -129.766269)
			(xy 66.646096 -129.710865) (xy 66.67608 -129.658931) (xy 66.712586 -129.611355) (xy 66.754991 -129.56895)
			(xy 66.802567 -129.532444) (xy 66.854501 -129.50246) (xy 66.909905 -129.479511) (xy 66.96783 -129.46399)
			(xy 67.027286 -129.456162) (xy 67.087254 -129.456162) (xy 67.14671 -129.46399) (xy 67.204635 -129.479511)
			(xy 67.260039 -129.50246) (xy 67.311973 -129.532444) (xy 67.359549 -129.56895) (xy 67.401954 -129.611355)
			(xy 67.43846 -129.658931) (xy 67.468444 -129.710865) (xy 67.491393 -129.766269) (xy 67.506914 -129.824194)
			(xy 67.514742 -129.88365) (xy 67.515232 -129.913634) (xy 67.515232 -130.769106) (xy 81.07426 -130.769106)
			(xy 81.07426 -129.905506) (xy 81.07475 -129.875522) (xy 81.082578 -129.816066) (xy 81.098099 -129.758141)
			(xy 81.121048 -129.702737) (xy 81.151032 -129.650803) (xy 81.187538 -129.603227) (xy 81.229943 -129.560822)
			(xy 81.277519 -129.524316) (xy 81.329453 -129.494332) (xy 81.384857 -129.471383) (xy 81.442782 -129.455862)
			(xy 81.502238 -129.448034) (xy 81.562206 -129.448034) (xy 81.621662 -129.455862) (xy 81.679587 -129.471383)
			(xy 81.734991 -129.494332) (xy 81.786925 -129.524316) (xy 81.834501 -129.560822) (xy 81.876906 -129.603227)
			(xy 81.913412 -129.650803) (xy 81.943396 -129.702737) (xy 81.966345 -129.758141) (xy 81.981866 -129.816066)
			(xy 81.989694 -129.875522) (xy 81.990184 -129.905506) (xy 81.990184 -130.769106) (xy 81.989694 -130.79909)
			(xy 81.981866 -130.858546) (xy 81.966345 -130.916471) (xy 81.943396 -130.971875) (xy 81.913412 -131.023809)
			(xy 81.876906 -131.071385) (xy 81.834501 -131.11379) (xy 81.786925 -131.150296) (xy 81.734991 -131.18028)
			(xy 81.679587 -131.203229) (xy 81.621662 -131.21875) (xy 81.562206 -131.226578) (xy 81.502238 -131.226578)
			(xy 81.442782 -131.21875) (xy 81.384857 -131.203229) (xy 81.329453 -131.18028) (xy 81.277519 -131.150296)
			(xy 81.229943 -131.11379) (xy 81.187538 -131.071385) (xy 81.151032 -131.023809) (xy 81.121048 -130.971875)
			(xy 81.098099 -130.916471) (xy 81.082578 -130.858546) (xy 81.07475 -130.79909) (xy 81.07426 -130.769106)
			(xy 67.515232 -130.769106) (xy 67.515232 -130.777234) (xy 67.514742 -130.807218) (xy 67.506914 -130.866674)
			(xy 67.491393 -130.924599) (xy 67.468444 -130.980003) (xy 67.43846 -131.031937) (xy 67.401954 -131.079513)
			(xy 67.359549 -131.121918) (xy 67.311973 -131.158424) (xy 67.260039 -131.188408) (xy 67.204635 -131.211357)
			(xy 67.14671 -131.226878) (xy 67.087254 -131.234706) (xy 67.027286 -131.234706) (xy 66.96783 -131.226878)
			(xy 66.909905 -131.211357) (xy 66.854501 -131.188408) (xy 66.802567 -131.158424) (xy 66.754991 -131.121918)
			(xy 66.712586 -131.079513) (xy 66.67608 -131.031937) (xy 66.646096 -130.980003) (xy 66.623147 -130.924599)
			(xy 66.607626 -130.866674) (xy 66.599798 -130.807218) (xy 66.599308 -130.777234) (xy 54.554628 -130.777234)
			(xy 54.554628 -131.29641) (xy 54.554138 -131.326378) (xy 54.546315 -131.3858) (xy 54.530802 -131.443693)
			(xy 54.507866 -131.499066) (xy 54.477899 -131.550972) (xy 54.441412 -131.598522) (xy 54.399032 -131.640902)
			(xy 54.351482 -131.677389) (xy 54.299576 -131.707356) (xy 54.244203 -131.730292) (xy 54.18631 -131.745805)
			(xy 54.126888 -131.753628) (xy 54.066952 -131.753628) (xy 54.00753 -131.745805) (xy 53.949637 -131.730292)
			(xy 53.894264 -131.707356) (xy 53.842358 -131.677389) (xy 53.794808 -131.640902) (xy 53.752428 -131.598522)
			(xy 53.715941 -131.550972) (xy 53.685974 -131.499066) (xy 53.663038 -131.443693) (xy 53.647525 -131.3858)
			(xy 53.639702 -131.326378) (xy 53.639212 -131.29641) (xy 35.583368 -131.29641) (xy 35.583368 -131.297934)
			(xy 35.582878 -131.327902) (xy 35.575055 -131.387324) (xy 35.559542 -131.445217) (xy 35.536606 -131.50059)
			(xy 35.506639 -131.552496) (xy 35.470152 -131.600046) (xy 35.427772 -131.642426) (xy 35.380222 -131.678913)
			(xy 35.328316 -131.70888) (xy 35.272943 -131.731816) (xy 35.21505 -131.747329) (xy 35.155628 -131.755152)
			(xy 35.095692 -131.755152) (xy 35.03627 -131.747329) (xy 34.978377 -131.731816) (xy 34.923004 -131.70888)
			(xy 34.871098 -131.678913) (xy 34.823548 -131.642426) (xy 34.781168 -131.600046) (xy 34.744681 -131.552496)
			(xy 34.714714 -131.50059) (xy 34.691778 -131.445217) (xy 34.676265 -131.387324) (xy 34.668442 -131.327902)
			(xy 34.667952 -131.297934) (xy 4.308094 -131.297934) (xy 4.308094 -133.104382) (xy 37.31006 -133.104382)
			(xy 37.31006 -132.240782) (xy 37.31055 -132.210814) (xy 37.318373 -132.151392) (xy 37.333886 -132.093499)
			(xy 37.356822 -132.038126) (xy 37.386789 -131.98622) (xy 37.423276 -131.93867) (xy 37.465656 -131.89629)
			(xy 37.513206 -131.859803) (xy 37.565112 -131.829836) (xy 37.620485 -131.8069) (xy 37.678378 -131.791387)
			(xy 37.7378 -131.783564) (xy 37.797736 -131.783564) (xy 37.857158 -131.791387) (xy 37.915051 -131.8069)
			(xy 37.970424 -131.829836) (xy 38.02233 -131.859803) (xy 38.06988 -131.89629) (xy 38.11226 -131.93867)
			(xy 38.148747 -131.98622) (xy 38.178714 -132.038126) (xy 38.20165 -132.093499) (xy 38.217163 -132.151392)
			(xy 38.224986 -132.210814) (xy 38.225476 -132.240782) (xy 38.225476 -133.096508) (xy 51.785012 -133.096508)
			(xy 51.785012 -132.232908) (xy 51.785502 -132.20294) (xy 51.793325 -132.143518) (xy 51.808838 -132.085625)
			(xy 51.831774 -132.030252) (xy 51.861741 -131.978346) (xy 51.898228 -131.930796) (xy 51.940608 -131.888416)
			(xy 51.988158 -131.851929) (xy 52.040064 -131.821962) (xy 52.095437 -131.799026) (xy 52.15333 -131.783513)
			(xy 52.212752 -131.77569) (xy 52.272688 -131.77569) (xy 52.33211 -131.783513) (xy 52.390003 -131.799026)
			(xy 52.445376 -131.821962) (xy 52.497282 -131.851929) (xy 52.544832 -131.888416) (xy 52.587212 -131.930796)
			(xy 52.623699 -131.978346) (xy 52.653666 -132.030252) (xy 52.676602 -132.085625) (xy 52.692115 -132.143518)
			(xy 52.699938 -132.20294) (xy 52.700428 -132.232908) (xy 52.700428 -132.577332) (xy 64.745108 -132.577332)
			(xy 64.745108 -131.713732) (xy 64.745598 -131.683748) (xy 64.753426 -131.624292) (xy 64.768947 -131.566367)
			(xy 64.791896 -131.510963) (xy 64.82188 -131.459029) (xy 64.858386 -131.411453) (xy 64.900791 -131.369048)
			(xy 64.948367 -131.332542) (xy 65.000301 -131.302558) (xy 65.055705 -131.279609) (xy 65.11363 -131.264088)
			(xy 65.173086 -131.25626) (xy 65.233054 -131.25626) (xy 65.29251 -131.264088) (xy 65.350435 -131.279609)
			(xy 65.405839 -131.302558) (xy 65.457773 -131.332542) (xy 65.505349 -131.369048) (xy 65.547754 -131.411453)
			(xy 65.58426 -131.459029) (xy 65.614244 -131.510963) (xy 65.637193 -131.566367) (xy 65.652714 -131.624292)
			(xy 65.660542 -131.683748) (xy 65.661032 -131.713732) (xy 65.661032 -132.575808) (xy 83.716368 -132.575808)
			(xy 83.716368 -131.712208) (xy 83.716858 -131.682224) (xy 83.724686 -131.622768) (xy 83.740207 -131.564843)
			(xy 83.763156 -131.509439) (xy 83.79314 -131.457505) (xy 83.829646 -131.409929) (xy 83.872051 -131.367524)
			(xy 83.919627 -131.331018) (xy 83.971561 -131.301034) (xy 84.026965 -131.278085) (xy 84.08489 -131.262564)
			(xy 84.144346 -131.254736) (xy 84.204314 -131.254736) (xy 84.26377 -131.262564) (xy 84.321695 -131.278085)
			(xy 84.369615 -131.297934) (xy 150.767796 -131.297934) (xy 150.767796 -130.434334) (xy 150.768286 -130.40435)
			(xy 150.776114 -130.344894) (xy 150.791635 -130.286969) (xy 150.814584 -130.231565) (xy 150.844568 -130.179631)
			(xy 150.881074 -130.132055) (xy 150.923479 -130.08965) (xy 150.971055 -130.053144) (xy 151.022989 -130.02316)
			(xy 151.078393 -130.000211) (xy 151.136318 -129.98469) (xy 151.195774 -129.976862) (xy 151.255742 -129.976862)
			(xy 151.315198 -129.98469) (xy 151.373123 -130.000211) (xy 151.428527 -130.02316) (xy 151.480461 -130.053144)
			(xy 151.528037 -130.08965) (xy 151.570442 -130.132055) (xy 151.606948 -130.179631) (xy 151.636932 -130.231565)
			(xy 151.659881 -130.286969) (xy 151.675402 -130.344894) (xy 151.68323 -130.40435) (xy 151.68372 -130.434334)
			(xy 151.68372 -131.29641) (xy 169.739056 -131.29641) (xy 169.739056 -130.43281) (xy 169.739546 -130.402826)
			(xy 169.747374 -130.34337) (xy 169.762895 -130.285445) (xy 169.785844 -130.230041) (xy 169.815828 -130.178107)
			(xy 169.852334 -130.130531) (xy 169.894739 -130.088126) (xy 169.942315 -130.05162) (xy 169.994249 -130.021636)
			(xy 170.049653 -129.998687) (xy 170.107578 -129.983166) (xy 170.167034 -129.975338) (xy 170.227002 -129.975338)
			(xy 170.286458 -129.983166) (xy 170.344383 -129.998687) (xy 170.399787 -130.021636) (xy 170.451721 -130.05162)
			(xy 170.499297 -130.088126) (xy 170.541702 -130.130531) (xy 170.578208 -130.178107) (xy 170.608192 -130.230041)
			(xy 170.631141 -130.285445) (xy 170.646662 -130.34337) (xy 170.65449 -130.402826) (xy 170.65498 -130.43281)
			(xy 170.65498 -130.777234) (xy 182.69966 -130.777234) (xy 182.69966 -129.913634) (xy 182.70015 -129.883666)
			(xy 182.707973 -129.824244) (xy 182.723486 -129.766351) (xy 182.746422 -129.710978) (xy 182.776389 -129.659072)
			(xy 182.812876 -129.611522) (xy 182.855256 -129.569142) (xy 182.902806 -129.532655) (xy 182.954712 -129.502688)
			(xy 183.010085 -129.479752) (xy 183.067978 -129.464239) (xy 183.1274 -129.456416) (xy 183.187336 -129.456416)
			(xy 183.246758 -129.464239) (xy 183.304651 -129.479752) (xy 183.360024 -129.502688) (xy 183.41193 -129.532655)
			(xy 183.45948 -129.569142) (xy 183.50186 -129.611522) (xy 183.538347 -129.659072) (xy 183.568314 -129.710978)
			(xy 183.59125 -129.766351) (xy 183.606763 -129.824244) (xy 183.614586 -129.883666) (xy 183.615076 -129.913634)
			(xy 183.615076 -130.769106) (xy 197.174612 -130.769106) (xy 197.174612 -129.905506) (xy 197.175102 -129.875538)
			(xy 197.182925 -129.816116) (xy 197.198438 -129.758223) (xy 197.221374 -129.70285) (xy 197.251341 -129.650944)
			(xy 197.287828 -129.603394) (xy 197.330208 -129.561014) (xy 197.377758 -129.524527) (xy 197.429664 -129.49456)
			(xy 197.485037 -129.471624) (xy 197.54293 -129.456111) (xy 197.602352 -129.448288) (xy 197.662288 -129.448288)
			(xy 197.72171 -129.456111) (xy 197.779603 -129.471624) (xy 197.834976 -129.49456) (xy 197.886882 -129.524527)
			(xy 197.934432 -129.561014) (xy 197.976812 -129.603394) (xy 198.013299 -129.650944) (xy 198.043266 -129.70285)
			(xy 198.066202 -129.758223) (xy 198.081715 -129.816116) (xy 198.089538 -129.875538) (xy 198.090028 -129.905506)
			(xy 198.090028 -130.769106) (xy 198.089538 -130.799074) (xy 198.081715 -130.858496) (xy 198.066202 -130.916389)
			(xy 198.043266 -130.971762) (xy 198.013299 -131.023668) (xy 197.976812 -131.071218) (xy 197.934432 -131.113598)
			(xy 197.886882 -131.150085) (xy 197.834976 -131.180052) (xy 197.779603 -131.202988) (xy 197.72171 -131.218501)
			(xy 197.662288 -131.226324) (xy 197.602352 -131.226324) (xy 197.54293 -131.218501) (xy 197.485037 -131.202988)
			(xy 197.429664 -131.180052) (xy 197.377758 -131.150085) (xy 197.330208 -131.113598) (xy 197.287828 -131.071218)
			(xy 197.251341 -131.023668) (xy 197.221374 -130.971762) (xy 197.198438 -130.916389) (xy 197.182925 -130.858496)
			(xy 197.175102 -130.799074) (xy 197.174612 -130.769106) (xy 183.615076 -130.769106) (xy 183.615076 -130.777234)
			(xy 183.614586 -130.807202) (xy 183.606763 -130.866624) (xy 183.59125 -130.924517) (xy 183.568314 -130.97989)
			(xy 183.538347 -131.031796) (xy 183.50186 -131.079346) (xy 183.45948 -131.121726) (xy 183.41193 -131.158213)
			(xy 183.360024 -131.18818) (xy 183.304651 -131.211116) (xy 183.246758 -131.226629) (xy 183.187336 -131.234452)
			(xy 183.1274 -131.234452) (xy 183.067978 -131.226629) (xy 183.010085 -131.211116) (xy 182.954712 -131.18818)
			(xy 182.902806 -131.158213) (xy 182.855256 -131.121726) (xy 182.812876 -131.079346) (xy 182.776389 -131.031796)
			(xy 182.746422 -130.97989) (xy 182.723486 -130.924517) (xy 182.707973 -130.866624) (xy 182.70015 -130.807202)
			(xy 182.69966 -130.777234) (xy 170.65498 -130.777234) (xy 170.65498 -131.29641) (xy 170.65449 -131.326394)
			(xy 170.646662 -131.38585) (xy 170.631141 -131.443775) (xy 170.608192 -131.499179) (xy 170.578208 -131.551113)
			(xy 170.541702 -131.598689) (xy 170.499297 -131.641094) (xy 170.451721 -131.6776) (xy 170.399787 -131.707584)
			(xy 170.344383 -131.730533) (xy 170.286458 -131.746054) (xy 170.227002 -131.753882) (xy 170.167034 -131.753882)
			(xy 170.107578 -131.746054) (xy 170.049653 -131.730533) (xy 169.994249 -131.707584) (xy 169.942315 -131.6776)
			(xy 169.894739 -131.641094) (xy 169.852334 -131.598689) (xy 169.815828 -131.551113) (xy 169.785844 -131.499179)
			(xy 169.762895 -131.443775) (xy 169.747374 -131.38585) (xy 169.739546 -131.326394) (xy 169.739056 -131.29641)
			(xy 151.68372 -131.29641) (xy 151.68372 -131.297934) (xy 151.68323 -131.327918) (xy 151.675402 -131.387374)
			(xy 151.659881 -131.445299) (xy 151.636932 -131.500703) (xy 151.606948 -131.552637) (xy 151.570442 -131.600213)
			(xy 151.528037 -131.642618) (xy 151.480461 -131.679124) (xy 151.428527 -131.709108) (xy 151.373123 -131.732057)
			(xy 151.315198 -131.747578) (xy 151.255742 -131.755406) (xy 151.195774 -131.755406) (xy 151.136318 -131.747578)
			(xy 151.078393 -131.732057) (xy 151.022989 -131.709108) (xy 150.971055 -131.679124) (xy 150.923479 -131.642618)
			(xy 150.881074 -131.600213) (xy 150.844568 -131.552637) (xy 150.814584 -131.500703) (xy 150.791635 -131.445299)
			(xy 150.776114 -131.387374) (xy 150.768286 -131.327918) (xy 150.767796 -131.297934) (xy 84.369615 -131.297934)
			(xy 84.377099 -131.301034) (xy 84.429033 -131.331018) (xy 84.476609 -131.367524) (xy 84.519014 -131.409929)
			(xy 84.55552 -131.457505) (xy 84.585504 -131.509439) (xy 84.608453 -131.564843) (xy 84.623974 -131.622768)
			(xy 84.631802 -131.682224) (xy 84.632292 -131.712208) (xy 84.632292 -132.575808) (xy 84.631802 -132.605792)
			(xy 84.623974 -132.665248) (xy 84.608453 -132.723173) (xy 84.585504 -132.778577) (xy 84.55552 -132.830511)
			(xy 84.519014 -132.878087) (xy 84.476609 -132.920492) (xy 84.429033 -132.956998) (xy 84.377099 -132.986982)
			(xy 84.321695 -133.009931) (xy 84.26377 -133.025452) (xy 84.204314 -133.03328) (xy 84.144346 -133.03328)
			(xy 84.08489 -133.025452) (xy 84.026965 -133.009931) (xy 83.971561 -132.986982) (xy 83.919627 -132.956998)
			(xy 83.872051 -132.920492) (xy 83.829646 -132.878087) (xy 83.79314 -132.830511) (xy 83.763156 -132.778577)
			(xy 83.740207 -132.723173) (xy 83.724686 -132.665248) (xy 83.716858 -132.605792) (xy 83.716368 -132.575808)
			(xy 65.661032 -132.575808) (xy 65.661032 -132.577332) (xy 65.660542 -132.607316) (xy 65.652714 -132.666772)
			(xy 65.637193 -132.724697) (xy 65.614244 -132.780101) (xy 65.58426 -132.832035) (xy 65.547754 -132.879611)
			(xy 65.505349 -132.922016) (xy 65.457773 -132.958522) (xy 65.405839 -132.988506) (xy 65.350435 -133.011455)
			(xy 65.29251 -133.026976) (xy 65.233054 -133.034804) (xy 65.173086 -133.034804) (xy 65.11363 -133.026976)
			(xy 65.055705 -133.011455) (xy 65.000301 -132.988506) (xy 64.948367 -132.958522) (xy 64.900791 -132.922016)
			(xy 64.858386 -132.879611) (xy 64.82188 -132.832035) (xy 64.791896 -132.780101) (xy 64.768947 -132.724697)
			(xy 64.753426 -132.666772) (xy 64.745598 -132.607316) (xy 64.745108 -132.577332) (xy 52.700428 -132.577332)
			(xy 52.700428 -133.096508) (xy 52.699938 -133.126476) (xy 52.692115 -133.185898) (xy 52.676602 -133.243791)
			(xy 52.653666 -133.299164) (xy 52.623699 -133.35107) (xy 52.587212 -133.39862) (xy 52.544832 -133.441)
			(xy 52.497282 -133.477487) (xy 52.445376 -133.507454) (xy 52.390003 -133.53039) (xy 52.33211 -133.545903)
			(xy 52.272688 -133.553726) (xy 52.212752 -133.553726) (xy 52.15333 -133.545903) (xy 52.095437 -133.53039)
			(xy 52.040064 -133.507454) (xy 51.988158 -133.477487) (xy 51.940608 -133.441) (xy 51.898228 -133.39862)
			(xy 51.861741 -133.35107) (xy 51.831774 -133.299164) (xy 51.808838 -133.243791) (xy 51.793325 -133.185898)
			(xy 51.785502 -133.126476) (xy 51.785012 -133.096508) (xy 38.225476 -133.096508) (xy 38.225476 -133.104382)
			(xy 38.224986 -133.13435) (xy 38.217163 -133.193772) (xy 38.20165 -133.251665) (xy 38.178714 -133.307038)
			(xy 38.148747 -133.358944) (xy 38.11226 -133.406494) (xy 38.06988 -133.448874) (xy 38.02233 -133.485361)
			(xy 37.970424 -133.515328) (xy 37.915051 -133.538264) (xy 37.857158 -133.553777) (xy 37.797736 -133.5616)
			(xy 37.7378 -133.5616) (xy 37.678378 -133.553777) (xy 37.620485 -133.538264) (xy 37.565112 -133.515328)
			(xy 37.513206 -133.485361) (xy 37.465656 -133.448874) (xy 37.423276 -133.406494) (xy 37.386789 -133.358944)
			(xy 37.356822 -133.307038) (xy 37.333886 -133.251665) (xy 37.318373 -133.193772) (xy 37.31055 -133.13435)
			(xy 37.31006 -133.104382) (xy 4.308094 -133.104382) (xy 4.308094 -134.897876) (xy 34.667952 -134.897876)
			(xy 34.667952 -134.034276) (xy 34.668442 -134.004308) (xy 34.676265 -133.944886) (xy 34.691778 -133.886993)
			(xy 34.714714 -133.83162) (xy 34.744681 -133.779714) (xy 34.781168 -133.732164) (xy 34.823548 -133.689784)
			(xy 34.871098 -133.653297) (xy 34.923004 -133.62333) (xy 34.978377 -133.600394) (xy 35.03627 -133.584881)
			(xy 35.095692 -133.577058) (xy 35.155628 -133.577058) (xy 35.21505 -133.584881) (xy 35.272943 -133.600394)
			(xy 35.328316 -133.62333) (xy 35.380222 -133.653297) (xy 35.427772 -133.689784) (xy 35.470152 -133.732164)
			(xy 35.506639 -133.779714) (xy 35.536606 -133.83162) (xy 35.559542 -133.886993) (xy 35.575055 -133.944886)
			(xy 35.582878 -134.004308) (xy 35.583368 -134.034276) (xy 35.583368 -134.896352) (xy 53.639212 -134.896352)
			(xy 53.639212 -134.032752) (xy 53.639702 -134.002784) (xy 53.647525 -133.943362) (xy 53.663038 -133.885469)
			(xy 53.685974 -133.830096) (xy 53.715941 -133.77819) (xy 53.752428 -133.73064) (xy 53.794808 -133.68826)
			(xy 53.842358 -133.651773) (xy 53.894264 -133.621806) (xy 53.949637 -133.59887) (xy 54.00753 -133.583357)
			(xy 54.066952 -133.575534) (xy 54.126888 -133.575534) (xy 54.18631 -133.583357) (xy 54.244203 -133.59887)
			(xy 54.299576 -133.621806) (xy 54.351482 -133.651773) (xy 54.399032 -133.68826) (xy 54.441412 -133.73064)
			(xy 54.477899 -133.77819) (xy 54.507866 -133.830096) (xy 54.530802 -133.885469) (xy 54.546315 -133.943362)
			(xy 54.554138 -134.002784) (xy 54.554628 -134.032752) (xy 54.554628 -134.377176) (xy 66.599308 -134.377176)
			(xy 66.599308 -133.513576) (xy 66.599798 -133.483592) (xy 66.607626 -133.424136) (xy 66.623147 -133.366211)
			(xy 66.646096 -133.310807) (xy 66.67608 -133.258873) (xy 66.712586 -133.211297) (xy 66.754991 -133.168892)
			(xy 66.802567 -133.132386) (xy 66.854501 -133.102402) (xy 66.909905 -133.079453) (xy 66.96783 -133.063932)
			(xy 67.027286 -133.056104) (xy 67.087254 -133.056104) (xy 67.14671 -133.063932) (xy 67.204635 -133.079453)
			(xy 67.260039 -133.102402) (xy 67.311973 -133.132386) (xy 67.359549 -133.168892) (xy 67.401954 -133.211297)
			(xy 67.43846 -133.258873) (xy 67.468444 -133.310807) (xy 67.491393 -133.366211) (xy 67.506914 -133.424136)
			(xy 67.514742 -133.483592) (xy 67.515232 -133.513576) (xy 67.515232 -134.369302) (xy 81.07426 -134.369302)
			(xy 81.07426 -133.505702) (xy 81.07475 -133.475718) (xy 81.082578 -133.416262) (xy 81.098099 -133.358337)
			(xy 81.121048 -133.302933) (xy 81.151032 -133.250999) (xy 81.187538 -133.203423) (xy 81.229943 -133.161018)
			(xy 81.277519 -133.124512) (xy 81.329453 -133.094528) (xy 81.384857 -133.071579) (xy 81.442782 -133.056058)
			(xy 81.502238 -133.04823) (xy 81.562206 -133.04823) (xy 81.621662 -133.056058) (xy 81.679587 -133.071579)
			(xy 81.734991 -133.094528) (xy 81.752059 -133.104382) (xy 153.409904 -133.104382) (xy 153.409904 -132.240782)
			(xy 153.410394 -132.210798) (xy 153.418222 -132.151342) (xy 153.433743 -132.093417) (xy 153.456692 -132.038013)
			(xy 153.486676 -131.986079) (xy 153.523182 -131.938503) (xy 153.565587 -131.896098) (xy 153.613163 -131.859592)
			(xy 153.665097 -131.829608) (xy 153.720501 -131.806659) (xy 153.778426 -131.791138) (xy 153.837882 -131.78331)
			(xy 153.89785 -131.78331) (xy 153.957306 -131.791138) (xy 154.015231 -131.806659) (xy 154.070635 -131.829608)
			(xy 154.122569 -131.859592) (xy 154.170145 -131.896098) (xy 154.21255 -131.938503) (xy 154.249056 -131.986079)
			(xy 154.27904 -132.038013) (xy 154.301989 -132.093417) (xy 154.31751 -132.151342) (xy 154.325338 -132.210798)
			(xy 154.325828 -132.240782) (xy 154.325828 -133.096508) (xy 167.884856 -133.096508) (xy 167.884856 -132.232908)
			(xy 167.885346 -132.202924) (xy 167.893174 -132.143468) (xy 167.908695 -132.085543) (xy 167.931644 -132.030139)
			(xy 167.961628 -131.978205) (xy 167.998134 -131.930629) (xy 168.040539 -131.888224) (xy 168.088115 -131.851718)
			(xy 168.140049 -131.821734) (xy 168.195453 -131.798785) (xy 168.253378 -131.783264) (xy 168.312834 -131.775436)
			(xy 168.372802 -131.775436) (xy 168.432258 -131.783264) (xy 168.490183 -131.798785) (xy 168.545587 -131.821734)
			(xy 168.597521 -131.851718) (xy 168.645097 -131.888224) (xy 168.687502 -131.930629) (xy 168.724008 -131.978205)
			(xy 168.753992 -132.030139) (xy 168.776941 -132.085543) (xy 168.792462 -132.143468) (xy 168.80029 -132.202924)
			(xy 168.80078 -132.232908) (xy 168.80078 -132.577332) (xy 180.84546 -132.577332) (xy 180.84546 -131.713732)
			(xy 180.84595 -131.683764) (xy 180.853773 -131.624342) (xy 180.869286 -131.566449) (xy 180.892222 -131.511076)
			(xy 180.922189 -131.45917) (xy 180.958676 -131.41162) (xy 181.001056 -131.36924) (xy 181.048606 -131.332753)
			(xy 181.100512 -131.302786) (xy 181.155885 -131.27985) (xy 181.213778 -131.264337) (xy 181.2732 -131.256514)
			(xy 181.333136 -131.256514) (xy 181.392558 -131.264337) (xy 181.450451 -131.27985) (xy 181.505824 -131.302786)
			(xy 181.55773 -131.332753) (xy 181.60528 -131.36924) (xy 181.64766 -131.41162) (xy 181.684147 -131.45917)
			(xy 181.714114 -131.511076) (xy 181.73705 -131.566449) (xy 181.752563 -131.624342) (xy 181.760386 -131.683764)
			(xy 181.760876 -131.713732) (xy 181.760876 -132.575808) (xy 199.81672 -132.575808) (xy 199.81672 -131.712208)
			(xy 199.81721 -131.68224) (xy 199.825033 -131.622818) (xy 199.840546 -131.564925) (xy 199.863482 -131.509552)
			(xy 199.893449 -131.457646) (xy 199.929936 -131.410096) (xy 199.972316 -131.367716) (xy 200.019866 -131.331229)
			(xy 200.071772 -131.301262) (xy 200.127145 -131.278326) (xy 200.185038 -131.262813) (xy 200.24446 -131.25499)
			(xy 200.304396 -131.25499) (xy 200.363818 -131.262813) (xy 200.421711 -131.278326) (xy 200.469049 -131.297934)
			(xy 266.86764 -131.297934) (xy 266.86764 -130.434334) (xy 266.86813 -130.40435) (xy 266.875958 -130.344894)
			(xy 266.891479 -130.286969) (xy 266.914428 -130.231565) (xy 266.944412 -130.179631) (xy 266.980918 -130.132055)
			(xy 267.023323 -130.08965) (xy 267.070899 -130.053144) (xy 267.122833 -130.02316) (xy 267.178237 -130.000211)
			(xy 267.236162 -129.98469) (xy 267.295618 -129.976862) (xy 267.355586 -129.976862) (xy 267.415042 -129.98469)
			(xy 267.472967 -130.000211) (xy 267.528371 -130.02316) (xy 267.580305 -130.053144) (xy 267.627881 -130.08965)
			(xy 267.670286 -130.132055) (xy 267.706792 -130.179631) (xy 267.736776 -130.231565) (xy 267.759725 -130.286969)
			(xy 267.775246 -130.344894) (xy 267.783074 -130.40435) (xy 267.783564 -130.434334) (xy 267.783564 -131.29641)
			(xy 285.8389 -131.29641) (xy 285.8389 -130.43281) (xy 285.83939 -130.402826) (xy 285.847218 -130.34337)
			(xy 285.862739 -130.285445) (xy 285.885688 -130.230041) (xy 285.915672 -130.178107) (xy 285.952178 -130.130531)
			(xy 285.994583 -130.088126) (xy 286.042159 -130.05162) (xy 286.094093 -130.021636) (xy 286.149497 -129.998687)
			(xy 286.207422 -129.983166) (xy 286.266878 -129.975338) (xy 286.326846 -129.975338) (xy 286.386302 -129.983166)
			(xy 286.444227 -129.998687) (xy 286.499631 -130.021636) (xy 286.551565 -130.05162) (xy 286.599141 -130.088126)
			(xy 286.641546 -130.130531) (xy 286.678052 -130.178107) (xy 286.708036 -130.230041) (xy 286.730985 -130.285445)
			(xy 286.746506 -130.34337) (xy 286.754334 -130.402826) (xy 286.754824 -130.43281) (xy 286.754824 -130.777234)
			(xy 298.799504 -130.777234) (xy 298.799504 -129.913634) (xy 298.799994 -129.883666) (xy 298.807817 -129.824244)
			(xy 298.82333 -129.766351) (xy 298.846266 -129.710978) (xy 298.876233 -129.659072) (xy 298.91272 -129.611522)
			(xy 298.9551 -129.569142) (xy 299.00265 -129.532655) (xy 299.054556 -129.502688) (xy 299.109929 -129.479752)
			(xy 299.167822 -129.464239) (xy 299.227244 -129.456416) (xy 299.28718 -129.456416) (xy 299.346602 -129.464239)
			(xy 299.404495 -129.479752) (xy 299.459868 -129.502688) (xy 299.511774 -129.532655) (xy 299.559324 -129.569142)
			(xy 299.601704 -129.611522) (xy 299.638191 -129.659072) (xy 299.668158 -129.710978) (xy 299.691094 -129.766351)
			(xy 299.706607 -129.824244) (xy 299.71443 -129.883666) (xy 299.71492 -129.913634) (xy 299.71492 -130.769106)
			(xy 313.274456 -130.769106) (xy 313.274456 -129.905506) (xy 313.274946 -129.875538) (xy 313.282769 -129.816116)
			(xy 313.298282 -129.758223) (xy 313.321218 -129.70285) (xy 313.351185 -129.650944) (xy 313.387672 -129.603394)
			(xy 313.430052 -129.561014) (xy 313.477602 -129.524527) (xy 313.529508 -129.49456) (xy 313.584881 -129.471624)
			(xy 313.642774 -129.456111) (xy 313.702196 -129.448288) (xy 313.762132 -129.448288) (xy 313.821554 -129.456111)
			(xy 313.879447 -129.471624) (xy 313.93482 -129.49456) (xy 313.986726 -129.524527) (xy 314.034276 -129.561014)
			(xy 314.076656 -129.603394) (xy 314.113143 -129.650944) (xy 314.14311 -129.70285) (xy 314.166046 -129.758223)
			(xy 314.181559 -129.816116) (xy 314.189382 -129.875538) (xy 314.189872 -129.905506) (xy 314.189872 -130.769106)
			(xy 314.189382 -130.799074) (xy 314.181559 -130.858496) (xy 314.166046 -130.916389) (xy 314.14311 -130.971762)
			(xy 314.113143 -131.023668) (xy 314.076656 -131.071218) (xy 314.034276 -131.113598) (xy 313.986726 -131.150085)
			(xy 313.93482 -131.180052) (xy 313.879447 -131.202988) (xy 313.821554 -131.218501) (xy 313.762132 -131.226324)
			(xy 313.702196 -131.226324) (xy 313.642774 -131.218501) (xy 313.584881 -131.202988) (xy 313.529508 -131.180052)
			(xy 313.477602 -131.150085) (xy 313.430052 -131.113598) (xy 313.387672 -131.071218) (xy 313.351185 -131.023668)
			(xy 313.321218 -130.971762) (xy 313.298282 -130.916389) (xy 313.282769 -130.858496) (xy 313.274946 -130.799074)
			(xy 313.274456 -130.769106) (xy 299.71492 -130.769106) (xy 299.71492 -130.777234) (xy 299.71443 -130.807202)
			(xy 299.706607 -130.866624) (xy 299.691094 -130.924517) (xy 299.668158 -130.97989) (xy 299.638191 -131.031796)
			(xy 299.601704 -131.079346) (xy 299.559324 -131.121726) (xy 299.511774 -131.158213) (xy 299.459868 -131.18818)
			(xy 299.404495 -131.211116) (xy 299.346602 -131.226629) (xy 299.28718 -131.234452) (xy 299.227244 -131.234452)
			(xy 299.167822 -131.226629) (xy 299.109929 -131.211116) (xy 299.054556 -131.18818) (xy 299.00265 -131.158213)
			(xy 298.9551 -131.121726) (xy 298.91272 -131.079346) (xy 298.876233 -131.031796) (xy 298.846266 -130.97989)
			(xy 298.82333 -130.924517) (xy 298.807817 -130.866624) (xy 298.799994 -130.807202) (xy 298.799504 -130.777234)
			(xy 286.754824 -130.777234) (xy 286.754824 -131.29641) (xy 286.754334 -131.326394) (xy 286.746506 -131.38585)
			(xy 286.730985 -131.443775) (xy 286.708036 -131.499179) (xy 286.678052 -131.551113) (xy 286.641546 -131.598689)
			(xy 286.599141 -131.641094) (xy 286.551565 -131.6776) (xy 286.499631 -131.707584) (xy 286.444227 -131.730533)
			(xy 286.386302 -131.746054) (xy 286.326846 -131.753882) (xy 286.266878 -131.753882) (xy 286.207422 -131.746054)
			(xy 286.149497 -131.730533) (xy 286.094093 -131.707584) (xy 286.042159 -131.6776) (xy 285.994583 -131.641094)
			(xy 285.952178 -131.598689) (xy 285.915672 -131.551113) (xy 285.885688 -131.499179) (xy 285.862739 -131.443775)
			(xy 285.847218 -131.38585) (xy 285.83939 -131.326394) (xy 285.8389 -131.29641) (xy 267.783564 -131.29641)
			(xy 267.783564 -131.297934) (xy 267.783074 -131.327918) (xy 267.775246 -131.387374) (xy 267.759725 -131.445299)
			(xy 267.736776 -131.500703) (xy 267.706792 -131.552637) (xy 267.670286 -131.600213) (xy 267.627881 -131.642618)
			(xy 267.580305 -131.679124) (xy 267.528371 -131.709108) (xy 267.472967 -131.732057) (xy 267.415042 -131.747578)
			(xy 267.355586 -131.755406) (xy 267.295618 -131.755406) (xy 267.236162 -131.747578) (xy 267.178237 -131.732057)
			(xy 267.122833 -131.709108) (xy 267.070899 -131.679124) (xy 267.023323 -131.642618) (xy 266.980918 -131.600213)
			(xy 266.944412 -131.552637) (xy 266.914428 -131.500703) (xy 266.891479 -131.445299) (xy 266.875958 -131.387374)
			(xy 266.86813 -131.327918) (xy 266.86764 -131.297934) (xy 200.469049 -131.297934) (xy 200.477084 -131.301262)
			(xy 200.52899 -131.331229) (xy 200.57654 -131.367716) (xy 200.61892 -131.410096) (xy 200.655407 -131.457646)
			(xy 200.685374 -131.509552) (xy 200.70831 -131.564925) (xy 200.723823 -131.622818) (xy 200.731646 -131.68224)
			(xy 200.732136 -131.712208) (xy 200.732136 -132.575808) (xy 200.731646 -132.605776) (xy 200.723823 -132.665198)
			(xy 200.70831 -132.723091) (xy 200.685374 -132.778464) (xy 200.655407 -132.83037) (xy 200.61892 -132.87792)
			(xy 200.57654 -132.9203) (xy 200.52899 -132.956787) (xy 200.477084 -132.986754) (xy 200.421711 -133.00969)
			(xy 200.363818 -133.025203) (xy 200.304396 -133.033026) (xy 200.24446 -133.033026) (xy 200.185038 -133.025203)
			(xy 200.127145 -133.00969) (xy 200.071772 -132.986754) (xy 200.019866 -132.956787) (xy 199.972316 -132.9203)
			(xy 199.929936 -132.87792) (xy 199.893449 -132.83037) (xy 199.863482 -132.778464) (xy 199.840546 -132.723091)
			(xy 199.825033 -132.665198) (xy 199.81721 -132.605776) (xy 199.81672 -132.575808) (xy 181.760876 -132.575808)
			(xy 181.760876 -132.577332) (xy 181.760386 -132.6073) (xy 181.752563 -132.666722) (xy 181.73705 -132.724615)
			(xy 181.714114 -132.779988) (xy 181.684147 -132.831894) (xy 181.64766 -132.879444) (xy 181.60528 -132.921824)
			(xy 181.55773 -132.958311) (xy 181.505824 -132.988278) (xy 181.450451 -133.011214) (xy 181.392558 -133.026727)
			(xy 181.333136 -133.03455) (xy 181.2732 -133.03455) (xy 181.213778 -133.026727) (xy 181.155885 -133.011214)
			(xy 181.100512 -132.988278) (xy 181.048606 -132.958311) (xy 181.001056 -132.921824) (xy 180.958676 -132.879444)
			(xy 180.922189 -132.831894) (xy 180.892222 -132.779988) (xy 180.869286 -132.724615) (xy 180.853773 -132.666722)
			(xy 180.84595 -132.6073) (xy 180.84546 -132.577332) (xy 168.80078 -132.577332) (xy 168.80078 -133.096508)
			(xy 168.80029 -133.126492) (xy 168.792462 -133.185948) (xy 168.776941 -133.243873) (xy 168.753992 -133.299277)
			(xy 168.724008 -133.351211) (xy 168.687502 -133.398787) (xy 168.645097 -133.441192) (xy 168.597521 -133.477698)
			(xy 168.545587 -133.507682) (xy 168.490183 -133.530631) (xy 168.432258 -133.546152) (xy 168.372802 -133.55398)
			(xy 168.312834 -133.55398) (xy 168.253378 -133.546152) (xy 168.195453 -133.530631) (xy 168.140049 -133.507682)
			(xy 168.088115 -133.477698) (xy 168.040539 -133.441192) (xy 167.998134 -133.398787) (xy 167.961628 -133.351211)
			(xy 167.931644 -133.299277) (xy 167.908695 -133.243873) (xy 167.893174 -133.185948) (xy 167.885346 -133.126492)
			(xy 167.884856 -133.096508) (xy 154.325828 -133.096508) (xy 154.325828 -133.104382) (xy 154.325338 -133.134366)
			(xy 154.31751 -133.193822) (xy 154.301989 -133.251747) (xy 154.27904 -133.307151) (xy 154.249056 -133.359085)
			(xy 154.21255 -133.406661) (xy 154.170145 -133.449066) (xy 154.122569 -133.485572) (xy 154.070635 -133.515556)
			(xy 154.015231 -133.538505) (xy 153.957306 -133.554026) (xy 153.89785 -133.561854) (xy 153.837882 -133.561854)
			(xy 153.778426 -133.554026) (xy 153.720501 -133.538505) (xy 153.665097 -133.515556) (xy 153.613163 -133.485572)
			(xy 153.565587 -133.449066) (xy 153.523182 -133.406661) (xy 153.486676 -133.359085) (xy 153.456692 -133.307151)
			(xy 153.433743 -133.251747) (xy 153.418222 -133.193822) (xy 153.410394 -133.134366) (xy 153.409904 -133.104382)
			(xy 81.752059 -133.104382) (xy 81.786925 -133.124512) (xy 81.834501 -133.161018) (xy 81.876906 -133.203423)
			(xy 81.913412 -133.250999) (xy 81.943396 -133.302933) (xy 81.966345 -133.358337) (xy 81.981866 -133.416262)
			(xy 81.989694 -133.475718) (xy 81.990184 -133.505702) (xy 81.990184 -134.369302) (xy 81.989694 -134.399286)
			(xy 81.981866 -134.458742) (xy 81.966345 -134.516667) (xy 81.943396 -134.572071) (xy 81.913412 -134.624005)
			(xy 81.876906 -134.671581) (xy 81.834501 -134.713986) (xy 81.786925 -134.750492) (xy 81.734991 -134.780476)
			(xy 81.679587 -134.803425) (xy 81.621662 -134.818946) (xy 81.562206 -134.826774) (xy 81.502238 -134.826774)
			(xy 81.442782 -134.818946) (xy 81.384857 -134.803425) (xy 81.329453 -134.780476) (xy 81.277519 -134.750492)
			(xy 81.229943 -134.713986) (xy 81.187538 -134.671581) (xy 81.151032 -134.624005) (xy 81.121048 -134.572071)
			(xy 81.098099 -134.516667) (xy 81.082578 -134.458742) (xy 81.07475 -134.399286) (xy 81.07426 -134.369302)
			(xy 67.515232 -134.369302) (xy 67.515232 -134.377176) (xy 67.514742 -134.40716) (xy 67.506914 -134.466616)
			(xy 67.491393 -134.524541) (xy 67.468444 -134.579945) (xy 67.43846 -134.631879) (xy 67.401954 -134.679455)
			(xy 67.359549 -134.72186) (xy 67.311973 -134.758366) (xy 67.260039 -134.78835) (xy 67.204635 -134.811299)
			(xy 67.14671 -134.82682) (xy 67.087254 -134.834648) (xy 67.027286 -134.834648) (xy 66.96783 -134.82682)
			(xy 66.909905 -134.811299) (xy 66.854501 -134.78835) (xy 66.802567 -134.758366) (xy 66.754991 -134.72186)
			(xy 66.712586 -134.679455) (xy 66.67608 -134.631879) (xy 66.646096 -134.579945) (xy 66.623147 -134.524541)
			(xy 66.607626 -134.466616) (xy 66.599798 -134.40716) (xy 66.599308 -134.377176) (xy 54.554628 -134.377176)
			(xy 54.554628 -134.896352) (xy 54.554138 -134.92632) (xy 54.546315 -134.985742) (xy 54.530802 -135.043635)
			(xy 54.507866 -135.099008) (xy 54.477899 -135.150914) (xy 54.441412 -135.198464) (xy 54.399032 -135.240844)
			(xy 54.351482 -135.277331) (xy 54.299576 -135.307298) (xy 54.244203 -135.330234) (xy 54.18631 -135.345747)
			(xy 54.126888 -135.35357) (xy 54.066952 -135.35357) (xy 54.00753 -135.345747) (xy 53.949637 -135.330234)
			(xy 53.894264 -135.307298) (xy 53.842358 -135.277331) (xy 53.794808 -135.240844) (xy 53.752428 -135.198464)
			(xy 53.715941 -135.150914) (xy 53.685974 -135.099008) (xy 53.663038 -135.043635) (xy 53.647525 -134.985742)
			(xy 53.639702 -134.92632) (xy 53.639212 -134.896352) (xy 35.583368 -134.896352) (xy 35.583368 -134.897876)
			(xy 35.582878 -134.927844) (xy 35.575055 -134.987266) (xy 35.559542 -135.045159) (xy 35.536606 -135.100532)
			(xy 35.506639 -135.152438) (xy 35.470152 -135.199988) (xy 35.427772 -135.242368) (xy 35.380222 -135.278855)
			(xy 35.328316 -135.308822) (xy 35.272943 -135.331758) (xy 35.21505 -135.347271) (xy 35.155628 -135.355094)
			(xy 35.095692 -135.355094) (xy 35.03627 -135.347271) (xy 34.978377 -135.331758) (xy 34.923004 -135.308822)
			(xy 34.871098 -135.278855) (xy 34.823548 -135.242368) (xy 34.781168 -135.199988) (xy 34.744681 -135.152438)
			(xy 34.714714 -135.100532) (xy 34.691778 -135.045159) (xy 34.676265 -134.987266) (xy 34.668442 -134.927844)
			(xy 34.667952 -134.897876) (xy 4.308094 -134.897876) (xy 4.308094 -136.704324) (xy 37.31006 -136.704324)
			(xy 37.31006 -135.840724) (xy 37.31055 -135.810756) (xy 37.318373 -135.751334) (xy 37.333886 -135.693441)
			(xy 37.356822 -135.638068) (xy 37.386789 -135.586162) (xy 37.423276 -135.538612) (xy 37.465656 -135.496232)
			(xy 37.513206 -135.459745) (xy 37.565112 -135.429778) (xy 37.620485 -135.406842) (xy 37.678378 -135.391329)
			(xy 37.7378 -135.383506) (xy 37.797736 -135.383506) (xy 37.857158 -135.391329) (xy 37.915051 -135.406842)
			(xy 37.970424 -135.429778) (xy 38.02233 -135.459745) (xy 38.06988 -135.496232) (xy 38.11226 -135.538612)
			(xy 38.148747 -135.586162) (xy 38.178714 -135.638068) (xy 38.20165 -135.693441) (xy 38.217163 -135.751334)
			(xy 38.224986 -135.810756) (xy 38.225476 -135.840724) (xy 38.225476 -136.69645) (xy 51.785012 -136.69645)
			(xy 51.785012 -135.83285) (xy 51.785502 -135.802882) (xy 51.793325 -135.74346) (xy 51.808838 -135.685567)
			(xy 51.831774 -135.630194) (xy 51.861741 -135.578288) (xy 51.898228 -135.530738) (xy 51.940608 -135.488358)
			(xy 51.988158 -135.451871) (xy 52.040064 -135.421904) (xy 52.095437 -135.398968) (xy 52.15333 -135.383455)
			(xy 52.212752 -135.375632) (xy 52.272688 -135.375632) (xy 52.33211 -135.383455) (xy 52.390003 -135.398968)
			(xy 52.445376 -135.421904) (xy 52.497282 -135.451871) (xy 52.544832 -135.488358) (xy 52.587212 -135.530738)
			(xy 52.623699 -135.578288) (xy 52.653666 -135.630194) (xy 52.676602 -135.685567) (xy 52.692115 -135.74346)
			(xy 52.699938 -135.802882) (xy 52.700428 -135.83285) (xy 52.700428 -136.177274) (xy 64.745108 -136.177274)
			(xy 64.745108 -135.313674) (xy 64.745598 -135.28369) (xy 64.753426 -135.224234) (xy 64.768947 -135.166309)
			(xy 64.791896 -135.110905) (xy 64.82188 -135.058971) (xy 64.858386 -135.011395) (xy 64.900791 -134.96899)
			(xy 64.948367 -134.932484) (xy 65.000301 -134.9025) (xy 65.055705 -134.879551) (xy 65.11363 -134.86403)
			(xy 65.173086 -134.856202) (xy 65.233054 -134.856202) (xy 65.29251 -134.86403) (xy 65.350435 -134.879551)
			(xy 65.405839 -134.9025) (xy 65.457773 -134.932484) (xy 65.505349 -134.96899) (xy 65.547754 -135.011395)
			(xy 65.58426 -135.058971) (xy 65.614244 -135.110905) (xy 65.637193 -135.166309) (xy 65.652714 -135.224234)
			(xy 65.660542 -135.28369) (xy 65.661032 -135.313674) (xy 65.661032 -136.17575) (xy 83.716368 -136.17575)
			(xy 83.716368 -135.31215) (xy 83.716858 -135.282166) (xy 83.724686 -135.22271) (xy 83.740207 -135.164785)
			(xy 83.763156 -135.109381) (xy 83.79314 -135.057447) (xy 83.829646 -135.009871) (xy 83.872051 -134.967466)
			(xy 83.919627 -134.93096) (xy 83.971561 -134.900976) (xy 84.026965 -134.878027) (xy 84.08489 -134.862506)
			(xy 84.144346 -134.854678) (xy 84.204314 -134.854678) (xy 84.26377 -134.862506) (xy 84.321695 -134.878027)
			(xy 84.369615 -134.897876) (xy 150.767796 -134.897876) (xy 150.767796 -134.034276) (xy 150.768286 -134.004292)
			(xy 150.776114 -133.944836) (xy 150.791635 -133.886911) (xy 150.814584 -133.831507) (xy 150.844568 -133.779573)
			(xy 150.881074 -133.731997) (xy 150.923479 -133.689592) (xy 150.971055 -133.653086) (xy 151.022989 -133.623102)
			(xy 151.078393 -133.600153) (xy 151.136318 -133.584632) (xy 151.195774 -133.576804) (xy 151.255742 -133.576804)
			(xy 151.315198 -133.584632) (xy 151.373123 -133.600153) (xy 151.428527 -133.623102) (xy 151.480461 -133.653086)
			(xy 151.528037 -133.689592) (xy 151.570442 -133.731997) (xy 151.606948 -133.779573) (xy 151.636932 -133.831507)
			(xy 151.659881 -133.886911) (xy 151.675402 -133.944836) (xy 151.68323 -134.004292) (xy 151.68372 -134.034276)
			(xy 151.68372 -134.896352) (xy 169.739056 -134.896352) (xy 169.739056 -134.032752) (xy 169.739546 -134.002768)
			(xy 169.747374 -133.943312) (xy 169.762895 -133.885387) (xy 169.785844 -133.829983) (xy 169.815828 -133.778049)
			(xy 169.852334 -133.730473) (xy 169.894739 -133.688068) (xy 169.942315 -133.651562) (xy 169.994249 -133.621578)
			(xy 170.049653 -133.598629) (xy 170.107578 -133.583108) (xy 170.167034 -133.57528) (xy 170.227002 -133.57528)
			(xy 170.286458 -133.583108) (xy 170.344383 -133.598629) (xy 170.399787 -133.621578) (xy 170.451721 -133.651562)
			(xy 170.499297 -133.688068) (xy 170.541702 -133.730473) (xy 170.578208 -133.778049) (xy 170.608192 -133.829983)
			(xy 170.631141 -133.885387) (xy 170.646662 -133.943312) (xy 170.65449 -134.002768) (xy 170.65498 -134.032752)
			(xy 170.65498 -134.377176) (xy 182.69966 -134.377176) (xy 182.69966 -133.513576) (xy 182.70015 -133.483608)
			(xy 182.707973 -133.424186) (xy 182.723486 -133.366293) (xy 182.746422 -133.31092) (xy 182.776389 -133.259014)
			(xy 182.812876 -133.211464) (xy 182.855256 -133.169084) (xy 182.902806 -133.132597) (xy 182.954712 -133.10263)
			(xy 183.010085 -133.079694) (xy 183.067978 -133.064181) (xy 183.1274 -133.056358) (xy 183.187336 -133.056358)
			(xy 183.246758 -133.064181) (xy 183.304651 -133.079694) (xy 183.360024 -133.10263) (xy 183.41193 -133.132597)
			(xy 183.45948 -133.169084) (xy 183.50186 -133.211464) (xy 183.538347 -133.259014) (xy 183.568314 -133.31092)
			(xy 183.59125 -133.366293) (xy 183.606763 -133.424186) (xy 183.614586 -133.483608) (xy 183.615076 -133.513576)
			(xy 183.615076 -134.369302) (xy 197.174612 -134.369302) (xy 197.174612 -133.505702) (xy 197.175102 -133.475734)
			(xy 197.182925 -133.416312) (xy 197.198438 -133.358419) (xy 197.221374 -133.303046) (xy 197.251341 -133.25114)
			(xy 197.287828 -133.20359) (xy 197.330208 -133.16121) (xy 197.377758 -133.124723) (xy 197.429664 -133.094756)
			(xy 197.485037 -133.07182) (xy 197.54293 -133.056307) (xy 197.602352 -133.048484) (xy 197.662288 -133.048484)
			(xy 197.72171 -133.056307) (xy 197.779603 -133.07182) (xy 197.834976 -133.094756) (xy 197.851649 -133.104382)
			(xy 269.509748 -133.104382) (xy 269.509748 -132.240782) (xy 269.510238 -132.210798) (xy 269.518066 -132.151342)
			(xy 269.533587 -132.093417) (xy 269.556536 -132.038013) (xy 269.58652 -131.986079) (xy 269.623026 -131.938503)
			(xy 269.665431 -131.896098) (xy 269.713007 -131.859592) (xy 269.764941 -131.829608) (xy 269.820345 -131.806659)
			(xy 269.87827 -131.791138) (xy 269.937726 -131.78331) (xy 269.997694 -131.78331) (xy 270.05715 -131.791138)
			(xy 270.115075 -131.806659) (xy 270.170479 -131.829608) (xy 270.222413 -131.859592) (xy 270.269989 -131.896098)
			(xy 270.312394 -131.938503) (xy 270.3489 -131.986079) (xy 270.378884 -132.038013) (xy 270.401833 -132.093417)
			(xy 270.417354 -132.151342) (xy 270.425182 -132.210798) (xy 270.425672 -132.240782) (xy 270.425672 -133.096508)
			(xy 283.9847 -133.096508) (xy 283.9847 -132.232908) (xy 283.98519 -132.202924) (xy 283.993018 -132.143468)
			(xy 284.008539 -132.085543) (xy 284.031488 -132.030139) (xy 284.061472 -131.978205) (xy 284.097978 -131.930629)
			(xy 284.140383 -131.888224) (xy 284.187959 -131.851718) (xy 284.239893 -131.821734) (xy 284.295297 -131.798785)
			(xy 284.353222 -131.783264) (xy 284.412678 -131.775436) (xy 284.472646 -131.775436) (xy 284.532102 -131.783264)
			(xy 284.590027 -131.798785) (xy 284.645431 -131.821734) (xy 284.697365 -131.851718) (xy 284.744941 -131.888224)
			(xy 284.787346 -131.930629) (xy 284.823852 -131.978205) (xy 284.853836 -132.030139) (xy 284.876785 -132.085543)
			(xy 284.892306 -132.143468) (xy 284.900134 -132.202924) (xy 284.900624 -132.232908) (xy 284.900624 -132.577332)
			(xy 296.945304 -132.577332) (xy 296.945304 -131.713732) (xy 296.945794 -131.683764) (xy 296.953617 -131.624342)
			(xy 296.96913 -131.566449) (xy 296.992066 -131.511076) (xy 297.022033 -131.45917) (xy 297.05852 -131.41162)
			(xy 297.1009 -131.36924) (xy 297.14845 -131.332753) (xy 297.200356 -131.302786) (xy 297.255729 -131.27985)
			(xy 297.313622 -131.264337) (xy 297.373044 -131.256514) (xy 297.43298 -131.256514) (xy 297.492402 -131.264337)
			(xy 297.550295 -131.27985) (xy 297.605668 -131.302786) (xy 297.657574 -131.332753) (xy 297.705124 -131.36924)
			(xy 297.747504 -131.41162) (xy 297.783991 -131.45917) (xy 297.813958 -131.511076) (xy 297.836894 -131.566449)
			(xy 297.852407 -131.624342) (xy 297.86023 -131.683764) (xy 297.86072 -131.713732) (xy 297.86072 -132.575808)
			(xy 315.916564 -132.575808) (xy 315.916564 -131.712208) (xy 315.917054 -131.68224) (xy 315.924877 -131.622818)
			(xy 315.94039 -131.564925) (xy 315.963326 -131.509552) (xy 315.993293 -131.457646) (xy 316.02978 -131.410096)
			(xy 316.07216 -131.367716) (xy 316.11971 -131.331229) (xy 316.171616 -131.301262) (xy 316.226989 -131.278326)
			(xy 316.284882 -131.262813) (xy 316.344304 -131.25499) (xy 316.40424 -131.25499) (xy 316.463662 -131.262813)
			(xy 316.521555 -131.278326) (xy 316.568893 -131.297934) (xy 382.967992 -131.297934) (xy 382.967992 -130.434334)
			(xy 382.968482 -130.404366) (xy 382.976305 -130.344944) (xy 382.991818 -130.287051) (xy 383.014754 -130.231678)
			(xy 383.044721 -130.179772) (xy 383.081208 -130.132222) (xy 383.123588 -130.089842) (xy 383.171138 -130.053355)
			(xy 383.223044 -130.023388) (xy 383.278417 -130.000452) (xy 383.33631 -129.984939) (xy 383.395732 -129.977116)
			(xy 383.455668 -129.977116) (xy 383.51509 -129.984939) (xy 383.572983 -130.000452) (xy 383.628356 -130.023388)
			(xy 383.680262 -130.053355) (xy 383.727812 -130.089842) (xy 383.770192 -130.132222) (xy 383.806679 -130.179772)
			(xy 383.836646 -130.231678) (xy 383.859582 -130.287051) (xy 383.875095 -130.344944) (xy 383.882918 -130.404366)
			(xy 383.883408 -130.434334) (xy 383.883408 -131.29641) (xy 401.939252 -131.29641) (xy 401.939252 -130.43281)
			(xy 401.939742 -130.402842) (xy 401.947565 -130.34342) (xy 401.963078 -130.285527) (xy 401.986014 -130.230154)
			(xy 402.015981 -130.178248) (xy 402.052468 -130.130698) (xy 402.094848 -130.088318) (xy 402.142398 -130.051831)
			(xy 402.194304 -130.021864) (xy 402.249677 -129.998928) (xy 402.30757 -129.983415) (xy 402.366992 -129.975592)
			(xy 402.426928 -129.975592) (xy 402.48635 -129.983415) (xy 402.544243 -129.998928) (xy 402.599616 -130.021864)
			(xy 402.651522 -130.051831) (xy 402.699072 -130.088318) (xy 402.741452 -130.130698) (xy 402.777939 -130.178248)
			(xy 402.807906 -130.230154) (xy 402.830842 -130.285527) (xy 402.846355 -130.34342) (xy 402.854178 -130.402842)
			(xy 402.854668 -130.43281) (xy 402.854668 -130.777234) (xy 414.899348 -130.777234) (xy 414.899348 -129.913634)
			(xy 414.899838 -129.88365) (xy 414.907666 -129.824194) (xy 414.923187 -129.766269) (xy 414.946136 -129.710865)
			(xy 414.97612 -129.658931) (xy 415.012626 -129.611355) (xy 415.055031 -129.56895) (xy 415.102607 -129.532444)
			(xy 415.154541 -129.50246) (xy 415.209945 -129.479511) (xy 415.26787 -129.46399) (xy 415.327326 -129.456162)
			(xy 415.387294 -129.456162) (xy 415.44675 -129.46399) (xy 415.504675 -129.479511) (xy 415.560079 -129.50246)
			(xy 415.612013 -129.532444) (xy 415.659589 -129.56895) (xy 415.701994 -129.611355) (xy 415.7385 -129.658931)
			(xy 415.768484 -129.710865) (xy 415.791433 -129.766269) (xy 415.806954 -129.824194) (xy 415.814782 -129.88365)
			(xy 415.815272 -129.913634) (xy 415.815272 -130.769106) (xy 429.3743 -130.769106) (xy 429.3743 -129.905506)
			(xy 429.37479 -129.875522) (xy 429.382618 -129.816066) (xy 429.398139 -129.758141) (xy 429.421088 -129.702737)
			(xy 429.451072 -129.650803) (xy 429.487578 -129.603227) (xy 429.529983 -129.560822) (xy 429.577559 -129.524316)
			(xy 429.629493 -129.494332) (xy 429.684897 -129.471383) (xy 429.742822 -129.455862) (xy 429.802278 -129.448034)
			(xy 429.862246 -129.448034) (xy 429.921702 -129.455862) (xy 429.979627 -129.471383) (xy 430.035031 -129.494332)
			(xy 430.086965 -129.524316) (xy 430.134541 -129.560822) (xy 430.176946 -129.603227) (xy 430.213452 -129.650803)
			(xy 430.243436 -129.702737) (xy 430.266385 -129.758141) (xy 430.281906 -129.816066) (xy 430.289734 -129.875522)
			(xy 430.290224 -129.905506) (xy 430.290224 -130.769106) (xy 430.289734 -130.79909) (xy 430.281906 -130.858546)
			(xy 430.266385 -130.916471) (xy 430.243436 -130.971875) (xy 430.213452 -131.023809) (xy 430.176946 -131.071385)
			(xy 430.134541 -131.11379) (xy 430.086965 -131.150296) (xy 430.035031 -131.18028) (xy 429.979627 -131.203229)
			(xy 429.921702 -131.21875) (xy 429.862246 -131.226578) (xy 429.802278 -131.226578) (xy 429.742822 -131.21875)
			(xy 429.684897 -131.203229) (xy 429.629493 -131.18028) (xy 429.577559 -131.150296) (xy 429.529983 -131.11379)
			(xy 429.487578 -131.071385) (xy 429.451072 -131.023809) (xy 429.421088 -130.971875) (xy 429.398139 -130.916471)
			(xy 429.382618 -130.858546) (xy 429.37479 -130.79909) (xy 429.3743 -130.769106) (xy 415.815272 -130.769106)
			(xy 415.815272 -130.777234) (xy 415.814782 -130.807218) (xy 415.806954 -130.866674) (xy 415.791433 -130.924599)
			(xy 415.768484 -130.980003) (xy 415.7385 -131.031937) (xy 415.701994 -131.079513) (xy 415.659589 -131.121918)
			(xy 415.612013 -131.158424) (xy 415.560079 -131.188408) (xy 415.504675 -131.211357) (xy 415.44675 -131.226878)
			(xy 415.387294 -131.234706) (xy 415.327326 -131.234706) (xy 415.26787 -131.226878) (xy 415.209945 -131.211357)
			(xy 415.154541 -131.188408) (xy 415.102607 -131.158424) (xy 415.055031 -131.121918) (xy 415.012626 -131.079513)
			(xy 414.97612 -131.031937) (xy 414.946136 -130.980003) (xy 414.923187 -130.924599) (xy 414.907666 -130.866674)
			(xy 414.899838 -130.807218) (xy 414.899348 -130.777234) (xy 402.854668 -130.777234) (xy 402.854668 -131.29641)
			(xy 402.854178 -131.326378) (xy 402.846355 -131.3858) (xy 402.830842 -131.443693) (xy 402.807906 -131.499066)
			(xy 402.777939 -131.550972) (xy 402.741452 -131.598522) (xy 402.699072 -131.640902) (xy 402.651522 -131.677389)
			(xy 402.599616 -131.707356) (xy 402.544243 -131.730292) (xy 402.48635 -131.745805) (xy 402.426928 -131.753628)
			(xy 402.366992 -131.753628) (xy 402.30757 -131.745805) (xy 402.249677 -131.730292) (xy 402.194304 -131.707356)
			(xy 402.142398 -131.677389) (xy 402.094848 -131.640902) (xy 402.052468 -131.598522) (xy 402.015981 -131.550972)
			(xy 401.986014 -131.499066) (xy 401.963078 -131.443693) (xy 401.947565 -131.3858) (xy 401.939742 -131.326378)
			(xy 401.939252 -131.29641) (xy 383.883408 -131.29641) (xy 383.883408 -131.297934) (xy 383.882918 -131.327902)
			(xy 383.875095 -131.387324) (xy 383.859582 -131.445217) (xy 383.836646 -131.50059) (xy 383.806679 -131.552496)
			(xy 383.770192 -131.600046) (xy 383.727812 -131.642426) (xy 383.680262 -131.678913) (xy 383.628356 -131.70888)
			(xy 383.572983 -131.731816) (xy 383.51509 -131.747329) (xy 383.455668 -131.755152) (xy 383.395732 -131.755152)
			(xy 383.33631 -131.747329) (xy 383.278417 -131.731816) (xy 383.223044 -131.70888) (xy 383.171138 -131.678913)
			(xy 383.123588 -131.642426) (xy 383.081208 -131.600046) (xy 383.044721 -131.552496) (xy 383.014754 -131.50059)
			(xy 382.991818 -131.445217) (xy 382.976305 -131.387324) (xy 382.968482 -131.327902) (xy 382.967992 -131.297934)
			(xy 316.568893 -131.297934) (xy 316.576928 -131.301262) (xy 316.628834 -131.331229) (xy 316.676384 -131.367716)
			(xy 316.718764 -131.410096) (xy 316.755251 -131.457646) (xy 316.785218 -131.509552) (xy 316.808154 -131.564925)
			(xy 316.823667 -131.622818) (xy 316.83149 -131.68224) (xy 316.83198 -131.712208) (xy 316.83198 -132.575808)
			(xy 316.83149 -132.605776) (xy 316.823667 -132.665198) (xy 316.808154 -132.723091) (xy 316.785218 -132.778464)
			(xy 316.755251 -132.83037) (xy 316.718764 -132.87792) (xy 316.676384 -132.9203) (xy 316.628834 -132.956787)
			(xy 316.576928 -132.986754) (xy 316.521555 -133.00969) (xy 316.463662 -133.025203) (xy 316.40424 -133.033026)
			(xy 316.344304 -133.033026) (xy 316.284882 -133.025203) (xy 316.226989 -133.00969) (xy 316.171616 -132.986754)
			(xy 316.11971 -132.956787) (xy 316.07216 -132.9203) (xy 316.02978 -132.87792) (xy 315.993293 -132.83037)
			(xy 315.963326 -132.778464) (xy 315.94039 -132.723091) (xy 315.924877 -132.665198) (xy 315.917054 -132.605776)
			(xy 315.916564 -132.575808) (xy 297.86072 -132.575808) (xy 297.86072 -132.577332) (xy 297.86023 -132.6073)
			(xy 297.852407 -132.666722) (xy 297.836894 -132.724615) (xy 297.813958 -132.779988) (xy 297.783991 -132.831894)
			(xy 297.747504 -132.879444) (xy 297.705124 -132.921824) (xy 297.657574 -132.958311) (xy 297.605668 -132.988278)
			(xy 297.550295 -133.011214) (xy 297.492402 -133.026727) (xy 297.43298 -133.03455) (xy 297.373044 -133.03455)
			(xy 297.313622 -133.026727) (xy 297.255729 -133.011214) (xy 297.200356 -132.988278) (xy 297.14845 -132.958311)
			(xy 297.1009 -132.921824) (xy 297.05852 -132.879444) (xy 297.022033 -132.831894) (xy 296.992066 -132.779988)
			(xy 296.96913 -132.724615) (xy 296.953617 -132.666722) (xy 296.945794 -132.6073) (xy 296.945304 -132.577332)
			(xy 284.900624 -132.577332) (xy 284.900624 -133.096508) (xy 284.900134 -133.126492) (xy 284.892306 -133.185948)
			(xy 284.876785 -133.243873) (xy 284.853836 -133.299277) (xy 284.823852 -133.351211) (xy 284.787346 -133.398787)
			(xy 284.744941 -133.441192) (xy 284.697365 -133.477698) (xy 284.645431 -133.507682) (xy 284.590027 -133.530631)
			(xy 284.532102 -133.546152) (xy 284.472646 -133.55398) (xy 284.412678 -133.55398) (xy 284.353222 -133.546152)
			(xy 284.295297 -133.530631) (xy 284.239893 -133.507682) (xy 284.187959 -133.477698) (xy 284.140383 -133.441192)
			(xy 284.097978 -133.398787) (xy 284.061472 -133.351211) (xy 284.031488 -133.299277) (xy 284.008539 -133.243873)
			(xy 283.993018 -133.185948) (xy 283.98519 -133.126492) (xy 283.9847 -133.096508) (xy 270.425672 -133.096508)
			(xy 270.425672 -133.104382) (xy 270.425182 -133.134366) (xy 270.417354 -133.193822) (xy 270.401833 -133.251747)
			(xy 270.378884 -133.307151) (xy 270.3489 -133.359085) (xy 270.312394 -133.406661) (xy 270.269989 -133.449066)
			(xy 270.222413 -133.485572) (xy 270.170479 -133.515556) (xy 270.115075 -133.538505) (xy 270.05715 -133.554026)
			(xy 269.997694 -133.561854) (xy 269.937726 -133.561854) (xy 269.87827 -133.554026) (xy 269.820345 -133.538505)
			(xy 269.764941 -133.515556) (xy 269.713007 -133.485572) (xy 269.665431 -133.449066) (xy 269.623026 -133.406661)
			(xy 269.58652 -133.359085) (xy 269.556536 -133.307151) (xy 269.533587 -133.251747) (xy 269.518066 -133.193822)
			(xy 269.510238 -133.134366) (xy 269.509748 -133.104382) (xy 197.851649 -133.104382) (xy 197.886882 -133.124723)
			(xy 197.934432 -133.16121) (xy 197.976812 -133.20359) (xy 198.013299 -133.25114) (xy 198.043266 -133.303046)
			(xy 198.066202 -133.358419) (xy 198.081715 -133.416312) (xy 198.089538 -133.475734) (xy 198.090028 -133.505702)
			(xy 198.090028 -134.369302) (xy 198.089538 -134.39927) (xy 198.081715 -134.458692) (xy 198.066202 -134.516585)
			(xy 198.043266 -134.571958) (xy 198.013299 -134.623864) (xy 197.976812 -134.671414) (xy 197.934432 -134.713794)
			(xy 197.886882 -134.750281) (xy 197.834976 -134.780248) (xy 197.779603 -134.803184) (xy 197.72171 -134.818697)
			(xy 197.662288 -134.82652) (xy 197.602352 -134.82652) (xy 197.54293 -134.818697) (xy 197.485037 -134.803184)
			(xy 197.429664 -134.780248) (xy 197.377758 -134.750281) (xy 197.330208 -134.713794) (xy 197.287828 -134.671414)
			(xy 197.251341 -134.623864) (xy 197.221374 -134.571958) (xy 197.198438 -134.516585) (xy 197.182925 -134.458692)
			(xy 197.175102 -134.39927) (xy 197.174612 -134.369302) (xy 183.615076 -134.369302) (xy 183.615076 -134.377176)
			(xy 183.614586 -134.407144) (xy 183.606763 -134.466566) (xy 183.59125 -134.524459) (xy 183.568314 -134.579832)
			(xy 183.538347 -134.631738) (xy 183.50186 -134.679288) (xy 183.45948 -134.721668) (xy 183.41193 -134.758155)
			(xy 183.360024 -134.788122) (xy 183.304651 -134.811058) (xy 183.246758 -134.826571) (xy 183.187336 -134.834394)
			(xy 183.1274 -134.834394) (xy 183.067978 -134.826571) (xy 183.010085 -134.811058) (xy 182.954712 -134.788122)
			(xy 182.902806 -134.758155) (xy 182.855256 -134.721668) (xy 182.812876 -134.679288) (xy 182.776389 -134.631738)
			(xy 182.746422 -134.579832) (xy 182.723486 -134.524459) (xy 182.707973 -134.466566) (xy 182.70015 -134.407144)
			(xy 182.69966 -134.377176) (xy 170.65498 -134.377176) (xy 170.65498 -134.896352) (xy 170.65449 -134.926336)
			(xy 170.646662 -134.985792) (xy 170.631141 -135.043717) (xy 170.608192 -135.099121) (xy 170.578208 -135.151055)
			(xy 170.541702 -135.198631) (xy 170.499297 -135.241036) (xy 170.451721 -135.277542) (xy 170.399787 -135.307526)
			(xy 170.344383 -135.330475) (xy 170.286458 -135.345996) (xy 170.227002 -135.353824) (xy 170.167034 -135.353824)
			(xy 170.107578 -135.345996) (xy 170.049653 -135.330475) (xy 169.994249 -135.307526) (xy 169.942315 -135.277542)
			(xy 169.894739 -135.241036) (xy 169.852334 -135.198631) (xy 169.815828 -135.151055) (xy 169.785844 -135.099121)
			(xy 169.762895 -135.043717) (xy 169.747374 -134.985792) (xy 169.739546 -134.926336) (xy 169.739056 -134.896352)
			(xy 151.68372 -134.896352) (xy 151.68372 -134.897876) (xy 151.68323 -134.92786) (xy 151.675402 -134.987316)
			(xy 151.659881 -135.045241) (xy 151.636932 -135.100645) (xy 151.606948 -135.152579) (xy 151.570442 -135.200155)
			(xy 151.528037 -135.24256) (xy 151.480461 -135.279066) (xy 151.428527 -135.30905) (xy 151.373123 -135.331999)
			(xy 151.315198 -135.34752) (xy 151.255742 -135.355348) (xy 151.195774 -135.355348) (xy 151.136318 -135.34752)
			(xy 151.078393 -135.331999) (xy 151.022989 -135.30905) (xy 150.971055 -135.279066) (xy 150.923479 -135.24256)
			(xy 150.881074 -135.200155) (xy 150.844568 -135.152579) (xy 150.814584 -135.100645) (xy 150.791635 -135.045241)
			(xy 150.776114 -134.987316) (xy 150.768286 -134.92786) (xy 150.767796 -134.897876) (xy 84.369615 -134.897876)
			(xy 84.377099 -134.900976) (xy 84.429033 -134.93096) (xy 84.476609 -134.967466) (xy 84.519014 -135.009871)
			(xy 84.55552 -135.057447) (xy 84.585504 -135.109381) (xy 84.608453 -135.164785) (xy 84.623974 -135.22271)
			(xy 84.631802 -135.282166) (xy 84.632292 -135.31215) (xy 84.632292 -136.17575) (xy 84.631802 -136.205734)
			(xy 84.623974 -136.26519) (xy 84.608453 -136.323115) (xy 84.585504 -136.378519) (xy 84.55552 -136.430453)
			(xy 84.519014 -136.478029) (xy 84.476609 -136.520434) (xy 84.429033 -136.55694) (xy 84.377099 -136.586924)
			(xy 84.321695 -136.609873) (xy 84.26377 -136.625394) (xy 84.204314 -136.633222) (xy 84.144346 -136.633222)
			(xy 84.08489 -136.625394) (xy 84.026965 -136.609873) (xy 83.971561 -136.586924) (xy 83.919627 -136.55694)
			(xy 83.872051 -136.520434) (xy 83.829646 -136.478029) (xy 83.79314 -136.430453) (xy 83.763156 -136.378519)
			(xy 83.740207 -136.323115) (xy 83.724686 -136.26519) (xy 83.716858 -136.205734) (xy 83.716368 -136.17575)
			(xy 65.661032 -136.17575) (xy 65.661032 -136.177274) (xy 65.660542 -136.207258) (xy 65.652714 -136.266714)
			(xy 65.637193 -136.324639) (xy 65.614244 -136.380043) (xy 65.58426 -136.431977) (xy 65.547754 -136.479553)
			(xy 65.505349 -136.521958) (xy 65.457773 -136.558464) (xy 65.405839 -136.588448) (xy 65.350435 -136.611397)
			(xy 65.29251 -136.626918) (xy 65.233054 -136.634746) (xy 65.173086 -136.634746) (xy 65.11363 -136.626918)
			(xy 65.055705 -136.611397) (xy 65.000301 -136.588448) (xy 64.948367 -136.558464) (xy 64.900791 -136.521958)
			(xy 64.858386 -136.479553) (xy 64.82188 -136.431977) (xy 64.791896 -136.380043) (xy 64.768947 -136.324639)
			(xy 64.753426 -136.266714) (xy 64.745598 -136.207258) (xy 64.745108 -136.177274) (xy 52.700428 -136.177274)
			(xy 52.700428 -136.69645) (xy 52.700299 -136.704324) (xy 153.409904 -136.704324) (xy 153.409904 -135.840724)
			(xy 153.410394 -135.81074) (xy 153.418222 -135.751284) (xy 153.433743 -135.693359) (xy 153.456692 -135.637955)
			(xy 153.486676 -135.586021) (xy 153.523182 -135.538445) (xy 153.565587 -135.49604) (xy 153.613163 -135.459534)
			(xy 153.665097 -135.42955) (xy 153.720501 -135.406601) (xy 153.778426 -135.39108) (xy 153.837882 -135.383252)
			(xy 153.89785 -135.383252) (xy 153.957306 -135.39108) (xy 154.015231 -135.406601) (xy 154.070635 -135.42955)
			(xy 154.122569 -135.459534) (xy 154.170145 -135.49604) (xy 154.21255 -135.538445) (xy 154.249056 -135.586021)
			(xy 154.27904 -135.637955) (xy 154.301989 -135.693359) (xy 154.31751 -135.751284) (xy 154.325338 -135.81074)
			(xy 154.325828 -135.840724) (xy 154.325828 -136.69645) (xy 167.884856 -136.69645) (xy 167.884856 -135.83285)
			(xy 167.885346 -135.802866) (xy 167.893174 -135.74341) (xy 167.908695 -135.685485) (xy 167.931644 -135.630081)
			(xy 167.961628 -135.578147) (xy 167.998134 -135.530571) (xy 168.040539 -135.488166) (xy 168.088115 -135.45166)
			(xy 168.140049 -135.421676) (xy 168.195453 -135.398727) (xy 168.253378 -135.383206) (xy 168.312834 -135.375378)
			(xy 168.372802 -135.375378) (xy 168.432258 -135.383206) (xy 168.490183 -135.398727) (xy 168.545587 -135.421676)
			(xy 168.597521 -135.45166) (xy 168.645097 -135.488166) (xy 168.687502 -135.530571) (xy 168.724008 -135.578147)
			(xy 168.753992 -135.630081) (xy 168.776941 -135.685485) (xy 168.792462 -135.74341) (xy 168.80029 -135.802866)
			(xy 168.80078 -135.83285) (xy 168.80078 -136.177274) (xy 180.84546 -136.177274) (xy 180.84546 -135.313674)
			(xy 180.84595 -135.283706) (xy 180.853773 -135.224284) (xy 180.869286 -135.166391) (xy 180.892222 -135.111018)
			(xy 180.922189 -135.059112) (xy 180.958676 -135.011562) (xy 181.001056 -134.969182) (xy 181.048606 -134.932695)
			(xy 181.100512 -134.902728) (xy 181.155885 -134.879792) (xy 181.213778 -134.864279) (xy 181.2732 -134.856456)
			(xy 181.333136 -134.856456) (xy 181.392558 -134.864279) (xy 181.450451 -134.879792) (xy 181.505824 -134.902728)
			(xy 181.55773 -134.932695) (xy 181.60528 -134.969182) (xy 181.64766 -135.011562) (xy 181.684147 -135.059112)
			(xy 181.714114 -135.111018) (xy 181.73705 -135.166391) (xy 181.752563 -135.224284) (xy 181.760386 -135.283706)
			(xy 181.760876 -135.313674) (xy 181.760876 -136.17575) (xy 199.81672 -136.17575) (xy 199.81672 -135.31215)
			(xy 199.81721 -135.282182) (xy 199.825033 -135.22276) (xy 199.840546 -135.164867) (xy 199.863482 -135.109494)
			(xy 199.893449 -135.057588) (xy 199.929936 -135.010038) (xy 199.972316 -134.967658) (xy 200.019866 -134.931171)
			(xy 200.071772 -134.901204) (xy 200.127145 -134.878268) (xy 200.185038 -134.862755) (xy 200.24446 -134.854932)
			(xy 200.304396 -134.854932) (xy 200.363818 -134.862755) (xy 200.421711 -134.878268) (xy 200.469049 -134.897876)
			(xy 266.86764 -134.897876) (xy 266.86764 -134.034276) (xy 266.86813 -134.004292) (xy 266.875958 -133.944836)
			(xy 266.891479 -133.886911) (xy 266.914428 -133.831507) (xy 266.944412 -133.779573) (xy 266.980918 -133.731997)
			(xy 267.023323 -133.689592) (xy 267.070899 -133.653086) (xy 267.122833 -133.623102) (xy 267.178237 -133.600153)
			(xy 267.236162 -133.584632) (xy 267.295618 -133.576804) (xy 267.355586 -133.576804) (xy 267.415042 -133.584632)
			(xy 267.472967 -133.600153) (xy 267.528371 -133.623102) (xy 267.580305 -133.653086) (xy 267.627881 -133.689592)
			(xy 267.670286 -133.731997) (xy 267.706792 -133.779573) (xy 267.736776 -133.831507) (xy 267.759725 -133.886911)
			(xy 267.775246 -133.944836) (xy 267.783074 -134.004292) (xy 267.783564 -134.034276) (xy 267.783564 -134.896352)
			(xy 285.8389 -134.896352) (xy 285.8389 -134.032752) (xy 285.83939 -134.002768) (xy 285.847218 -133.943312)
			(xy 285.862739 -133.885387) (xy 285.885688 -133.829983) (xy 285.915672 -133.778049) (xy 285.952178 -133.730473)
			(xy 285.994583 -133.688068) (xy 286.042159 -133.651562) (xy 286.094093 -133.621578) (xy 286.149497 -133.598629)
			(xy 286.207422 -133.583108) (xy 286.266878 -133.57528) (xy 286.326846 -133.57528) (xy 286.386302 -133.583108)
			(xy 286.444227 -133.598629) (xy 286.499631 -133.621578) (xy 286.551565 -133.651562) (xy 286.599141 -133.688068)
			(xy 286.641546 -133.730473) (xy 286.678052 -133.778049) (xy 286.708036 -133.829983) (xy 286.730985 -133.885387)
			(xy 286.746506 -133.943312) (xy 286.754334 -134.002768) (xy 286.754824 -134.032752) (xy 286.754824 -134.377176)
			(xy 298.799504 -134.377176) (xy 298.799504 -133.513576) (xy 298.799994 -133.483608) (xy 298.807817 -133.424186)
			(xy 298.82333 -133.366293) (xy 298.846266 -133.31092) (xy 298.876233 -133.259014) (xy 298.91272 -133.211464)
			(xy 298.9551 -133.169084) (xy 299.00265 -133.132597) (xy 299.054556 -133.10263) (xy 299.109929 -133.079694)
			(xy 299.167822 -133.064181) (xy 299.227244 -133.056358) (xy 299.28718 -133.056358) (xy 299.346602 -133.064181)
			(xy 299.404495 -133.079694) (xy 299.459868 -133.10263) (xy 299.511774 -133.132597) (xy 299.559324 -133.169084)
			(xy 299.601704 -133.211464) (xy 299.638191 -133.259014) (xy 299.668158 -133.31092) (xy 299.691094 -133.366293)
			(xy 299.706607 -133.424186) (xy 299.71443 -133.483608) (xy 299.71492 -133.513576) (xy 299.71492 -134.369302)
			(xy 313.274456 -134.369302) (xy 313.274456 -133.505702) (xy 313.274946 -133.475734) (xy 313.282769 -133.416312)
			(xy 313.298282 -133.358419) (xy 313.321218 -133.303046) (xy 313.351185 -133.25114) (xy 313.387672 -133.20359)
			(xy 313.430052 -133.16121) (xy 313.477602 -133.124723) (xy 313.529508 -133.094756) (xy 313.584881 -133.07182)
			(xy 313.642774 -133.056307) (xy 313.702196 -133.048484) (xy 313.762132 -133.048484) (xy 313.821554 -133.056307)
			(xy 313.879447 -133.07182) (xy 313.93482 -133.094756) (xy 313.951493 -133.104382) (xy 385.6101 -133.104382)
			(xy 385.6101 -132.240782) (xy 385.61059 -132.210814) (xy 385.618413 -132.151392) (xy 385.633926 -132.093499)
			(xy 385.656862 -132.038126) (xy 385.686829 -131.98622) (xy 385.723316 -131.93867) (xy 385.765696 -131.89629)
			(xy 385.813246 -131.859803) (xy 385.865152 -131.829836) (xy 385.920525 -131.8069) (xy 385.978418 -131.791387)
			(xy 386.03784 -131.783564) (xy 386.097776 -131.783564) (xy 386.157198 -131.791387) (xy 386.215091 -131.8069)
			(xy 386.270464 -131.829836) (xy 386.32237 -131.859803) (xy 386.36992 -131.89629) (xy 386.4123 -131.93867)
			(xy 386.448787 -131.98622) (xy 386.478754 -132.038126) (xy 386.50169 -132.093499) (xy 386.517203 -132.151392)
			(xy 386.525026 -132.210814) (xy 386.525516 -132.240782) (xy 386.525516 -133.096508) (xy 400.085052 -133.096508)
			(xy 400.085052 -132.232908) (xy 400.085542 -132.20294) (xy 400.093365 -132.143518) (xy 400.108878 -132.085625)
			(xy 400.131814 -132.030252) (xy 400.161781 -131.978346) (xy 400.198268 -131.930796) (xy 400.240648 -131.888416)
			(xy 400.288198 -131.851929) (xy 400.340104 -131.821962) (xy 400.395477 -131.799026) (xy 400.45337 -131.783513)
			(xy 400.512792 -131.77569) (xy 400.572728 -131.77569) (xy 400.63215 -131.783513) (xy 400.690043 -131.799026)
			(xy 400.745416 -131.821962) (xy 400.797322 -131.851929) (xy 400.844872 -131.888416) (xy 400.887252 -131.930796)
			(xy 400.923739 -131.978346) (xy 400.953706 -132.030252) (xy 400.976642 -132.085625) (xy 400.992155 -132.143518)
			(xy 400.999978 -132.20294) (xy 401.000468 -132.232908) (xy 401.000468 -132.577332) (xy 413.045148 -132.577332)
			(xy 413.045148 -131.713732) (xy 413.045638 -131.683748) (xy 413.053466 -131.624292) (xy 413.068987 -131.566367)
			(xy 413.091936 -131.510963) (xy 413.12192 -131.459029) (xy 413.158426 -131.411453) (xy 413.200831 -131.369048)
			(xy 413.248407 -131.332542) (xy 413.300341 -131.302558) (xy 413.355745 -131.279609) (xy 413.41367 -131.264088)
			(xy 413.473126 -131.25626) (xy 413.533094 -131.25626) (xy 413.59255 -131.264088) (xy 413.650475 -131.279609)
			(xy 413.705879 -131.302558) (xy 413.757813 -131.332542) (xy 413.805389 -131.369048) (xy 413.847794 -131.411453)
			(xy 413.8843 -131.459029) (xy 413.914284 -131.510963) (xy 413.937233 -131.566367) (xy 413.952754 -131.624292)
			(xy 413.960582 -131.683748) (xy 413.961072 -131.713732) (xy 413.961072 -132.575808) (xy 432.016408 -132.575808)
			(xy 432.016408 -131.712208) (xy 432.016898 -131.682224) (xy 432.024726 -131.622768) (xy 432.040247 -131.564843)
			(xy 432.063196 -131.509439) (xy 432.09318 -131.457505) (xy 432.129686 -131.409929) (xy 432.172091 -131.367524)
			(xy 432.219667 -131.331018) (xy 432.271601 -131.301034) (xy 432.327005 -131.278085) (xy 432.38493 -131.262564)
			(xy 432.444386 -131.254736) (xy 432.504354 -131.254736) (xy 432.56381 -131.262564) (xy 432.621735 -131.278085)
			(xy 432.677139 -131.301034) (xy 432.729073 -131.331018) (xy 432.776649 -131.367524) (xy 432.819054 -131.409929)
			(xy 432.85556 -131.457505) (xy 432.885544 -131.509439) (xy 432.908493 -131.564843) (xy 432.924014 -131.622768)
			(xy 432.931842 -131.682224) (xy 432.932332 -131.712208) (xy 432.932332 -132.575808) (xy 432.931842 -132.605792)
			(xy 432.924014 -132.665248) (xy 432.908493 -132.723173) (xy 432.885544 -132.778577) (xy 432.85556 -132.830511)
			(xy 432.819054 -132.878087) (xy 432.776649 -132.920492) (xy 432.729073 -132.956998) (xy 432.677139 -132.986982)
			(xy 432.621735 -133.009931) (xy 432.56381 -133.025452) (xy 432.504354 -133.03328) (xy 432.444386 -133.03328)
			(xy 432.38493 -133.025452) (xy 432.327005 -133.009931) (xy 432.271601 -132.986982) (xy 432.219667 -132.956998)
			(xy 432.172091 -132.920492) (xy 432.129686 -132.878087) (xy 432.09318 -132.830511) (xy 432.063196 -132.778577)
			(xy 432.040247 -132.723173) (xy 432.024726 -132.665248) (xy 432.016898 -132.605792) (xy 432.016408 -132.575808)
			(xy 413.961072 -132.575808) (xy 413.961072 -132.577332) (xy 413.960582 -132.607316) (xy 413.952754 -132.666772)
			(xy 413.937233 -132.724697) (xy 413.914284 -132.780101) (xy 413.8843 -132.832035) (xy 413.847794 -132.879611)
			(xy 413.805389 -132.922016) (xy 413.757813 -132.958522) (xy 413.705879 -132.988506) (xy 413.650475 -133.011455)
			(xy 413.59255 -133.026976) (xy 413.533094 -133.034804) (xy 413.473126 -133.034804) (xy 413.41367 -133.026976)
			(xy 413.355745 -133.011455) (xy 413.300341 -132.988506) (xy 413.248407 -132.958522) (xy 413.200831 -132.922016)
			(xy 413.158426 -132.879611) (xy 413.12192 -132.832035) (xy 413.091936 -132.780101) (xy 413.068987 -132.724697)
			(xy 413.053466 -132.666772) (xy 413.045638 -132.607316) (xy 413.045148 -132.577332) (xy 401.000468 -132.577332)
			(xy 401.000468 -133.096508) (xy 400.999978 -133.126476) (xy 400.992155 -133.185898) (xy 400.976642 -133.243791)
			(xy 400.953706 -133.299164) (xy 400.923739 -133.35107) (xy 400.887252 -133.39862) (xy 400.844872 -133.441)
			(xy 400.797322 -133.477487) (xy 400.745416 -133.507454) (xy 400.690043 -133.53039) (xy 400.63215 -133.545903)
			(xy 400.572728 -133.553726) (xy 400.512792 -133.553726) (xy 400.45337 -133.545903) (xy 400.395477 -133.53039)
			(xy 400.340104 -133.507454) (xy 400.288198 -133.477487) (xy 400.240648 -133.441) (xy 400.198268 -133.39862)
			(xy 400.161781 -133.35107) (xy 400.131814 -133.299164) (xy 400.108878 -133.243791) (xy 400.093365 -133.185898)
			(xy 400.085542 -133.126476) (xy 400.085052 -133.096508) (xy 386.525516 -133.096508) (xy 386.525516 -133.104382)
			(xy 386.525026 -133.13435) (xy 386.517203 -133.193772) (xy 386.50169 -133.251665) (xy 386.478754 -133.307038)
			(xy 386.448787 -133.358944) (xy 386.4123 -133.406494) (xy 386.36992 -133.448874) (xy 386.32237 -133.485361)
			(xy 386.270464 -133.515328) (xy 386.215091 -133.538264) (xy 386.157198 -133.553777) (xy 386.097776 -133.5616)
			(xy 386.03784 -133.5616) (xy 385.978418 -133.553777) (xy 385.920525 -133.538264) (xy 385.865152 -133.515328)
			(xy 385.813246 -133.485361) (xy 385.765696 -133.448874) (xy 385.723316 -133.406494) (xy 385.686829 -133.358944)
			(xy 385.656862 -133.307038) (xy 385.633926 -133.251665) (xy 385.618413 -133.193772) (xy 385.61059 -133.13435)
			(xy 385.6101 -133.104382) (xy 313.951493 -133.104382) (xy 313.986726 -133.124723) (xy 314.034276 -133.16121)
			(xy 314.076656 -133.20359) (xy 314.113143 -133.25114) (xy 314.14311 -133.303046) (xy 314.166046 -133.358419)
			(xy 314.181559 -133.416312) (xy 314.189382 -133.475734) (xy 314.189872 -133.505702) (xy 314.189872 -134.369302)
			(xy 314.189382 -134.39927) (xy 314.181559 -134.458692) (xy 314.166046 -134.516585) (xy 314.14311 -134.571958)
			(xy 314.113143 -134.623864) (xy 314.076656 -134.671414) (xy 314.034276 -134.713794) (xy 313.986726 -134.750281)
			(xy 313.93482 -134.780248) (xy 313.879447 -134.803184) (xy 313.821554 -134.818697) (xy 313.762132 -134.82652)
			(xy 313.702196 -134.82652) (xy 313.642774 -134.818697) (xy 313.584881 -134.803184) (xy 313.529508 -134.780248)
			(xy 313.477602 -134.750281) (xy 313.430052 -134.713794) (xy 313.387672 -134.671414) (xy 313.351185 -134.623864)
			(xy 313.321218 -134.571958) (xy 313.298282 -134.516585) (xy 313.282769 -134.458692) (xy 313.274946 -134.39927)
			(xy 313.274456 -134.369302) (xy 299.71492 -134.369302) (xy 299.71492 -134.377176) (xy 299.71443 -134.407144)
			(xy 299.706607 -134.466566) (xy 299.691094 -134.524459) (xy 299.668158 -134.579832) (xy 299.638191 -134.631738)
			(xy 299.601704 -134.679288) (xy 299.559324 -134.721668) (xy 299.511774 -134.758155) (xy 299.459868 -134.788122)
			(xy 299.404495 -134.811058) (xy 299.346602 -134.826571) (xy 299.28718 -134.834394) (xy 299.227244 -134.834394)
			(xy 299.167822 -134.826571) (xy 299.109929 -134.811058) (xy 299.054556 -134.788122) (xy 299.00265 -134.758155)
			(xy 298.9551 -134.721668) (xy 298.91272 -134.679288) (xy 298.876233 -134.631738) (xy 298.846266 -134.579832)
			(xy 298.82333 -134.524459) (xy 298.807817 -134.466566) (xy 298.799994 -134.407144) (xy 298.799504 -134.377176)
			(xy 286.754824 -134.377176) (xy 286.754824 -134.896352) (xy 286.754334 -134.926336) (xy 286.746506 -134.985792)
			(xy 286.730985 -135.043717) (xy 286.708036 -135.099121) (xy 286.678052 -135.151055) (xy 286.641546 -135.198631)
			(xy 286.599141 -135.241036) (xy 286.551565 -135.277542) (xy 286.499631 -135.307526) (xy 286.444227 -135.330475)
			(xy 286.386302 -135.345996) (xy 286.326846 -135.353824) (xy 286.266878 -135.353824) (xy 286.207422 -135.345996)
			(xy 286.149497 -135.330475) (xy 286.094093 -135.307526) (xy 286.042159 -135.277542) (xy 285.994583 -135.241036)
			(xy 285.952178 -135.198631) (xy 285.915672 -135.151055) (xy 285.885688 -135.099121) (xy 285.862739 -135.043717)
			(xy 285.847218 -134.985792) (xy 285.83939 -134.926336) (xy 285.8389 -134.896352) (xy 267.783564 -134.896352)
			(xy 267.783564 -134.897876) (xy 267.783074 -134.92786) (xy 267.775246 -134.987316) (xy 267.759725 -135.045241)
			(xy 267.736776 -135.100645) (xy 267.706792 -135.152579) (xy 267.670286 -135.200155) (xy 267.627881 -135.24256)
			(xy 267.580305 -135.279066) (xy 267.528371 -135.30905) (xy 267.472967 -135.331999) (xy 267.415042 -135.34752)
			(xy 267.355586 -135.355348) (xy 267.295618 -135.355348) (xy 267.236162 -135.34752) (xy 267.178237 -135.331999)
			(xy 267.122833 -135.30905) (xy 267.070899 -135.279066) (xy 267.023323 -135.24256) (xy 266.980918 -135.200155)
			(xy 266.944412 -135.152579) (xy 266.914428 -135.100645) (xy 266.891479 -135.045241) (xy 266.875958 -134.987316)
			(xy 266.86813 -134.92786) (xy 266.86764 -134.897876) (xy 200.469049 -134.897876) (xy 200.477084 -134.901204)
			(xy 200.52899 -134.931171) (xy 200.57654 -134.967658) (xy 200.61892 -135.010038) (xy 200.655407 -135.057588)
			(xy 200.685374 -135.109494) (xy 200.70831 -135.164867) (xy 200.723823 -135.22276) (xy 200.731646 -135.282182)
			(xy 200.732136 -135.31215) (xy 200.732136 -136.17575) (xy 200.731646 -136.205718) (xy 200.723823 -136.26514)
			(xy 200.70831 -136.323033) (xy 200.685374 -136.378406) (xy 200.655407 -136.430312) (xy 200.61892 -136.477862)
			(xy 200.57654 -136.520242) (xy 200.52899 -136.556729) (xy 200.477084 -136.586696) (xy 200.421711 -136.609632)
			(xy 200.363818 -136.625145) (xy 200.304396 -136.632968) (xy 200.24446 -136.632968) (xy 200.185038 -136.625145)
			(xy 200.127145 -136.609632) (xy 200.071772 -136.586696) (xy 200.019866 -136.556729) (xy 199.972316 -136.520242)
			(xy 199.929936 -136.477862) (xy 199.893449 -136.430312) (xy 199.863482 -136.378406) (xy 199.840546 -136.323033)
			(xy 199.825033 -136.26514) (xy 199.81721 -136.205718) (xy 199.81672 -136.17575) (xy 181.760876 -136.17575)
			(xy 181.760876 -136.177274) (xy 181.760386 -136.207242) (xy 181.752563 -136.266664) (xy 181.73705 -136.324557)
			(xy 181.714114 -136.37993) (xy 181.684147 -136.431836) (xy 181.64766 -136.479386) (xy 181.60528 -136.521766)
			(xy 181.55773 -136.558253) (xy 181.505824 -136.58822) (xy 181.450451 -136.611156) (xy 181.392558 -136.626669)
			(xy 181.333136 -136.634492) (xy 181.2732 -136.634492) (xy 181.213778 -136.626669) (xy 181.155885 -136.611156)
			(xy 181.100512 -136.58822) (xy 181.048606 -136.558253) (xy 181.001056 -136.521766) (xy 180.958676 -136.479386)
			(xy 180.922189 -136.431836) (xy 180.892222 -136.37993) (xy 180.869286 -136.324557) (xy 180.853773 -136.266664)
			(xy 180.84595 -136.207242) (xy 180.84546 -136.177274) (xy 168.80078 -136.177274) (xy 168.80078 -136.69645)
			(xy 168.800651 -136.704324) (xy 269.509748 -136.704324) (xy 269.509748 -135.840724) (xy 269.510238 -135.81074)
			(xy 269.518066 -135.751284) (xy 269.533587 -135.693359) (xy 269.556536 -135.637955) (xy 269.58652 -135.586021)
			(xy 269.623026 -135.538445) (xy 269.665431 -135.49604) (xy 269.713007 -135.459534) (xy 269.764941 -135.42955)
			(xy 269.820345 -135.406601) (xy 269.87827 -135.39108) (xy 269.937726 -135.383252) (xy 269.997694 -135.383252)
			(xy 270.05715 -135.39108) (xy 270.115075 -135.406601) (xy 270.170479 -135.42955) (xy 270.222413 -135.459534)
			(xy 270.269989 -135.49604) (xy 270.312394 -135.538445) (xy 270.3489 -135.586021) (xy 270.378884 -135.637955)
			(xy 270.401833 -135.693359) (xy 270.417354 -135.751284) (xy 270.425182 -135.81074) (xy 270.425672 -135.840724)
			(xy 270.425672 -136.69645) (xy 283.9847 -136.69645) (xy 283.9847 -135.83285) (xy 283.98519 -135.802866)
			(xy 283.993018 -135.74341) (xy 284.008539 -135.685485) (xy 284.031488 -135.630081) (xy 284.061472 -135.578147)
			(xy 284.097978 -135.530571) (xy 284.140383 -135.488166) (xy 284.187959 -135.45166) (xy 284.239893 -135.421676)
			(xy 284.295297 -135.398727) (xy 284.353222 -135.383206) (xy 284.412678 -135.375378) (xy 284.472646 -135.375378)
			(xy 284.532102 -135.383206) (xy 284.590027 -135.398727) (xy 284.645431 -135.421676) (xy 284.697365 -135.45166)
			(xy 284.744941 -135.488166) (xy 284.787346 -135.530571) (xy 284.823852 -135.578147) (xy 284.853836 -135.630081)
			(xy 284.876785 -135.685485) (xy 284.892306 -135.74341) (xy 284.900134 -135.802866) (xy 284.900624 -135.83285)
			(xy 284.900624 -136.177274) (xy 296.945304 -136.177274) (xy 296.945304 -135.313674) (xy 296.945794 -135.283706)
			(xy 296.953617 -135.224284) (xy 296.96913 -135.166391) (xy 296.992066 -135.111018) (xy 297.022033 -135.059112)
			(xy 297.05852 -135.011562) (xy 297.1009 -134.969182) (xy 297.14845 -134.932695) (xy 297.200356 -134.902728)
			(xy 297.255729 -134.879792) (xy 297.313622 -134.864279) (xy 297.373044 -134.856456) (xy 297.43298 -134.856456)
			(xy 297.492402 -134.864279) (xy 297.550295 -134.879792) (xy 297.605668 -134.902728) (xy 297.657574 -134.932695)
			(xy 297.705124 -134.969182) (xy 297.747504 -135.011562) (xy 297.783991 -135.059112) (xy 297.813958 -135.111018)
			(xy 297.836894 -135.166391) (xy 297.852407 -135.224284) (xy 297.86023 -135.283706) (xy 297.86072 -135.313674)
			(xy 297.86072 -136.17575) (xy 315.916564 -136.17575) (xy 315.916564 -135.31215) (xy 315.917054 -135.282182)
			(xy 315.924877 -135.22276) (xy 315.94039 -135.164867) (xy 315.963326 -135.109494) (xy 315.993293 -135.057588)
			(xy 316.02978 -135.010038) (xy 316.07216 -134.967658) (xy 316.11971 -134.931171) (xy 316.171616 -134.901204)
			(xy 316.226989 -134.878268) (xy 316.284882 -134.862755) (xy 316.344304 -134.854932) (xy 316.40424 -134.854932)
			(xy 316.463662 -134.862755) (xy 316.521555 -134.878268) (xy 316.568893 -134.897876) (xy 382.967992 -134.897876)
			(xy 382.967992 -134.034276) (xy 382.968482 -134.004308) (xy 382.976305 -133.944886) (xy 382.991818 -133.886993)
			(xy 383.014754 -133.83162) (xy 383.044721 -133.779714) (xy 383.081208 -133.732164) (xy 383.123588 -133.689784)
			(xy 383.171138 -133.653297) (xy 383.223044 -133.62333) (xy 383.278417 -133.600394) (xy 383.33631 -133.584881)
			(xy 383.395732 -133.577058) (xy 383.455668 -133.577058) (xy 383.51509 -133.584881) (xy 383.572983 -133.600394)
			(xy 383.628356 -133.62333) (xy 383.680262 -133.653297) (xy 383.727812 -133.689784) (xy 383.770192 -133.732164)
			(xy 383.806679 -133.779714) (xy 383.836646 -133.83162) (xy 383.859582 -133.886993) (xy 383.875095 -133.944886)
			(xy 383.882918 -134.004308) (xy 383.883408 -134.034276) (xy 383.883408 -134.896352) (xy 401.939252 -134.896352)
			(xy 401.939252 -134.032752) (xy 401.939742 -134.002784) (xy 401.947565 -133.943362) (xy 401.963078 -133.885469)
			(xy 401.986014 -133.830096) (xy 402.015981 -133.77819) (xy 402.052468 -133.73064) (xy 402.094848 -133.68826)
			(xy 402.142398 -133.651773) (xy 402.194304 -133.621806) (xy 402.249677 -133.59887) (xy 402.30757 -133.583357)
			(xy 402.366992 -133.575534) (xy 402.426928 -133.575534) (xy 402.48635 -133.583357) (xy 402.544243 -133.59887)
			(xy 402.599616 -133.621806) (xy 402.651522 -133.651773) (xy 402.699072 -133.68826) (xy 402.741452 -133.73064)
			(xy 402.777939 -133.77819) (xy 402.807906 -133.830096) (xy 402.830842 -133.885469) (xy 402.846355 -133.943362)
			(xy 402.854178 -134.002784) (xy 402.854668 -134.032752) (xy 402.854668 -134.377176) (xy 414.899348 -134.377176)
			(xy 414.899348 -133.513576) (xy 414.899838 -133.483592) (xy 414.907666 -133.424136) (xy 414.923187 -133.366211)
			(xy 414.946136 -133.310807) (xy 414.97612 -133.258873) (xy 415.012626 -133.211297) (xy 415.055031 -133.168892)
			(xy 415.102607 -133.132386) (xy 415.154541 -133.102402) (xy 415.209945 -133.079453) (xy 415.26787 -133.063932)
			(xy 415.327326 -133.056104) (xy 415.387294 -133.056104) (xy 415.44675 -133.063932) (xy 415.504675 -133.079453)
			(xy 415.560079 -133.102402) (xy 415.612013 -133.132386) (xy 415.659589 -133.168892) (xy 415.701994 -133.211297)
			(xy 415.7385 -133.258873) (xy 415.768484 -133.310807) (xy 415.791433 -133.366211) (xy 415.806954 -133.424136)
			(xy 415.814782 -133.483592) (xy 415.815272 -133.513576) (xy 415.815272 -134.369302) (xy 429.3743 -134.369302)
			(xy 429.3743 -133.505702) (xy 429.37479 -133.475718) (xy 429.382618 -133.416262) (xy 429.398139 -133.358337)
			(xy 429.421088 -133.302933) (xy 429.451072 -133.250999) (xy 429.487578 -133.203423) (xy 429.529983 -133.161018)
			(xy 429.577559 -133.124512) (xy 429.629493 -133.094528) (xy 429.684897 -133.071579) (xy 429.742822 -133.056058)
			(xy 429.802278 -133.04823) (xy 429.862246 -133.04823) (xy 429.921702 -133.056058) (xy 429.979627 -133.071579)
			(xy 430.035031 -133.094528) (xy 430.086965 -133.124512) (xy 430.134541 -133.161018) (xy 430.176946 -133.203423)
			(xy 430.213452 -133.250999) (xy 430.243436 -133.302933) (xy 430.266385 -133.358337) (xy 430.281906 -133.416262)
			(xy 430.289734 -133.475718) (xy 430.290224 -133.505702) (xy 430.290224 -134.369302) (xy 430.289734 -134.399286)
			(xy 430.281906 -134.458742) (xy 430.266385 -134.516667) (xy 430.243436 -134.572071) (xy 430.213452 -134.624005)
			(xy 430.176946 -134.671581) (xy 430.134541 -134.713986) (xy 430.086965 -134.750492) (xy 430.035031 -134.780476)
			(xy 429.979627 -134.803425) (xy 429.921702 -134.818946) (xy 429.862246 -134.826774) (xy 429.802278 -134.826774)
			(xy 429.742822 -134.818946) (xy 429.684897 -134.803425) (xy 429.629493 -134.780476) (xy 429.577559 -134.750492)
			(xy 429.529983 -134.713986) (xy 429.487578 -134.671581) (xy 429.451072 -134.624005) (xy 429.421088 -134.572071)
			(xy 429.398139 -134.516667) (xy 429.382618 -134.458742) (xy 429.37479 -134.399286) (xy 429.3743 -134.369302)
			(xy 415.815272 -134.369302) (xy 415.815272 -134.377176) (xy 415.814782 -134.40716) (xy 415.806954 -134.466616)
			(xy 415.791433 -134.524541) (xy 415.768484 -134.579945) (xy 415.7385 -134.631879) (xy 415.701994 -134.679455)
			(xy 415.659589 -134.72186) (xy 415.612013 -134.758366) (xy 415.560079 -134.78835) (xy 415.504675 -134.811299)
			(xy 415.44675 -134.82682) (xy 415.387294 -134.834648) (xy 415.327326 -134.834648) (xy 415.26787 -134.82682)
			(xy 415.209945 -134.811299) (xy 415.154541 -134.78835) (xy 415.102607 -134.758366) (xy 415.055031 -134.72186)
			(xy 415.012626 -134.679455) (xy 414.97612 -134.631879) (xy 414.946136 -134.579945) (xy 414.923187 -134.524541)
			(xy 414.907666 -134.466616) (xy 414.899838 -134.40716) (xy 414.899348 -134.377176) (xy 402.854668 -134.377176)
			(xy 402.854668 -134.896352) (xy 402.854178 -134.92632) (xy 402.846355 -134.985742) (xy 402.830842 -135.043635)
			(xy 402.807906 -135.099008) (xy 402.777939 -135.150914) (xy 402.741452 -135.198464) (xy 402.699072 -135.240844)
			(xy 402.651522 -135.277331) (xy 402.599616 -135.307298) (xy 402.544243 -135.330234) (xy 402.48635 -135.345747)
			(xy 402.426928 -135.35357) (xy 402.366992 -135.35357) (xy 402.30757 -135.345747) (xy 402.249677 -135.330234)
			(xy 402.194304 -135.307298) (xy 402.142398 -135.277331) (xy 402.094848 -135.240844) (xy 402.052468 -135.198464)
			(xy 402.015981 -135.150914) (xy 401.986014 -135.099008) (xy 401.963078 -135.043635) (xy 401.947565 -134.985742)
			(xy 401.939742 -134.92632) (xy 401.939252 -134.896352) (xy 383.883408 -134.896352) (xy 383.883408 -134.897876)
			(xy 383.882918 -134.927844) (xy 383.875095 -134.987266) (xy 383.859582 -135.045159) (xy 383.836646 -135.100532)
			(xy 383.806679 -135.152438) (xy 383.770192 -135.199988) (xy 383.727812 -135.242368) (xy 383.680262 -135.278855)
			(xy 383.628356 -135.308822) (xy 383.572983 -135.331758) (xy 383.51509 -135.347271) (xy 383.455668 -135.355094)
			(xy 383.395732 -135.355094) (xy 383.33631 -135.347271) (xy 383.278417 -135.331758) (xy 383.223044 -135.308822)
			(xy 383.171138 -135.278855) (xy 383.123588 -135.242368) (xy 383.081208 -135.199988) (xy 383.044721 -135.152438)
			(xy 383.014754 -135.100532) (xy 382.991818 -135.045159) (xy 382.976305 -134.987266) (xy 382.968482 -134.927844)
			(xy 382.967992 -134.897876) (xy 316.568893 -134.897876) (xy 316.576928 -134.901204) (xy 316.628834 -134.931171)
			(xy 316.676384 -134.967658) (xy 316.718764 -135.010038) (xy 316.755251 -135.057588) (xy 316.785218 -135.109494)
			(xy 316.808154 -135.164867) (xy 316.823667 -135.22276) (xy 316.83149 -135.282182) (xy 316.83198 -135.31215)
			(xy 316.83198 -136.17575) (xy 316.83149 -136.205718) (xy 316.823667 -136.26514) (xy 316.808154 -136.323033)
			(xy 316.785218 -136.378406) (xy 316.755251 -136.430312) (xy 316.718764 -136.477862) (xy 316.676384 -136.520242)
			(xy 316.628834 -136.556729) (xy 316.576928 -136.586696) (xy 316.521555 -136.609632) (xy 316.463662 -136.625145)
			(xy 316.40424 -136.632968) (xy 316.344304 -136.632968) (xy 316.284882 -136.625145) (xy 316.226989 -136.609632)
			(xy 316.171616 -136.586696) (xy 316.11971 -136.556729) (xy 316.07216 -136.520242) (xy 316.02978 -136.477862)
			(xy 315.993293 -136.430312) (xy 315.963326 -136.378406) (xy 315.94039 -136.323033) (xy 315.924877 -136.26514)
			(xy 315.917054 -136.205718) (xy 315.916564 -136.17575) (xy 297.86072 -136.17575) (xy 297.86072 -136.177274)
			(xy 297.86023 -136.207242) (xy 297.852407 -136.266664) (xy 297.836894 -136.324557) (xy 297.813958 -136.37993)
			(xy 297.783991 -136.431836) (xy 297.747504 -136.479386) (xy 297.705124 -136.521766) (xy 297.657574 -136.558253)
			(xy 297.605668 -136.58822) (xy 297.550295 -136.611156) (xy 297.492402 -136.626669) (xy 297.43298 -136.634492)
			(xy 297.373044 -136.634492) (xy 297.313622 -136.626669) (xy 297.255729 -136.611156) (xy 297.200356 -136.58822)
			(xy 297.14845 -136.558253) (xy 297.1009 -136.521766) (xy 297.05852 -136.479386) (xy 297.022033 -136.431836)
			(xy 296.992066 -136.37993) (xy 296.96913 -136.324557) (xy 296.953617 -136.266664) (xy 296.945794 -136.207242)
			(xy 296.945304 -136.177274) (xy 284.900624 -136.177274) (xy 284.900624 -136.69645) (xy 284.900495 -136.704324)
			(xy 385.6101 -136.704324) (xy 385.6101 -135.840724) (xy 385.61059 -135.810756) (xy 385.618413 -135.751334)
			(xy 385.633926 -135.693441) (xy 385.656862 -135.638068) (xy 385.686829 -135.586162) (xy 385.723316 -135.538612)
			(xy 385.765696 -135.496232) (xy 385.813246 -135.459745) (xy 385.865152 -135.429778) (xy 385.920525 -135.406842)
			(xy 385.978418 -135.391329) (xy 386.03784 -135.383506) (xy 386.097776 -135.383506) (xy 386.157198 -135.391329)
			(xy 386.215091 -135.406842) (xy 386.270464 -135.429778) (xy 386.32237 -135.459745) (xy 386.36992 -135.496232)
			(xy 386.4123 -135.538612) (xy 386.448787 -135.586162) (xy 386.478754 -135.638068) (xy 386.50169 -135.693441)
			(xy 386.517203 -135.751334) (xy 386.525026 -135.810756) (xy 386.525516 -135.840724) (xy 386.525516 -136.69645)
			(xy 400.085052 -136.69645) (xy 400.085052 -135.83285) (xy 400.085542 -135.802882) (xy 400.093365 -135.74346)
			(xy 400.108878 -135.685567) (xy 400.131814 -135.630194) (xy 400.161781 -135.578288) (xy 400.198268 -135.530738)
			(xy 400.240648 -135.488358) (xy 400.288198 -135.451871) (xy 400.340104 -135.421904) (xy 400.395477 -135.398968)
			(xy 400.45337 -135.383455) (xy 400.512792 -135.375632) (xy 400.572728 -135.375632) (xy 400.63215 -135.383455)
			(xy 400.690043 -135.398968) (xy 400.745416 -135.421904) (xy 400.797322 -135.451871) (xy 400.844872 -135.488358)
			(xy 400.887252 -135.530738) (xy 400.923739 -135.578288) (xy 400.953706 -135.630194) (xy 400.976642 -135.685567)
			(xy 400.992155 -135.74346) (xy 400.999978 -135.802882) (xy 401.000468 -135.83285) (xy 401.000468 -136.177274)
			(xy 413.045148 -136.177274) (xy 413.045148 -135.313674) (xy 413.045638 -135.28369) (xy 413.053466 -135.224234)
			(xy 413.068987 -135.166309) (xy 413.091936 -135.110905) (xy 413.12192 -135.058971) (xy 413.158426 -135.011395)
			(xy 413.200831 -134.96899) (xy 413.248407 -134.932484) (xy 413.300341 -134.9025) (xy 413.355745 -134.879551)
			(xy 413.41367 -134.86403) (xy 413.473126 -134.856202) (xy 413.533094 -134.856202) (xy 413.59255 -134.86403)
			(xy 413.650475 -134.879551) (xy 413.705879 -134.9025) (xy 413.757813 -134.932484) (xy 413.805389 -134.96899)
			(xy 413.847794 -135.011395) (xy 413.8843 -135.058971) (xy 413.914284 -135.110905) (xy 413.937233 -135.166309)
			(xy 413.952754 -135.224234) (xy 413.960582 -135.28369) (xy 413.961072 -135.313674) (xy 413.961072 -136.17575)
			(xy 432.016408 -136.17575) (xy 432.016408 -135.31215) (xy 432.016898 -135.282166) (xy 432.024726 -135.22271)
			(xy 432.040247 -135.164785) (xy 432.063196 -135.109381) (xy 432.09318 -135.057447) (xy 432.129686 -135.009871)
			(xy 432.172091 -134.967466) (xy 432.219667 -134.93096) (xy 432.271601 -134.900976) (xy 432.327005 -134.878027)
			(xy 432.38493 -134.862506) (xy 432.444386 -134.854678) (xy 432.504354 -134.854678) (xy 432.56381 -134.862506)
			(xy 432.621735 -134.878027) (xy 432.677139 -134.900976) (xy 432.729073 -134.93096) (xy 432.776649 -134.967466)
			(xy 432.819054 -135.009871) (xy 432.85556 -135.057447) (xy 432.885544 -135.109381) (xy 432.908493 -135.164785)
			(xy 432.924014 -135.22271) (xy 432.931842 -135.282166) (xy 432.932332 -135.31215) (xy 432.932332 -136.17575)
			(xy 432.931842 -136.205734) (xy 432.924014 -136.26519) (xy 432.908493 -136.323115) (xy 432.885544 -136.378519)
			(xy 432.85556 -136.430453) (xy 432.819054 -136.478029) (xy 432.776649 -136.520434) (xy 432.729073 -136.55694)
			(xy 432.677139 -136.586924) (xy 432.621735 -136.609873) (xy 432.56381 -136.625394) (xy 432.504354 -136.633222)
			(xy 432.444386 -136.633222) (xy 432.38493 -136.625394) (xy 432.327005 -136.609873) (xy 432.271601 -136.586924)
			(xy 432.219667 -136.55694) (xy 432.172091 -136.520434) (xy 432.129686 -136.478029) (xy 432.09318 -136.430453)
			(xy 432.063196 -136.378519) (xy 432.040247 -136.323115) (xy 432.024726 -136.26519) (xy 432.016898 -136.205734)
			(xy 432.016408 -136.17575) (xy 413.961072 -136.17575) (xy 413.961072 -136.177274) (xy 413.960582 -136.207258)
			(xy 413.952754 -136.266714) (xy 413.937233 -136.324639) (xy 413.914284 -136.380043) (xy 413.8843 -136.431977)
			(xy 413.847794 -136.479553) (xy 413.805389 -136.521958) (xy 413.757813 -136.558464) (xy 413.705879 -136.588448)
			(xy 413.650475 -136.611397) (xy 413.59255 -136.626918) (xy 413.533094 -136.634746) (xy 413.473126 -136.634746)
			(xy 413.41367 -136.626918) (xy 413.355745 -136.611397) (xy 413.300341 -136.588448) (xy 413.248407 -136.558464)
			(xy 413.200831 -136.521958) (xy 413.158426 -136.479553) (xy 413.12192 -136.431977) (xy 413.091936 -136.380043)
			(xy 413.068987 -136.324639) (xy 413.053466 -136.266714) (xy 413.045638 -136.207258) (xy 413.045148 -136.177274)
			(xy 401.000468 -136.177274) (xy 401.000468 -136.69645) (xy 400.999978 -136.726418) (xy 400.992155 -136.78584)
			(xy 400.976642 -136.843733) (xy 400.953706 -136.899106) (xy 400.923739 -136.951012) (xy 400.887252 -136.998562)
			(xy 400.844872 -137.040942) (xy 400.797322 -137.077429) (xy 400.745416 -137.107396) (xy 400.690043 -137.130332)
			(xy 400.63215 -137.145845) (xy 400.572728 -137.153668) (xy 400.512792 -137.153668) (xy 400.45337 -137.145845)
			(xy 400.395477 -137.130332) (xy 400.340104 -137.107396) (xy 400.288198 -137.077429) (xy 400.240648 -137.040942)
			(xy 400.198268 -136.998562) (xy 400.161781 -136.951012) (xy 400.131814 -136.899106) (xy 400.108878 -136.843733)
			(xy 400.093365 -136.78584) (xy 400.085542 -136.726418) (xy 400.085052 -136.69645) (xy 386.525516 -136.69645)
			(xy 386.525516 -136.704324) (xy 386.525026 -136.734292) (xy 386.517203 -136.793714) (xy 386.50169 -136.851607)
			(xy 386.478754 -136.90698) (xy 386.448787 -136.958886) (xy 386.4123 -137.006436) (xy 386.36992 -137.048816)
			(xy 386.32237 -137.085303) (xy 386.270464 -137.11527) (xy 386.215091 -137.138206) (xy 386.157198 -137.153719)
			(xy 386.097776 -137.161542) (xy 386.03784 -137.161542) (xy 385.978418 -137.153719) (xy 385.920525 -137.138206)
			(xy 385.865152 -137.11527) (xy 385.813246 -137.085303) (xy 385.765696 -137.048816) (xy 385.723316 -137.006436)
			(xy 385.686829 -136.958886) (xy 385.656862 -136.90698) (xy 385.633926 -136.851607) (xy 385.618413 -136.793714)
			(xy 385.61059 -136.734292) (xy 385.6101 -136.704324) (xy 284.900495 -136.704324) (xy 284.900134 -136.726434)
			(xy 284.892306 -136.78589) (xy 284.876785 -136.843815) (xy 284.853836 -136.899219) (xy 284.823852 -136.951153)
			(xy 284.787346 -136.998729) (xy 284.744941 -137.041134) (xy 284.697365 -137.07764) (xy 284.645431 -137.107624)
			(xy 284.590027 -137.130573) (xy 284.532102 -137.146094) (xy 284.472646 -137.153922) (xy 284.412678 -137.153922)
			(xy 284.353222 -137.146094) (xy 284.295297 -137.130573) (xy 284.239893 -137.107624) (xy 284.187959 -137.07764)
			(xy 284.140383 -137.041134) (xy 284.097978 -136.998729) (xy 284.061472 -136.951153) (xy 284.031488 -136.899219)
			(xy 284.008539 -136.843815) (xy 283.993018 -136.78589) (xy 283.98519 -136.726434) (xy 283.9847 -136.69645)
			(xy 270.425672 -136.69645) (xy 270.425672 -136.704324) (xy 270.425182 -136.734308) (xy 270.417354 -136.793764)
			(xy 270.401833 -136.851689) (xy 270.378884 -136.907093) (xy 270.3489 -136.959027) (xy 270.312394 -137.006603)
			(xy 270.269989 -137.049008) (xy 270.222413 -137.085514) (xy 270.170479 -137.115498) (xy 270.115075 -137.138447)
			(xy 270.05715 -137.153968) (xy 269.997694 -137.161796) (xy 269.937726 -137.161796) (xy 269.87827 -137.153968)
			(xy 269.820345 -137.138447) (xy 269.764941 -137.115498) (xy 269.713007 -137.085514) (xy 269.665431 -137.049008)
			(xy 269.623026 -137.006603) (xy 269.58652 -136.959027) (xy 269.556536 -136.907093) (xy 269.533587 -136.851689)
			(xy 269.518066 -136.793764) (xy 269.510238 -136.734308) (xy 269.509748 -136.704324) (xy 168.800651 -136.704324)
			(xy 168.80029 -136.726434) (xy 168.792462 -136.78589) (xy 168.776941 -136.843815) (xy 168.753992 -136.899219)
			(xy 168.724008 -136.951153) (xy 168.687502 -136.998729) (xy 168.645097 -137.041134) (xy 168.597521 -137.07764)
			(xy 168.545587 -137.107624) (xy 168.490183 -137.130573) (xy 168.432258 -137.146094) (xy 168.372802 -137.153922)
			(xy 168.312834 -137.153922) (xy 168.253378 -137.146094) (xy 168.195453 -137.130573) (xy 168.140049 -137.107624)
			(xy 168.088115 -137.07764) (xy 168.040539 -137.041134) (xy 167.998134 -136.998729) (xy 167.961628 -136.951153)
			(xy 167.931644 -136.899219) (xy 167.908695 -136.843815) (xy 167.893174 -136.78589) (xy 167.885346 -136.726434)
			(xy 167.884856 -136.69645) (xy 154.325828 -136.69645) (xy 154.325828 -136.704324) (xy 154.325338 -136.734308)
			(xy 154.31751 -136.793764) (xy 154.301989 -136.851689) (xy 154.27904 -136.907093) (xy 154.249056 -136.959027)
			(xy 154.21255 -137.006603) (xy 154.170145 -137.049008) (xy 154.122569 -137.085514) (xy 154.070635 -137.115498)
			(xy 154.015231 -137.138447) (xy 153.957306 -137.153968) (xy 153.89785 -137.161796) (xy 153.837882 -137.161796)
			(xy 153.778426 -137.153968) (xy 153.720501 -137.138447) (xy 153.665097 -137.115498) (xy 153.613163 -137.085514)
			(xy 153.565587 -137.049008) (xy 153.523182 -137.006603) (xy 153.486676 -136.959027) (xy 153.456692 -136.907093)
			(xy 153.433743 -136.851689) (xy 153.418222 -136.793764) (xy 153.410394 -136.734308) (xy 153.409904 -136.704324)
			(xy 52.700299 -136.704324) (xy 52.699938 -136.726418) (xy 52.692115 -136.78584) (xy 52.676602 -136.843733)
			(xy 52.653666 -136.899106) (xy 52.623699 -136.951012) (xy 52.587212 -136.998562) (xy 52.544832 -137.040942)
			(xy 52.497282 -137.077429) (xy 52.445376 -137.107396) (xy 52.390003 -137.130332) (xy 52.33211 -137.145845)
			(xy 52.272688 -137.153668) (xy 52.212752 -137.153668) (xy 52.15333 -137.145845) (xy 52.095437 -137.130332)
			(xy 52.040064 -137.107396) (xy 51.988158 -137.077429) (xy 51.940608 -137.040942) (xy 51.898228 -136.998562)
			(xy 51.861741 -136.951012) (xy 51.831774 -136.899106) (xy 51.808838 -136.843733) (xy 51.793325 -136.78584)
			(xy 51.785502 -136.726418) (xy 51.785012 -136.69645) (xy 38.225476 -136.69645) (xy 38.225476 -136.704324)
			(xy 38.224986 -136.734292) (xy 38.217163 -136.793714) (xy 38.20165 -136.851607) (xy 38.178714 -136.90698)
			(xy 38.148747 -136.958886) (xy 38.11226 -137.006436) (xy 38.06988 -137.048816) (xy 38.02233 -137.085303)
			(xy 37.970424 -137.11527) (xy 37.915051 -137.138206) (xy 37.857158 -137.153719) (xy 37.797736 -137.161542)
			(xy 37.7378 -137.161542) (xy 37.678378 -137.153719) (xy 37.620485 -137.138206) (xy 37.565112 -137.11527)
			(xy 37.513206 -137.085303) (xy 37.465656 -137.048816) (xy 37.423276 -137.006436) (xy 37.386789 -136.958886)
			(xy 37.356822 -136.90698) (xy 37.333886 -136.851607) (xy 37.318373 -136.793714) (xy 37.31055 -136.734292)
			(xy 37.31006 -136.704324) (xy 4.308094 -136.704324) (xy 4.308094 -138.496548) (xy 43.97248 -138.496548)
			(xy 43.97248 -137.632948) (xy 43.97297 -137.602964) (xy 43.980798 -137.543508) (xy 43.996319 -137.485583)
			(xy 44.019268 -137.430179) (xy 44.049252 -137.378245) (xy 44.085758 -137.330669) (xy 44.128163 -137.288264)
			(xy 44.175739 -137.251758) (xy 44.227673 -137.221774) (xy 44.283077 -137.198825) (xy 44.341002 -137.183304)
			(xy 44.400458 -137.175476) (xy 44.460426 -137.175476) (xy 44.519882 -137.183304) (xy 44.577807 -137.198825)
			(xy 44.633211 -137.221774) (xy 44.685145 -137.251758) (xy 44.732721 -137.288264) (xy 44.775126 -137.330669)
			(xy 44.811632 -137.378245) (xy 44.841616 -137.430179) (xy 44.864565 -137.485583) (xy 44.880086 -137.543508)
			(xy 44.887914 -137.602964) (xy 44.888404 -137.632948) (xy 44.888404 -138.496548) (xy 160.072324 -138.496548)
			(xy 160.072324 -137.632948) (xy 160.072814 -137.602964) (xy 160.080642 -137.543508) (xy 160.096163 -137.485583)
			(xy 160.119112 -137.430179) (xy 160.149096 -137.378245) (xy 160.185602 -137.330669) (xy 160.228007 -137.288264)
			(xy 160.275583 -137.251758) (xy 160.327517 -137.221774) (xy 160.382921 -137.198825) (xy 160.440846 -137.183304)
			(xy 160.500302 -137.175476) (xy 160.56027 -137.175476) (xy 160.619726 -137.183304) (xy 160.677651 -137.198825)
			(xy 160.733055 -137.221774) (xy 160.784989 -137.251758) (xy 160.832565 -137.288264) (xy 160.87497 -137.330669)
			(xy 160.911476 -137.378245) (xy 160.94146 -137.430179) (xy 160.964409 -137.485583) (xy 160.97993 -137.543508)
			(xy 160.987758 -137.602964) (xy 160.988248 -137.632948) (xy 160.988248 -138.496548) (xy 276.172676 -138.496548)
			(xy 276.172676 -137.632948) (xy 276.173166 -137.60298) (xy 276.180989 -137.543558) (xy 276.196502 -137.485665)
			(xy 276.219438 -137.430292) (xy 276.249405 -137.378386) (xy 276.285892 -137.330836) (xy 276.328272 -137.288456)
			(xy 276.375822 -137.251969) (xy 276.427728 -137.222002) (xy 276.483101 -137.199066) (xy 276.540994 -137.183553)
			(xy 276.600416 -137.17573) (xy 276.660352 -137.17573) (xy 276.719774 -137.183553) (xy 276.777667 -137.199066)
			(xy 276.83304 -137.222002) (xy 276.884946 -137.251969) (xy 276.932496 -137.288456) (xy 276.974876 -137.330836)
			(xy 277.011363 -137.378386) (xy 277.04133 -137.430292) (xy 277.064266 -137.485665) (xy 277.079779 -137.543558)
			(xy 277.087602 -137.60298) (xy 277.088092 -137.632948) (xy 277.088092 -138.496548) (xy 277.088084 -138.497056)
			(xy 392.27252 -138.497056) (xy 392.27252 -137.633456) (xy 392.27301 -137.603472) (xy 392.280838 -137.544016)
			(xy 392.296359 -137.486091) (xy 392.319308 -137.430687) (xy 392.349292 -137.378753) (xy 392.385798 -137.331177)
			(xy 392.428203 -137.288772) (xy 392.475779 -137.252266) (xy 392.527713 -137.222282) (xy 392.583117 -137.199333)
			(xy 392.641042 -137.183812) (xy 392.700498 -137.175984) (xy 392.760466 -137.175984) (xy 392.819922 -137.183812)
			(xy 392.877847 -137.199333) (xy 392.933251 -137.222282) (xy 392.985185 -137.252266) (xy 393.032761 -137.288772)
			(xy 393.075166 -137.331177) (xy 393.111672 -137.378753) (xy 393.141656 -137.430687) (xy 393.164605 -137.486091)
			(xy 393.180126 -137.544016) (xy 393.187954 -137.603472) (xy 393.188444 -137.633456) (xy 393.188444 -138.497056)
			(xy 393.187954 -138.52704) (xy 393.180126 -138.586496) (xy 393.164605 -138.644421) (xy 393.141656 -138.699825)
			(xy 393.111672 -138.751759) (xy 393.075166 -138.799335) (xy 393.032761 -138.84174) (xy 392.985185 -138.878246)
			(xy 392.933251 -138.90823) (xy 392.877847 -138.931179) (xy 392.819922 -138.9467) (xy 392.760466 -138.954528)
			(xy 392.700498 -138.954528) (xy 392.641042 -138.9467) (xy 392.583117 -138.931179) (xy 392.527713 -138.90823)
			(xy 392.475779 -138.878246) (xy 392.428203 -138.84174) (xy 392.385798 -138.799335) (xy 392.349292 -138.751759)
			(xy 392.319308 -138.699825) (xy 392.296359 -138.644421) (xy 392.280838 -138.586496) (xy 392.27301 -138.52704)
			(xy 392.27252 -138.497056) (xy 277.088084 -138.497056) (xy 277.087602 -138.526516) (xy 277.079779 -138.585938)
			(xy 277.064266 -138.643831) (xy 277.04133 -138.699204) (xy 277.011363 -138.75111) (xy 276.974876 -138.79866)
			(xy 276.932496 -138.84104) (xy 276.884946 -138.877527) (xy 276.83304 -138.907494) (xy 276.777667 -138.93043)
			(xy 276.719774 -138.945943) (xy 276.660352 -138.953766) (xy 276.600416 -138.953766) (xy 276.540994 -138.945943)
			(xy 276.483101 -138.93043) (xy 276.427728 -138.907494) (xy 276.375822 -138.877527) (xy 276.328272 -138.84104)
			(xy 276.285892 -138.79866) (xy 276.249405 -138.75111) (xy 276.219438 -138.699204) (xy 276.196502 -138.643831)
			(xy 276.180989 -138.585938) (xy 276.173166 -138.526516) (xy 276.172676 -138.496548) (xy 160.988248 -138.496548)
			(xy 160.987758 -138.526532) (xy 160.97993 -138.585988) (xy 160.964409 -138.643913) (xy 160.94146 -138.699317)
			(xy 160.911476 -138.751251) (xy 160.87497 -138.798827) (xy 160.832565 -138.841232) (xy 160.784989 -138.877738)
			(xy 160.733055 -138.907722) (xy 160.677651 -138.930671) (xy 160.619726 -138.946192) (xy 160.56027 -138.95402)
			(xy 160.500302 -138.95402) (xy 160.440846 -138.946192) (xy 160.382921 -138.930671) (xy 160.327517 -138.907722)
			(xy 160.275583 -138.877738) (xy 160.228007 -138.841232) (xy 160.185602 -138.798827) (xy 160.149096 -138.751251)
			(xy 160.119112 -138.699317) (xy 160.096163 -138.643913) (xy 160.080642 -138.585988) (xy 160.072814 -138.526532)
			(xy 160.072324 -138.496548) (xy 44.888404 -138.496548) (xy 44.887914 -138.526532) (xy 44.880086 -138.585988)
			(xy 44.864565 -138.643913) (xy 44.841616 -138.699317) (xy 44.811632 -138.751251) (xy 44.775126 -138.798827)
			(xy 44.732721 -138.841232) (xy 44.685145 -138.877738) (xy 44.633211 -138.907722) (xy 44.577807 -138.930671)
			(xy 44.519882 -138.946192) (xy 44.460426 -138.95402) (xy 44.400458 -138.95402) (xy 44.341002 -138.946192)
			(xy 44.283077 -138.930671) (xy 44.227673 -138.907722) (xy 44.175739 -138.877738) (xy 44.128163 -138.841232)
			(xy 44.085758 -138.798827) (xy 44.049252 -138.751251) (xy 44.019268 -138.699317) (xy 43.996319 -138.643913)
			(xy 43.980798 -138.585988) (xy 43.97297 -138.526532) (xy 43.97248 -138.496548) (xy 4.308094 -138.496548)
			(xy 4.308094 -143.48714) (xy 66.599308 -143.48714) (xy 66.599308 -142.62354) (xy 66.599798 -142.593556)
			(xy 66.607626 -142.5341) (xy 66.623147 -142.476175) (xy 66.646096 -142.420771) (xy 66.67608 -142.368837)
			(xy 66.712586 -142.321261) (xy 66.754991 -142.278856) (xy 66.802567 -142.24235) (xy 66.854501 -142.212366)
			(xy 66.909905 -142.189417) (xy 66.96783 -142.173896) (xy 67.027286 -142.166068) (xy 67.087254 -142.166068)
			(xy 67.14671 -142.173896) (xy 67.204635 -142.189417) (xy 67.260039 -142.212366) (xy 67.311973 -142.24235)
			(xy 67.359549 -142.278856) (xy 67.401954 -142.321261) (xy 67.43846 -142.368837) (xy 67.468444 -142.420771)
			(xy 67.491393 -142.476175) (xy 67.506914 -142.5341) (xy 67.514742 -142.593556) (xy 67.515232 -142.62354)
			(xy 67.515232 -143.479266) (xy 81.07426 -143.479266) (xy 81.07426 -142.615666) (xy 81.07475 -142.585682)
			(xy 81.082578 -142.526226) (xy 81.098099 -142.468301) (xy 81.121048 -142.412897) (xy 81.151032 -142.360963)
			(xy 81.187538 -142.313387) (xy 81.229943 -142.270982) (xy 81.277519 -142.234476) (xy 81.329453 -142.204492)
			(xy 81.384857 -142.181543) (xy 81.442782 -142.166022) (xy 81.502238 -142.158194) (xy 81.562206 -142.158194)
			(xy 81.621662 -142.166022) (xy 81.679587 -142.181543) (xy 81.734991 -142.204492) (xy 81.786925 -142.234476)
			(xy 81.834501 -142.270982) (xy 81.876906 -142.313387) (xy 81.913412 -142.360963) (xy 81.943396 -142.412897)
			(xy 81.966345 -142.468301) (xy 81.981866 -142.526226) (xy 81.989694 -142.585682) (xy 81.990184 -142.615666)
			(xy 81.990184 -143.479266) (xy 81.990055 -143.48714) (xy 182.69966 -143.48714) (xy 182.69966 -142.62354)
			(xy 182.70015 -142.593572) (xy 182.707973 -142.53415) (xy 182.723486 -142.476257) (xy 182.746422 -142.420884)
			(xy 182.776389 -142.368978) (xy 182.812876 -142.321428) (xy 182.855256 -142.279048) (xy 182.902806 -142.242561)
			(xy 182.954712 -142.212594) (xy 183.010085 -142.189658) (xy 183.067978 -142.174145) (xy 183.1274 -142.166322)
			(xy 183.187336 -142.166322) (xy 183.246758 -142.174145) (xy 183.304651 -142.189658) (xy 183.360024 -142.212594)
			(xy 183.41193 -142.242561) (xy 183.45948 -142.279048) (xy 183.50186 -142.321428) (xy 183.538347 -142.368978)
			(xy 183.568314 -142.420884) (xy 183.59125 -142.476257) (xy 183.606763 -142.53415) (xy 183.614586 -142.593572)
			(xy 183.615076 -142.62354) (xy 183.615076 -143.479266) (xy 197.174612 -143.479266) (xy 197.174612 -142.615666)
			(xy 197.175102 -142.585698) (xy 197.182925 -142.526276) (xy 197.198438 -142.468383) (xy 197.221374 -142.41301)
			(xy 197.251341 -142.361104) (xy 197.287828 -142.313554) (xy 197.330208 -142.271174) (xy 197.377758 -142.234687)
			(xy 197.429664 -142.20472) (xy 197.485037 -142.181784) (xy 197.54293 -142.166271) (xy 197.602352 -142.158448)
			(xy 197.662288 -142.158448) (xy 197.72171 -142.166271) (xy 197.779603 -142.181784) (xy 197.834976 -142.20472)
			(xy 197.886882 -142.234687) (xy 197.934432 -142.271174) (xy 197.976812 -142.313554) (xy 198.013299 -142.361104)
			(xy 198.043266 -142.41301) (xy 198.066202 -142.468383) (xy 198.081715 -142.526276) (xy 198.089538 -142.585698)
			(xy 198.090028 -142.615666) (xy 198.090028 -143.479266) (xy 198.089899 -143.48714) (xy 298.799504 -143.48714)
			(xy 298.799504 -142.62354) (xy 298.799994 -142.593572) (xy 298.807817 -142.53415) (xy 298.82333 -142.476257)
			(xy 298.846266 -142.420884) (xy 298.876233 -142.368978) (xy 298.91272 -142.321428) (xy 298.9551 -142.279048)
			(xy 299.00265 -142.242561) (xy 299.054556 -142.212594) (xy 299.109929 -142.189658) (xy 299.167822 -142.174145)
			(xy 299.227244 -142.166322) (xy 299.28718 -142.166322) (xy 299.346602 -142.174145) (xy 299.404495 -142.189658)
			(xy 299.459868 -142.212594) (xy 299.511774 -142.242561) (xy 299.559324 -142.279048) (xy 299.601704 -142.321428)
			(xy 299.638191 -142.368978) (xy 299.668158 -142.420884) (xy 299.691094 -142.476257) (xy 299.706607 -142.53415)
			(xy 299.71443 -142.593572) (xy 299.71492 -142.62354) (xy 299.71492 -143.479266) (xy 313.274456 -143.479266)
			(xy 313.274456 -142.615666) (xy 313.274946 -142.585698) (xy 313.282769 -142.526276) (xy 313.298282 -142.468383)
			(xy 313.321218 -142.41301) (xy 313.351185 -142.361104) (xy 313.387672 -142.313554) (xy 313.430052 -142.271174)
			(xy 313.477602 -142.234687) (xy 313.529508 -142.20472) (xy 313.584881 -142.181784) (xy 313.642774 -142.166271)
			(xy 313.702196 -142.158448) (xy 313.762132 -142.158448) (xy 313.821554 -142.166271) (xy 313.879447 -142.181784)
			(xy 313.93482 -142.20472) (xy 313.986726 -142.234687) (xy 314.034276 -142.271174) (xy 314.076656 -142.313554)
			(xy 314.113143 -142.361104) (xy 314.14311 -142.41301) (xy 314.166046 -142.468383) (xy 314.181559 -142.526276)
			(xy 314.189382 -142.585698) (xy 314.189872 -142.615666) (xy 314.189872 -143.479266) (xy 314.189743 -143.48714)
			(xy 414.899348 -143.48714) (xy 414.899348 -142.62354) (xy 414.899838 -142.593556) (xy 414.907666 -142.5341)
			(xy 414.923187 -142.476175) (xy 414.946136 -142.420771) (xy 414.97612 -142.368837) (xy 415.012626 -142.321261)
			(xy 415.055031 -142.278856) (xy 415.102607 -142.24235) (xy 415.154541 -142.212366) (xy 415.209945 -142.189417)
			(xy 415.26787 -142.173896) (xy 415.327326 -142.166068) (xy 415.387294 -142.166068) (xy 415.44675 -142.173896)
			(xy 415.504675 -142.189417) (xy 415.560079 -142.212366) (xy 415.612013 -142.24235) (xy 415.659589 -142.278856)
			(xy 415.701994 -142.321261) (xy 415.7385 -142.368837) (xy 415.768484 -142.420771) (xy 415.791433 -142.476175)
			(xy 415.806954 -142.5341) (xy 415.814782 -142.593556) (xy 415.815272 -142.62354) (xy 415.815272 -143.479266)
			(xy 429.3743 -143.479266) (xy 429.3743 -142.615666) (xy 429.37479 -142.585682) (xy 429.382618 -142.526226)
			(xy 429.398139 -142.468301) (xy 429.421088 -142.412897) (xy 429.451072 -142.360963) (xy 429.487578 -142.313387)
			(xy 429.529983 -142.270982) (xy 429.577559 -142.234476) (xy 429.629493 -142.204492) (xy 429.684897 -142.181543)
			(xy 429.742822 -142.166022) (xy 429.802278 -142.158194) (xy 429.862246 -142.158194) (xy 429.921702 -142.166022)
			(xy 429.979627 -142.181543) (xy 430.035031 -142.204492) (xy 430.086965 -142.234476) (xy 430.134541 -142.270982)
			(xy 430.176946 -142.313387) (xy 430.213452 -142.360963) (xy 430.243436 -142.412897) (xy 430.266385 -142.468301)
			(xy 430.281906 -142.526226) (xy 430.289734 -142.585682) (xy 430.290224 -142.615666) (xy 430.290224 -143.479266)
			(xy 430.289734 -143.50925) (xy 430.281906 -143.568706) (xy 430.266385 -143.626631) (xy 430.243436 -143.682035)
			(xy 430.213452 -143.733969) (xy 430.176946 -143.781545) (xy 430.134541 -143.82395) (xy 430.086965 -143.860456)
			(xy 430.035031 -143.89044) (xy 429.979627 -143.913389) (xy 429.921702 -143.92891) (xy 429.862246 -143.936738)
			(xy 429.802278 -143.936738) (xy 429.742822 -143.92891) (xy 429.684897 -143.913389) (xy 429.629493 -143.89044)
			(xy 429.577559 -143.860456) (xy 429.529983 -143.82395) (xy 429.487578 -143.781545) (xy 429.451072 -143.733969)
			(xy 429.421088 -143.682035) (xy 429.398139 -143.626631) (xy 429.382618 -143.568706) (xy 429.37479 -143.50925)
			(xy 429.3743 -143.479266) (xy 415.815272 -143.479266) (xy 415.815272 -143.48714) (xy 415.814782 -143.517124)
			(xy 415.806954 -143.57658) (xy 415.791433 -143.634505) (xy 415.768484 -143.689909) (xy 415.7385 -143.741843)
			(xy 415.701994 -143.789419) (xy 415.659589 -143.831824) (xy 415.612013 -143.86833) (xy 415.560079 -143.898314)
			(xy 415.504675 -143.921263) (xy 415.44675 -143.936784) (xy 415.387294 -143.944612) (xy 415.327326 -143.944612)
			(xy 415.26787 -143.936784) (xy 415.209945 -143.921263) (xy 415.154541 -143.898314) (xy 415.102607 -143.86833)
			(xy 415.055031 -143.831824) (xy 415.012626 -143.789419) (xy 414.97612 -143.741843) (xy 414.946136 -143.689909)
			(xy 414.923187 -143.634505) (xy 414.907666 -143.57658) (xy 414.899838 -143.517124) (xy 414.899348 -143.48714)
			(xy 314.189743 -143.48714) (xy 314.189382 -143.509234) (xy 314.181559 -143.568656) (xy 314.166046 -143.626549)
			(xy 314.14311 -143.681922) (xy 314.113143 -143.733828) (xy 314.076656 -143.781378) (xy 314.034276 -143.823758)
			(xy 313.986726 -143.860245) (xy 313.93482 -143.890212) (xy 313.879447 -143.913148) (xy 313.821554 -143.928661)
			(xy 313.762132 -143.936484) (xy 313.702196 -143.936484) (xy 313.642774 -143.928661) (xy 313.584881 -143.913148)
			(xy 313.529508 -143.890212) (xy 313.477602 -143.860245) (xy 313.430052 -143.823758) (xy 313.387672 -143.781378)
			(xy 313.351185 -143.733828) (xy 313.321218 -143.681922) (xy 313.298282 -143.626549) (xy 313.282769 -143.568656)
			(xy 313.274946 -143.509234) (xy 313.274456 -143.479266) (xy 299.71492 -143.479266) (xy 299.71492 -143.48714)
			(xy 299.71443 -143.517108) (xy 299.706607 -143.57653) (xy 299.691094 -143.634423) (xy 299.668158 -143.689796)
			(xy 299.638191 -143.741702) (xy 299.601704 -143.789252) (xy 299.559324 -143.831632) (xy 299.511774 -143.868119)
			(xy 299.459868 -143.898086) (xy 299.404495 -143.921022) (xy 299.346602 -143.936535) (xy 299.28718 -143.944358)
			(xy 299.227244 -143.944358) (xy 299.167822 -143.936535) (xy 299.109929 -143.921022) (xy 299.054556 -143.898086)
			(xy 299.00265 -143.868119) (xy 298.9551 -143.831632) (xy 298.91272 -143.789252) (xy 298.876233 -143.741702)
			(xy 298.846266 -143.689796) (xy 298.82333 -143.634423) (xy 298.807817 -143.57653) (xy 298.799994 -143.517108)
			(xy 298.799504 -143.48714) (xy 198.089899 -143.48714) (xy 198.089538 -143.509234) (xy 198.081715 -143.568656)
			(xy 198.066202 -143.626549) (xy 198.043266 -143.681922) (xy 198.013299 -143.733828) (xy 197.976812 -143.781378)
			(xy 197.934432 -143.823758) (xy 197.886882 -143.860245) (xy 197.834976 -143.890212) (xy 197.779603 -143.913148)
			(xy 197.72171 -143.928661) (xy 197.662288 -143.936484) (xy 197.602352 -143.936484) (xy 197.54293 -143.928661)
			(xy 197.485037 -143.913148) (xy 197.429664 -143.890212) (xy 197.377758 -143.860245) (xy 197.330208 -143.823758)
			(xy 197.287828 -143.781378) (xy 197.251341 -143.733828) (xy 197.221374 -143.681922) (xy 197.198438 -143.626549)
			(xy 197.182925 -143.568656) (xy 197.175102 -143.509234) (xy 197.174612 -143.479266) (xy 183.615076 -143.479266)
			(xy 183.615076 -143.48714) (xy 183.614586 -143.517108) (xy 183.606763 -143.57653) (xy 183.59125 -143.634423)
			(xy 183.568314 -143.689796) (xy 183.538347 -143.741702) (xy 183.50186 -143.789252) (xy 183.45948 -143.831632)
			(xy 183.41193 -143.868119) (xy 183.360024 -143.898086) (xy 183.304651 -143.921022) (xy 183.246758 -143.936535)
			(xy 183.187336 -143.944358) (xy 183.1274 -143.944358) (xy 183.067978 -143.936535) (xy 183.010085 -143.921022)
			(xy 182.954712 -143.898086) (xy 182.902806 -143.868119) (xy 182.855256 -143.831632) (xy 182.812876 -143.789252)
			(xy 182.776389 -143.741702) (xy 182.746422 -143.689796) (xy 182.723486 -143.634423) (xy 182.707973 -143.57653)
			(xy 182.70015 -143.517108) (xy 182.69966 -143.48714) (xy 81.990055 -143.48714) (xy 81.989694 -143.50925)
			(xy 81.981866 -143.568706) (xy 81.966345 -143.626631) (xy 81.943396 -143.682035) (xy 81.913412 -143.733969)
			(xy 81.876906 -143.781545) (xy 81.834501 -143.82395) (xy 81.786925 -143.860456) (xy 81.734991 -143.89044)
			(xy 81.679587 -143.913389) (xy 81.621662 -143.92891) (xy 81.562206 -143.936738) (xy 81.502238 -143.936738)
			(xy 81.442782 -143.92891) (xy 81.384857 -143.913389) (xy 81.329453 -143.89044) (xy 81.277519 -143.860456)
			(xy 81.229943 -143.82395) (xy 81.187538 -143.781545) (xy 81.151032 -143.733969) (xy 81.121048 -143.682035)
			(xy 81.098099 -143.626631) (xy 81.082578 -143.568706) (xy 81.07475 -143.50925) (xy 81.07426 -143.479266)
			(xy 67.515232 -143.479266) (xy 67.515232 -143.48714) (xy 67.514742 -143.517124) (xy 67.506914 -143.57658)
			(xy 67.491393 -143.634505) (xy 67.468444 -143.689909) (xy 67.43846 -143.741843) (xy 67.401954 -143.789419)
			(xy 67.359549 -143.831824) (xy 67.311973 -143.86833) (xy 67.260039 -143.898314) (xy 67.204635 -143.921263)
			(xy 67.14671 -143.936784) (xy 67.087254 -143.944612) (xy 67.027286 -143.944612) (xy 66.96783 -143.936784)
			(xy 66.909905 -143.921263) (xy 66.854501 -143.898314) (xy 66.802567 -143.86833) (xy 66.754991 -143.831824)
			(xy 66.712586 -143.789419) (xy 66.67608 -143.741843) (xy 66.646096 -143.689909) (xy 66.623147 -143.634505)
			(xy 66.607626 -143.57658) (xy 66.599798 -143.517124) (xy 66.599308 -143.48714) (xy 4.308094 -143.48714)
			(xy 4.308094 -145.287238) (xy 64.745108 -145.287238) (xy 64.745108 -144.423638) (xy 64.745598 -144.393654)
			(xy 64.753426 -144.334198) (xy 64.768947 -144.276273) (xy 64.791896 -144.220869) (xy 64.82188 -144.168935)
			(xy 64.858386 -144.121359) (xy 64.900791 -144.078954) (xy 64.948367 -144.042448) (xy 65.000301 -144.012464)
			(xy 65.055705 -143.989515) (xy 65.11363 -143.973994) (xy 65.173086 -143.966166) (xy 65.233054 -143.966166)
			(xy 65.29251 -143.973994) (xy 65.350435 -143.989515) (xy 65.405839 -144.012464) (xy 65.457773 -144.042448)
			(xy 65.505349 -144.078954) (xy 65.547754 -144.121359) (xy 65.58426 -144.168935) (xy 65.614244 -144.220869)
			(xy 65.637193 -144.276273) (xy 65.652714 -144.334198) (xy 65.660542 -144.393654) (xy 65.661032 -144.423638)
			(xy 65.661032 -145.285714) (xy 83.716368 -145.285714) (xy 83.716368 -144.422114) (xy 83.716858 -144.39213)
			(xy 83.724686 -144.332674) (xy 83.740207 -144.274749) (xy 83.763156 -144.219345) (xy 83.79314 -144.167411)
			(xy 83.829646 -144.119835) (xy 83.872051 -144.07743) (xy 83.919627 -144.040924) (xy 83.971561 -144.01094)
			(xy 84.026965 -143.987991) (xy 84.08489 -143.97247) (xy 84.144346 -143.964642) (xy 84.204314 -143.964642)
			(xy 84.26377 -143.97247) (xy 84.321695 -143.987991) (xy 84.377099 -144.01094) (xy 84.429033 -144.040924)
			(xy 84.476609 -144.07743) (xy 84.519014 -144.119835) (xy 84.55552 -144.167411) (xy 84.585504 -144.219345)
			(xy 84.608453 -144.274749) (xy 84.623974 -144.332674) (xy 84.631802 -144.39213) (xy 84.632292 -144.422114)
			(xy 84.632292 -145.285714) (xy 84.632267 -145.287238) (xy 180.84546 -145.287238) (xy 180.84546 -144.423638)
			(xy 180.84595 -144.39367) (xy 180.853773 -144.334248) (xy 180.869286 -144.276355) (xy 180.892222 -144.220982)
			(xy 180.922189 -144.169076) (xy 180.958676 -144.121526) (xy 181.001056 -144.079146) (xy 181.048606 -144.042659)
			(xy 181.100512 -144.012692) (xy 181.155885 -143.989756) (xy 181.213778 -143.974243) (xy 181.2732 -143.96642)
			(xy 181.333136 -143.96642) (xy 181.392558 -143.974243) (xy 181.450451 -143.989756) (xy 181.505824 -144.012692)
			(xy 181.55773 -144.042659) (xy 181.60528 -144.079146) (xy 181.64766 -144.121526) (xy 181.684147 -144.169076)
			(xy 181.714114 -144.220982) (xy 181.73705 -144.276355) (xy 181.752563 -144.334248) (xy 181.760386 -144.39367)
			(xy 181.760876 -144.423638) (xy 181.760876 -145.285714) (xy 199.81672 -145.285714) (xy 199.81672 -144.422114)
			(xy 199.81721 -144.392146) (xy 199.825033 -144.332724) (xy 199.840546 -144.274831) (xy 199.863482 -144.219458)
			(xy 199.893449 -144.167552) (xy 199.929936 -144.120002) (xy 199.972316 -144.077622) (xy 200.019866 -144.041135)
			(xy 200.071772 -144.011168) (xy 200.127145 -143.988232) (xy 200.185038 -143.972719) (xy 200.24446 -143.964896)
			(xy 200.304396 -143.964896) (xy 200.363818 -143.972719) (xy 200.421711 -143.988232) (xy 200.477084 -144.011168)
			(xy 200.52899 -144.041135) (xy 200.57654 -144.077622) (xy 200.61892 -144.120002) (xy 200.655407 -144.167552)
			(xy 200.685374 -144.219458) (xy 200.70831 -144.274831) (xy 200.723823 -144.332724) (xy 200.731646 -144.392146)
			(xy 200.732136 -144.422114) (xy 200.732136 -145.285714) (xy 200.732111 -145.287238) (xy 296.945304 -145.287238)
			(xy 296.945304 -144.423638) (xy 296.945794 -144.39367) (xy 296.953617 -144.334248) (xy 296.96913 -144.276355)
			(xy 296.992066 -144.220982) (xy 297.022033 -144.169076) (xy 297.05852 -144.121526) (xy 297.1009 -144.079146)
			(xy 297.14845 -144.042659) (xy 297.200356 -144.012692) (xy 297.255729 -143.989756) (xy 297.313622 -143.974243)
			(xy 297.373044 -143.96642) (xy 297.43298 -143.96642) (xy 297.492402 -143.974243) (xy 297.550295 -143.989756)
			(xy 297.605668 -144.012692) (xy 297.657574 -144.042659) (xy 297.705124 -144.079146) (xy 297.747504 -144.121526)
			(xy 297.783991 -144.169076) (xy 297.813958 -144.220982) (xy 297.836894 -144.276355) (xy 297.852407 -144.334248)
			(xy 297.86023 -144.39367) (xy 297.86072 -144.423638) (xy 297.86072 -145.285714) (xy 315.916564 -145.285714)
			(xy 315.916564 -144.422114) (xy 315.917054 -144.392146) (xy 315.924877 -144.332724) (xy 315.94039 -144.274831)
			(xy 315.963326 -144.219458) (xy 315.993293 -144.167552) (xy 316.02978 -144.120002) (xy 316.07216 -144.077622)
			(xy 316.11971 -144.041135) (xy 316.171616 -144.011168) (xy 316.226989 -143.988232) (xy 316.284882 -143.972719)
			(xy 316.344304 -143.964896) (xy 316.40424 -143.964896) (xy 316.463662 -143.972719) (xy 316.521555 -143.988232)
			(xy 316.576928 -144.011168) (xy 316.628834 -144.041135) (xy 316.676384 -144.077622) (xy 316.718764 -144.120002)
			(xy 316.755251 -144.167552) (xy 316.785218 -144.219458) (xy 316.808154 -144.274831) (xy 316.823667 -144.332724)
			(xy 316.83149 -144.392146) (xy 316.83198 -144.422114) (xy 316.83198 -145.285714) (xy 316.831955 -145.287238)
			(xy 413.045148 -145.287238) (xy 413.045148 -144.423638) (xy 413.045638 -144.393654) (xy 413.053466 -144.334198)
			(xy 413.068987 -144.276273) (xy 413.091936 -144.220869) (xy 413.12192 -144.168935) (xy 413.158426 -144.121359)
			(xy 413.200831 -144.078954) (xy 413.248407 -144.042448) (xy 413.300341 -144.012464) (xy 413.355745 -143.989515)
			(xy 413.41367 -143.973994) (xy 413.473126 -143.966166) (xy 413.533094 -143.966166) (xy 413.59255 -143.973994)
			(xy 413.650475 -143.989515) (xy 413.705879 -144.012464) (xy 413.757813 -144.042448) (xy 413.805389 -144.078954)
			(xy 413.847794 -144.121359) (xy 413.8843 -144.168935) (xy 413.914284 -144.220869) (xy 413.937233 -144.276273)
			(xy 413.952754 -144.334198) (xy 413.960582 -144.393654) (xy 413.961072 -144.423638) (xy 413.961072 -145.285714)
			(xy 432.016408 -145.285714) (xy 432.016408 -144.422114) (xy 432.016898 -144.39213) (xy 432.024726 -144.332674)
			(xy 432.040247 -144.274749) (xy 432.063196 -144.219345) (xy 432.09318 -144.167411) (xy 432.129686 -144.119835)
			(xy 432.172091 -144.07743) (xy 432.219667 -144.040924) (xy 432.271601 -144.01094) (xy 432.327005 -143.987991)
			(xy 432.38493 -143.97247) (xy 432.444386 -143.964642) (xy 432.504354 -143.964642) (xy 432.56381 -143.97247)
			(xy 432.621735 -143.987991) (xy 432.677139 -144.01094) (xy 432.729073 -144.040924) (xy 432.776649 -144.07743)
			(xy 432.819054 -144.119835) (xy 432.85556 -144.167411) (xy 432.885544 -144.219345) (xy 432.908493 -144.274749)
			(xy 432.924014 -144.332674) (xy 432.931842 -144.39213) (xy 432.932332 -144.422114) (xy 432.932332 -145.285714)
			(xy 432.931842 -145.315698) (xy 432.924014 -145.375154) (xy 432.908493 -145.433079) (xy 432.885544 -145.488483)
			(xy 432.85556 -145.540417) (xy 432.819054 -145.587993) (xy 432.776649 -145.630398) (xy 432.729073 -145.666904)
			(xy 432.677139 -145.696888) (xy 432.621735 -145.719837) (xy 432.56381 -145.735358) (xy 432.504354 -145.743186)
			(xy 432.444386 -145.743186) (xy 432.38493 -145.735358) (xy 432.327005 -145.719837) (xy 432.271601 -145.696888)
			(xy 432.219667 -145.666904) (xy 432.172091 -145.630398) (xy 432.129686 -145.587993) (xy 432.09318 -145.540417)
			(xy 432.063196 -145.488483) (xy 432.040247 -145.433079) (xy 432.024726 -145.375154) (xy 432.016898 -145.315698)
			(xy 432.016408 -145.285714) (xy 413.961072 -145.285714) (xy 413.961072 -145.287238) (xy 413.960582 -145.317222)
			(xy 413.952754 -145.376678) (xy 413.937233 -145.434603) (xy 413.914284 -145.490007) (xy 413.8843 -145.541941)
			(xy 413.847794 -145.589517) (xy 413.805389 -145.631922) (xy 413.757813 -145.668428) (xy 413.705879 -145.698412)
			(xy 413.650475 -145.721361) (xy 413.59255 -145.736882) (xy 413.533094 -145.74471) (xy 413.473126 -145.74471)
			(xy 413.41367 -145.736882) (xy 413.355745 -145.721361) (xy 413.300341 -145.698412) (xy 413.248407 -145.668428)
			(xy 413.200831 -145.631922) (xy 413.158426 -145.589517) (xy 413.12192 -145.541941) (xy 413.091936 -145.490007)
			(xy 413.068987 -145.434603) (xy 413.053466 -145.376678) (xy 413.045638 -145.317222) (xy 413.045148 -145.287238)
			(xy 316.831955 -145.287238) (xy 316.83149 -145.315682) (xy 316.823667 -145.375104) (xy 316.808154 -145.432997)
			(xy 316.785218 -145.48837) (xy 316.755251 -145.540276) (xy 316.718764 -145.587826) (xy 316.676384 -145.630206)
			(xy 316.628834 -145.666693) (xy 316.576928 -145.69666) (xy 316.521555 -145.719596) (xy 316.463662 -145.735109)
			(xy 316.40424 -145.742932) (xy 316.344304 -145.742932) (xy 316.284882 -145.735109) (xy 316.226989 -145.719596)
			(xy 316.171616 -145.69666) (xy 316.11971 -145.666693) (xy 316.07216 -145.630206) (xy 316.02978 -145.587826)
			(xy 315.993293 -145.540276) (xy 315.963326 -145.48837) (xy 315.94039 -145.432997) (xy 315.924877 -145.375104)
			(xy 315.917054 -145.315682) (xy 315.916564 -145.285714) (xy 297.86072 -145.285714) (xy 297.86072 -145.287238)
			(xy 297.86023 -145.317206) (xy 297.852407 -145.376628) (xy 297.836894 -145.434521) (xy 297.813958 -145.489894)
			(xy 297.783991 -145.5418) (xy 297.747504 -145.58935) (xy 297.705124 -145.63173) (xy 297.657574 -145.668217)
			(xy 297.605668 -145.698184) (xy 297.550295 -145.72112) (xy 297.492402 -145.736633) (xy 297.43298 -145.744456)
			(xy 297.373044 -145.744456) (xy 297.313622 -145.736633) (xy 297.255729 -145.72112) (xy 297.200356 -145.698184)
			(xy 297.14845 -145.668217) (xy 297.1009 -145.63173) (xy 297.05852 -145.58935) (xy 297.022033 -145.5418)
			(xy 296.992066 -145.489894) (xy 296.96913 -145.434521) (xy 296.953617 -145.376628) (xy 296.945794 -145.317206)
			(xy 296.945304 -145.287238) (xy 200.732111 -145.287238) (xy 200.731646 -145.315682) (xy 200.723823 -145.375104)
			(xy 200.70831 -145.432997) (xy 200.685374 -145.48837) (xy 200.655407 -145.540276) (xy 200.61892 -145.587826)
			(xy 200.57654 -145.630206) (xy 200.52899 -145.666693) (xy 200.477084 -145.69666) (xy 200.421711 -145.719596)
			(xy 200.363818 -145.735109) (xy 200.304396 -145.742932) (xy 200.24446 -145.742932) (xy 200.185038 -145.735109)
			(xy 200.127145 -145.719596) (xy 200.071772 -145.69666) (xy 200.019866 -145.666693) (xy 199.972316 -145.630206)
			(xy 199.929936 -145.587826) (xy 199.893449 -145.540276) (xy 199.863482 -145.48837) (xy 199.840546 -145.432997)
			(xy 199.825033 -145.375104) (xy 199.81721 -145.315682) (xy 199.81672 -145.285714) (xy 181.760876 -145.285714)
			(xy 181.760876 -145.287238) (xy 181.760386 -145.317206) (xy 181.752563 -145.376628) (xy 181.73705 -145.434521)
			(xy 181.714114 -145.489894) (xy 181.684147 -145.5418) (xy 181.64766 -145.58935) (xy 181.60528 -145.63173)
			(xy 181.55773 -145.668217) (xy 181.505824 -145.698184) (xy 181.450451 -145.72112) (xy 181.392558 -145.736633)
			(xy 181.333136 -145.744456) (xy 181.2732 -145.744456) (xy 181.213778 -145.736633) (xy 181.155885 -145.72112)
			(xy 181.100512 -145.698184) (xy 181.048606 -145.668217) (xy 181.001056 -145.63173) (xy 180.958676 -145.58935)
			(xy 180.922189 -145.5418) (xy 180.892222 -145.489894) (xy 180.869286 -145.434521) (xy 180.853773 -145.376628)
			(xy 180.84595 -145.317206) (xy 180.84546 -145.287238) (xy 84.632267 -145.287238) (xy 84.631802 -145.315698)
			(xy 84.623974 -145.375154) (xy 84.608453 -145.433079) (xy 84.585504 -145.488483) (xy 84.55552 -145.540417)
			(xy 84.519014 -145.587993) (xy 84.476609 -145.630398) (xy 84.429033 -145.666904) (xy 84.377099 -145.696888)
			(xy 84.321695 -145.719837) (xy 84.26377 -145.735358) (xy 84.204314 -145.743186) (xy 84.144346 -145.743186)
			(xy 84.08489 -145.735358) (xy 84.026965 -145.719837) (xy 83.971561 -145.696888) (xy 83.919627 -145.666904)
			(xy 83.872051 -145.630398) (xy 83.829646 -145.587993) (xy 83.79314 -145.540417) (xy 83.763156 -145.488483)
			(xy 83.740207 -145.433079) (xy 83.724686 -145.375154) (xy 83.716858 -145.315698) (xy 83.716368 -145.285714)
			(xy 65.661032 -145.285714) (xy 65.661032 -145.287238) (xy 65.660542 -145.317222) (xy 65.652714 -145.376678)
			(xy 65.637193 -145.434603) (xy 65.614244 -145.490007) (xy 65.58426 -145.541941) (xy 65.547754 -145.589517)
			(xy 65.505349 -145.631922) (xy 65.457773 -145.668428) (xy 65.405839 -145.698412) (xy 65.350435 -145.721361)
			(xy 65.29251 -145.736882) (xy 65.233054 -145.74471) (xy 65.173086 -145.74471) (xy 65.11363 -145.736882)
			(xy 65.055705 -145.721361) (xy 65.000301 -145.698412) (xy 64.948367 -145.668428) (xy 64.900791 -145.631922)
			(xy 64.858386 -145.589517) (xy 64.82188 -145.541941) (xy 64.791896 -145.490007) (xy 64.768947 -145.434603)
			(xy 64.753426 -145.376678) (xy 64.745598 -145.317222) (xy 64.745108 -145.287238) (xy 4.308094 -145.287238)
			(xy 4.308094 -147.087336) (xy 66.599308 -147.087336) (xy 66.599308 -146.223736) (xy 66.599798 -146.193752)
			(xy 66.607626 -146.134296) (xy 66.623147 -146.076371) (xy 66.646096 -146.020967) (xy 66.67608 -145.969033)
			(xy 66.712586 -145.921457) (xy 66.754991 -145.879052) (xy 66.802567 -145.842546) (xy 66.854501 -145.812562)
			(xy 66.909905 -145.789613) (xy 66.96783 -145.774092) (xy 67.027286 -145.766264) (xy 67.087254 -145.766264)
			(xy 67.14671 -145.774092) (xy 67.204635 -145.789613) (xy 67.260039 -145.812562) (xy 67.311973 -145.842546)
			(xy 67.359549 -145.879052) (xy 67.401954 -145.921457) (xy 67.43846 -145.969033) (xy 67.468444 -146.020967)
			(xy 67.491393 -146.076371) (xy 67.506914 -146.134296) (xy 67.514742 -146.193752) (xy 67.515232 -146.223736)
			(xy 67.515232 -147.079208) (xy 81.07426 -147.079208) (xy 81.07426 -146.215608) (xy 81.07475 -146.185624)
			(xy 81.082578 -146.126168) (xy 81.098099 -146.068243) (xy 81.121048 -146.012839) (xy 81.151032 -145.960905)
			(xy 81.187538 -145.913329) (xy 81.229943 -145.870924) (xy 81.277519 -145.834418) (xy 81.329453 -145.804434)
			(xy 81.384857 -145.781485) (xy 81.442782 -145.765964) (xy 81.502238 -145.758136) (xy 81.562206 -145.758136)
			(xy 81.621662 -145.765964) (xy 81.679587 -145.781485) (xy 81.734991 -145.804434) (xy 81.786925 -145.834418)
			(xy 81.834501 -145.870924) (xy 81.876906 -145.913329) (xy 81.913412 -145.960905) (xy 81.943396 -146.012839)
			(xy 81.966345 -146.068243) (xy 81.981866 -146.126168) (xy 81.989694 -146.185624) (xy 81.990184 -146.215608)
			(xy 81.990184 -147.079208) (xy 81.990051 -147.087336) (xy 182.69966 -147.087336) (xy 182.69966 -146.223736)
			(xy 182.70015 -146.193768) (xy 182.707973 -146.134346) (xy 182.723486 -146.076453) (xy 182.746422 -146.02108)
			(xy 182.776389 -145.969174) (xy 182.812876 -145.921624) (xy 182.855256 -145.879244) (xy 182.902806 -145.842757)
			(xy 182.954712 -145.81279) (xy 183.010085 -145.789854) (xy 183.067978 -145.774341) (xy 183.1274 -145.766518)
			(xy 183.187336 -145.766518) (xy 183.246758 -145.774341) (xy 183.304651 -145.789854) (xy 183.360024 -145.81279)
			(xy 183.41193 -145.842757) (xy 183.45948 -145.879244) (xy 183.50186 -145.921624) (xy 183.538347 -145.969174)
			(xy 183.568314 -146.02108) (xy 183.59125 -146.076453) (xy 183.606763 -146.134346) (xy 183.614586 -146.193768)
			(xy 183.615076 -146.223736) (xy 183.615076 -147.079208) (xy 197.174612 -147.079208) (xy 197.174612 -146.215608)
			(xy 197.175102 -146.18564) (xy 197.182925 -146.126218) (xy 197.198438 -146.068325) (xy 197.221374 -146.012952)
			(xy 197.251341 -145.961046) (xy 197.287828 -145.913496) (xy 197.330208 -145.871116) (xy 197.377758 -145.834629)
			(xy 197.429664 -145.804662) (xy 197.485037 -145.781726) (xy 197.54293 -145.766213) (xy 197.602352 -145.75839)
			(xy 197.662288 -145.75839) (xy 197.72171 -145.766213) (xy 197.779603 -145.781726) (xy 197.834976 -145.804662)
			(xy 197.886882 -145.834629) (xy 197.934432 -145.871116) (xy 197.976812 -145.913496) (xy 198.013299 -145.961046)
			(xy 198.043266 -146.012952) (xy 198.066202 -146.068325) (xy 198.081715 -146.126218) (xy 198.089538 -146.18564)
			(xy 198.090028 -146.215608) (xy 198.090028 -147.079208) (xy 198.089895 -147.087336) (xy 298.799504 -147.087336)
			(xy 298.799504 -146.223736) (xy 298.799994 -146.193768) (xy 298.807817 -146.134346) (xy 298.82333 -146.076453)
			(xy 298.846266 -146.02108) (xy 298.876233 -145.969174) (xy 298.91272 -145.921624) (xy 298.9551 -145.879244)
			(xy 299.00265 -145.842757) (xy 299.054556 -145.81279) (xy 299.109929 -145.789854) (xy 299.167822 -145.774341)
			(xy 299.227244 -145.766518) (xy 299.28718 -145.766518) (xy 299.346602 -145.774341) (xy 299.404495 -145.789854)
			(xy 299.459868 -145.81279) (xy 299.511774 -145.842757) (xy 299.559324 -145.879244) (xy 299.601704 -145.921624)
			(xy 299.638191 -145.969174) (xy 299.668158 -146.02108) (xy 299.691094 -146.076453) (xy 299.706607 -146.134346)
			(xy 299.71443 -146.193768) (xy 299.71492 -146.223736) (xy 299.71492 -147.079208) (xy 313.274456 -147.079208)
			(xy 313.274456 -146.215608) (xy 313.274946 -146.18564) (xy 313.282769 -146.126218) (xy 313.298282 -146.068325)
			(xy 313.321218 -146.012952) (xy 313.351185 -145.961046) (xy 313.387672 -145.913496) (xy 313.430052 -145.871116)
			(xy 313.477602 -145.834629) (xy 313.529508 -145.804662) (xy 313.584881 -145.781726) (xy 313.642774 -145.766213)
			(xy 313.702196 -145.75839) (xy 313.762132 -145.75839) (xy 313.821554 -145.766213) (xy 313.879447 -145.781726)
			(xy 313.93482 -145.804662) (xy 313.986726 -145.834629) (xy 314.034276 -145.871116) (xy 314.076656 -145.913496)
			(xy 314.113143 -145.961046) (xy 314.14311 -146.012952) (xy 314.166046 -146.068325) (xy 314.181559 -146.126218)
			(xy 314.189382 -146.18564) (xy 314.189872 -146.215608) (xy 314.189872 -147.079208) (xy 314.189739 -147.087336)
			(xy 414.899348 -147.087336) (xy 414.899348 -146.223736) (xy 414.899838 -146.193752) (xy 414.907666 -146.134296)
			(xy 414.923187 -146.076371) (xy 414.946136 -146.020967) (xy 414.97612 -145.969033) (xy 415.012626 -145.921457)
			(xy 415.055031 -145.879052) (xy 415.102607 -145.842546) (xy 415.154541 -145.812562) (xy 415.209945 -145.789613)
			(xy 415.26787 -145.774092) (xy 415.327326 -145.766264) (xy 415.387294 -145.766264) (xy 415.44675 -145.774092)
			(xy 415.504675 -145.789613) (xy 415.560079 -145.812562) (xy 415.612013 -145.842546) (xy 415.659589 -145.879052)
			(xy 415.701994 -145.921457) (xy 415.7385 -145.969033) (xy 415.768484 -146.020967) (xy 415.791433 -146.076371)
			(xy 415.806954 -146.134296) (xy 415.814782 -146.193752) (xy 415.815272 -146.223736) (xy 415.815272 -147.079208)
			(xy 429.3743 -147.079208) (xy 429.3743 -146.215608) (xy 429.37479 -146.185624) (xy 429.382618 -146.126168)
			(xy 429.398139 -146.068243) (xy 429.421088 -146.012839) (xy 429.451072 -145.960905) (xy 429.487578 -145.913329)
			(xy 429.529983 -145.870924) (xy 429.577559 -145.834418) (xy 429.629493 -145.804434) (xy 429.684897 -145.781485)
			(xy 429.742822 -145.765964) (xy 429.802278 -145.758136) (xy 429.862246 -145.758136) (xy 429.921702 -145.765964)
			(xy 429.979627 -145.781485) (xy 430.035031 -145.804434) (xy 430.086965 -145.834418) (xy 430.134541 -145.870924)
			(xy 430.176946 -145.913329) (xy 430.213452 -145.960905) (xy 430.243436 -146.012839) (xy 430.266385 -146.068243)
			(xy 430.281906 -146.126168) (xy 430.289734 -146.185624) (xy 430.290224 -146.215608) (xy 430.290224 -147.079208)
			(xy 430.289734 -147.109192) (xy 430.281906 -147.168648) (xy 430.266385 -147.226573) (xy 430.243436 -147.281977)
			(xy 430.213452 -147.333911) (xy 430.176946 -147.381487) (xy 430.134541 -147.423892) (xy 430.086965 -147.460398)
			(xy 430.035031 -147.490382) (xy 429.979627 -147.513331) (xy 429.921702 -147.528852) (xy 429.862246 -147.53668)
			(xy 429.802278 -147.53668) (xy 429.742822 -147.528852) (xy 429.684897 -147.513331) (xy 429.629493 -147.490382)
			(xy 429.577559 -147.460398) (xy 429.529983 -147.423892) (xy 429.487578 -147.381487) (xy 429.451072 -147.333911)
			(xy 429.421088 -147.281977) (xy 429.398139 -147.226573) (xy 429.382618 -147.168648) (xy 429.37479 -147.109192)
			(xy 429.3743 -147.079208) (xy 415.815272 -147.079208) (xy 415.815272 -147.087336) (xy 415.814782 -147.11732)
			(xy 415.806954 -147.176776) (xy 415.791433 -147.234701) (xy 415.768484 -147.290105) (xy 415.7385 -147.342039)
			(xy 415.701994 -147.389615) (xy 415.659589 -147.43202) (xy 415.612013 -147.468526) (xy 415.560079 -147.49851)
			(xy 415.504675 -147.521459) (xy 415.44675 -147.53698) (xy 415.387294 -147.544808) (xy 415.327326 -147.544808)
			(xy 415.26787 -147.53698) (xy 415.209945 -147.521459) (xy 415.154541 -147.49851) (xy 415.102607 -147.468526)
			(xy 415.055031 -147.43202) (xy 415.012626 -147.389615) (xy 414.97612 -147.342039) (xy 414.946136 -147.290105)
			(xy 414.923187 -147.234701) (xy 414.907666 -147.176776) (xy 414.899838 -147.11732) (xy 414.899348 -147.087336)
			(xy 314.189739 -147.087336) (xy 314.189382 -147.109176) (xy 314.181559 -147.168598) (xy 314.166046 -147.226491)
			(xy 314.14311 -147.281864) (xy 314.113143 -147.33377) (xy 314.076656 -147.38132) (xy 314.034276 -147.4237)
			(xy 313.986726 -147.460187) (xy 313.93482 -147.490154) (xy 313.879447 -147.51309) (xy 313.821554 -147.528603)
			(xy 313.762132 -147.536426) (xy 313.702196 -147.536426) (xy 313.642774 -147.528603) (xy 313.584881 -147.51309)
			(xy 313.529508 -147.490154) (xy 313.477602 -147.460187) (xy 313.430052 -147.4237) (xy 313.387672 -147.38132)
			(xy 313.351185 -147.33377) (xy 313.321218 -147.281864) (xy 313.298282 -147.226491) (xy 313.282769 -147.168598)
			(xy 313.274946 -147.109176) (xy 313.274456 -147.079208) (xy 299.71492 -147.079208) (xy 299.71492 -147.087336)
			(xy 299.71443 -147.117304) (xy 299.706607 -147.176726) (xy 299.691094 -147.234619) (xy 299.668158 -147.289992)
			(xy 299.638191 -147.341898) (xy 299.601704 -147.389448) (xy 299.559324 -147.431828) (xy 299.511774 -147.468315)
			(xy 299.459868 -147.498282) (xy 299.404495 -147.521218) (xy 299.346602 -147.536731) (xy 299.28718 -147.544554)
			(xy 299.227244 -147.544554) (xy 299.167822 -147.536731) (xy 299.109929 -147.521218) (xy 299.054556 -147.498282)
			(xy 299.00265 -147.468315) (xy 298.9551 -147.431828) (xy 298.91272 -147.389448) (xy 298.876233 -147.341898)
			(xy 298.846266 -147.289992) (xy 298.82333 -147.234619) (xy 298.807817 -147.176726) (xy 298.799994 -147.117304)
			(xy 298.799504 -147.087336) (xy 198.089895 -147.087336) (xy 198.089538 -147.109176) (xy 198.081715 -147.168598)
			(xy 198.066202 -147.226491) (xy 198.043266 -147.281864) (xy 198.013299 -147.33377) (xy 197.976812 -147.38132)
			(xy 197.934432 -147.4237) (xy 197.886882 -147.460187) (xy 197.834976 -147.490154) (xy 197.779603 -147.51309)
			(xy 197.72171 -147.528603) (xy 197.662288 -147.536426) (xy 197.602352 -147.536426) (xy 197.54293 -147.528603)
			(xy 197.485037 -147.51309) (xy 197.429664 -147.490154) (xy 197.377758 -147.460187) (xy 197.330208 -147.4237)
			(xy 197.287828 -147.38132) (xy 197.251341 -147.33377) (xy 197.221374 -147.281864) (xy 197.198438 -147.226491)
			(xy 197.182925 -147.168598) (xy 197.175102 -147.109176) (xy 197.174612 -147.079208) (xy 183.615076 -147.079208)
			(xy 183.615076 -147.087336) (xy 183.614586 -147.117304) (xy 183.606763 -147.176726) (xy 183.59125 -147.234619)
			(xy 183.568314 -147.289992) (xy 183.538347 -147.341898) (xy 183.50186 -147.389448) (xy 183.45948 -147.431828)
			(xy 183.41193 -147.468315) (xy 183.360024 -147.498282) (xy 183.304651 -147.521218) (xy 183.246758 -147.536731)
			(xy 183.187336 -147.544554) (xy 183.1274 -147.544554) (xy 183.067978 -147.536731) (xy 183.010085 -147.521218)
			(xy 182.954712 -147.498282) (xy 182.902806 -147.468315) (xy 182.855256 -147.431828) (xy 182.812876 -147.389448)
			(xy 182.776389 -147.341898) (xy 182.746422 -147.289992) (xy 182.723486 -147.234619) (xy 182.707973 -147.176726)
			(xy 182.70015 -147.117304) (xy 182.69966 -147.087336) (xy 81.990051 -147.087336) (xy 81.989694 -147.109192)
			(xy 81.981866 -147.168648) (xy 81.966345 -147.226573) (xy 81.943396 -147.281977) (xy 81.913412 -147.333911)
			(xy 81.876906 -147.381487) (xy 81.834501 -147.423892) (xy 81.786925 -147.460398) (xy 81.734991 -147.490382)
			(xy 81.679587 -147.513331) (xy 81.621662 -147.528852) (xy 81.562206 -147.53668) (xy 81.502238 -147.53668)
			(xy 81.442782 -147.528852) (xy 81.384857 -147.513331) (xy 81.329453 -147.490382) (xy 81.277519 -147.460398)
			(xy 81.229943 -147.423892) (xy 81.187538 -147.381487) (xy 81.151032 -147.333911) (xy 81.121048 -147.281977)
			(xy 81.098099 -147.226573) (xy 81.082578 -147.168648) (xy 81.07475 -147.109192) (xy 81.07426 -147.079208)
			(xy 67.515232 -147.079208) (xy 67.515232 -147.087336) (xy 67.514742 -147.11732) (xy 67.506914 -147.176776)
			(xy 67.491393 -147.234701) (xy 67.468444 -147.290105) (xy 67.43846 -147.342039) (xy 67.401954 -147.389615)
			(xy 67.359549 -147.43202) (xy 67.311973 -147.468526) (xy 67.260039 -147.49851) (xy 67.204635 -147.521459)
			(xy 67.14671 -147.53698) (xy 67.087254 -147.544808) (xy 67.027286 -147.544808) (xy 66.96783 -147.53698)
			(xy 66.909905 -147.521459) (xy 66.854501 -147.49851) (xy 66.802567 -147.468526) (xy 66.754991 -147.43202)
			(xy 66.712586 -147.389615) (xy 66.67608 -147.342039) (xy 66.646096 -147.290105) (xy 66.623147 -147.234701)
			(xy 66.607626 -147.176776) (xy 66.599798 -147.11732) (xy 66.599308 -147.087336) (xy 4.308094 -147.087336)
			(xy 4.308094 -148.887434) (xy 64.745108 -148.887434) (xy 64.745108 -148.023834) (xy 64.745598 -147.99385)
			(xy 64.753426 -147.934394) (xy 64.768947 -147.876469) (xy 64.791896 -147.821065) (xy 64.82188 -147.769131)
			(xy 64.858386 -147.721555) (xy 64.900791 -147.67915) (xy 64.948367 -147.642644) (xy 65.000301 -147.61266)
			(xy 65.055705 -147.589711) (xy 65.11363 -147.57419) (xy 65.173086 -147.566362) (xy 65.233054 -147.566362)
			(xy 65.29251 -147.57419) (xy 65.350435 -147.589711) (xy 65.405839 -147.61266) (xy 65.457773 -147.642644)
			(xy 65.505349 -147.67915) (xy 65.547754 -147.721555) (xy 65.58426 -147.769131) (xy 65.614244 -147.821065)
			(xy 65.637193 -147.876469) (xy 65.652714 -147.934394) (xy 65.660542 -147.99385) (xy 65.661032 -148.023834)
			(xy 65.661032 -148.88591) (xy 83.716368 -148.88591) (xy 83.716368 -148.02231) (xy 83.716858 -147.992326)
			(xy 83.724686 -147.93287) (xy 83.740207 -147.874945) (xy 83.763156 -147.819541) (xy 83.79314 -147.767607)
			(xy 83.829646 -147.720031) (xy 83.872051 -147.677626) (xy 83.919627 -147.64112) (xy 83.971561 -147.611136)
			(xy 84.026965 -147.588187) (xy 84.08489 -147.572666) (xy 84.144346 -147.564838) (xy 84.204314 -147.564838)
			(xy 84.26377 -147.572666) (xy 84.321695 -147.588187) (xy 84.377099 -147.611136) (xy 84.429033 -147.64112)
			(xy 84.476609 -147.677626) (xy 84.519014 -147.720031) (xy 84.55552 -147.767607) (xy 84.585504 -147.819541)
			(xy 84.608453 -147.874945) (xy 84.623974 -147.93287) (xy 84.631802 -147.992326) (xy 84.632292 -148.02231)
			(xy 84.632292 -148.88591) (xy 84.632267 -148.887434) (xy 180.84546 -148.887434) (xy 180.84546 -148.023834)
			(xy 180.84595 -147.993866) (xy 180.853773 -147.934444) (xy 180.869286 -147.876551) (xy 180.892222 -147.821178)
			(xy 180.922189 -147.769272) (xy 180.958676 -147.721722) (xy 181.001056 -147.679342) (xy 181.048606 -147.642855)
			(xy 181.100512 -147.612888) (xy 181.155885 -147.589952) (xy 181.213778 -147.574439) (xy 181.2732 -147.566616)
			(xy 181.333136 -147.566616) (xy 181.392558 -147.574439) (xy 181.450451 -147.589952) (xy 181.505824 -147.612888)
			(xy 181.55773 -147.642855) (xy 181.60528 -147.679342) (xy 181.64766 -147.721722) (xy 181.684147 -147.769272)
			(xy 181.714114 -147.821178) (xy 181.73705 -147.876551) (xy 181.752563 -147.934444) (xy 181.760386 -147.993866)
			(xy 181.760876 -148.023834) (xy 181.760876 -148.88591) (xy 199.81672 -148.88591) (xy 199.81672 -148.02231)
			(xy 199.81721 -147.992342) (xy 199.825033 -147.93292) (xy 199.840546 -147.875027) (xy 199.863482 -147.819654)
			(xy 199.893449 -147.767748) (xy 199.929936 -147.720198) (xy 199.972316 -147.677818) (xy 200.019866 -147.641331)
			(xy 200.071772 -147.611364) (xy 200.127145 -147.588428) (xy 200.185038 -147.572915) (xy 200.24446 -147.565092)
			(xy 200.304396 -147.565092) (xy 200.363818 -147.572915) (xy 200.421711 -147.588428) (xy 200.477084 -147.611364)
			(xy 200.52899 -147.641331) (xy 200.57654 -147.677818) (xy 200.61892 -147.720198) (xy 200.655407 -147.767748)
			(xy 200.685374 -147.819654) (xy 200.70831 -147.875027) (xy 200.723823 -147.93292) (xy 200.731646 -147.992342)
			(xy 200.732136 -148.02231) (xy 200.732136 -148.88591) (xy 200.731646 -148.915878) (xy 200.723823 -148.9753)
			(xy 200.70831 -149.033193) (xy 200.685374 -149.088566) (xy 200.655407 -149.140472) (xy 200.61892 -149.188022)
			(xy 200.57654 -149.230402) (xy 200.52899 -149.266889) (xy 200.477084 -149.296856) (xy 200.421711 -149.319792)
			(xy 200.363818 -149.335305) (xy 200.304396 -149.343128) (xy 200.24446 -149.343128) (xy 200.185038 -149.335305)
			(xy 200.127145 -149.319792) (xy 200.071772 -149.296856) (xy 200.019866 -149.266889) (xy 199.972316 -149.230402)
			(xy 199.929936 -149.188022) (xy 199.893449 -149.140472) (xy 199.863482 -149.088566) (xy 199.840546 -149.033193)
			(xy 199.825033 -148.9753) (xy 199.81721 -148.915878) (xy 199.81672 -148.88591) (xy 181.760876 -148.88591)
			(xy 181.760876 -148.887434) (xy 181.760386 -148.917402) (xy 181.752563 -148.976824) (xy 181.73705 -149.034717)
			(xy 181.714114 -149.09009) (xy 181.684147 -149.141996) (xy 181.64766 -149.189546) (xy 181.60528 -149.231926)
			(xy 181.55773 -149.268413) (xy 181.505824 -149.29838) (xy 181.450451 -149.321316) (xy 181.392558 -149.336829)
			(xy 181.333136 -149.344652) (xy 181.2732 -149.344652) (xy 181.213778 -149.336829) (xy 181.155885 -149.321316)
			(xy 181.100512 -149.29838) (xy 181.048606 -149.268413) (xy 181.001056 -149.231926) (xy 180.958676 -149.189546)
			(xy 180.922189 -149.141996) (xy 180.892222 -149.09009) (xy 180.869286 -149.034717) (xy 180.853773 -148.976824)
			(xy 180.84595 -148.917402) (xy 180.84546 -148.887434) (xy 84.632267 -148.887434) (xy 84.631802 -148.915894)
			(xy 84.623974 -148.97535) (xy 84.608453 -149.033275) (xy 84.585504 -149.088679) (xy 84.55552 -149.140613)
			(xy 84.519014 -149.188189) (xy 84.476609 -149.230594) (xy 84.429033 -149.2671) (xy 84.377099 -149.297084)
			(xy 84.321695 -149.320033) (xy 84.26377 -149.335554) (xy 84.204314 -149.343382) (xy 84.144346 -149.343382)
			(xy 84.08489 -149.335554) (xy 84.026965 -149.320033) (xy 83.971561 -149.297084) (xy 83.919627 -149.2671)
			(xy 83.872051 -149.230594) (xy 83.829646 -149.188189) (xy 83.79314 -149.140613) (xy 83.763156 -149.088679)
			(xy 83.740207 -149.033275) (xy 83.724686 -148.97535) (xy 83.716858 -148.915894) (xy 83.716368 -148.88591)
			(xy 65.661032 -148.88591) (xy 65.661032 -148.887434) (xy 65.660542 -148.917418) (xy 65.652714 -148.976874)
			(xy 65.637193 -149.034799) (xy 65.614244 -149.090203) (xy 65.58426 -149.142137) (xy 65.547754 -149.189713)
			(xy 65.505349 -149.232118) (xy 65.457773 -149.268624) (xy 65.405839 -149.298608) (xy 65.350435 -149.321557)
			(xy 65.29251 -149.337078) (xy 65.233054 -149.344906) (xy 65.173086 -149.344906) (xy 65.11363 -149.337078)
			(xy 65.055705 -149.321557) (xy 65.000301 -149.298608) (xy 64.948367 -149.268624) (xy 64.900791 -149.232118)
			(xy 64.858386 -149.189713) (xy 64.82188 -149.142137) (xy 64.791896 -149.090203) (xy 64.768947 -149.034799)
			(xy 64.753426 -148.976874) (xy 64.745598 -148.917418) (xy 64.745108 -148.887434) (xy 4.308094 -148.887434)
			(xy 4.308094 -150.687278) (xy 66.599308 -150.687278) (xy 66.599308 -149.823678) (xy 66.599798 -149.793694)
			(xy 66.607626 -149.734238) (xy 66.623147 -149.676313) (xy 66.646096 -149.620909) (xy 66.67608 -149.568975)
			(xy 66.712586 -149.521399) (xy 66.754991 -149.478994) (xy 66.802567 -149.442488) (xy 66.854501 -149.412504)
			(xy 66.909905 -149.389555) (xy 66.96783 -149.374034) (xy 67.027286 -149.366206) (xy 67.087254 -149.366206)
			(xy 67.14671 -149.374034) (xy 67.204635 -149.389555) (xy 67.260039 -149.412504) (xy 67.311973 -149.442488)
			(xy 67.359549 -149.478994) (xy 67.401954 -149.521399) (xy 67.43846 -149.568975) (xy 67.468444 -149.620909)
			(xy 67.491393 -149.676313) (xy 67.506914 -149.734238) (xy 67.514742 -149.793694) (xy 67.515232 -149.823678)
			(xy 67.515232 -150.67915) (xy 81.07426 -150.67915) (xy 81.07426 -149.81555) (xy 81.07475 -149.785566)
			(xy 81.082578 -149.72611) (xy 81.098099 -149.668185) (xy 81.121048 -149.612781) (xy 81.151032 -149.560847)
			(xy 81.187538 -149.513271) (xy 81.229943 -149.470866) (xy 81.277519 -149.43436) (xy 81.329453 -149.404376)
			(xy 81.384857 -149.381427) (xy 81.442782 -149.365906) (xy 81.502238 -149.358078) (xy 81.562206 -149.358078)
			(xy 81.621662 -149.365906) (xy 81.679587 -149.381427) (xy 81.734991 -149.404376) (xy 81.786925 -149.43436)
			(xy 81.834501 -149.470866) (xy 81.876906 -149.513271) (xy 81.913412 -149.560847) (xy 81.943396 -149.612781)
			(xy 81.966345 -149.668185) (xy 81.981866 -149.72611) (xy 81.989694 -149.785566) (xy 81.990184 -149.81555)
			(xy 81.990184 -150.67915) (xy 81.990051 -150.687278) (xy 182.69966 -150.687278) (xy 182.69966 -149.823678)
			(xy 182.70015 -149.79371) (xy 182.707973 -149.734288) (xy 182.723486 -149.676395) (xy 182.746422 -149.621022)
			(xy 182.776389 -149.569116) (xy 182.812876 -149.521566) (xy 182.855256 -149.479186) (xy 182.902806 -149.442699)
			(xy 182.954712 -149.412732) (xy 183.010085 -149.389796) (xy 183.067978 -149.374283) (xy 183.1274 -149.36646)
			(xy 183.187336 -149.36646) (xy 183.246758 -149.374283) (xy 183.304651 -149.389796) (xy 183.360024 -149.412732)
			(xy 183.41193 -149.442699) (xy 183.45948 -149.479186) (xy 183.50186 -149.521566) (xy 183.538347 -149.569116)
			(xy 183.568314 -149.621022) (xy 183.59125 -149.676395) (xy 183.606763 -149.734288) (xy 183.614586 -149.79371)
			(xy 183.615076 -149.823678) (xy 183.615076 -150.67915) (xy 197.174612 -150.67915) (xy 197.174612 -149.81555)
			(xy 197.175102 -149.785582) (xy 197.182925 -149.72616) (xy 197.198438 -149.668267) (xy 197.221374 -149.612894)
			(xy 197.251341 -149.560988) (xy 197.287828 -149.513438) (xy 197.330208 -149.471058) (xy 197.377758 -149.434571)
			(xy 197.429664 -149.404604) (xy 197.485037 -149.381668) (xy 197.54293 -149.366155) (xy 197.602352 -149.358332)
			(xy 197.662288 -149.358332) (xy 197.72171 -149.366155) (xy 197.779603 -149.381668) (xy 197.834976 -149.404604)
			(xy 197.886882 -149.434571) (xy 197.934432 -149.471058) (xy 197.976812 -149.513438) (xy 198.013299 -149.560988)
			(xy 198.043266 -149.612894) (xy 198.066202 -149.668267) (xy 198.072386 -149.691344) (xy 236.708188 -149.691344)
			(xy 236.708188 -148.827744) (xy 236.708678 -148.79776) (xy 236.716506 -148.738304) (xy 236.732027 -148.680379)
			(xy 236.754976 -148.624975) (xy 236.78496 -148.573041) (xy 236.821466 -148.525465) (xy 236.863871 -148.48306)
			(xy 236.911447 -148.446554) (xy 236.963381 -148.41657) (xy 237.018785 -148.393621) (xy 237.07671 -148.3781)
			(xy 237.136166 -148.370272) (xy 237.196134 -148.370272) (xy 237.25559 -148.3781) (xy 237.313515 -148.393621)
			(xy 237.368919 -148.41657) (xy 237.420853 -148.446554) (xy 237.468429 -148.48306) (xy 237.510834 -148.525465)
			(xy 237.54734 -148.573041) (xy 237.577324 -148.624975) (xy 237.600273 -148.680379) (xy 237.615794 -148.738304)
			(xy 237.623622 -148.79776) (xy 237.624112 -148.827744) (xy 237.624112 -148.887434) (xy 296.945304 -148.887434)
			(xy 296.945304 -148.023834) (xy 296.945794 -147.993866) (xy 296.953617 -147.934444) (xy 296.96913 -147.876551)
			(xy 296.992066 -147.821178) (xy 297.022033 -147.769272) (xy 297.05852 -147.721722) (xy 297.1009 -147.679342)
			(xy 297.14845 -147.642855) (xy 297.200356 -147.612888) (xy 297.255729 -147.589952) (xy 297.313622 -147.574439)
			(xy 297.373044 -147.566616) (xy 297.43298 -147.566616) (xy 297.492402 -147.574439) (xy 297.550295 -147.589952)
			(xy 297.605668 -147.612888) (xy 297.657574 -147.642855) (xy 297.705124 -147.679342) (xy 297.747504 -147.721722)
			(xy 297.783991 -147.769272) (xy 297.813958 -147.821178) (xy 297.836894 -147.876551) (xy 297.852407 -147.934444)
			(xy 297.86023 -147.993866) (xy 297.86072 -148.023834) (xy 297.86072 -148.88591) (xy 315.916564 -148.88591)
			(xy 315.916564 -148.02231) (xy 315.917054 -147.992342) (xy 315.924877 -147.93292) (xy 315.94039 -147.875027)
			(xy 315.963326 -147.819654) (xy 315.993293 -147.767748) (xy 316.02978 -147.720198) (xy 316.07216 -147.677818)
			(xy 316.11971 -147.641331) (xy 316.171616 -147.611364) (xy 316.226989 -147.588428) (xy 316.284882 -147.572915)
			(xy 316.344304 -147.565092) (xy 316.40424 -147.565092) (xy 316.463662 -147.572915) (xy 316.521555 -147.588428)
			(xy 316.576928 -147.611364) (xy 316.628834 -147.641331) (xy 316.676384 -147.677818) (xy 316.718764 -147.720198)
			(xy 316.755251 -147.767748) (xy 316.785218 -147.819654) (xy 316.808154 -147.875027) (xy 316.823667 -147.93292)
			(xy 316.83149 -147.992342) (xy 316.83198 -148.02231) (xy 316.83198 -148.88591) (xy 316.831955 -148.887434)
			(xy 413.045148 -148.887434) (xy 413.045148 -148.023834) (xy 413.045638 -147.99385) (xy 413.053466 -147.934394)
			(xy 413.068987 -147.876469) (xy 413.091936 -147.821065) (xy 413.12192 -147.769131) (xy 413.158426 -147.721555)
			(xy 413.200831 -147.67915) (xy 413.248407 -147.642644) (xy 413.300341 -147.61266) (xy 413.355745 -147.589711)
			(xy 413.41367 -147.57419) (xy 413.473126 -147.566362) (xy 413.533094 -147.566362) (xy 413.59255 -147.57419)
			(xy 413.650475 -147.589711) (xy 413.705879 -147.61266) (xy 413.757813 -147.642644) (xy 413.805389 -147.67915)
			(xy 413.847794 -147.721555) (xy 413.8843 -147.769131) (xy 413.914284 -147.821065) (xy 413.937233 -147.876469)
			(xy 413.952754 -147.934394) (xy 413.960582 -147.99385) (xy 413.961072 -148.023834) (xy 413.961072 -148.88591)
			(xy 432.016408 -148.88591) (xy 432.016408 -148.02231) (xy 432.016898 -147.992326) (xy 432.024726 -147.93287)
			(xy 432.040247 -147.874945) (xy 432.063196 -147.819541) (xy 432.09318 -147.767607) (xy 432.129686 -147.720031)
			(xy 432.172091 -147.677626) (xy 432.219667 -147.64112) (xy 432.271601 -147.611136) (xy 432.327005 -147.588187)
			(xy 432.38493 -147.572666) (xy 432.444386 -147.564838) (xy 432.504354 -147.564838) (xy 432.56381 -147.572666)
			(xy 432.621735 -147.588187) (xy 432.677139 -147.611136) (xy 432.729073 -147.64112) (xy 432.776649 -147.677626)
			(xy 432.819054 -147.720031) (xy 432.85556 -147.767607) (xy 432.885544 -147.819541) (xy 432.908493 -147.874945)
			(xy 432.924014 -147.93287) (xy 432.931842 -147.992326) (xy 432.932332 -148.02231) (xy 432.932332 -148.88591)
			(xy 432.931842 -148.915894) (xy 432.924014 -148.97535) (xy 432.908493 -149.033275) (xy 432.885544 -149.088679)
			(xy 432.85556 -149.140613) (xy 432.819054 -149.188189) (xy 432.776649 -149.230594) (xy 432.729073 -149.2671)
			(xy 432.677139 -149.297084) (xy 432.621735 -149.320033) (xy 432.56381 -149.335554) (xy 432.504354 -149.343382)
			(xy 432.444386 -149.343382) (xy 432.38493 -149.335554) (xy 432.327005 -149.320033) (xy 432.271601 -149.297084)
			(xy 432.219667 -149.2671) (xy 432.172091 -149.230594) (xy 432.129686 -149.188189) (xy 432.09318 -149.140613)
			(xy 432.063196 -149.088679) (xy 432.040247 -149.033275) (xy 432.024726 -148.97535) (xy 432.016898 -148.915894)
			(xy 432.016408 -148.88591) (xy 413.961072 -148.88591) (xy 413.961072 -148.887434) (xy 413.960582 -148.917418)
			(xy 413.952754 -148.976874) (xy 413.937233 -149.034799) (xy 413.914284 -149.090203) (xy 413.8843 -149.142137)
			(xy 413.847794 -149.189713) (xy 413.805389 -149.232118) (xy 413.757813 -149.268624) (xy 413.705879 -149.298608)
			(xy 413.650475 -149.321557) (xy 413.59255 -149.337078) (xy 413.533094 -149.344906) (xy 413.473126 -149.344906)
			(xy 413.41367 -149.337078) (xy 413.355745 -149.321557) (xy 413.300341 -149.298608) (xy 413.248407 -149.268624)
			(xy 413.200831 -149.232118) (xy 413.158426 -149.189713) (xy 413.12192 -149.142137) (xy 413.091936 -149.090203)
			(xy 413.068987 -149.034799) (xy 413.053466 -148.976874) (xy 413.045638 -148.917418) (xy 413.045148 -148.887434)
			(xy 316.831955 -148.887434) (xy 316.83149 -148.915878) (xy 316.823667 -148.9753) (xy 316.808154 -149.033193)
			(xy 316.785218 -149.088566) (xy 316.755251 -149.140472) (xy 316.718764 -149.188022) (xy 316.676384 -149.230402)
			(xy 316.628834 -149.266889) (xy 316.576928 -149.296856) (xy 316.521555 -149.319792) (xy 316.463662 -149.335305)
			(xy 316.40424 -149.343128) (xy 316.344304 -149.343128) (xy 316.284882 -149.335305) (xy 316.226989 -149.319792)
			(xy 316.171616 -149.296856) (xy 316.11971 -149.266889) (xy 316.07216 -149.230402) (xy 316.02978 -149.188022)
			(xy 315.993293 -149.140472) (xy 315.963326 -149.088566) (xy 315.94039 -149.033193) (xy 315.924877 -148.9753)
			(xy 315.917054 -148.915878) (xy 315.916564 -148.88591) (xy 297.86072 -148.88591) (xy 297.86072 -148.887434)
			(xy 297.86023 -148.917402) (xy 297.852407 -148.976824) (xy 297.836894 -149.034717) (xy 297.813958 -149.09009)
			(xy 297.783991 -149.141996) (xy 297.747504 -149.189546) (xy 297.705124 -149.231926) (xy 297.657574 -149.268413)
			(xy 297.605668 -149.29838) (xy 297.550295 -149.321316) (xy 297.492402 -149.336829) (xy 297.43298 -149.344652)
			(xy 297.373044 -149.344652) (xy 297.313622 -149.336829) (xy 297.255729 -149.321316) (xy 297.200356 -149.29838)
			(xy 297.14845 -149.268413) (xy 297.1009 -149.231926) (xy 297.05852 -149.189546) (xy 297.022033 -149.141996)
			(xy 296.992066 -149.09009) (xy 296.96913 -149.034717) (xy 296.953617 -148.976824) (xy 296.945794 -148.917402)
			(xy 296.945304 -148.887434) (xy 237.624112 -148.887434) (xy 237.624112 -149.691344) (xy 237.623622 -149.721328)
			(xy 237.615794 -149.780784) (xy 237.600273 -149.838709) (xy 237.577324 -149.894113) (xy 237.54734 -149.946047)
			(xy 237.510834 -149.993623) (xy 237.468429 -150.036028) (xy 237.420853 -150.072534) (xy 237.368919 -150.102518)
			(xy 237.313515 -150.125467) (xy 237.25559 -150.140988) (xy 237.196134 -150.148816) (xy 237.136166 -150.148816)
			(xy 237.07671 -150.140988) (xy 237.018785 -150.125467) (xy 236.963381 -150.102518) (xy 236.911447 -150.072534)
			(xy 236.863871 -150.036028) (xy 236.821466 -149.993623) (xy 236.78496 -149.946047) (xy 236.754976 -149.894113)
			(xy 236.732027 -149.838709) (xy 236.716506 -149.780784) (xy 236.708678 -149.721328) (xy 236.708188 -149.691344)
			(xy 198.072386 -149.691344) (xy 198.081715 -149.72616) (xy 198.089538 -149.785582) (xy 198.090028 -149.81555)
			(xy 198.090028 -150.67915) (xy 198.089538 -150.709118) (xy 198.081715 -150.76854) (xy 198.066202 -150.826433)
			(xy 198.043266 -150.881806) (xy 198.013299 -150.933712) (xy 197.976812 -150.981262) (xy 197.934432 -151.023642)
			(xy 197.886882 -151.060129) (xy 197.834976 -151.090096) (xy 197.779603 -151.113032) (xy 197.72171 -151.128545)
			(xy 197.662288 -151.136368) (xy 197.602352 -151.136368) (xy 197.54293 -151.128545) (xy 197.485037 -151.113032)
			(xy 197.429664 -151.090096) (xy 197.377758 -151.060129) (xy 197.330208 -151.023642) (xy 197.287828 -150.981262)
			(xy 197.251341 -150.933712) (xy 197.221374 -150.881806) (xy 197.198438 -150.826433) (xy 197.182925 -150.76854)
			(xy 197.175102 -150.709118) (xy 197.174612 -150.67915) (xy 183.615076 -150.67915) (xy 183.615076 -150.687278)
			(xy 183.614586 -150.717246) (xy 183.606763 -150.776668) (xy 183.59125 -150.834561) (xy 183.568314 -150.889934)
			(xy 183.538347 -150.94184) (xy 183.50186 -150.98939) (xy 183.45948 -151.03177) (xy 183.41193 -151.068257)
			(xy 183.360024 -151.098224) (xy 183.304651 -151.12116) (xy 183.246758 -151.136673) (xy 183.187336 -151.144496)
			(xy 183.1274 -151.144496) (xy 183.067978 -151.136673) (xy 183.010085 -151.12116) (xy 182.954712 -151.098224)
			(xy 182.902806 -151.068257) (xy 182.855256 -151.03177) (xy 182.812876 -150.98939) (xy 182.776389 -150.94184)
			(xy 182.746422 -150.889934) (xy 182.723486 -150.834561) (xy 182.707973 -150.776668) (xy 182.70015 -150.717246)
			(xy 182.69966 -150.687278) (xy 81.990051 -150.687278) (xy 81.989694 -150.709134) (xy 81.981866 -150.76859)
			(xy 81.966345 -150.826515) (xy 81.943396 -150.881919) (xy 81.913412 -150.933853) (xy 81.876906 -150.981429)
			(xy 81.834501 -151.023834) (xy 81.786925 -151.06034) (xy 81.734991 -151.090324) (xy 81.679587 -151.113273)
			(xy 81.621662 -151.128794) (xy 81.562206 -151.136622) (xy 81.502238 -151.136622) (xy 81.442782 -151.128794)
			(xy 81.384857 -151.113273) (xy 81.329453 -151.090324) (xy 81.277519 -151.06034) (xy 81.229943 -151.023834)
			(xy 81.187538 -150.981429) (xy 81.151032 -150.933853) (xy 81.121048 -150.881919) (xy 81.098099 -150.826515)
			(xy 81.082578 -150.76859) (xy 81.07475 -150.709134) (xy 81.07426 -150.67915) (xy 67.515232 -150.67915)
			(xy 67.515232 -150.687278) (xy 67.514742 -150.717262) (xy 67.506914 -150.776718) (xy 67.491393 -150.834643)
			(xy 67.468444 -150.890047) (xy 67.43846 -150.941981) (xy 67.401954 -150.989557) (xy 67.359549 -151.031962)
			(xy 67.311973 -151.068468) (xy 67.260039 -151.098452) (xy 67.204635 -151.121401) (xy 67.14671 -151.136922)
			(xy 67.087254 -151.14475) (xy 67.027286 -151.14475) (xy 66.96783 -151.136922) (xy 66.909905 -151.121401)
			(xy 66.854501 -151.098452) (xy 66.802567 -151.068468) (xy 66.754991 -151.031962) (xy 66.712586 -150.989557)
			(xy 66.67608 -150.941981) (xy 66.646096 -150.890047) (xy 66.623147 -150.834643) (xy 66.607626 -150.776718)
			(xy 66.599798 -150.717262) (xy 66.599308 -150.687278) (xy 4.308094 -150.687278) (xy 4.308094 -152.487376)
			(xy 64.745108 -152.487376) (xy 64.745108 -151.623776) (xy 64.745598 -151.593792) (xy 64.753426 -151.534336)
			(xy 64.768947 -151.476411) (xy 64.791896 -151.421007) (xy 64.82188 -151.369073) (xy 64.858386 -151.321497)
			(xy 64.900791 -151.279092) (xy 64.948367 -151.242586) (xy 65.000301 -151.212602) (xy 65.055705 -151.189653)
			(xy 65.11363 -151.174132) (xy 65.173086 -151.166304) (xy 65.233054 -151.166304) (xy 65.29251 -151.174132)
			(xy 65.350435 -151.189653) (xy 65.405839 -151.212602) (xy 65.457773 -151.242586) (xy 65.505349 -151.279092)
			(xy 65.547754 -151.321497) (xy 65.58426 -151.369073) (xy 65.614244 -151.421007) (xy 65.637193 -151.476411)
			(xy 65.652714 -151.534336) (xy 65.660542 -151.593792) (xy 65.661032 -151.623776) (xy 65.661032 -152.485852)
			(xy 83.716368 -152.485852) (xy 83.716368 -151.622252) (xy 83.716858 -151.592268) (xy 83.724686 -151.532812)
			(xy 83.740207 -151.474887) (xy 83.763156 -151.419483) (xy 83.79314 -151.367549) (xy 83.829646 -151.319973)
			(xy 83.872051 -151.277568) (xy 83.919627 -151.241062) (xy 83.971561 -151.211078) (xy 84.026965 -151.188129)
			(xy 84.08489 -151.172608) (xy 84.144346 -151.16478) (xy 84.204314 -151.16478) (xy 84.26377 -151.172608)
			(xy 84.321695 -151.188129) (xy 84.377099 -151.211078) (xy 84.429033 -151.241062) (xy 84.476609 -151.277568)
			(xy 84.519014 -151.319973) (xy 84.55552 -151.367549) (xy 84.585504 -151.419483) (xy 84.608453 -151.474887)
			(xy 84.623974 -151.532812) (xy 84.631802 -151.592268) (xy 84.632292 -151.622252) (xy 84.632292 -152.485852)
			(xy 84.632267 -152.487376) (xy 180.84546 -152.487376) (xy 180.84546 -151.623776) (xy 180.84595 -151.593808)
			(xy 180.853773 -151.534386) (xy 180.869286 -151.476493) (xy 180.892222 -151.42112) (xy 180.922189 -151.369214)
			(xy 180.958676 -151.321664) (xy 181.001056 -151.279284) (xy 181.048606 -151.242797) (xy 181.100512 -151.21283)
			(xy 181.155885 -151.189894) (xy 181.213778 -151.174381) (xy 181.2732 -151.166558) (xy 181.333136 -151.166558)
			(xy 181.392558 -151.174381) (xy 181.450451 -151.189894) (xy 181.505824 -151.21283) (xy 181.55773 -151.242797)
			(xy 181.60528 -151.279284) (xy 181.64766 -151.321664) (xy 181.684147 -151.369214) (xy 181.714114 -151.42112)
			(xy 181.73705 -151.476493) (xy 181.752563 -151.534386) (xy 181.760386 -151.593808) (xy 181.760876 -151.623776)
			(xy 181.760876 -152.485852) (xy 199.81672 -152.485852) (xy 199.81672 -151.622252) (xy 199.81721 -151.592284)
			(xy 199.825033 -151.532862) (xy 199.840546 -151.474969) (xy 199.863482 -151.419596) (xy 199.893449 -151.36769)
			(xy 199.929936 -151.32014) (xy 199.972316 -151.27776) (xy 200.019866 -151.241273) (xy 200.071772 -151.211306)
			(xy 200.127145 -151.18837) (xy 200.185038 -151.172857) (xy 200.24446 -151.165034) (xy 200.304396 -151.165034)
			(xy 200.363818 -151.172857) (xy 200.421711 -151.18837) (xy 200.477084 -151.211306) (xy 200.52899 -151.241273)
			(xy 200.57654 -151.27776) (xy 200.61892 -151.32014) (xy 200.655407 -151.36769) (xy 200.685374 -151.419596)
			(xy 200.70831 -151.474969) (xy 200.723823 -151.532862) (xy 200.731646 -151.592284) (xy 200.732136 -151.622252)
			(xy 200.732136 -151.914098) (xy 236.712252 -151.914098) (xy 236.712252 -151.050498) (xy 236.712742 -151.020514)
			(xy 236.72057 -150.961058) (xy 236.736091 -150.903133) (xy 236.75904 -150.847729) (xy 236.789024 -150.795795)
			(xy 236.82553 -150.748219) (xy 236.867935 -150.705814) (xy 236.915511 -150.669308) (xy 236.967445 -150.639324)
			(xy 237.022849 -150.616375) (xy 237.080774 -150.600854) (xy 237.14023 -150.593026) (xy 237.200198 -150.593026)
			(xy 237.259654 -150.600854) (xy 237.317579 -150.616375) (xy 237.372983 -150.639324) (xy 237.424917 -150.669308)
			(xy 237.448336 -150.687278) (xy 298.799504 -150.687278) (xy 298.799504 -149.823678) (xy 298.799994 -149.79371)
			(xy 298.807817 -149.734288) (xy 298.82333 -149.676395) (xy 298.846266 -149.621022) (xy 298.876233 -149.569116)
			(xy 298.91272 -149.521566) (xy 298.9551 -149.479186) (xy 299.00265 -149.442699) (xy 299.054556 -149.412732)
			(xy 299.109929 -149.389796) (xy 299.167822 -149.374283) (xy 299.227244 -149.36646) (xy 299.28718 -149.36646)
			(xy 299.346602 -149.374283) (xy 299.404495 -149.389796) (xy 299.459868 -149.412732) (xy 299.511774 -149.442699)
			(xy 299.559324 -149.479186) (xy 299.601704 -149.521566) (xy 299.638191 -149.569116) (xy 299.668158 -149.621022)
			(xy 299.691094 -149.676395) (xy 299.706607 -149.734288) (xy 299.71443 -149.79371) (xy 299.71492 -149.823678)
			(xy 299.71492 -150.67915) (xy 313.274456 -150.67915) (xy 313.274456 -149.81555) (xy 313.274946 -149.785582)
			(xy 313.282769 -149.72616) (xy 313.298282 -149.668267) (xy 313.321218 -149.612894) (xy 313.351185 -149.560988)
			(xy 313.387672 -149.513438) (xy 313.430052 -149.471058) (xy 313.477602 -149.434571) (xy 313.529508 -149.404604)
			(xy 313.584881 -149.381668) (xy 313.642774 -149.366155) (xy 313.702196 -149.358332) (xy 313.762132 -149.358332)
			(xy 313.821554 -149.366155) (xy 313.879447 -149.381668) (xy 313.93482 -149.404604) (xy 313.986726 -149.434571)
			(xy 314.034276 -149.471058) (xy 314.076656 -149.513438) (xy 314.113143 -149.560988) (xy 314.14311 -149.612894)
			(xy 314.166046 -149.668267) (xy 314.181559 -149.72616) (xy 314.189382 -149.785582) (xy 314.189872 -149.81555)
			(xy 314.189872 -150.67915) (xy 314.189739 -150.687278) (xy 414.899348 -150.687278) (xy 414.899348 -149.823678)
			(xy 414.899838 -149.793694) (xy 414.907666 -149.734238) (xy 414.923187 -149.676313) (xy 414.946136 -149.620909)
			(xy 414.97612 -149.568975) (xy 415.012626 -149.521399) (xy 415.055031 -149.478994) (xy 415.102607 -149.442488)
			(xy 415.154541 -149.412504) (xy 415.209945 -149.389555) (xy 415.26787 -149.374034) (xy 415.327326 -149.366206)
			(xy 415.387294 -149.366206) (xy 415.44675 -149.374034) (xy 415.504675 -149.389555) (xy 415.560079 -149.412504)
			(xy 415.612013 -149.442488) (xy 415.659589 -149.478994) (xy 415.701994 -149.521399) (xy 415.7385 -149.568975)
			(xy 415.768484 -149.620909) (xy 415.791433 -149.676313) (xy 415.806954 -149.734238) (xy 415.814782 -149.793694)
			(xy 415.815272 -149.823678) (xy 415.815272 -150.67915) (xy 429.3743 -150.67915) (xy 429.3743 -149.81555)
			(xy 429.37479 -149.785566) (xy 429.382618 -149.72611) (xy 429.398139 -149.668185) (xy 429.421088 -149.612781)
			(xy 429.451072 -149.560847) (xy 429.487578 -149.513271) (xy 429.529983 -149.470866) (xy 429.577559 -149.43436)
			(xy 429.629493 -149.404376) (xy 429.684897 -149.381427) (xy 429.742822 -149.365906) (xy 429.802278 -149.358078)
			(xy 429.862246 -149.358078) (xy 429.921702 -149.365906) (xy 429.979627 -149.381427) (xy 430.035031 -149.404376)
			(xy 430.086965 -149.43436) (xy 430.134541 -149.470866) (xy 430.176946 -149.513271) (xy 430.213452 -149.560847)
			(xy 430.243436 -149.612781) (xy 430.266385 -149.668185) (xy 430.281906 -149.72611) (xy 430.289734 -149.785566)
			(xy 430.290224 -149.81555) (xy 430.290224 -150.67915) (xy 430.289734 -150.709134) (xy 430.281906 -150.76859)
			(xy 430.266385 -150.826515) (xy 430.243436 -150.881919) (xy 430.213452 -150.933853) (xy 430.176946 -150.981429)
			(xy 430.134541 -151.023834) (xy 430.086965 -151.06034) (xy 430.035031 -151.090324) (xy 429.979627 -151.113273)
			(xy 429.921702 -151.128794) (xy 429.862246 -151.136622) (xy 429.802278 -151.136622) (xy 429.742822 -151.128794)
			(xy 429.684897 -151.113273) (xy 429.629493 -151.090324) (xy 429.577559 -151.06034) (xy 429.529983 -151.023834)
			(xy 429.487578 -150.981429) (xy 429.451072 -150.933853) (xy 429.421088 -150.881919) (xy 429.398139 -150.826515)
			(xy 429.382618 -150.76859) (xy 429.37479 -150.709134) (xy 429.3743 -150.67915) (xy 415.815272 -150.67915)
			(xy 415.815272 -150.687278) (xy 415.814782 -150.717262) (xy 415.806954 -150.776718) (xy 415.791433 -150.834643)
			(xy 415.768484 -150.890047) (xy 415.7385 -150.941981) (xy 415.701994 -150.989557) (xy 415.659589 -151.031962)
			(xy 415.612013 -151.068468) (xy 415.560079 -151.098452) (xy 415.504675 -151.121401) (xy 415.44675 -151.136922)
			(xy 415.387294 -151.14475) (xy 415.327326 -151.14475) (xy 415.26787 -151.136922) (xy 415.209945 -151.121401)
			(xy 415.154541 -151.098452) (xy 415.102607 -151.068468) (xy 415.055031 -151.031962) (xy 415.012626 -150.989557)
			(xy 414.97612 -150.941981) (xy 414.946136 -150.890047) (xy 414.923187 -150.834643) (xy 414.907666 -150.776718)
			(xy 414.899838 -150.717262) (xy 414.899348 -150.687278) (xy 314.189739 -150.687278) (xy 314.189382 -150.709118)
			(xy 314.181559 -150.76854) (xy 314.166046 -150.826433) (xy 314.14311 -150.881806) (xy 314.113143 -150.933712)
			(xy 314.076656 -150.981262) (xy 314.034276 -151.023642) (xy 313.986726 -151.060129) (xy 313.93482 -151.090096)
			(xy 313.879447 -151.113032) (xy 313.821554 -151.128545) (xy 313.762132 -151.136368) (xy 313.702196 -151.136368)
			(xy 313.642774 -151.128545) (xy 313.584881 -151.113032) (xy 313.529508 -151.090096) (xy 313.477602 -151.060129)
			(xy 313.430052 -151.023642) (xy 313.387672 -150.981262) (xy 313.351185 -150.933712) (xy 313.321218 -150.881806)
			(xy 313.298282 -150.826433) (xy 313.282769 -150.76854) (xy 313.274946 -150.709118) (xy 313.274456 -150.67915)
			(xy 299.71492 -150.67915) (xy 299.71492 -150.687278) (xy 299.71443 -150.717246) (xy 299.706607 -150.776668)
			(xy 299.691094 -150.834561) (xy 299.668158 -150.889934) (xy 299.638191 -150.94184) (xy 299.601704 -150.98939)
			(xy 299.559324 -151.03177) (xy 299.511774 -151.068257) (xy 299.459868 -151.098224) (xy 299.404495 -151.12116)
			(xy 299.346602 -151.136673) (xy 299.28718 -151.144496) (xy 299.227244 -151.144496) (xy 299.167822 -151.136673)
			(xy 299.109929 -151.12116) (xy 299.054556 -151.098224) (xy 299.00265 -151.068257) (xy 298.9551 -151.03177)
			(xy 298.91272 -150.98939) (xy 298.876233 -150.94184) (xy 298.846266 -150.889934) (xy 298.82333 -150.834561)
			(xy 298.807817 -150.776668) (xy 298.799994 -150.717246) (xy 298.799504 -150.687278) (xy 237.448336 -150.687278)
			(xy 237.472493 -150.705814) (xy 237.514898 -150.748219) (xy 237.551404 -150.795795) (xy 237.581388 -150.847729)
			(xy 237.604337 -150.903133) (xy 237.619858 -150.961058) (xy 237.627686 -151.020514) (xy 237.628176 -151.050498)
			(xy 237.628176 -151.914098) (xy 237.627686 -151.944082) (xy 237.619858 -152.003538) (xy 237.604337 -152.061463)
			(xy 237.581388 -152.116867) (xy 237.551404 -152.168801) (xy 237.514898 -152.216377) (xy 237.472493 -152.258782)
			(xy 237.424917 -152.295288) (xy 237.372983 -152.325272) (xy 237.317579 -152.348221) (xy 237.259654 -152.363742)
			(xy 237.200198 -152.37157) (xy 237.14023 -152.37157) (xy 237.080774 -152.363742) (xy 237.022849 -152.348221)
			(xy 236.967445 -152.325272) (xy 236.915511 -152.295288) (xy 236.867935 -152.258782) (xy 236.82553 -152.216377)
			(xy 236.789024 -152.168801) (xy 236.75904 -152.116867) (xy 236.736091 -152.061463) (xy 236.72057 -152.003538)
			(xy 236.712742 -151.944082) (xy 236.712252 -151.914098) (xy 200.732136 -151.914098) (xy 200.732136 -152.485852)
			(xy 200.732111 -152.487376) (xy 296.945304 -152.487376) (xy 296.945304 -151.623776) (xy 296.945794 -151.593808)
			(xy 296.953617 -151.534386) (xy 296.96913 -151.476493) (xy 296.992066 -151.42112) (xy 297.022033 -151.369214)
			(xy 297.05852 -151.321664) (xy 297.1009 -151.279284) (xy 297.14845 -151.242797) (xy 297.200356 -151.21283)
			(xy 297.255729 -151.189894) (xy 297.313622 -151.174381) (xy 297.373044 -151.166558) (xy 297.43298 -151.166558)
			(xy 297.492402 -151.174381) (xy 297.550295 -151.189894) (xy 297.605668 -151.21283) (xy 297.657574 -151.242797)
			(xy 297.705124 -151.279284) (xy 297.747504 -151.321664) (xy 297.783991 -151.369214) (xy 297.813958 -151.42112)
			(xy 297.836894 -151.476493) (xy 297.852407 -151.534386) (xy 297.86023 -151.593808) (xy 297.86072 -151.623776)
			(xy 297.86072 -152.485852) (xy 315.916564 -152.485852) (xy 315.916564 -151.622252) (xy 315.917054 -151.592284)
			(xy 315.924877 -151.532862) (xy 315.94039 -151.474969) (xy 315.963326 -151.419596) (xy 315.993293 -151.36769)
			(xy 316.02978 -151.32014) (xy 316.07216 -151.27776) (xy 316.11971 -151.241273) (xy 316.171616 -151.211306)
			(xy 316.226989 -151.18837) (xy 316.284882 -151.172857) (xy 316.344304 -151.165034) (xy 316.40424 -151.165034)
			(xy 316.463662 -151.172857) (xy 316.521555 -151.18837) (xy 316.576928 -151.211306) (xy 316.628834 -151.241273)
			(xy 316.676384 -151.27776) (xy 316.718764 -151.32014) (xy 316.755251 -151.36769) (xy 316.785218 -151.419596)
			(xy 316.808154 -151.474969) (xy 316.823667 -151.532862) (xy 316.83149 -151.592284) (xy 316.83198 -151.622252)
			(xy 316.83198 -152.485852) (xy 316.831955 -152.487376) (xy 413.045148 -152.487376) (xy 413.045148 -151.623776)
			(xy 413.045638 -151.593792) (xy 413.053466 -151.534336) (xy 413.068987 -151.476411) (xy 413.091936 -151.421007)
			(xy 413.12192 -151.369073) (xy 413.158426 -151.321497) (xy 413.200831 -151.279092) (xy 413.248407 -151.242586)
			(xy 413.300341 -151.212602) (xy 413.355745 -151.189653) (xy 413.41367 -151.174132) (xy 413.473126 -151.166304)
			(xy 413.533094 -151.166304) (xy 413.59255 -151.174132) (xy 413.650475 -151.189653) (xy 413.705879 -151.212602)
			(xy 413.757813 -151.242586) (xy 413.805389 -151.279092) (xy 413.847794 -151.321497) (xy 413.8843 -151.369073)
			(xy 413.914284 -151.421007) (xy 413.937233 -151.476411) (xy 413.952754 -151.534336) (xy 413.960582 -151.593792)
			(xy 413.961072 -151.623776) (xy 413.961072 -152.485852) (xy 432.016408 -152.485852) (xy 432.016408 -151.622252)
			(xy 432.016898 -151.592268) (xy 432.024726 -151.532812) (xy 432.040247 -151.474887) (xy 432.063196 -151.419483)
			(xy 432.09318 -151.367549) (xy 432.129686 -151.319973) (xy 432.172091 -151.277568) (xy 432.219667 -151.241062)
			(xy 432.271601 -151.211078) (xy 432.327005 -151.188129) (xy 432.38493 -151.172608) (xy 432.444386 -151.16478)
			(xy 432.504354 -151.16478) (xy 432.56381 -151.172608) (xy 432.621735 -151.188129) (xy 432.677139 -151.211078)
			(xy 432.729073 -151.241062) (xy 432.776649 -151.277568) (xy 432.819054 -151.319973) (xy 432.85556 -151.367549)
			(xy 432.885544 -151.419483) (xy 432.908493 -151.474887) (xy 432.924014 -151.532812) (xy 432.931842 -151.592268)
			(xy 432.932332 -151.622252) (xy 432.932332 -152.485852) (xy 432.931842 -152.515836) (xy 432.924014 -152.575292)
			(xy 432.908493 -152.633217) (xy 432.885544 -152.688621) (xy 432.85556 -152.740555) (xy 432.819054 -152.788131)
			(xy 432.776649 -152.830536) (xy 432.729073 -152.867042) (xy 432.677139 -152.897026) (xy 432.621735 -152.919975)
			(xy 432.56381 -152.935496) (xy 432.504354 -152.943324) (xy 432.444386 -152.943324) (xy 432.38493 -152.935496)
			(xy 432.327005 -152.919975) (xy 432.271601 -152.897026) (xy 432.219667 -152.867042) (xy 432.172091 -152.830536)
			(xy 432.129686 -152.788131) (xy 432.09318 -152.740555) (xy 432.063196 -152.688621) (xy 432.040247 -152.633217)
			(xy 432.024726 -152.575292) (xy 432.016898 -152.515836) (xy 432.016408 -152.485852) (xy 413.961072 -152.485852)
			(xy 413.961072 -152.487376) (xy 413.960582 -152.51736) (xy 413.952754 -152.576816) (xy 413.937233 -152.634741)
			(xy 413.914284 -152.690145) (xy 413.8843 -152.742079) (xy 413.847794 -152.789655) (xy 413.805389 -152.83206)
			(xy 413.757813 -152.868566) (xy 413.705879 -152.89855) (xy 413.650475 -152.921499) (xy 413.59255 -152.93702)
			(xy 413.533094 -152.944848) (xy 413.473126 -152.944848) (xy 413.41367 -152.93702) (xy 413.355745 -152.921499)
			(xy 413.300341 -152.89855) (xy 413.248407 -152.868566) (xy 413.200831 -152.83206) (xy 413.158426 -152.789655)
			(xy 413.12192 -152.742079) (xy 413.091936 -152.690145) (xy 413.068987 -152.634741) (xy 413.053466 -152.576816)
			(xy 413.045638 -152.51736) (xy 413.045148 -152.487376) (xy 316.831955 -152.487376) (xy 316.83149 -152.51582)
			(xy 316.823667 -152.575242) (xy 316.808154 -152.633135) (xy 316.785218 -152.688508) (xy 316.755251 -152.740414)
			(xy 316.718764 -152.787964) (xy 316.676384 -152.830344) (xy 316.628834 -152.866831) (xy 316.576928 -152.896798)
			(xy 316.521555 -152.919734) (xy 316.463662 -152.935247) (xy 316.40424 -152.94307) (xy 316.344304 -152.94307)
			(xy 316.284882 -152.935247) (xy 316.226989 -152.919734) (xy 316.171616 -152.896798) (xy 316.11971 -152.866831)
			(xy 316.07216 -152.830344) (xy 316.02978 -152.787964) (xy 315.993293 -152.740414) (xy 315.963326 -152.688508)
			(xy 315.94039 -152.633135) (xy 315.924877 -152.575242) (xy 315.917054 -152.51582) (xy 315.916564 -152.485852)
			(xy 297.86072 -152.485852) (xy 297.86072 -152.487376) (xy 297.86023 -152.517344) (xy 297.852407 -152.576766)
			(xy 297.836894 -152.634659) (xy 297.813958 -152.690032) (xy 297.783991 -152.741938) (xy 297.747504 -152.789488)
			(xy 297.705124 -152.831868) (xy 297.657574 -152.868355) (xy 297.605668 -152.898322) (xy 297.550295 -152.921258)
			(xy 297.492402 -152.936771) (xy 297.43298 -152.944594) (xy 297.373044 -152.944594) (xy 297.313622 -152.936771)
			(xy 297.255729 -152.921258) (xy 297.200356 -152.898322) (xy 297.14845 -152.868355) (xy 297.1009 -152.831868)
			(xy 297.05852 -152.789488) (xy 297.022033 -152.741938) (xy 296.992066 -152.690032) (xy 296.96913 -152.634659)
			(xy 296.953617 -152.576766) (xy 296.945794 -152.517344) (xy 296.945304 -152.487376) (xy 200.732111 -152.487376)
			(xy 200.731646 -152.51582) (xy 200.723823 -152.575242) (xy 200.70831 -152.633135) (xy 200.685374 -152.688508)
			(xy 200.655407 -152.740414) (xy 200.61892 -152.787964) (xy 200.57654 -152.830344) (xy 200.52899 -152.866831)
			(xy 200.477084 -152.896798) (xy 200.421711 -152.919734) (xy 200.363818 -152.935247) (xy 200.304396 -152.94307)
			(xy 200.24446 -152.94307) (xy 200.185038 -152.935247) (xy 200.127145 -152.919734) (xy 200.071772 -152.896798)
			(xy 200.019866 -152.866831) (xy 199.972316 -152.830344) (xy 199.929936 -152.787964) (xy 199.893449 -152.740414)
			(xy 199.863482 -152.688508) (xy 199.840546 -152.633135) (xy 199.825033 -152.575242) (xy 199.81721 -152.51582)
			(xy 199.81672 -152.485852) (xy 181.760876 -152.485852) (xy 181.760876 -152.487376) (xy 181.760386 -152.517344)
			(xy 181.752563 -152.576766) (xy 181.73705 -152.634659) (xy 181.714114 -152.690032) (xy 181.684147 -152.741938)
			(xy 181.64766 -152.789488) (xy 181.60528 -152.831868) (xy 181.55773 -152.868355) (xy 181.505824 -152.898322)
			(xy 181.450451 -152.921258) (xy 181.392558 -152.936771) (xy 181.333136 -152.944594) (xy 181.2732 -152.944594)
			(xy 181.213778 -152.936771) (xy 181.155885 -152.921258) (xy 181.100512 -152.898322) (xy 181.048606 -152.868355)
			(xy 181.001056 -152.831868) (xy 180.958676 -152.789488) (xy 180.922189 -152.741938) (xy 180.892222 -152.690032)
			(xy 180.869286 -152.634659) (xy 180.853773 -152.576766) (xy 180.84595 -152.517344) (xy 180.84546 -152.487376)
			(xy 84.632267 -152.487376) (xy 84.631802 -152.515836) (xy 84.623974 -152.575292) (xy 84.608453 -152.633217)
			(xy 84.585504 -152.688621) (xy 84.55552 -152.740555) (xy 84.519014 -152.788131) (xy 84.476609 -152.830536)
			(xy 84.429033 -152.867042) (xy 84.377099 -152.897026) (xy 84.321695 -152.919975) (xy 84.26377 -152.935496)
			(xy 84.204314 -152.943324) (xy 84.144346 -152.943324) (xy 84.08489 -152.935496) (xy 84.026965 -152.919975)
			(xy 83.971561 -152.897026) (xy 83.919627 -152.867042) (xy 83.872051 -152.830536) (xy 83.829646 -152.788131)
			(xy 83.79314 -152.740555) (xy 83.763156 -152.688621) (xy 83.740207 -152.633217) (xy 83.724686 -152.575292)
			(xy 83.716858 -152.515836) (xy 83.716368 -152.485852) (xy 65.661032 -152.485852) (xy 65.661032 -152.487376)
			(xy 65.660542 -152.51736) (xy 65.652714 -152.576816) (xy 65.637193 -152.634741) (xy 65.614244 -152.690145)
			(xy 65.58426 -152.742079) (xy 65.547754 -152.789655) (xy 65.505349 -152.83206) (xy 65.457773 -152.868566)
			(xy 65.405839 -152.89855) (xy 65.350435 -152.921499) (xy 65.29251 -152.93702) (xy 65.233054 -152.944848)
			(xy 65.173086 -152.944848) (xy 65.11363 -152.93702) (xy 65.055705 -152.921499) (xy 65.000301 -152.89855)
			(xy 64.948367 -152.868566) (xy 64.900791 -152.83206) (xy 64.858386 -152.789655) (xy 64.82188 -152.742079)
			(xy 64.791896 -152.690145) (xy 64.768947 -152.634741) (xy 64.753426 -152.576816) (xy 64.745598 -152.51736)
			(xy 64.745108 -152.487376) (xy 4.308094 -152.487376) (xy 4.308094 -154.28722) (xy 66.599308 -154.28722)
			(xy 66.599308 -153.42362) (xy 66.599798 -153.393636) (xy 66.607626 -153.33418) (xy 66.623147 -153.276255)
			(xy 66.646096 -153.220851) (xy 66.67608 -153.168917) (xy 66.712586 -153.121341) (xy 66.754991 -153.078936)
			(xy 66.802567 -153.04243) (xy 66.854501 -153.012446) (xy 66.909905 -152.989497) (xy 66.96783 -152.973976)
			(xy 67.027286 -152.966148) (xy 67.087254 -152.966148) (xy 67.14671 -152.973976) (xy 67.204635 -152.989497)
			(xy 67.260039 -153.012446) (xy 67.311973 -153.04243) (xy 67.359549 -153.078936) (xy 67.401954 -153.121341)
			(xy 67.43846 -153.168917) (xy 67.468444 -153.220851) (xy 67.491393 -153.276255) (xy 67.506914 -153.33418)
			(xy 67.514742 -153.393636) (xy 67.515232 -153.42362) (xy 67.515232 -154.279346) (xy 81.07426 -154.279346)
			(xy 81.07426 -153.415746) (xy 81.07475 -153.385762) (xy 81.082578 -153.326306) (xy 81.098099 -153.268381)
			(xy 81.121048 -153.212977) (xy 81.151032 -153.161043) (xy 81.187538 -153.113467) (xy 81.229943 -153.071062)
			(xy 81.277519 -153.034556) (xy 81.329453 -153.004572) (xy 81.384857 -152.981623) (xy 81.442782 -152.966102)
			(xy 81.502238 -152.958274) (xy 81.562206 -152.958274) (xy 81.621662 -152.966102) (xy 81.679587 -152.981623)
			(xy 81.734991 -153.004572) (xy 81.786925 -153.034556) (xy 81.834501 -153.071062) (xy 81.876906 -153.113467)
			(xy 81.913412 -153.161043) (xy 81.943396 -153.212977) (xy 81.966345 -153.268381) (xy 81.981866 -153.326306)
			(xy 81.989694 -153.385762) (xy 81.990184 -153.415746) (xy 81.990184 -154.279346) (xy 81.990055 -154.28722)
			(xy 182.69966 -154.28722) (xy 182.69966 -153.42362) (xy 182.70015 -153.393652) (xy 182.707973 -153.33423)
			(xy 182.723486 -153.276337) (xy 182.746422 -153.220964) (xy 182.776389 -153.169058) (xy 182.812876 -153.121508)
			(xy 182.855256 -153.079128) (xy 182.902806 -153.042641) (xy 182.954712 -153.012674) (xy 183.010085 -152.989738)
			(xy 183.067978 -152.974225) (xy 183.1274 -152.966402) (xy 183.187336 -152.966402) (xy 183.246758 -152.974225)
			(xy 183.304651 -152.989738) (xy 183.360024 -153.012674) (xy 183.41193 -153.042641) (xy 183.45948 -153.079128)
			(xy 183.50186 -153.121508) (xy 183.538347 -153.169058) (xy 183.568314 -153.220964) (xy 183.59125 -153.276337)
			(xy 183.606763 -153.33423) (xy 183.614586 -153.393652) (xy 183.615076 -153.42362) (xy 183.615076 -154.279346)
			(xy 197.174612 -154.279346) (xy 197.174612 -153.415746) (xy 197.175102 -153.385778) (xy 197.182925 -153.326356)
			(xy 197.198438 -153.268463) (xy 197.221374 -153.21309) (xy 197.251341 -153.161184) (xy 197.287828 -153.113634)
			(xy 197.330208 -153.071254) (xy 197.377758 -153.034767) (xy 197.429664 -153.0048) (xy 197.485037 -152.981864)
			(xy 197.54293 -152.966351) (xy 197.602352 -152.958528) (xy 197.662288 -152.958528) (xy 197.72171 -152.966351)
			(xy 197.779603 -152.981864) (xy 197.834976 -153.0048) (xy 197.886882 -153.034767) (xy 197.934432 -153.071254)
			(xy 197.976812 -153.113634) (xy 198.013299 -153.161184) (xy 198.043266 -153.21309) (xy 198.066202 -153.268463)
			(xy 198.081715 -153.326356) (xy 198.089538 -153.385778) (xy 198.090028 -153.415746) (xy 198.090028 -154.279346)
			(xy 198.089899 -154.28722) (xy 298.799504 -154.28722) (xy 298.799504 -153.42362) (xy 298.799994 -153.393652)
			(xy 298.807817 -153.33423) (xy 298.82333 -153.276337) (xy 298.846266 -153.220964) (xy 298.876233 -153.169058)
			(xy 298.91272 -153.121508) (xy 298.9551 -153.079128) (xy 299.00265 -153.042641) (xy 299.054556 -153.012674)
			(xy 299.109929 -152.989738) (xy 299.167822 -152.974225) (xy 299.227244 -152.966402) (xy 299.28718 -152.966402)
			(xy 299.346602 -152.974225) (xy 299.404495 -152.989738) (xy 299.459868 -153.012674) (xy 299.511774 -153.042641)
			(xy 299.559324 -153.079128) (xy 299.601704 -153.121508) (xy 299.638191 -153.169058) (xy 299.668158 -153.220964)
			(xy 299.691094 -153.276337) (xy 299.706607 -153.33423) (xy 299.71443 -153.393652) (xy 299.71492 -153.42362)
			(xy 299.71492 -154.279346) (xy 313.274456 -154.279346) (xy 313.274456 -153.415746) (xy 313.274946 -153.385778)
			(xy 313.282769 -153.326356) (xy 313.298282 -153.268463) (xy 313.321218 -153.21309) (xy 313.351185 -153.161184)
			(xy 313.387672 -153.113634) (xy 313.430052 -153.071254) (xy 313.477602 -153.034767) (xy 313.529508 -153.0048)
			(xy 313.584881 -152.981864) (xy 313.642774 -152.966351) (xy 313.702196 -152.958528) (xy 313.762132 -152.958528)
			(xy 313.821554 -152.966351) (xy 313.879447 -152.981864) (xy 313.93482 -153.0048) (xy 313.986726 -153.034767)
			(xy 314.034276 -153.071254) (xy 314.076656 -153.113634) (xy 314.113143 -153.161184) (xy 314.14311 -153.21309)
			(xy 314.166046 -153.268463) (xy 314.181559 -153.326356) (xy 314.189382 -153.385778) (xy 314.189872 -153.415746)
			(xy 314.189872 -154.279346) (xy 314.189743 -154.28722) (xy 414.899348 -154.28722) (xy 414.899348 -153.42362)
			(xy 414.899838 -153.393636) (xy 414.907666 -153.33418) (xy 414.923187 -153.276255) (xy 414.946136 -153.220851)
			(xy 414.97612 -153.168917) (xy 415.012626 -153.121341) (xy 415.055031 -153.078936) (xy 415.102607 -153.04243)
			(xy 415.154541 -153.012446) (xy 415.209945 -152.989497) (xy 415.26787 -152.973976) (xy 415.327326 -152.966148)
			(xy 415.387294 -152.966148) (xy 415.44675 -152.973976) (xy 415.504675 -152.989497) (xy 415.560079 -153.012446)
			(xy 415.612013 -153.04243) (xy 415.659589 -153.078936) (xy 415.701994 -153.121341) (xy 415.7385 -153.168917)
			(xy 415.768484 -153.220851) (xy 415.791433 -153.276255) (xy 415.806954 -153.33418) (xy 415.814782 -153.393636)
			(xy 415.815272 -153.42362) (xy 415.815272 -154.279346) (xy 429.3743 -154.279346) (xy 429.3743 -153.415746)
			(xy 429.37479 -153.385762) (xy 429.382618 -153.326306) (xy 429.398139 -153.268381) (xy 429.421088 -153.212977)
			(xy 429.451072 -153.161043) (xy 429.487578 -153.113467) (xy 429.529983 -153.071062) (xy 429.577559 -153.034556)
			(xy 429.629493 -153.004572) (xy 429.684897 -152.981623) (xy 429.742822 -152.966102) (xy 429.802278 -152.958274)
			(xy 429.862246 -152.958274) (xy 429.921702 -152.966102) (xy 429.979627 -152.981623) (xy 430.035031 -153.004572)
			(xy 430.086965 -153.034556) (xy 430.134541 -153.071062) (xy 430.176946 -153.113467) (xy 430.213452 -153.161043)
			(xy 430.243436 -153.212977) (xy 430.266385 -153.268381) (xy 430.281906 -153.326306) (xy 430.289734 -153.385762)
			(xy 430.290224 -153.415746) (xy 430.290224 -154.279346) (xy 430.289734 -154.30933) (xy 430.281906 -154.368786)
			(xy 430.266385 -154.426711) (xy 430.243436 -154.482115) (xy 430.213452 -154.534049) (xy 430.176946 -154.581625)
			(xy 430.134541 -154.62403) (xy 430.086965 -154.660536) (xy 430.035031 -154.69052) (xy 429.979627 -154.713469)
			(xy 429.921702 -154.72899) (xy 429.862246 -154.736818) (xy 429.802278 -154.736818) (xy 429.742822 -154.72899)
			(xy 429.684897 -154.713469) (xy 429.629493 -154.69052) (xy 429.577559 -154.660536) (xy 429.529983 -154.62403)
			(xy 429.487578 -154.581625) (xy 429.451072 -154.534049) (xy 429.421088 -154.482115) (xy 429.398139 -154.426711)
			(xy 429.382618 -154.368786) (xy 429.37479 -154.30933) (xy 429.3743 -154.279346) (xy 415.815272 -154.279346)
			(xy 415.815272 -154.28722) (xy 415.814782 -154.317204) (xy 415.806954 -154.37666) (xy 415.791433 -154.434585)
			(xy 415.768484 -154.489989) (xy 415.7385 -154.541923) (xy 415.701994 -154.589499) (xy 415.659589 -154.631904)
			(xy 415.612013 -154.66841) (xy 415.560079 -154.698394) (xy 415.504675 -154.721343) (xy 415.44675 -154.736864)
			(xy 415.387294 -154.744692) (xy 415.327326 -154.744692) (xy 415.26787 -154.736864) (xy 415.209945 -154.721343)
			(xy 415.154541 -154.698394) (xy 415.102607 -154.66841) (xy 415.055031 -154.631904) (xy 415.012626 -154.589499)
			(xy 414.97612 -154.541923) (xy 414.946136 -154.489989) (xy 414.923187 -154.434585) (xy 414.907666 -154.37666)
			(xy 414.899838 -154.317204) (xy 414.899348 -154.28722) (xy 314.189743 -154.28722) (xy 314.189382 -154.309314)
			(xy 314.181559 -154.368736) (xy 314.166046 -154.426629) (xy 314.14311 -154.482002) (xy 314.113143 -154.533908)
			(xy 314.076656 -154.581458) (xy 314.034276 -154.623838) (xy 313.986726 -154.660325) (xy 313.93482 -154.690292)
			(xy 313.879447 -154.713228) (xy 313.821554 -154.728741) (xy 313.762132 -154.736564) (xy 313.702196 -154.736564)
			(xy 313.642774 -154.728741) (xy 313.584881 -154.713228) (xy 313.529508 -154.690292) (xy 313.477602 -154.660325)
			(xy 313.430052 -154.623838) (xy 313.387672 -154.581458) (xy 313.351185 -154.533908) (xy 313.321218 -154.482002)
			(xy 313.298282 -154.426629) (xy 313.282769 -154.368736) (xy 313.274946 -154.309314) (xy 313.274456 -154.279346)
			(xy 299.71492 -154.279346) (xy 299.71492 -154.28722) (xy 299.71443 -154.317188) (xy 299.706607 -154.37661)
			(xy 299.691094 -154.434503) (xy 299.668158 -154.489876) (xy 299.638191 -154.541782) (xy 299.601704 -154.589332)
			(xy 299.559324 -154.631712) (xy 299.511774 -154.668199) (xy 299.459868 -154.698166) (xy 299.404495 -154.721102)
			(xy 299.346602 -154.736615) (xy 299.28718 -154.744438) (xy 299.227244 -154.744438) (xy 299.167822 -154.736615)
			(xy 299.109929 -154.721102) (xy 299.054556 -154.698166) (xy 299.00265 -154.668199) (xy 298.9551 -154.631712)
			(xy 298.91272 -154.589332) (xy 298.876233 -154.541782) (xy 298.846266 -154.489876) (xy 298.82333 -154.434503)
			(xy 298.807817 -154.37661) (xy 298.799994 -154.317188) (xy 298.799504 -154.28722) (xy 198.089899 -154.28722)
			(xy 198.089538 -154.309314) (xy 198.081715 -154.368736) (xy 198.066202 -154.426629) (xy 198.043266 -154.482002)
			(xy 198.013299 -154.533908) (xy 197.976812 -154.581458) (xy 197.934432 -154.623838) (xy 197.886882 -154.660325)
			(xy 197.834976 -154.690292) (xy 197.779603 -154.713228) (xy 197.72171 -154.728741) (xy 197.662288 -154.736564)
			(xy 197.602352 -154.736564) (xy 197.54293 -154.728741) (xy 197.485037 -154.713228) (xy 197.429664 -154.690292)
			(xy 197.377758 -154.660325) (xy 197.330208 -154.623838) (xy 197.287828 -154.581458) (xy 197.251341 -154.533908)
			(xy 197.221374 -154.482002) (xy 197.198438 -154.426629) (xy 197.182925 -154.368736) (xy 197.175102 -154.309314)
			(xy 197.174612 -154.279346) (xy 183.615076 -154.279346) (xy 183.615076 -154.28722) (xy 183.614586 -154.317188)
			(xy 183.606763 -154.37661) (xy 183.59125 -154.434503) (xy 183.568314 -154.489876) (xy 183.538347 -154.541782)
			(xy 183.50186 -154.589332) (xy 183.45948 -154.631712) (xy 183.41193 -154.668199) (xy 183.360024 -154.698166)
			(xy 183.304651 -154.721102) (xy 183.246758 -154.736615) (xy 183.187336 -154.744438) (xy 183.1274 -154.744438)
			(xy 183.067978 -154.736615) (xy 183.010085 -154.721102) (xy 182.954712 -154.698166) (xy 182.902806 -154.668199)
			(xy 182.855256 -154.631712) (xy 182.812876 -154.589332) (xy 182.776389 -154.541782) (xy 182.746422 -154.489876)
			(xy 182.723486 -154.434503) (xy 182.707973 -154.37661) (xy 182.70015 -154.317188) (xy 182.69966 -154.28722)
			(xy 81.990055 -154.28722) (xy 81.989694 -154.30933) (xy 81.981866 -154.368786) (xy 81.966345 -154.426711)
			(xy 81.943396 -154.482115) (xy 81.913412 -154.534049) (xy 81.876906 -154.581625) (xy 81.834501 -154.62403)
			(xy 81.786925 -154.660536) (xy 81.734991 -154.69052) (xy 81.679587 -154.713469) (xy 81.621662 -154.72899)
			(xy 81.562206 -154.736818) (xy 81.502238 -154.736818) (xy 81.442782 -154.72899) (xy 81.384857 -154.713469)
			(xy 81.329453 -154.69052) (xy 81.277519 -154.660536) (xy 81.229943 -154.62403) (xy 81.187538 -154.581625)
			(xy 81.151032 -154.534049) (xy 81.121048 -154.482115) (xy 81.098099 -154.426711) (xy 81.082578 -154.368786)
			(xy 81.07475 -154.30933) (xy 81.07426 -154.279346) (xy 67.515232 -154.279346) (xy 67.515232 -154.28722)
			(xy 67.514742 -154.317204) (xy 67.506914 -154.37666) (xy 67.491393 -154.434585) (xy 67.468444 -154.489989)
			(xy 67.43846 -154.541923) (xy 67.401954 -154.589499) (xy 67.359549 -154.631904) (xy 67.311973 -154.66841)
			(xy 67.260039 -154.698394) (xy 67.204635 -154.721343) (xy 67.14671 -154.736864) (xy 67.087254 -154.744692)
			(xy 67.027286 -154.744692) (xy 66.96783 -154.736864) (xy 66.909905 -154.721343) (xy 66.854501 -154.698394)
			(xy 66.802567 -154.66841) (xy 66.754991 -154.631904) (xy 66.712586 -154.589499) (xy 66.67608 -154.541923)
			(xy 66.646096 -154.489989) (xy 66.623147 -154.434585) (xy 66.607626 -154.37666) (xy 66.599798 -154.317204)
			(xy 66.599308 -154.28722) (xy 4.308094 -154.28722) (xy 4.308094 -156.087318) (xy 64.745108 -156.087318)
			(xy 64.745108 -155.223718) (xy 64.745598 -155.193734) (xy 64.753426 -155.134278) (xy 64.768947 -155.076353)
			(xy 64.791896 -155.020949) (xy 64.82188 -154.969015) (xy 64.858386 -154.921439) (xy 64.900791 -154.879034)
			(xy 64.948367 -154.842528) (xy 65.000301 -154.812544) (xy 65.055705 -154.789595) (xy 65.11363 -154.774074)
			(xy 65.173086 -154.766246) (xy 65.233054 -154.766246) (xy 65.29251 -154.774074) (xy 65.350435 -154.789595)
			(xy 65.405839 -154.812544) (xy 65.457773 -154.842528) (xy 65.505349 -154.879034) (xy 65.547754 -154.921439)
			(xy 65.58426 -154.969015) (xy 65.614244 -155.020949) (xy 65.637193 -155.076353) (xy 65.652714 -155.134278)
			(xy 65.660542 -155.193734) (xy 65.661032 -155.223718) (xy 65.661032 -156.085794) (xy 83.716368 -156.085794)
			(xy 83.716368 -155.222194) (xy 83.716858 -155.19221) (xy 83.724686 -155.132754) (xy 83.740207 -155.074829)
			(xy 83.763156 -155.019425) (xy 83.79314 -154.967491) (xy 83.829646 -154.919915) (xy 83.872051 -154.87751)
			(xy 83.919627 -154.841004) (xy 83.971561 -154.81102) (xy 84.026965 -154.788071) (xy 84.08489 -154.77255)
			(xy 84.144346 -154.764722) (xy 84.204314 -154.764722) (xy 84.26377 -154.77255) (xy 84.321695 -154.788071)
			(xy 84.377099 -154.81102) (xy 84.429033 -154.841004) (xy 84.476609 -154.87751) (xy 84.519014 -154.919915)
			(xy 84.55552 -154.967491) (xy 84.585504 -155.019425) (xy 84.608453 -155.074829) (xy 84.623974 -155.132754)
			(xy 84.631802 -155.19221) (xy 84.632292 -155.222194) (xy 84.632292 -156.085794) (xy 84.632267 -156.087318)
			(xy 180.84546 -156.087318) (xy 180.84546 -155.223718) (xy 180.84595 -155.19375) (xy 180.853773 -155.134328)
			(xy 180.869286 -155.076435) (xy 180.892222 -155.021062) (xy 180.922189 -154.969156) (xy 180.958676 -154.921606)
			(xy 181.001056 -154.879226) (xy 181.048606 -154.842739) (xy 181.100512 -154.812772) (xy 181.155885 -154.789836)
			(xy 181.213778 -154.774323) (xy 181.2732 -154.7665) (xy 181.333136 -154.7665) (xy 181.392558 -154.774323)
			(xy 181.450451 -154.789836) (xy 181.505824 -154.812772) (xy 181.55773 -154.842739) (xy 181.60528 -154.879226)
			(xy 181.64766 -154.921606) (xy 181.684147 -154.969156) (xy 181.714114 -155.021062) (xy 181.73705 -155.076435)
			(xy 181.752563 -155.134328) (xy 181.760386 -155.19375) (xy 181.760876 -155.223718) (xy 181.760876 -156.085794)
			(xy 199.81672 -156.085794) (xy 199.81672 -155.222194) (xy 199.81721 -155.192226) (xy 199.825033 -155.132804)
			(xy 199.840546 -155.074911) (xy 199.863482 -155.019538) (xy 199.893449 -154.967632) (xy 199.929936 -154.920082)
			(xy 199.972316 -154.877702) (xy 200.019866 -154.841215) (xy 200.071772 -154.811248) (xy 200.127145 -154.788312)
			(xy 200.185038 -154.772799) (xy 200.24446 -154.764976) (xy 200.304396 -154.764976) (xy 200.363818 -154.772799)
			(xy 200.421711 -154.788312) (xy 200.477084 -154.811248) (xy 200.52899 -154.841215) (xy 200.57654 -154.877702)
			(xy 200.61892 -154.920082) (xy 200.655407 -154.967632) (xy 200.685374 -155.019538) (xy 200.70831 -155.074911)
			(xy 200.723823 -155.132804) (xy 200.731646 -155.192226) (xy 200.732136 -155.222194) (xy 200.732136 -156.085794)
			(xy 200.732111 -156.087318) (xy 296.945304 -156.087318) (xy 296.945304 -155.223718) (xy 296.945794 -155.19375)
			(xy 296.953617 -155.134328) (xy 296.96913 -155.076435) (xy 296.992066 -155.021062) (xy 297.022033 -154.969156)
			(xy 297.05852 -154.921606) (xy 297.1009 -154.879226) (xy 297.14845 -154.842739) (xy 297.200356 -154.812772)
			(xy 297.255729 -154.789836) (xy 297.313622 -154.774323) (xy 297.373044 -154.7665) (xy 297.43298 -154.7665)
			(xy 297.492402 -154.774323) (xy 297.550295 -154.789836) (xy 297.605668 -154.812772) (xy 297.657574 -154.842739)
			(xy 297.705124 -154.879226) (xy 297.747504 -154.921606) (xy 297.783991 -154.969156) (xy 297.813958 -155.021062)
			(xy 297.836894 -155.076435) (xy 297.852407 -155.134328) (xy 297.86023 -155.19375) (xy 297.86072 -155.223718)
			(xy 297.86072 -156.085794) (xy 315.916564 -156.085794) (xy 315.916564 -155.222194) (xy 315.917054 -155.192226)
			(xy 315.924877 -155.132804) (xy 315.94039 -155.074911) (xy 315.963326 -155.019538) (xy 315.993293 -154.967632)
			(xy 316.02978 -154.920082) (xy 316.07216 -154.877702) (xy 316.11971 -154.841215) (xy 316.171616 -154.811248)
			(xy 316.226989 -154.788312) (xy 316.284882 -154.772799) (xy 316.344304 -154.764976) (xy 316.40424 -154.764976)
			(xy 316.463662 -154.772799) (xy 316.521555 -154.788312) (xy 316.576928 -154.811248) (xy 316.628834 -154.841215)
			(xy 316.676384 -154.877702) (xy 316.718764 -154.920082) (xy 316.755251 -154.967632) (xy 316.785218 -155.019538)
			(xy 316.808154 -155.074911) (xy 316.823667 -155.132804) (xy 316.83149 -155.192226) (xy 316.83198 -155.222194)
			(xy 316.83198 -156.085794) (xy 316.831955 -156.087318) (xy 413.045148 -156.087318) (xy 413.045148 -155.223718)
			(xy 413.045638 -155.193734) (xy 413.053466 -155.134278) (xy 413.068987 -155.076353) (xy 413.091936 -155.020949)
			(xy 413.12192 -154.969015) (xy 413.158426 -154.921439) (xy 413.200831 -154.879034) (xy 413.248407 -154.842528)
			(xy 413.300341 -154.812544) (xy 413.355745 -154.789595) (xy 413.41367 -154.774074) (xy 413.473126 -154.766246)
			(xy 413.533094 -154.766246) (xy 413.59255 -154.774074) (xy 413.650475 -154.789595) (xy 413.705879 -154.812544)
			(xy 413.757813 -154.842528) (xy 413.805389 -154.879034) (xy 413.847794 -154.921439) (xy 413.8843 -154.969015)
			(xy 413.914284 -155.020949) (xy 413.937233 -155.076353) (xy 413.952754 -155.134278) (xy 413.960582 -155.193734)
			(xy 413.961072 -155.223718) (xy 413.961072 -156.085794) (xy 432.016408 -156.085794) (xy 432.016408 -155.222194)
			(xy 432.016898 -155.19221) (xy 432.024726 -155.132754) (xy 432.040247 -155.074829) (xy 432.063196 -155.019425)
			(xy 432.09318 -154.967491) (xy 432.129686 -154.919915) (xy 432.172091 -154.87751) (xy 432.219667 -154.841004)
			(xy 432.271601 -154.81102) (xy 432.327005 -154.788071) (xy 432.38493 -154.77255) (xy 432.444386 -154.764722)
			(xy 432.504354 -154.764722) (xy 432.56381 -154.77255) (xy 432.621735 -154.788071) (xy 432.677139 -154.81102)
			(xy 432.729073 -154.841004) (xy 432.776649 -154.87751) (xy 432.819054 -154.919915) (xy 432.85556 -154.967491)
			(xy 432.885544 -155.019425) (xy 432.908493 -155.074829) (xy 432.924014 -155.132754) (xy 432.931842 -155.19221)
			(xy 432.932332 -155.222194) (xy 432.932332 -156.085794) (xy 432.931842 -156.115778) (xy 432.924014 -156.175234)
			(xy 432.908493 -156.233159) (xy 432.885544 -156.288563) (xy 432.85556 -156.340497) (xy 432.819054 -156.388073)
			(xy 432.776649 -156.430478) (xy 432.729073 -156.466984) (xy 432.677139 -156.496968) (xy 432.621735 -156.519917)
			(xy 432.56381 -156.535438) (xy 432.504354 -156.543266) (xy 432.444386 -156.543266) (xy 432.38493 -156.535438)
			(xy 432.327005 -156.519917) (xy 432.271601 -156.496968) (xy 432.219667 -156.466984) (xy 432.172091 -156.430478)
			(xy 432.129686 -156.388073) (xy 432.09318 -156.340497) (xy 432.063196 -156.288563) (xy 432.040247 -156.233159)
			(xy 432.024726 -156.175234) (xy 432.016898 -156.115778) (xy 432.016408 -156.085794) (xy 413.961072 -156.085794)
			(xy 413.961072 -156.087318) (xy 413.960582 -156.117302) (xy 413.952754 -156.176758) (xy 413.937233 -156.234683)
			(xy 413.914284 -156.290087) (xy 413.8843 -156.342021) (xy 413.847794 -156.389597) (xy 413.805389 -156.432002)
			(xy 413.757813 -156.468508) (xy 413.705879 -156.498492) (xy 413.650475 -156.521441) (xy 413.59255 -156.536962)
			(xy 413.533094 -156.54479) (xy 413.473126 -156.54479) (xy 413.41367 -156.536962) (xy 413.355745 -156.521441)
			(xy 413.300341 -156.498492) (xy 413.248407 -156.468508) (xy 413.200831 -156.432002) (xy 413.158426 -156.389597)
			(xy 413.12192 -156.342021) (xy 413.091936 -156.290087) (xy 413.068987 -156.234683) (xy 413.053466 -156.176758)
			(xy 413.045638 -156.117302) (xy 413.045148 -156.087318) (xy 316.831955 -156.087318) (xy 316.83149 -156.115762)
			(xy 316.823667 -156.175184) (xy 316.808154 -156.233077) (xy 316.785218 -156.28845) (xy 316.755251 -156.340356)
			(xy 316.718764 -156.387906) (xy 316.676384 -156.430286) (xy 316.628834 -156.466773) (xy 316.576928 -156.49674)
			(xy 316.521555 -156.519676) (xy 316.463662 -156.535189) (xy 316.40424 -156.543012) (xy 316.344304 -156.543012)
			(xy 316.284882 -156.535189) (xy 316.226989 -156.519676) (xy 316.171616 -156.49674) (xy 316.11971 -156.466773)
			(xy 316.07216 -156.430286) (xy 316.02978 -156.387906) (xy 315.993293 -156.340356) (xy 315.963326 -156.28845)
			(xy 315.94039 -156.233077) (xy 315.924877 -156.175184) (xy 315.917054 -156.115762) (xy 315.916564 -156.085794)
			(xy 297.86072 -156.085794) (xy 297.86072 -156.087318) (xy 297.86023 -156.117286) (xy 297.852407 -156.176708)
			(xy 297.836894 -156.234601) (xy 297.813958 -156.289974) (xy 297.783991 -156.34188) (xy 297.747504 -156.38943)
			(xy 297.705124 -156.43181) (xy 297.657574 -156.468297) (xy 297.605668 -156.498264) (xy 297.550295 -156.5212)
			(xy 297.492402 -156.536713) (xy 297.43298 -156.544536) (xy 297.373044 -156.544536) (xy 297.313622 -156.536713)
			(xy 297.255729 -156.5212) (xy 297.200356 -156.498264) (xy 297.14845 -156.468297) (xy 297.1009 -156.43181)
			(xy 297.05852 -156.38943) (xy 297.022033 -156.34188) (xy 296.992066 -156.289974) (xy 296.96913 -156.234601)
			(xy 296.953617 -156.176708) (xy 296.945794 -156.117286) (xy 296.945304 -156.087318) (xy 200.732111 -156.087318)
			(xy 200.731646 -156.115762) (xy 200.723823 -156.175184) (xy 200.70831 -156.233077) (xy 200.685374 -156.28845)
			(xy 200.655407 -156.340356) (xy 200.61892 -156.387906) (xy 200.57654 -156.430286) (xy 200.52899 -156.466773)
			(xy 200.477084 -156.49674) (xy 200.421711 -156.519676) (xy 200.363818 -156.535189) (xy 200.304396 -156.543012)
			(xy 200.24446 -156.543012) (xy 200.185038 -156.535189) (xy 200.127145 -156.519676) (xy 200.071772 -156.49674)
			(xy 200.019866 -156.466773) (xy 199.972316 -156.430286) (xy 199.929936 -156.387906) (xy 199.893449 -156.340356)
			(xy 199.863482 -156.28845) (xy 199.840546 -156.233077) (xy 199.825033 -156.175184) (xy 199.81721 -156.115762)
			(xy 199.81672 -156.085794) (xy 181.760876 -156.085794) (xy 181.760876 -156.087318) (xy 181.760386 -156.117286)
			(xy 181.752563 -156.176708) (xy 181.73705 -156.234601) (xy 181.714114 -156.289974) (xy 181.684147 -156.34188)
			(xy 181.64766 -156.38943) (xy 181.60528 -156.43181) (xy 181.55773 -156.468297) (xy 181.505824 -156.498264)
			(xy 181.450451 -156.5212) (xy 181.392558 -156.536713) (xy 181.333136 -156.544536) (xy 181.2732 -156.544536)
			(xy 181.213778 -156.536713) (xy 181.155885 -156.5212) (xy 181.100512 -156.498264) (xy 181.048606 -156.468297)
			(xy 181.001056 -156.43181) (xy 180.958676 -156.38943) (xy 180.922189 -156.34188) (xy 180.892222 -156.289974)
			(xy 180.869286 -156.234601) (xy 180.853773 -156.176708) (xy 180.84595 -156.117286) (xy 180.84546 -156.087318)
			(xy 84.632267 -156.087318) (xy 84.631802 -156.115778) (xy 84.623974 -156.175234) (xy 84.608453 -156.233159)
			(xy 84.585504 -156.288563) (xy 84.55552 -156.340497) (xy 84.519014 -156.388073) (xy 84.476609 -156.430478)
			(xy 84.429033 -156.466984) (xy 84.377099 -156.496968) (xy 84.321695 -156.519917) (xy 84.26377 -156.535438)
			(xy 84.204314 -156.543266) (xy 84.144346 -156.543266) (xy 84.08489 -156.535438) (xy 84.026965 -156.519917)
			(xy 83.971561 -156.496968) (xy 83.919627 -156.466984) (xy 83.872051 -156.430478) (xy 83.829646 -156.388073)
			(xy 83.79314 -156.340497) (xy 83.763156 -156.288563) (xy 83.740207 -156.233159) (xy 83.724686 -156.175234)
			(xy 83.716858 -156.115778) (xy 83.716368 -156.085794) (xy 65.661032 -156.085794) (xy 65.661032 -156.087318)
			(xy 65.660542 -156.117302) (xy 65.652714 -156.176758) (xy 65.637193 -156.234683) (xy 65.614244 -156.290087)
			(xy 65.58426 -156.342021) (xy 65.547754 -156.389597) (xy 65.505349 -156.432002) (xy 65.457773 -156.468508)
			(xy 65.405839 -156.498492) (xy 65.350435 -156.521441) (xy 65.29251 -156.536962) (xy 65.233054 -156.54479)
			(xy 65.173086 -156.54479) (xy 65.11363 -156.536962) (xy 65.055705 -156.521441) (xy 65.000301 -156.498492)
			(xy 64.948367 -156.468508) (xy 64.900791 -156.432002) (xy 64.858386 -156.389597) (xy 64.82188 -156.342021)
			(xy 64.791896 -156.290087) (xy 64.768947 -156.234683) (xy 64.753426 -156.176758) (xy 64.745598 -156.117302)
			(xy 64.745108 -156.087318) (xy 4.308094 -156.087318) (xy 4.308094 -157.900066) (xy 228.314505 -157.900066)
			(xy 228.314505 -157.840134) (xy 228.322328 -157.780714) (xy 228.33784 -157.722823) (xy 228.360775 -157.667453)
			(xy 228.390741 -157.61555) (xy 228.427226 -157.568002) (xy 228.469605 -157.525624) (xy 228.517153 -157.489139)
			(xy 228.569056 -157.459173) (xy 228.624427 -157.436238) (xy 228.682318 -157.420727) (xy 228.741738 -157.412905)
			(xy 228.771704 -157.412436) (xy 229.635304 -157.412436) (xy 229.665274 -157.412838) (xy 229.724702 -157.420663)
			(xy 229.7826 -157.436177) (xy 229.837978 -157.459116) (xy 229.889888 -157.489086) (xy 229.937442 -157.525576)
			(xy 229.979827 -157.567961) (xy 230.016316 -157.615515) (xy 230.046286 -157.667425) (xy 230.069224 -157.722803)
			(xy 230.084738 -157.780702) (xy 230.092562 -157.84013) (xy 230.092562 -157.90007) (xy 230.089876 -157.920473)
			(xy 230.557725 -157.920473) (xy 230.557725 -157.860527) (xy 230.56555 -157.801095) (xy 230.581066 -157.743192)
			(xy 230.604007 -157.68781) (xy 230.633981 -157.635897) (xy 230.670475 -157.58834) (xy 230.712864 -157.545953)
			(xy 230.760423 -157.509463) (xy 230.812339 -157.479493) (xy 230.867722 -157.456555) (xy 230.925626 -157.441044)
			(xy 230.985059 -157.433223) (xy 231.015032 -157.432756) (xy 231.878632 -157.432756) (xy 231.908596 -157.43332)
			(xy 231.968011 -157.441146) (xy 232.025896 -157.45666) (xy 232.081261 -157.479596) (xy 232.133158 -157.509563)
			(xy 232.180701 -157.546046) (xy 232.223075 -157.588423) (xy 232.259555 -157.635968) (xy 232.289518 -157.687868)
			(xy 232.31245 -157.743235) (xy 232.32796 -157.801121) (xy 232.335782 -157.860536) (xy 232.335782 -157.920464)
			(xy 232.32796 -157.979879) (xy 232.31245 -158.037765) (xy 232.289518 -158.093132) (xy 232.259555 -158.145032)
			(xy 232.223075 -158.192577) (xy 232.180701 -158.234954) (xy 232.133158 -158.271437) (xy 232.081261 -158.301404)
			(xy 232.025896 -158.32434) (xy 231.968011 -158.339854) (xy 231.908596 -158.34768) (xy 231.878632 -158.348172)
			(xy 231.015032 -158.348172) (xy 230.985059 -158.347777) (xy 230.925626 -158.339956) (xy 230.867722 -158.324445)
			(xy 230.812339 -158.301507) (xy 230.760423 -158.271537) (xy 230.712864 -158.235047) (xy 230.670475 -158.19266)
			(xy 230.633981 -158.145103) (xy 230.604007 -158.09319) (xy 230.581066 -158.037808) (xy 230.56555 -157.979905)
			(xy 230.557725 -157.920473) (xy 230.089876 -157.920473) (xy 230.084738 -157.959498) (xy 230.069224 -158.017397)
			(xy 230.046286 -158.072775) (xy 230.016316 -158.124685) (xy 229.979827 -158.172239) (xy 229.937442 -158.214624)
			(xy 229.889888 -158.251114) (xy 229.837978 -158.281084) (xy 229.7826 -158.304023) (xy 229.724702 -158.319537)
			(xy 229.665274 -158.327362) (xy 229.635304 -158.327852) (xy 228.771704 -158.327852) (xy 228.741738 -158.327295)
			(xy 228.682318 -158.319473) (xy 228.624427 -158.303962) (xy 228.569056 -158.281027) (xy 228.517153 -158.251061)
			(xy 228.469605 -158.214576) (xy 228.427226 -158.172198) (xy 228.390741 -158.12465) (xy 228.360775 -158.072747)
			(xy 228.33784 -158.017377) (xy 228.322328 -157.959486) (xy 228.314505 -157.900066) (xy 4.308094 -157.900066)
			(xy 4.308094 -160.1851) (xy 45.524179 -160.1851) (xy 45.528134 -160.093263) (xy 45.539969 -160.002106)
			(xy 45.559596 -159.912303) (xy 45.58687 -159.824521) (xy 45.62159 -159.739407) (xy 45.663498 -159.657594)
			(xy 45.712284 -159.579686) (xy 45.767587 -159.506261) (xy 45.828997 -159.437861) (xy 45.896059 -159.374994)
			(xy 45.968278 -159.318124) (xy 46.045118 -159.267673) (xy 46.126011 -159.224014) (xy 46.210357 -159.187471)
			(xy 46.297533 -159.158314) (xy 46.386892 -159.13676) (xy 46.477773 -159.122966) (xy 46.569504 -159.117036)
			(xy 46.661405 -159.119014) (xy 46.752796 -159.128885) (xy 46.843 -159.146575) (xy 46.931349 -159.171955)
			(xy 47.017189 -159.204835) (xy 47.099885 -159.244973) (xy 47.178825 -159.292072) (xy 47.253423 -159.345782)
			(xy 47.323129 -159.405706) (xy 47.387424 -159.4714) (xy 47.445835 -159.542378) (xy 47.497927 -159.618115)
			(xy 47.543316 -159.69805) (xy 47.581666 -159.78159) (xy 47.612691 -159.868118) (xy 47.636164 -159.956993)
			(xy 47.65191 -160.047557) (xy 47.659812 -160.139139) (xy 47.660306 -160.1851) (xy 69.888875 -160.1851)
			(xy 69.892831 -160.093241) (xy 69.904668 -160.002062) (xy 69.9243 -159.912238) (xy 69.951581 -159.824435)
			(xy 69.986309 -159.739302) (xy 70.028227 -159.657469) (xy 70.077025 -159.579542) (xy 70.13234 -159.506099)
			(xy 70.193765 -159.437683) (xy 70.260844 -159.374801) (xy 70.333079 -159.317918) (xy 70.409938 -159.267455)
			(xy 70.49085 -159.223786) (xy 70.575216 -159.187234) (xy 70.662412 -159.15807) (xy 70.751793 -159.13651)
			(xy 70.842696 -159.122714) (xy 70.934449 -159.116782) (xy 71.026371 -159.118761) (xy 71.117784 -159.128634)
			(xy 71.208009 -159.146329) (xy 71.29638 -159.171714) (xy 71.38224 -159.204602) (xy 71.464956 -159.24475)
			(xy 71.543914 -159.291859) (xy 71.618531 -159.345582) (xy 71.688252 -159.40552) (xy 71.752563 -159.47123)
			(xy 71.810988 -159.542226) (xy 71.863093 -159.61798) (xy 71.908492 -159.697934) (xy 71.946851 -159.781494)
			(xy 71.977884 -159.868043) (xy 72.001362 -159.956939) (xy 72.017112 -160.047524) (xy 72.025016 -160.139128)
			(xy 72.02551 -160.1851) (xy 161.624277 -160.1851) (xy 161.628232 -160.093263) (xy 161.640067 -160.002106)
			(xy 161.659694 -159.912303) (xy 161.686968 -159.824521) (xy 161.721688 -159.739407) (xy 161.763596 -159.657594)
			(xy 161.812382 -159.579686) (xy 161.867685 -159.506261) (xy 161.929095 -159.437861) (xy 161.996157 -159.374994)
			(xy 162.068376 -159.318124) (xy 162.145216 -159.267673) (xy 162.226109 -159.224014) (xy 162.310455 -159.187471)
			(xy 162.397631 -159.158314) (xy 162.48699 -159.13676) (xy 162.577871 -159.122966) (xy 162.669602 -159.117036)
			(xy 162.761503 -159.119014) (xy 162.852894 -159.128885) (xy 162.943098 -159.146575) (xy 163.031447 -159.171955)
			(xy 163.117287 -159.204835) (xy 163.199983 -159.244973) (xy 163.278923 -159.292072) (xy 163.353521 -159.345782)
			(xy 163.423227 -159.405706) (xy 163.487522 -159.4714) (xy 163.545933 -159.542378) (xy 163.598025 -159.618115)
			(xy 163.643414 -159.69805) (xy 163.681764 -159.78159) (xy 163.712789 -159.868118) (xy 163.736262 -159.956993)
			(xy 163.752008 -160.047557) (xy 163.75991 -160.139139) (xy 163.760404 -160.1851) (xy 185.988973 -160.1851)
			(xy 185.992929 -160.093241) (xy 186.004766 -160.002062) (xy 186.024398 -159.912238) (xy 186.051679 -159.824435)
			(xy 186.086407 -159.739302) (xy 186.128325 -159.657469) (xy 186.177123 -159.579542) (xy 186.232438 -159.506099)
			(xy 186.293863 -159.437683) (xy 186.360942 -159.374801) (xy 186.433177 -159.317918) (xy 186.510036 -159.267455)
			(xy 186.590948 -159.223786) (xy 186.675314 -159.187234) (xy 186.76251 -159.15807) (xy 186.851891 -159.13651)
			(xy 186.942794 -159.122714) (xy 187.034547 -159.116782) (xy 187.126469 -159.118761) (xy 187.217882 -159.128634)
			(xy 187.308107 -159.146329) (xy 187.396478 -159.171714) (xy 187.482338 -159.204602) (xy 187.565054 -159.24475)
			(xy 187.644012 -159.291859) (xy 187.718629 -159.345582) (xy 187.78835 -159.40552) (xy 187.852661 -159.47123)
			(xy 187.911086 -159.542226) (xy 187.963191 -159.61798) (xy 188.00859 -159.697934) (xy 188.046949 -159.781494)
			(xy 188.077982 -159.868043) (xy 188.10146 -159.956939) (xy 188.11721 -160.047524) (xy 188.125114 -160.139128)
			(xy 188.125608 -160.1851) (xy 277.724121 -160.1851) (xy 277.728076 -160.093263) (xy 277.739911 -160.002106)
			(xy 277.759538 -159.912303) (xy 277.786812 -159.824521) (xy 277.821532 -159.739407) (xy 277.86344 -159.657594)
			(xy 277.912226 -159.579686) (xy 277.967529 -159.506261) (xy 278.028939 -159.437861) (xy 278.096001 -159.374994)
			(xy 278.16822 -159.318124) (xy 278.24506 -159.267673) (xy 278.325953 -159.224014) (xy 278.410299 -159.187471)
			(xy 278.497475 -159.158314) (xy 278.586834 -159.13676) (xy 278.677715 -159.122966) (xy 278.769446 -159.117036)
			(xy 278.861347 -159.119014) (xy 278.952738 -159.128885) (xy 279.042942 -159.146575) (xy 279.131291 -159.171955)
			(xy 279.217131 -159.204835) (xy 279.299827 -159.244973) (xy 279.378767 -159.292072) (xy 279.453365 -159.345782)
			(xy 279.523071 -159.405706) (xy 279.587366 -159.4714) (xy 279.645777 -159.542378) (xy 279.697869 -159.618115)
			(xy 279.743258 -159.69805) (xy 279.781608 -159.78159) (xy 279.812633 -159.868118) (xy 279.836106 -159.956993)
			(xy 279.851852 -160.047557) (xy 279.859754 -160.139139) (xy 279.860248 -160.1851) (xy 302.088817 -160.1851)
			(xy 302.092773 -160.093241) (xy 302.10461 -160.002062) (xy 302.124242 -159.912238) (xy 302.151523 -159.824435)
			(xy 302.186251 -159.739302) (xy 302.228169 -159.657469) (xy 302.276967 -159.579542) (xy 302.332282 -159.506099)
			(xy 302.393707 -159.437683) (xy 302.460786 -159.374801) (xy 302.533021 -159.317918) (xy 302.60988 -159.267455)
			(xy 302.690792 -159.223786) (xy 302.775158 -159.187234) (xy 302.862354 -159.15807) (xy 302.951735 -159.13651)
			(xy 303.042638 -159.122714) (xy 303.134391 -159.116782) (xy 303.226313 -159.118761) (xy 303.317726 -159.128634)
			(xy 303.407951 -159.146329) (xy 303.496322 -159.171714) (xy 303.582182 -159.204602) (xy 303.664898 -159.24475)
			(xy 303.743856 -159.291859) (xy 303.818473 -159.345582) (xy 303.888194 -159.40552) (xy 303.952505 -159.47123)
			(xy 304.01093 -159.542226) (xy 304.063035 -159.61798) (xy 304.108434 -159.697934) (xy 304.146793 -159.781494)
			(xy 304.177826 -159.868043) (xy 304.201304 -159.956939) (xy 304.217054 -160.047524) (xy 304.224958 -160.139128)
			(xy 304.225452 -160.1851) (xy 393.824219 -160.1851) (xy 393.828174 -160.093263) (xy 393.840009 -160.002106)
			(xy 393.859636 -159.912303) (xy 393.88691 -159.824521) (xy 393.92163 -159.739407) (xy 393.963538 -159.657594)
			(xy 394.012324 -159.579686) (xy 394.067627 -159.506261) (xy 394.129037 -159.437861) (xy 394.196099 -159.374994)
			(xy 394.268318 -159.318124) (xy 394.345158 -159.267673) (xy 394.426051 -159.224014) (xy 394.510397 -159.187471)
			(xy 394.597573 -159.158314) (xy 394.686932 -159.13676) (xy 394.777813 -159.122966) (xy 394.869544 -159.117036)
			(xy 394.961445 -159.119014) (xy 395.052836 -159.128885) (xy 395.14304 -159.146575) (xy 395.231389 -159.171955)
			(xy 395.317229 -159.204835) (xy 395.399925 -159.244973) (xy 395.478865 -159.292072) (xy 395.553463 -159.345782)
			(xy 395.623169 -159.405706) (xy 395.687464 -159.4714) (xy 395.745875 -159.542378) (xy 395.797967 -159.618115)
			(xy 395.843356 -159.69805) (xy 395.881706 -159.78159) (xy 395.912731 -159.868118) (xy 395.936204 -159.956993)
			(xy 395.95195 -160.047557) (xy 395.959852 -160.139139) (xy 395.960346 -160.1851) (xy 418.188915 -160.1851)
			(xy 418.192871 -160.093241) (xy 418.204708 -160.002062) (xy 418.22434 -159.912238) (xy 418.251621 -159.824435)
			(xy 418.286349 -159.739302) (xy 418.328267 -159.657469) (xy 418.377065 -159.579542) (xy 418.43238 -159.506099)
			(xy 418.493805 -159.437683) (xy 418.560884 -159.374801) (xy 418.633119 -159.317918) (xy 418.709978 -159.267455)
			(xy 418.79089 -159.223786) (xy 418.875256 -159.187234) (xy 418.962452 -159.15807) (xy 419.051833 -159.13651)
			(xy 419.142736 -159.122714) (xy 419.234489 -159.116782) (xy 419.326411 -159.118761) (xy 419.417824 -159.128634)
			(xy 419.508049 -159.146329) (xy 419.59642 -159.171714) (xy 419.68228 -159.204602) (xy 419.764996 -159.24475)
			(xy 419.843954 -159.291859) (xy 419.918571 -159.345582) (xy 419.988292 -159.40552) (xy 420.052603 -159.47123)
			(xy 420.111028 -159.542226) (xy 420.163133 -159.61798) (xy 420.208532 -159.697934) (xy 420.246891 -159.781494)
			(xy 420.277924 -159.868043) (xy 420.301402 -159.956939) (xy 420.317152 -160.047524) (xy 420.325056 -160.139128)
			(xy 420.32555 -160.1851) (xy 420.325056 -160.231072) (xy 420.317152 -160.322676) (xy 420.301402 -160.413261)
			(xy 420.277924 -160.502157) (xy 420.246891 -160.588706) (xy 420.208532 -160.672266) (xy 420.163133 -160.75222)
			(xy 420.111028 -160.827974) (xy 420.052603 -160.89897) (xy 419.988292 -160.96468) (xy 419.918571 -161.024618)
			(xy 419.843954 -161.078341) (xy 419.764996 -161.12545) (xy 419.68228 -161.165598) (xy 419.59642 -161.198486)
			(xy 419.508049 -161.223871) (xy 419.417824 -161.241566) (xy 419.326411 -161.251439) (xy 419.234489 -161.253418)
			(xy 419.142736 -161.247486) (xy 419.051833 -161.23369) (xy 418.962452 -161.21213) (xy 418.875256 -161.182966)
			(xy 418.79089 -161.146414) (xy 418.709978 -161.102745) (xy 418.633119 -161.052282) (xy 418.560884 -160.995399)
			(xy 418.493805 -160.932517) (xy 418.43238 -160.864101) (xy 418.377065 -160.790658) (xy 418.328267 -160.712731)
			(xy 418.286349 -160.630898) (xy 418.251621 -160.545765) (xy 418.22434 -160.457962) (xy 418.204708 -160.368138)
			(xy 418.192871 -160.276959) (xy 418.188915 -160.1851) (xy 395.960346 -160.1851) (xy 395.959852 -160.231061)
			(xy 395.95195 -160.322643) (xy 395.936204 -160.413207) (xy 395.912731 -160.502082) (xy 395.881706 -160.58861)
			(xy 395.843356 -160.67215) (xy 395.797967 -160.752085) (xy 395.745875 -160.827822) (xy 395.687464 -160.8988)
			(xy 395.623169 -160.964494) (xy 395.553463 -161.024418) (xy 395.478865 -161.078128) (xy 395.399925 -161.125227)
			(xy 395.317229 -161.165365) (xy 395.231389 -161.198245) (xy 395.14304 -161.223625) (xy 395.052836 -161.241315)
			(xy 394.961445 -161.251186) (xy 394.869544 -161.253164) (xy 394.777813 -161.247234) (xy 394.686932 -161.23344)
			(xy 394.597573 -161.211886) (xy 394.510397 -161.182729) (xy 394.426051 -161.146186) (xy 394.345158 -161.102527)
			(xy 394.268318 -161.052076) (xy 394.196099 -160.995206) (xy 394.129037 -160.932339) (xy 394.067627 -160.863939)
			(xy 394.012324 -160.790514) (xy 393.963538 -160.712606) (xy 393.92163 -160.630793) (xy 393.88691 -160.545679)
			(xy 393.859636 -160.457897) (xy 393.840009 -160.368094) (xy 393.828174 -160.276937) (xy 393.824219 -160.1851)
			(xy 304.225452 -160.1851) (xy 304.224958 -160.231072) (xy 304.217054 -160.322676) (xy 304.201304 -160.413261)
			(xy 304.177826 -160.502157) (xy 304.146793 -160.588706) (xy 304.108434 -160.672266) (xy 304.063035 -160.75222)
			(xy 304.01093 -160.827974) (xy 303.952505 -160.89897) (xy 303.888194 -160.96468) (xy 303.818473 -161.024618)
			(xy 303.743856 -161.078341) (xy 303.664898 -161.12545) (xy 303.582182 -161.165598) (xy 303.496322 -161.198486)
			(xy 303.407951 -161.223871) (xy 303.317726 -161.241566) (xy 303.226313 -161.251439) (xy 303.134391 -161.253418)
			(xy 303.042638 -161.247486) (xy 302.951735 -161.23369) (xy 302.862354 -161.21213) (xy 302.775158 -161.182966)
			(xy 302.690792 -161.146414) (xy 302.60988 -161.102745) (xy 302.533021 -161.052282) (xy 302.460786 -160.995399)
			(xy 302.393707 -160.932517) (xy 302.332282 -160.864101) (xy 302.276967 -160.790658) (xy 302.228169 -160.712731)
			(xy 302.186251 -160.630898) (xy 302.151523 -160.545765) (xy 302.124242 -160.457962) (xy 302.10461 -160.368138)
			(xy 302.092773 -160.276959) (xy 302.088817 -160.1851) (xy 279.860248 -160.1851) (xy 279.859754 -160.231061)
			(xy 279.851852 -160.322643) (xy 279.836106 -160.413207) (xy 279.812633 -160.502082) (xy 279.781608 -160.58861)
			(xy 279.743258 -160.67215) (xy 279.697869 -160.752085) (xy 279.645777 -160.827822) (xy 279.587366 -160.8988)
			(xy 279.523071 -160.964494) (xy 279.453365 -161.024418) (xy 279.378767 -161.078128) (xy 279.299827 -161.125227)
			(xy 279.217131 -161.165365) (xy 279.131291 -161.198245) (xy 279.042942 -161.223625) (xy 278.952738 -161.241315)
			(xy 278.861347 -161.251186) (xy 278.769446 -161.253164) (xy 278.677715 -161.247234) (xy 278.586834 -161.23344)
			(xy 278.497475 -161.211886) (xy 278.410299 -161.182729) (xy 278.325953 -161.146186) (xy 278.24506 -161.102527)
			(xy 278.16822 -161.052076) (xy 278.096001 -160.995206) (xy 278.028939 -160.932339) (xy 277.967529 -160.863939)
			(xy 277.912226 -160.790514) (xy 277.86344 -160.712606) (xy 277.821532 -160.630793) (xy 277.786812 -160.545679)
			(xy 277.759538 -160.457897) (xy 277.739911 -160.368094) (xy 277.728076 -160.276937) (xy 277.724121 -160.1851)
			(xy 188.125608 -160.1851) (xy 188.125114 -160.231072) (xy 188.11721 -160.322676) (xy 188.10146 -160.413261)
			(xy 188.077982 -160.502157) (xy 188.046949 -160.588706) (xy 188.00859 -160.672266) (xy 187.963191 -160.75222)
			(xy 187.911086 -160.827974) (xy 187.852661 -160.89897) (xy 187.78835 -160.96468) (xy 187.718629 -161.024618)
			(xy 187.644012 -161.078341) (xy 187.565054 -161.12545) (xy 187.482338 -161.165598) (xy 187.396478 -161.198486)
			(xy 187.308107 -161.223871) (xy 187.217882 -161.241566) (xy 187.126469 -161.251439) (xy 187.034547 -161.253418)
			(xy 186.942794 -161.247486) (xy 186.851891 -161.23369) (xy 186.76251 -161.21213) (xy 186.675314 -161.182966)
			(xy 186.590948 -161.146414) (xy 186.510036 -161.102745) (xy 186.433177 -161.052282) (xy 186.360942 -160.995399)
			(xy 186.293863 -160.932517) (xy 186.232438 -160.864101) (xy 186.177123 -160.790658) (xy 186.128325 -160.712731)
			(xy 186.086407 -160.630898) (xy 186.051679 -160.545765) (xy 186.024398 -160.457962) (xy 186.004766 -160.368138)
			(xy 185.992929 -160.276959) (xy 185.988973 -160.1851) (xy 163.760404 -160.1851) (xy 163.75991 -160.231061)
			(xy 163.752008 -160.322643) (xy 163.736262 -160.413207) (xy 163.712789 -160.502082) (xy 163.681764 -160.58861)
			(xy 163.643414 -160.67215) (xy 163.598025 -160.752085) (xy 163.545933 -160.827822) (xy 163.487522 -160.8988)
			(xy 163.423227 -160.964494) (xy 163.353521 -161.024418) (xy 163.278923 -161.078128) (xy 163.199983 -161.125227)
			(xy 163.117287 -161.165365) (xy 163.031447 -161.198245) (xy 162.943098 -161.223625) (xy 162.852894 -161.241315)
			(xy 162.761503 -161.251186) (xy 162.669602 -161.253164) (xy 162.577871 -161.247234) (xy 162.48699 -161.23344)
			(xy 162.397631 -161.211886) (xy 162.310455 -161.182729) (xy 162.226109 -161.146186) (xy 162.145216 -161.102527)
			(xy 162.068376 -161.052076) (xy 161.996157 -160.995206) (xy 161.929095 -160.932339) (xy 161.867685 -160.863939)
			(xy 161.812382 -160.790514) (xy 161.763596 -160.712606) (xy 161.721688 -160.630793) (xy 161.686968 -160.545679)
			(xy 161.659694 -160.457897) (xy 161.640067 -160.368094) (xy 161.628232 -160.276937) (xy 161.624277 -160.1851)
			(xy 72.02551 -160.1851) (xy 72.025016 -160.231072) (xy 72.017112 -160.322676) (xy 72.001362 -160.413261)
			(xy 71.977884 -160.502157) (xy 71.946851 -160.588706) (xy 71.908492 -160.672266) (xy 71.863093 -160.75222)
			(xy 71.810988 -160.827974) (xy 71.752563 -160.89897) (xy 71.688252 -160.96468) (xy 71.618531 -161.024618)
			(xy 71.543914 -161.078341) (xy 71.464956 -161.12545) (xy 71.38224 -161.165598) (xy 71.29638 -161.198486)
			(xy 71.208009 -161.223871) (xy 71.117784 -161.241566) (xy 71.026371 -161.251439) (xy 70.934449 -161.253418)
			(xy 70.842696 -161.247486) (xy 70.751793 -161.23369) (xy 70.662412 -161.21213) (xy 70.575216 -161.182966)
			(xy 70.49085 -161.146414) (xy 70.409938 -161.102745) (xy 70.333079 -161.052282) (xy 70.260844 -160.995399)
			(xy 70.193765 -160.932517) (xy 70.13234 -160.864101) (xy 70.077025 -160.790658) (xy 70.028227 -160.712731)
			(xy 69.986309 -160.630898) (xy 69.951581 -160.545765) (xy 69.9243 -160.457962) (xy 69.904668 -160.368138)
			(xy 69.892831 -160.276959) (xy 69.888875 -160.1851) (xy 47.660306 -160.1851) (xy 47.659812 -160.231061)
			(xy 47.65191 -160.322643) (xy 47.636164 -160.413207) (xy 47.612691 -160.502082) (xy 47.581666 -160.58861)
			(xy 47.543316 -160.67215) (xy 47.497927 -160.752085) (xy 47.445835 -160.827822) (xy 47.387424 -160.8988)
			(xy 47.323129 -160.964494) (xy 47.253423 -161.024418) (xy 47.178825 -161.078128) (xy 47.099885 -161.125227)
			(xy 47.017189 -161.165365) (xy 46.931349 -161.198245) (xy 46.843 -161.223625) (xy 46.752796 -161.241315)
			(xy 46.661405 -161.251186) (xy 46.569504 -161.253164) (xy 46.477773 -161.247234) (xy 46.386892 -161.23344)
			(xy 46.297533 -161.211886) (xy 46.210357 -161.182729) (xy 46.126011 -161.146186) (xy 46.045118 -161.102527)
			(xy 45.968278 -161.052076) (xy 45.896059 -160.995206) (xy 45.828997 -160.932339) (xy 45.767587 -160.863939)
			(xy 45.712284 -160.790514) (xy 45.663498 -160.712606) (xy 45.62159 -160.630793) (xy 45.58687 -160.545679)
			(xy 45.559596 -160.457897) (xy 45.539969 -160.368094) (xy 45.528134 -160.276937) (xy 45.524179 -160.1851)
			(xy 4.308094 -160.1851) (xy 4.308094 -168.065164) (xy 135.245906 -168.065164) (xy 135.245906 -168.005236)
			(xy 135.253728 -167.94582) (xy 135.269237 -167.887933) (xy 135.29217 -167.832566) (xy 135.322132 -167.780665)
			(xy 135.358612 -167.733119) (xy 135.400986 -167.690742) (xy 135.448529 -167.654257) (xy 135.500426 -167.624289)
			(xy 135.555791 -167.601351) (xy 135.613677 -167.585836) (xy 135.673092 -167.578009) (xy 135.703056 -167.577516)
			(xy 136.566656 -167.577516) (xy 136.596628 -167.577934) (xy 136.656061 -167.585754) (xy 136.713965 -167.601264)
			(xy 136.769348 -167.6242) (xy 136.821264 -167.654169) (xy 136.868823 -167.690658) (xy 136.911213 -167.733044)
			(xy 136.947707 -167.7806) (xy 136.977681 -167.832512) (xy 137.000622 -167.887894) (xy 137.016138 -167.945796)
			(xy 137.023963 -168.005228) (xy 137.023963 -168.065172) (xy 137.016138 -168.124604) (xy 137.000622 -168.182506)
			(xy 136.977681 -168.237888) (xy 136.947707 -168.2898) (xy 136.911213 -168.337356) (xy 136.868823 -168.379742)
			(xy 136.821264 -168.416231) (xy 136.769348 -168.4462) (xy 136.713965 -168.469136) (xy 136.656061 -168.484646)
			(xy 136.596628 -168.492466) (xy 136.566656 -168.492932) (xy 135.703056 -168.492932) (xy 135.673092 -168.492391)
			(xy 135.613677 -168.484564) (xy 135.555791 -168.469049) (xy 135.500426 -168.446111) (xy 135.448529 -168.416143)
			(xy 135.400986 -168.379658) (xy 135.358612 -168.337281) (xy 135.322132 -168.289735) (xy 135.29217 -168.237834)
			(xy 135.269237 -168.182467) (xy 135.253728 -168.12458) (xy 135.245906 -168.065164) (xy 4.308094 -168.065164)
			(xy 4.308094 -168.700164) (xy 133.213906 -168.700164) (xy 133.213906 -168.640236) (xy 133.221728 -168.58082)
			(xy 133.237237 -168.522933) (xy 133.26017 -168.467566) (xy 133.290132 -168.415665) (xy 133.326612 -168.368119)
			(xy 133.368986 -168.325742) (xy 133.416529 -168.289257) (xy 133.468426 -168.259289) (xy 133.523791 -168.236351)
			(xy 133.581677 -168.220836) (xy 133.641092 -168.213009) (xy 133.671056 -168.212516) (xy 134.534656 -168.212516)
			(xy 134.564628 -168.212934) (xy 134.624061 -168.220754) (xy 134.681965 -168.236264) (xy 134.737348 -168.2592)
			(xy 134.789264 -168.289169) (xy 134.836823 -168.325658) (xy 134.879213 -168.368044) (xy 134.915707 -168.4156)
			(xy 134.945681 -168.467512) (xy 134.968622 -168.522894) (xy 134.984138 -168.580796) (xy 134.991963 -168.640228)
			(xy 134.991963 -168.700172) (xy 134.984138 -168.759604) (xy 134.968622 -168.817506) (xy 134.945681 -168.872888)
			(xy 134.915707 -168.9248) (xy 134.879213 -168.972356) (xy 134.836823 -169.014742) (xy 134.789264 -169.051231)
			(xy 134.737348 -169.0812) (xy 134.681965 -169.104136) (xy 134.624061 -169.119646) (xy 134.564628 -169.127466)
			(xy 134.534656 -169.127932) (xy 133.671056 -169.127932) (xy 133.641092 -169.127391) (xy 133.581677 -169.119564)
			(xy 133.523791 -169.104049) (xy 133.468426 -169.081111) (xy 133.416529 -169.051143) (xy 133.368986 -169.014658)
			(xy 133.326612 -168.972281) (xy 133.290132 -168.924735) (xy 133.26017 -168.872834) (xy 133.237237 -168.817467)
			(xy 133.221728 -168.75958) (xy 133.213906 -168.700164) (xy 4.308094 -168.700164) (xy 4.308094 -169.61389)
			(xy 245.108869 -169.61389) (xy 245.108869 -169.55391) (xy 245.116699 -169.494444) (xy 245.132223 -169.436508)
			(xy 245.155178 -169.381095) (xy 245.185169 -169.329152) (xy 245.221684 -169.281569) (xy 245.264097 -169.239158)
			(xy 245.311684 -169.202648) (xy 245.363629 -169.172661) (xy 245.419045 -169.149711) (xy 245.476981 -169.134191)
			(xy 245.536448 -169.126367) (xy 245.566438 -169.1259) (xy 246.430038 -169.1259) (xy 246.460018 -169.126468)
			(xy 246.519465 -169.134299) (xy 246.577381 -169.149822) (xy 246.632776 -169.172772) (xy 246.684702 -169.202755)
			(xy 246.73227 -169.239259) (xy 246.774667 -169.281659) (xy 246.811166 -169.32923) (xy 246.841145 -169.381158)
			(xy 246.86409 -169.436555) (xy 246.879608 -169.494472) (xy 246.887434 -169.55392) (xy 246.887434 -169.61388)
			(xy 246.879608 -169.673328) (xy 246.86409 -169.731245) (xy 246.841145 -169.786642) (xy 246.811166 -169.83857)
			(xy 246.774667 -169.886141) (xy 246.73227 -169.928541) (xy 246.684702 -169.965045) (xy 246.632776 -169.995028)
			(xy 246.577381 -170.017978) (xy 246.519465 -170.033501) (xy 246.460018 -170.041332) (xy 246.430038 -170.041824)
			(xy 245.566438 -170.041824) (xy 245.536448 -170.041433) (xy 245.476981 -170.033609) (xy 245.419045 -170.018089)
			(xy 245.363629 -169.995139) (xy 245.311684 -169.965152) (xy 245.264097 -169.928642) (xy 245.221684 -169.886231)
			(xy 245.185169 -169.838648) (xy 245.155178 -169.786705) (xy 245.132223 -169.731292) (xy 245.116699 -169.673356)
			(xy 245.108869 -169.61389) (xy 4.308094 -169.61389) (xy 4.308094 -174.805086) (xy 141.546072 -174.805086)
			(xy 141.546072 -173.941486) (xy 141.546562 -173.911518) (xy 141.554385 -173.852096) (xy 141.569898 -173.794203)
			(xy 141.592834 -173.73883) (xy 141.622801 -173.686924) (xy 141.659288 -173.639374) (xy 141.701668 -173.596994)
			(xy 141.749218 -173.560507) (xy 141.801124 -173.53054) (xy 141.856497 -173.507604) (xy 141.91439 -173.492091)
			(xy 141.973812 -173.484268) (xy 142.033748 -173.484268) (xy 142.09317 -173.492091) (xy 142.106698 -173.495716)
			(xy 257.519424 -173.495716) (xy 257.519424 -172.632116) (xy 257.519914 -172.602132) (xy 257.527742 -172.542676)
			(xy 257.543263 -172.484751) (xy 257.566212 -172.429347) (xy 257.596196 -172.377413) (xy 257.632702 -172.329837)
			(xy 257.675107 -172.287432) (xy 257.722683 -172.250926) (xy 257.774617 -172.220942) (xy 257.830021 -172.197993)
			(xy 257.887946 -172.182472) (xy 257.947402 -172.174644) (xy 258.00737 -172.174644) (xy 258.066826 -172.182472)
			(xy 258.124751 -172.197993) (xy 258.180155 -172.220942) (xy 258.232089 -172.250926) (xy 258.279665 -172.287432)
			(xy 258.32207 -172.329837) (xy 258.358576 -172.377413) (xy 258.38856 -172.429347) (xy 258.411509 -172.484751)
			(xy 258.42703 -172.542676) (xy 258.434858 -172.602132) (xy 258.435348 -172.632116) (xy 258.435348 -173.495716)
			(xy 258.434858 -173.5257) (xy 258.42703 -173.585156) (xy 258.411509 -173.643081) (xy 258.38856 -173.698485)
			(xy 258.358576 -173.750419) (xy 258.32207 -173.797995) (xy 258.279665 -173.8404) (xy 258.232089 -173.876906)
			(xy 258.180155 -173.90689) (xy 258.124751 -173.929839) (xy 258.066826 -173.94536) (xy 258.00737 -173.953188)
			(xy 257.947402 -173.953188) (xy 257.887946 -173.94536) (xy 257.830021 -173.929839) (xy 257.774617 -173.90689)
			(xy 257.722683 -173.876906) (xy 257.675107 -173.8404) (xy 257.632702 -173.797995) (xy 257.596196 -173.750419)
			(xy 257.566212 -173.698485) (xy 257.543263 -173.643081) (xy 257.527742 -173.585156) (xy 257.519914 -173.5257)
			(xy 257.519424 -173.495716) (xy 142.106698 -173.495716) (xy 142.151063 -173.507604) (xy 142.206436 -173.53054)
			(xy 142.258342 -173.560507) (xy 142.305892 -173.596994) (xy 142.348272 -173.639374) (xy 142.384759 -173.686924)
			(xy 142.414726 -173.73883) (xy 142.437662 -173.794203) (xy 142.453175 -173.852096) (xy 142.460998 -173.911518)
			(xy 142.461488 -173.941486) (xy 142.461488 -174.805086) (xy 142.460998 -174.835054) (xy 142.453175 -174.894476)
			(xy 142.437662 -174.952369) (xy 142.414726 -175.007742) (xy 142.384759 -175.059648) (xy 142.348272 -175.107198)
			(xy 142.305892 -175.149578) (xy 142.258342 -175.186065) (xy 142.206436 -175.216032) (xy 142.151063 -175.238968)
			(xy 142.09317 -175.254481) (xy 142.033748 -175.262304) (xy 141.973812 -175.262304) (xy 141.91439 -175.254481)
			(xy 141.856497 -175.238968) (xy 141.801124 -175.216032) (xy 141.749218 -175.186065) (xy 141.701668 -175.149578)
			(xy 141.659288 -175.107198) (xy 141.622801 -175.059648) (xy 141.592834 -175.007742) (xy 141.569898 -174.952369)
			(xy 141.554385 -174.894476) (xy 141.546562 -174.835054) (xy 141.546072 -174.805086) (xy 4.308094 -174.805086)
			(xy 4.308094 -176.837086) (xy 142.181072 -176.837086) (xy 142.181072 -175.973486) (xy 142.181562 -175.943518)
			(xy 142.189385 -175.884096) (xy 142.204898 -175.826203) (xy 142.227834 -175.77083) (xy 142.257801 -175.718924)
			(xy 142.294288 -175.671374) (xy 142.336668 -175.628994) (xy 142.384218 -175.592507) (xy 142.436124 -175.56254)
			(xy 142.491497 -175.539604) (xy 142.54939 -175.524091) (xy 142.608812 -175.516268) (xy 142.668748 -175.516268)
			(xy 142.72817 -175.524091) (xy 142.786063 -175.539604) (xy 142.841436 -175.56254) (xy 142.893342 -175.592507)
			(xy 142.940892 -175.628994) (xy 142.983272 -175.671374) (xy 143.019759 -175.718924) (xy 143.049726 -175.77083)
			(xy 143.072662 -175.826203) (xy 143.088175 -175.884096) (xy 143.095998 -175.943518) (xy 143.096488 -175.973486)
			(xy 143.096488 -176.837086) (xy 143.095998 -176.867054) (xy 143.088175 -176.926476) (xy 143.072662 -176.984369)
			(xy 143.049726 -177.039742) (xy 143.019759 -177.091648) (xy 142.983272 -177.139198) (xy 142.940892 -177.181578)
			(xy 142.893342 -177.218065) (xy 142.841436 -177.248032) (xy 142.786063 -177.270968) (xy 142.72817 -177.286481)
			(xy 142.668748 -177.294304) (xy 142.608812 -177.294304) (xy 142.54939 -177.286481) (xy 142.491497 -177.270968)
			(xy 142.436124 -177.248032) (xy 142.384218 -177.218065) (xy 142.336668 -177.181578) (xy 142.294288 -177.139198)
			(xy 142.257801 -177.091648) (xy 142.227834 -177.039742) (xy 142.204898 -176.984369) (xy 142.189385 -176.926476)
			(xy 142.181562 -176.867054) (xy 142.181072 -176.837086) (xy 4.308094 -176.837086) (xy 4.308094 -178.995324)
			(xy 123.198636 -178.995324) (xy 123.198636 -178.131724) (xy 123.199126 -178.10174) (xy 123.206954 -178.042284)
			(xy 123.222475 -177.984359) (xy 123.245424 -177.928955) (xy 123.275408 -177.877021) (xy 123.311914 -177.829445)
			(xy 123.354319 -177.78704) (xy 123.401895 -177.750534) (xy 123.453829 -177.72055) (xy 123.509233 -177.697601)
			(xy 123.567158 -177.68208) (xy 123.626614 -177.674252) (xy 123.686582 -177.674252) (xy 123.746038 -177.68208)
			(xy 123.803963 -177.697601) (xy 123.859367 -177.72055) (xy 123.911301 -177.750534) (xy 123.958877 -177.78704)
			(xy 124.001282 -177.829445) (xy 124.037788 -177.877021) (xy 124.067772 -177.928955) (xy 124.090721 -177.984359)
			(xy 124.106242 -178.042284) (xy 124.11407 -178.10174) (xy 124.11456 -178.131724) (xy 124.11456 -178.869086)
			(xy 141.546072 -178.869086) (xy 141.546072 -178.005486) (xy 141.546562 -177.975518) (xy 141.554385 -177.916096)
			(xy 141.569898 -177.858203) (xy 141.592834 -177.80283) (xy 141.622801 -177.750924) (xy 141.659288 -177.703374)
			(xy 141.701668 -177.660994) (xy 141.749218 -177.624507) (xy 141.801124 -177.59454) (xy 141.856497 -177.571604)
			(xy 141.91439 -177.556091) (xy 141.973812 -177.548268) (xy 142.033748 -177.548268) (xy 142.09317 -177.556091)
			(xy 142.151063 -177.571604) (xy 142.206436 -177.59454) (xy 142.258342 -177.624507) (xy 142.305892 -177.660994)
			(xy 142.348272 -177.703374) (xy 142.384759 -177.750924) (xy 142.414726 -177.80283) (xy 142.437662 -177.858203)
			(xy 142.453175 -177.916096) (xy 142.460998 -177.975518) (xy 142.461488 -178.005486) (xy 142.461488 -178.869086)
			(xy 142.460998 -178.899054) (xy 142.453175 -178.958476) (xy 142.437662 -179.016369) (xy 142.414726 -179.071742)
			(xy 142.384759 -179.123648) (xy 142.348272 -179.171198) (xy 142.305892 -179.213578) (xy 142.258342 -179.250065)
			(xy 142.206436 -179.280032) (xy 142.151063 -179.302968) (xy 142.09317 -179.318481) (xy 142.033748 -179.326304)
			(xy 141.973812 -179.326304) (xy 141.91439 -179.318481) (xy 141.856497 -179.302968) (xy 141.801124 -179.280032)
			(xy 141.749218 -179.250065) (xy 141.701668 -179.213578) (xy 141.659288 -179.171198) (xy 141.622801 -179.123648)
			(xy 141.592834 -179.071742) (xy 141.569898 -179.016369) (xy 141.554385 -178.958476) (xy 141.546562 -178.899054)
			(xy 141.546072 -178.869086) (xy 124.11456 -178.869086) (xy 124.11456 -178.995324) (xy 124.11407 -179.025308)
			(xy 124.106242 -179.084764) (xy 124.090721 -179.142689) (xy 124.067772 -179.198093) (xy 124.037788 -179.250027)
			(xy 124.001282 -179.297603) (xy 123.958877 -179.340008) (xy 123.911301 -179.376514) (xy 123.859367 -179.406498)
			(xy 123.803963 -179.429447) (xy 123.746038 -179.444968) (xy 123.686582 -179.452796) (xy 123.626614 -179.452796)
			(xy 123.567158 -179.444968) (xy 123.509233 -179.429447) (xy 123.453829 -179.406498) (xy 123.401895 -179.376514)
			(xy 123.354319 -179.340008) (xy 123.311914 -179.297603) (xy 123.275408 -179.250027) (xy 123.245424 -179.198093)
			(xy 123.222475 -179.142689) (xy 123.206954 -179.084764) (xy 123.199126 -179.025308) (xy 123.198636 -178.995324)
			(xy 4.308094 -178.995324) (xy 4.308094 -180.901086) (xy 142.181072 -180.901086) (xy 142.181072 -180.037486)
			(xy 142.181562 -180.007518) (xy 142.189385 -179.948096) (xy 142.204898 -179.890203) (xy 142.227834 -179.83483)
			(xy 142.257801 -179.782924) (xy 142.294288 -179.735374) (xy 142.336668 -179.692994) (xy 142.384218 -179.656507)
			(xy 142.436124 -179.62654) (xy 142.491497 -179.603604) (xy 142.54939 -179.588091) (xy 142.608812 -179.580268)
			(xy 142.668748 -179.580268) (xy 142.72817 -179.588091) (xy 142.786063 -179.603604) (xy 142.841436 -179.62654)
			(xy 142.893342 -179.656507) (xy 142.940892 -179.692994) (xy 142.983272 -179.735374) (xy 143.019759 -179.782924)
			(xy 143.049726 -179.83483) (xy 143.072662 -179.890203) (xy 143.088175 -179.948096) (xy 143.095998 -180.007518)
			(xy 143.096488 -180.037486) (xy 143.096488 -180.901086) (xy 143.095998 -180.931054) (xy 143.088175 -180.990476)
			(xy 143.072662 -181.048369) (xy 143.049726 -181.103742) (xy 143.019759 -181.155648) (xy 142.983272 -181.203198)
			(xy 142.940892 -181.245578) (xy 142.893342 -181.282065) (xy 142.841436 -181.312032) (xy 142.786063 -181.334968)
			(xy 142.72817 -181.350481) (xy 142.668748 -181.358304) (xy 142.608812 -181.358304) (xy 142.54939 -181.350481)
			(xy 142.491497 -181.334968) (xy 142.436124 -181.312032) (xy 142.384218 -181.282065) (xy 142.336668 -181.245578)
			(xy 142.294288 -181.203198) (xy 142.257801 -181.155648) (xy 142.227834 -181.103742) (xy 142.204898 -181.048369)
			(xy 142.189385 -180.990476) (xy 142.181562 -180.931054) (xy 142.181072 -180.901086) (xy 4.308094 -180.901086)
			(xy 4.308094 -182.933086) (xy 141.546072 -182.933086) (xy 141.546072 -182.069486) (xy 141.546562 -182.039518)
			(xy 141.554385 -181.980096) (xy 141.569898 -181.922203) (xy 141.592834 -181.86683) (xy 141.622801 -181.814924)
			(xy 141.659288 -181.767374) (xy 141.701668 -181.724994) (xy 141.749218 -181.688507) (xy 141.801124 -181.65854)
			(xy 141.856497 -181.635604) (xy 141.91439 -181.620091) (xy 141.973812 -181.612268) (xy 142.033748 -181.612268)
			(xy 142.09317 -181.620091) (xy 142.151063 -181.635604) (xy 142.206436 -181.65854) (xy 142.258342 -181.688507)
			(xy 142.305892 -181.724994) (xy 142.348272 -181.767374) (xy 142.384759 -181.814924) (xy 142.414726 -181.86683)
			(xy 142.437662 -181.922203) (xy 142.453175 -181.980096) (xy 142.460998 -182.039518) (xy 142.461488 -182.069486)
			(xy 142.461488 -182.933086) (xy 142.460998 -182.963054) (xy 142.453175 -183.022476) (xy 142.437662 -183.080369)
			(xy 142.414726 -183.135742) (xy 142.384759 -183.187648) (xy 142.348272 -183.235198) (xy 142.305892 -183.277578)
			(xy 142.258342 -183.314065) (xy 142.206436 -183.344032) (xy 142.151063 -183.366968) (xy 142.09317 -183.382481)
			(xy 142.033748 -183.390304) (xy 141.973812 -183.390304) (xy 141.91439 -183.382481) (xy 141.856497 -183.366968)
			(xy 141.801124 -183.344032) (xy 141.749218 -183.314065) (xy 141.701668 -183.277578) (xy 141.659288 -183.235198)
			(xy 141.622801 -183.187648) (xy 141.592834 -183.135742) (xy 141.569898 -183.080369) (xy 141.554385 -183.022476)
			(xy 141.546562 -182.963054) (xy 141.546072 -182.933086) (xy 4.308094 -182.933086) (xy 4.308094 -187.124582)
			(xy 135.58115 -187.124582) (xy 135.58115 -187.064618) (xy 135.588977 -187.005166) (xy 135.604497 -186.947244)
			(xy 135.627444 -186.891844) (xy 135.657426 -186.839912) (xy 135.69393 -186.792339) (xy 135.736331 -186.749937)
			(xy 135.783904 -186.713432) (xy 135.835835 -186.683448) (xy 135.891235 -186.6605) (xy 135.949156 -186.644979)
			(xy 136.008608 -186.637151) (xy 136.03859 -186.63666) (xy 136.90219 -186.63666) (xy 136.932178 -186.637085)
			(xy 136.99164 -186.644912) (xy 137.049571 -186.660433) (xy 137.104981 -186.683384) (xy 137.156922 -186.713371)
			(xy 137.204504 -186.749881) (xy 137.246913 -186.792289) (xy 137.283424 -186.83987) (xy 137.313412 -186.89181)
			(xy 137.336363 -186.947219) (xy 137.351886 -187.005151) (xy 137.359715 -187.064612) (xy 137.359715 -187.124588)
			(xy 137.351886 -187.184049) (xy 137.336363 -187.241981) (xy 137.313412 -187.29739) (xy 137.283424 -187.34933)
			(xy 137.246913 -187.396911) (xy 137.204504 -187.439319) (xy 137.156922 -187.475829) (xy 137.104981 -187.505816)
			(xy 137.049571 -187.528767) (xy 136.99164 -187.544288) (xy 136.932178 -187.552115) (xy 136.90219 -187.552584)
			(xy 136.03859 -187.552584) (xy 136.008608 -187.552049) (xy 135.949156 -187.544221) (xy 135.891235 -187.5287)
			(xy 135.835835 -187.505752) (xy 135.783904 -187.475768) (xy 135.736331 -187.439263) (xy 135.69393 -187.396861)
			(xy 135.657426 -187.349288) (xy 135.627444 -187.297356) (xy 135.604497 -187.241956) (xy 135.588977 -187.184034)
			(xy 135.58115 -187.124582) (xy 4.308094 -187.124582) (xy 4.308094 -188.252885) (xy 128.656818 -188.252885)
			(xy 128.656818 -188.192915) (xy 128.664646 -188.133459) (xy 128.680167 -188.075533) (xy 128.703116 -188.020128)
			(xy 128.733101 -187.968193) (xy 128.769608 -187.920615) (xy 128.812012 -187.87821) (xy 128.859589 -187.841703)
			(xy 128.911524 -187.811718) (xy 128.966929 -187.788768) (xy 129.024855 -187.773246) (xy 129.084311 -187.765418)
			(xy 129.114296 -187.764928) (xy 129.977896 -187.764928) (xy 130.007881 -187.765417) (xy 130.067339 -187.773244)
			(xy 130.125266 -187.788765) (xy 130.180671 -187.811714) (xy 130.232607 -187.841699) (xy 130.280185 -187.878207)
			(xy 130.322591 -187.920612) (xy 130.359098 -187.96819) (xy 130.389084 -188.020125) (xy 130.412034 -188.075531)
			(xy 130.427555 -188.133458) (xy 130.435383 -188.192915) (xy 130.435383 -188.252885) (xy 130.434185 -188.261981)
			(xy 131.046262 -188.261981) (xy 131.046262 -188.202019) (xy 131.054088 -188.14257) (xy 131.069607 -188.084651)
			(xy 131.092553 -188.029253) (xy 131.122533 -187.977324) (xy 131.159034 -187.929752) (xy 131.201432 -187.887351)
			(xy 131.249002 -187.850847) (xy 131.30093 -187.820864) (xy 131.356326 -187.797915) (xy 131.414244 -187.782393)
			(xy 131.473693 -187.774564) (xy 131.503674 -187.774072) (xy 132.367274 -187.774072) (xy 132.397263 -187.774472)
			(xy 132.456728 -187.782297) (xy 132.514663 -187.797818) (xy 132.570077 -187.820768) (xy 132.62202 -187.850755)
			(xy 132.669605 -187.887266) (xy 132.712017 -187.929675) (xy 132.74853 -187.977258) (xy 132.77852 -188.0292)
			(xy 132.801474 -188.084612) (xy 132.816998 -188.142546) (xy 132.824827 -188.202011) (xy 132.824827 -188.261989)
			(xy 132.816998 -188.321454) (xy 132.801474 -188.379388) (xy 132.79518 -188.394582) (xy 133.54915 -188.394582)
			(xy 133.54915 -188.334618) (xy 133.556977 -188.275166) (xy 133.572497 -188.217244) (xy 133.595444 -188.161844)
			(xy 133.625426 -188.109912) (xy 133.66193 -188.062339) (xy 133.704331 -188.019937) (xy 133.751904 -187.983432)
			(xy 133.803835 -187.953448) (xy 133.859235 -187.9305) (xy 133.917156 -187.914979) (xy 133.976608 -187.907151)
			(xy 134.00659 -187.90666) (xy 134.87019 -187.90666) (xy 134.900178 -187.907085) (xy 134.95964 -187.914912)
			(xy 135.017571 -187.930433) (xy 135.072981 -187.953384) (xy 135.124922 -187.983371) (xy 135.172504 -188.019881)
			(xy 135.214913 -188.062289) (xy 135.251424 -188.10987) (xy 135.281412 -188.16181) (xy 135.304363 -188.217219)
			(xy 135.319886 -188.275151) (xy 135.327715 -188.334612) (xy 135.327715 -188.394588) (xy 135.319886 -188.454049)
			(xy 135.304363 -188.511981) (xy 135.281412 -188.56739) (xy 135.251424 -188.61933) (xy 135.214913 -188.666911)
			(xy 135.172504 -188.709319) (xy 135.124922 -188.745829) (xy 135.072981 -188.775816) (xy 135.017571 -188.798767)
			(xy 134.95964 -188.814288) (xy 134.900178 -188.822115) (xy 134.87019 -188.822584) (xy 134.00659 -188.822584)
			(xy 133.976608 -188.822049) (xy 133.917156 -188.814221) (xy 133.859235 -188.7987) (xy 133.803835 -188.775752)
			(xy 133.751904 -188.745768) (xy 133.704331 -188.709263) (xy 133.66193 -188.666861) (xy 133.625426 -188.619288)
			(xy 133.595444 -188.567356) (xy 133.572497 -188.511956) (xy 133.556977 -188.454034) (xy 133.54915 -188.394582)
			(xy 132.79518 -188.394582) (xy 132.77852 -188.4348) (xy 132.74853 -188.486742) (xy 132.712017 -188.534325)
			(xy 132.669605 -188.576734) (xy 132.62202 -188.613245) (xy 132.570077 -188.643232) (xy 132.514663 -188.666182)
			(xy 132.456728 -188.681703) (xy 132.397263 -188.689528) (xy 132.367274 -188.689996) (xy 131.503674 -188.689996)
			(xy 131.473693 -188.689436) (xy 131.414244 -188.681607) (xy 131.356326 -188.666085) (xy 131.30093 -188.643136)
			(xy 131.249002 -188.613153) (xy 131.201432 -188.576649) (xy 131.159034 -188.534248) (xy 131.122533 -188.486676)
			(xy 131.092553 -188.434747) (xy 131.069607 -188.379349) (xy 131.054088 -188.32143) (xy 131.046262 -188.261981)
			(xy 130.434185 -188.261981) (xy 130.427555 -188.312342) (xy 130.412034 -188.370269) (xy 130.389084 -188.425675)
			(xy 130.359098 -188.47761) (xy 130.322591 -188.525188) (xy 130.280185 -188.567593) (xy 130.232607 -188.604101)
			(xy 130.180671 -188.634086) (xy 130.125266 -188.657035) (xy 130.067339 -188.672556) (xy 130.007881 -188.680383)
			(xy 129.977896 -188.680852) (xy 129.114296 -188.680852) (xy 129.084311 -188.680382) (xy 129.024855 -188.672554)
			(xy 128.966929 -188.657032) (xy 128.911524 -188.634082) (xy 128.859589 -188.604097) (xy 128.812012 -188.56759)
			(xy 128.769608 -188.525185) (xy 128.733101 -188.477607) (xy 128.703116 -188.425672) (xy 128.680167 -188.370267)
			(xy 128.664646 -188.312341) (xy 128.656818 -188.252885) (xy 4.308094 -188.252885) (xy 4.308094 -195.726088)
			(xy 126.922185 -195.726088) (xy 126.922185 -195.666112) (xy 126.930014 -195.606648) (xy 126.945538 -195.548715)
			(xy 126.968491 -195.493304) (xy 126.99848 -195.441364) (xy 127.034993 -195.393782) (xy 127.077404 -195.351373)
			(xy 127.124989 -195.314864) (xy 127.176931 -195.284878) (xy 127.232344 -195.261928) (xy 127.290278 -195.246408)
			(xy 127.349742 -195.238583) (xy 127.37973 -195.238116) (xy 128.24333 -195.238116) (xy 128.273312 -195.238652)
			(xy 128.332761 -195.246482) (xy 128.39068 -195.262005) (xy 128.446078 -195.284955) (xy 128.498007 -195.314939)
			(xy 128.545577 -195.351444) (xy 128.587976 -195.393845) (xy 128.624478 -195.441418) (xy 128.654459 -195.493349)
			(xy 128.677405 -195.548748) (xy 128.692924 -195.606668) (xy 128.70075 -195.666118) (xy 128.70075 -195.726082)
			(xy 128.692924 -195.785532) (xy 128.677405 -195.843452) (xy 128.654459 -195.898851) (xy 128.624478 -195.950782)
			(xy 128.587976 -195.998355) (xy 128.545577 -196.040756) (xy 128.498007 -196.077261) (xy 128.446078 -196.107245)
			(xy 128.39068 -196.130195) (xy 128.332761 -196.145718) (xy 128.273312 -196.153548) (xy 128.24333 -196.15404)
			(xy 127.37973 -196.15404) (xy 127.349742 -196.153617) (xy 127.290278 -196.145792) (xy 127.232344 -196.130272)
			(xy 127.176931 -196.107322) (xy 127.124989 -196.077336) (xy 127.077404 -196.040827) (xy 127.034993 -195.998418)
			(xy 126.99848 -195.950836) (xy 126.968491 -195.898896) (xy 126.945538 -195.843485) (xy 126.930014 -195.785552)
			(xy 126.922185 -195.726088) (xy 4.308094 -195.726088) (xy 4.308094 -198.543743) (xy 138.243774 -198.543743)
			(xy 138.24519 -198.489257) (xy 138.254343 -198.435528) (xy 138.271047 -198.383647) (xy 138.294963 -198.33467)
			(xy 138.325603 -198.289594) (xy 138.362344 -198.249336) (xy 138.40444 -198.214715) (xy 138.451033 -198.186434)
			(xy 138.501175 -198.165071) (xy 138.553847 -198.151058) (xy 138.607977 -198.144682) (xy 138.635232 -198.144892)
			(xy 138.636502 -198.144892) (xy 139.488672 -198.144892) (xy 139.515926 -198.145353) (xy 139.56988 -198.153107)
			(xy 139.622181 -198.168461) (xy 139.671765 -198.191102) (xy 139.717622 -198.220569) (xy 139.758818 -198.256263)
			(xy 139.794514 -198.297456) (xy 139.823985 -198.34331) (xy 139.846629 -198.392892) (xy 139.861987 -198.445192)
			(xy 139.869745 -198.499146) (xy 139.869745 -198.553654) (xy 139.861987 -198.607608) (xy 139.846629 -198.659908)
			(xy 139.823985 -198.70949) (xy 139.794514 -198.755344) (xy 139.758818 -198.796537) (xy 139.717622 -198.832231)
			(xy 139.671765 -198.861698) (xy 139.622181 -198.884339) (xy 139.56988 -198.899693) (xy 139.515926 -198.907447)
			(xy 139.488672 -198.907908) (xy 139.477343 -198.907862) (xy 139.454723 -198.90659) (xy 139.44346 -198.905368)
			(xy 139.440412 -198.90486) (xy 138.672824 -198.90486) (xy 138.669776 -198.905368) (xy 138.642662 -198.908134)
			(xy 138.588177 -198.906693) (xy 138.534452 -198.897514) (xy 138.482579 -198.880785) (xy 138.433613 -198.856847)
			(xy 138.388552 -198.826185) (xy 138.348311 -198.789424) (xy 138.31371 -198.747312) (xy 138.285452 -198.700706)
			(xy 138.264112 -198.650554) (xy 138.250125 -198.597875) (xy 138.243774 -198.543743) (xy 4.308094 -198.543743)
			(xy 4.308094 -201.379368) (xy 98.428551 -201.379368) (xy 98.428551 -201.324832) (xy 98.436313 -201.270851)
			(xy 98.451678 -201.218525) (xy 98.474333 -201.168917) (xy 98.503818 -201.123039) (xy 98.539531 -201.081824)
			(xy 98.580747 -201.046112) (xy 98.626626 -201.016628) (xy 98.676234 -200.993974) (xy 98.728561 -200.978611)
			(xy 98.782542 -200.970851) (xy 98.80981 -200.970388) (xy 99.67341 -200.970388) (xy 99.700682 -200.970775)
			(xy 99.754672 -200.978539) (xy 99.807007 -200.993907) (xy 99.856623 -201.016567) (xy 99.902508 -201.046057)
			(xy 99.94373 -201.081777) (xy 99.979449 -201.123) (xy 100.008938 -201.168886) (xy 100.031596 -201.218502)
			(xy 100.046963 -201.270838) (xy 100.054725 -201.324828) (xy 100.054725 -201.379372) (xy 100.046963 -201.433362)
			(xy 100.031596 -201.485698) (xy 100.008938 -201.535314) (xy 99.979449 -201.5812) (xy 99.94373 -201.622423)
			(xy 99.902508 -201.658143) (xy 99.856623 -201.687633) (xy 99.807007 -201.710293) (xy 99.754672 -201.725661)
			(xy 99.700682 -201.733425) (xy 99.67341 -201.733912) (xy 98.80981 -201.733912) (xy 98.782542 -201.733349)
			(xy 98.728561 -201.725589) (xy 98.676234 -201.710226) (xy 98.626626 -201.687572) (xy 98.580747 -201.658088)
			(xy 98.539531 -201.622376) (xy 98.503818 -201.581161) (xy 98.474333 -201.535283) (xy 98.451678 -201.485675)
			(xy 98.436313 -201.433349) (xy 98.428551 -201.379368) (xy 4.308094 -201.379368) (xy 4.308094 -209.380836)
			(xy 445.288416 -209.380836) (xy 445.288416 -208.517236) (xy 445.288906 -208.487268) (xy 445.296729 -208.427846)
			(xy 445.312242 -208.369953) (xy 445.335178 -208.31458) (xy 445.365145 -208.262674) (xy 445.401632 -208.215124)
			(xy 445.444012 -208.172744) (xy 445.491562 -208.136257) (xy 445.543468 -208.10629) (xy 445.598841 -208.083354)
			(xy 445.656734 -208.067841) (xy 445.716156 -208.060018) (xy 445.776092 -208.060018) (xy 445.835514 -208.067841)
			(xy 445.893407 -208.083354) (xy 445.94878 -208.10629) (xy 446.000686 -208.136257) (xy 446.048236 -208.172744)
			(xy 446.090616 -208.215124) (xy 446.127103 -208.262674) (xy 446.15707 -208.31458) (xy 446.180006 -208.369953)
			(xy 446.195519 -208.427846) (xy 446.203342 -208.487268) (xy 446.203832 -208.517236) (xy 446.203832 -209.380836)
			(xy 446.203342 -209.410804) (xy 446.195519 -209.470226) (xy 446.180006 -209.528119) (xy 446.15707 -209.583492)
			(xy 446.127103 -209.635398) (xy 446.090616 -209.682948) (xy 446.048236 -209.725328) (xy 446.000686 -209.761815)
			(xy 445.94878 -209.791782) (xy 445.893407 -209.814718) (xy 445.835514 -209.830231) (xy 445.776092 -209.838054)
			(xy 445.716156 -209.838054) (xy 445.656734 -209.830231) (xy 445.598841 -209.814718) (xy 445.543468 -209.791782)
			(xy 445.491562 -209.761815) (xy 445.444012 -209.725328) (xy 445.401632 -209.682948) (xy 445.365145 -209.635398)
			(xy 445.335178 -209.583492) (xy 445.312242 -209.528119) (xy 445.296729 -209.470226) (xy 445.288906 -209.410804)
			(xy 445.288416 -209.380836) (xy 4.308094 -209.380836) (xy 4.308094 -225.261473) (xy 239.822113 -225.261473)
			(xy 239.822113 -225.201527) (xy 239.829938 -225.142093) (xy 239.845454 -225.084189) (xy 239.868395 -225.028806)
			(xy 239.89837 -224.976891) (xy 239.934864 -224.929333) (xy 239.977254 -224.886945) (xy 240.024814 -224.850454)
			(xy 240.076731 -224.820483) (xy 240.132115 -224.797545) (xy 240.19002 -224.782032) (xy 240.249455 -224.774211)
			(xy 240.279428 -224.773744) (xy 241.143028 -224.773744) (xy 241.172991 -224.774332) (xy 241.232405 -224.782157)
			(xy 241.290289 -224.79767) (xy 241.345653 -224.820606) (xy 241.39755 -224.850571) (xy 241.445091 -224.887054)
			(xy 241.487465 -224.92943) (xy 241.523944 -224.976974) (xy 241.553907 -225.028872) (xy 241.576839 -225.084238)
			(xy 241.592348 -225.142123) (xy 241.60017 -225.201537) (xy 241.60017 -225.261463) (xy 241.592348 -225.320877)
			(xy 241.576839 -225.378762) (xy 241.553907 -225.434128) (xy 241.523944 -225.486026) (xy 241.487465 -225.53357)
			(xy 241.445091 -225.575946) (xy 241.39755 -225.612429) (xy 241.345653 -225.642394) (xy 241.290289 -225.66533)
			(xy 241.232405 -225.680843) (xy 241.172991 -225.688668) (xy 241.143028 -225.68916) (xy 240.279428 -225.68916)
			(xy 240.249455 -225.688789) (xy 240.19002 -225.680968) (xy 240.132115 -225.665455) (xy 240.076731 -225.642517)
			(xy 240.024814 -225.612546) (xy 239.977254 -225.576055) (xy 239.934864 -225.533667) (xy 239.89837 -225.486109)
			(xy 239.868395 -225.434194) (xy 239.845454 -225.378811) (xy 239.829938 -225.320907) (xy 239.822113 -225.261473)
			(xy 4.308094 -225.261473) (xy 4.308094 -230.903589) (xy 383.216061 -230.903589) (xy 383.216061 -230.843611)
			(xy 383.22389 -230.784147) (xy 383.239413 -230.726213) (xy 383.262366 -230.670801) (xy 383.292355 -230.618858)
			(xy 383.328867 -230.571275) (xy 383.371278 -230.528865) (xy 383.418862 -230.492353) (xy 383.470804 -230.462364)
			(xy 383.526216 -230.439412) (xy 383.584151 -230.423889) (xy 383.643615 -230.416061) (xy 383.673604 -230.415592)
			(xy 384.537204 -230.415592) (xy 384.567185 -230.416174) (xy 384.626634 -230.424001) (xy 384.684553 -230.439521)
			(xy 384.739951 -230.462468) (xy 384.79188 -230.492449) (xy 384.839451 -230.528952) (xy 384.88185 -230.571352)
			(xy 384.918353 -230.618924) (xy 384.948334 -230.670853) (xy 384.97128 -230.726251) (xy 384.986799 -230.78417)
			(xy 384.994626 -230.843619) (xy 384.994626 -230.903581) (xy 384.986799 -230.96303) (xy 384.97128 -231.020949)
			(xy 384.948334 -231.076347) (xy 384.918353 -231.128276) (xy 384.88185 -231.175848) (xy 384.839451 -231.218248)
			(xy 384.79188 -231.254751) (xy 384.739951 -231.284732) (xy 384.684553 -231.307679) (xy 384.626634 -231.323199)
			(xy 384.567185 -231.331026) (xy 384.537204 -231.331516) (xy 383.673604 -231.331516) (xy 383.643615 -231.331139)
			(xy 383.584151 -231.323311) (xy 383.526216 -231.307788) (xy 383.470804 -231.284836) (xy 383.418862 -231.254847)
			(xy 383.371278 -231.218335) (xy 383.328867 -231.175925) (xy 383.292355 -231.128342) (xy 383.262366 -231.076399)
			(xy 383.239413 -231.020987) (xy 383.22389 -230.963053) (xy 383.216061 -230.903589) (xy 4.308094 -230.903589)
			(xy 4.308094 -234.655869) (xy 448.021157 -234.655869) (xy 448.021157 -234.595931) (xy 448.028981 -234.536505)
			(xy 448.044494 -234.478608) (xy 448.067432 -234.423232) (xy 448.097401 -234.371324) (xy 448.13389 -234.323771)
			(xy 448.176273 -234.281388) (xy 448.223825 -234.2449) (xy 448.275734 -234.214931) (xy 448.33111 -234.191993)
			(xy 448.389007 -234.17648) (xy 448.448433 -234.168657) (xy 448.478402 -234.168188) (xy 449.342002 -234.168188)
			(xy 449.371969 -234.168686) (xy 449.431391 -234.176509) (xy 449.489283 -234.192022) (xy 449.544656 -234.214958)
			(xy 449.596561 -234.244925) (xy 449.64411 -234.281411) (xy 449.68649 -234.323792) (xy 449.722976 -234.371341)
			(xy 449.752943 -234.423246) (xy 449.775879 -234.478618) (xy 449.791391 -234.536511) (xy 449.799214 -234.595933)
			(xy 449.799214 -234.655867) (xy 449.791391 -234.715289) (xy 449.775879 -234.773182) (xy 449.752943 -234.828554)
			(xy 449.722976 -234.880459) (xy 449.68649 -234.928008) (xy 449.64411 -234.970389) (xy 449.596561 -235.006875)
			(xy 449.544656 -235.036842) (xy 449.489283 -235.059778) (xy 449.431391 -235.075291) (xy 449.371969 -235.083114)
			(xy 449.342002 -235.083604) (xy 448.478402 -235.083604) (xy 448.448433 -235.083143) (xy 448.389007 -235.07532)
			(xy 448.33111 -235.059807) (xy 448.275734 -235.036869) (xy 448.223825 -235.0069) (xy 448.176273 -234.970412)
			(xy 448.13389 -234.928029) (xy 448.097401 -234.880476) (xy 448.067432 -234.828568) (xy 448.044494 -234.773192)
			(xy 448.028981 -234.715295) (xy 448.021157 -234.655869) (xy 4.308094 -234.655869) (xy 4.308094 -239.07907)
			(xy 153.398934 -239.07907) (xy 153.398934 -239.01913) (xy 153.406758 -238.959703) (xy 153.422271 -238.901805)
			(xy 153.445208 -238.846427) (xy 153.475178 -238.794517) (xy 153.511666 -238.746963) (xy 153.554049 -238.704578)
			(xy 153.601602 -238.668088) (xy 153.653511 -238.638116) (xy 153.708888 -238.615177) (xy 153.766785 -238.599661)
			(xy 153.826212 -238.591835) (xy 153.856182 -238.591344) (xy 154.719782 -238.591344) (xy 154.749749 -238.591908)
			(xy 154.809169 -238.599729) (xy 154.867061 -238.615239) (xy 154.922433 -238.638172) (xy 154.974337 -238.668138)
			(xy 155.021886 -238.704622) (xy 155.064267 -238.747) (xy 155.100752 -238.794548) (xy 155.13072 -238.846451)
			(xy 155.153656 -238.901822) (xy 155.169168 -238.959713) (xy 155.176991 -239.019133) (xy 155.176991 -239.079067)
			(xy 155.169168 -239.138487) (xy 155.153656 -239.196378) (xy 155.13072 -239.251749) (xy 155.100752 -239.303652)
			(xy 155.064267 -239.3512) (xy 155.021886 -239.393578) (xy 154.974337 -239.430062) (xy 154.922433 -239.460028)
			(xy 154.867061 -239.482961) (xy 154.809169 -239.498471) (xy 154.749749 -239.506292) (xy 154.719782 -239.50676)
			(xy 153.856182 -239.50676) (xy 153.826212 -239.506365) (xy 153.766785 -239.498539) (xy 153.708888 -239.483023)
			(xy 153.653511 -239.460084) (xy 153.601602 -239.430112) (xy 153.554049 -239.393622) (xy 153.511666 -239.351237)
			(xy 153.475178 -239.303683) (xy 153.445208 -239.251773) (xy 153.422271 -239.196395) (xy 153.406758 -239.138497)
			(xy 153.398934 -239.07907) (xy 4.308094 -239.07907) (xy 4.308094 -241.031522) (xy 4.307605 -241.10188)
			(xy 4.299704 -241.242374) (xy 4.283937 -241.382205) (xy 4.260354 -241.52093) (xy 4.229028 -241.658116)
			(xy 4.190059 -241.793328) (xy 4.143568 -241.926143) (xy 4.089703 -242.056141) (xy 4.028633 -242.182915)
			(xy 3.960549 -242.306064) (xy 3.885667 -242.425201) (xy 3.804222 -242.539952) (xy 3.71647 -242.649955)
			(xy 3.622687 -242.754863) (xy 3.573272 -242.80495) (xy 0.94488 -245.433342) (xy 0.907568 -245.471336)
			(xy 0.837834 -245.55183) (xy 0.774017 -245.637091) (xy 0.716442 -245.726686) (xy 0.665403 -245.820159)
			(xy 0.62116 -245.917033) (xy 0.583936 -246.016815) (xy 0.553923 -246.118998) (xy 0.531273 -246.223061)
			(xy 0.5161 -246.328474) (xy 0.508483 -246.4347) (xy 0.508 -246.48795) (xy 0.508 -270.89989) (xy 26.882353 -270.89989)
			(xy 26.886342 -270.75135) (xy 26.898299 -270.603237) (xy 26.918189 -270.45598) (xy 26.945954 -270.310004)
			(xy 26.981515 -270.165727) (xy 27.024769 -270.023568) (xy 27.075591 -269.883935) (xy 27.133835 -269.747232)
			(xy 27.199333 -269.613852) (xy 27.271896 -269.48418) (xy 27.351314 -269.35859) (xy 27.437359 -269.237443)
			(xy 27.529783 -269.12109) (xy 27.628319 -269.009866) (xy 27.732683 -268.904091) (xy 27.842575 -268.804071)
			(xy 27.957676 -268.710093) (xy 28.077656 -268.622429) (xy 28.202169 -268.541332) (xy 28.330855 -268.467035)
			(xy 28.463344 -268.399753) (xy 28.599253 -268.339679) (xy 28.738191 -268.286987) (xy 28.879757 -268.241828)
			(xy 29.023543 -268.204333) (xy 29.169134 -268.174611) (xy 29.31611 -268.152746) (xy 29.464049 -268.138802)
			(xy 29.612522 -268.132818) (xy 29.761103 -268.134813) (xy 29.909362 -268.144781) (xy 30.056873 -268.162692)
			(xy 30.203209 -268.188495) (xy 30.34795 -268.222115) (xy 30.490677 -268.263457) (xy 30.63098 -268.3124)
			(xy 30.768453 -268.368803) (xy 30.9027 -268.432504) (xy 31.033335 -268.50332) (xy 31.15998 -268.581045)
			(xy 31.28227 -268.665456) (xy 31.399853 -268.756309) (xy 31.51239 -268.853343) (xy 31.619557 -268.956278)
			(xy 31.721044 -269.064817) (xy 31.816558 -269.178646) (xy 31.905825 -269.297439) (xy 31.988586 -269.420851)
			(xy 32.064604 -269.548529) (xy 32.133659 -269.680102) (xy 32.195552 -269.815193) (xy 32.250105 -269.95341)
			(xy 32.29716 -270.094357) (xy 32.336582 -270.237627) (xy 32.368256 -270.382806) (xy 32.392092 -270.529475)
			(xy 32.408021 -270.677213) (xy 32.415997 -270.825593) (xy 32.416496 -270.89989) (xy 86.882487 -270.89989)
			(xy 86.886476 -270.75135) (xy 86.898433 -270.603237) (xy 86.918323 -270.45598) (xy 86.946088 -270.310004)
			(xy 86.981649 -270.165727) (xy 87.024903 -270.023568) (xy 87.075725 -269.883935) (xy 87.133969 -269.747232)
			(xy 87.199467 -269.613852) (xy 87.27203 -269.48418) (xy 87.351448 -269.35859) (xy 87.437493 -269.237443)
			(xy 87.529917 -269.12109) (xy 87.628453 -269.009866) (xy 87.732817 -268.904091) (xy 87.842709 -268.804071)
			(xy 87.95781 -268.710093) (xy 88.07779 -268.622429) (xy 88.202303 -268.541332) (xy 88.330989 -268.467035)
			(xy 88.463478 -268.399753) (xy 88.599387 -268.339679) (xy 88.738325 -268.286987) (xy 88.879891 -268.241828)
			(xy 89.023677 -268.204333) (xy 89.169268 -268.174611) (xy 89.316244 -268.152746) (xy 89.464183 -268.138802)
			(xy 89.612656 -268.132818) (xy 89.761237 -268.134813) (xy 89.909496 -268.144781) (xy 90.057007 -268.162692)
			(xy 90.203343 -268.188495) (xy 90.348084 -268.222115) (xy 90.490811 -268.263457) (xy 90.631114 -268.3124)
			(xy 90.768587 -268.368803) (xy 90.902834 -268.432504) (xy 91.033469 -268.50332) (xy 91.160114 -268.581045)
			(xy 91.282404 -268.665456) (xy 91.399987 -268.756309) (xy 91.512524 -268.853343) (xy 91.619691 -268.956278)
			(xy 91.721178 -269.064817) (xy 91.816692 -269.178646) (xy 91.905959 -269.297439) (xy 91.98872 -269.420851)
			(xy 92.064738 -269.548529) (xy 92.133793 -269.680102) (xy 92.195686 -269.815193) (xy 92.250239 -269.95341)
			(xy 92.297294 -270.094357) (xy 92.336716 -270.237627) (xy 92.36839 -270.382806) (xy 92.392226 -270.529475)
			(xy 92.408155 -270.677213) (xy 92.416131 -270.825593) (xy 92.41663 -270.89989) (xy 142.982451 -270.89989)
			(xy 142.98644 -270.75135) (xy 142.998397 -270.603237) (xy 143.018287 -270.45598) (xy 143.046052 -270.310004)
			(xy 143.081613 -270.165727) (xy 143.124867 -270.023568) (xy 143.175689 -269.883935) (xy 143.233933 -269.747232)
			(xy 143.299431 -269.613852) (xy 143.371994 -269.48418) (xy 143.451412 -269.35859) (xy 143.537457 -269.237443)
			(xy 143.629881 -269.12109) (xy 143.728417 -269.009866) (xy 143.832781 -268.904091) (xy 143.942673 -268.804071)
			(xy 144.057774 -268.710093) (xy 144.177754 -268.622429) (xy 144.302267 -268.541332) (xy 144.430953 -268.467035)
			(xy 144.563442 -268.399753) (xy 144.699351 -268.339679) (xy 144.838289 -268.286987) (xy 144.979855 -268.241828)
			(xy 145.123641 -268.204333) (xy 145.269232 -268.174611) (xy 145.416208 -268.152746) (xy 145.564147 -268.138802)
			(xy 145.71262 -268.132818) (xy 145.861201 -268.134813) (xy 146.00946 -268.144781) (xy 146.156971 -268.162692)
			(xy 146.303307 -268.188495) (xy 146.448048 -268.222115) (xy 146.590775 -268.263457) (xy 146.731078 -268.3124)
			(xy 146.868551 -268.368803) (xy 147.002798 -268.432504) (xy 147.133433 -268.50332) (xy 147.260078 -268.581045)
			(xy 147.382368 -268.665456) (xy 147.499951 -268.756309) (xy 147.612488 -268.853343) (xy 147.719655 -268.956278)
			(xy 147.821142 -269.064817) (xy 147.916656 -269.178646) (xy 148.005923 -269.297439) (xy 148.088684 -269.420851)
			(xy 148.164702 -269.548529) (xy 148.233757 -269.680102) (xy 148.29565 -269.815193) (xy 148.350203 -269.95341)
			(xy 148.397258 -270.094357) (xy 148.43668 -270.237627) (xy 148.468354 -270.382806) (xy 148.49219 -270.529475)
			(xy 148.508119 -270.677213) (xy 148.516095 -270.825593) (xy 148.516594 -270.89989) (xy 202.982331 -270.89989)
			(xy 202.98632 -270.75135) (xy 202.998277 -270.603237) (xy 203.018167 -270.45598) (xy 203.045932 -270.310004)
			(xy 203.081493 -270.165727) (xy 203.124747 -270.023568) (xy 203.175569 -269.883935) (xy 203.233813 -269.747232)
			(xy 203.299311 -269.613852) (xy 203.371874 -269.48418) (xy 203.451292 -269.35859) (xy 203.537337 -269.237443)
			(xy 203.629761 -269.12109) (xy 203.728297 -269.009866) (xy 203.832661 -268.904091) (xy 203.942553 -268.804071)
			(xy 204.057654 -268.710093) (xy 204.177634 -268.622429) (xy 204.302147 -268.541332) (xy 204.430833 -268.467035)
			(xy 204.563322 -268.399753) (xy 204.699231 -268.339679) (xy 204.838169 -268.286987) (xy 204.979735 -268.241828)
			(xy 205.123521 -268.204333) (xy 205.269112 -268.174611) (xy 205.416088 -268.152746) (xy 205.564027 -268.138802)
			(xy 205.7125 -268.132818) (xy 205.861081 -268.134813) (xy 206.00934 -268.144781) (xy 206.156851 -268.162692)
			(xy 206.303187 -268.188495) (xy 206.447928 -268.222115) (xy 206.590655 -268.263457) (xy 206.730958 -268.3124)
			(xy 206.868431 -268.368803) (xy 207.002678 -268.432504) (xy 207.133313 -268.50332) (xy 207.259958 -268.581045)
			(xy 207.382248 -268.665456) (xy 207.499831 -268.756309) (xy 207.612368 -268.853343) (xy 207.719535 -268.956278)
			(xy 207.821022 -269.064817) (xy 207.916536 -269.178646) (xy 208.005803 -269.297439) (xy 208.088564 -269.420851)
			(xy 208.164582 -269.548529) (xy 208.233637 -269.680102) (xy 208.29553 -269.815193) (xy 208.350083 -269.95341)
			(xy 208.397138 -270.094357) (xy 208.43656 -270.237627) (xy 208.468234 -270.382806) (xy 208.49207 -270.529475)
			(xy 208.507999 -270.677213) (xy 208.515975 -270.825593) (xy 208.516474 -270.89989) (xy 259.082549 -270.89989)
			(xy 259.086538 -270.75135) (xy 259.098495 -270.603237) (xy 259.118385 -270.45598) (xy 259.14615 -270.310004)
			(xy 259.181711 -270.165727) (xy 259.224965 -270.023568) (xy 259.275787 -269.883935) (xy 259.334031 -269.747232)
			(xy 259.399529 -269.613852) (xy 259.472092 -269.48418) (xy 259.55151 -269.35859) (xy 259.637555 -269.237443)
			(xy 259.729979 -269.12109) (xy 259.828515 -269.009866) (xy 259.932879 -268.904091) (xy 260.042771 -268.804071)
			(xy 260.157872 -268.710093) (xy 260.277852 -268.622429) (xy 260.402365 -268.541332) (xy 260.531051 -268.467035)
			(xy 260.66354 -268.399753) (xy 260.799449 -268.339679) (xy 260.938387 -268.286987) (xy 261.079953 -268.241828)
			(xy 261.223739 -268.204333) (xy 261.36933 -268.174611) (xy 261.516306 -268.152746) (xy 261.664245 -268.138802)
			(xy 261.812718 -268.132818) (xy 261.961299 -268.134813) (xy 262.109558 -268.144781) (xy 262.257069 -268.162692)
			(xy 262.403405 -268.188495) (xy 262.548146 -268.222115) (xy 262.690873 -268.263457) (xy 262.831176 -268.3124)
			(xy 262.968649 -268.368803) (xy 263.102896 -268.432504) (xy 263.233531 -268.50332) (xy 263.360176 -268.581045)
			(xy 263.482466 -268.665456) (xy 263.600049 -268.756309) (xy 263.712586 -268.853343) (xy 263.819753 -268.956278)
			(xy 263.92124 -269.064817) (xy 264.016754 -269.178646) (xy 264.106021 -269.297439) (xy 264.188782 -269.420851)
			(xy 264.2648 -269.548529) (xy 264.333855 -269.680102) (xy 264.395748 -269.815193) (xy 264.450301 -269.95341)
			(xy 264.497356 -270.094357) (xy 264.536778 -270.237627) (xy 264.568452 -270.382806) (xy 264.592288 -270.529475)
			(xy 264.608217 -270.677213) (xy 264.616193 -270.825593) (xy 264.616692 -270.89989) (xy 319.082429 -270.89989)
			(xy 319.086418 -270.75135) (xy 319.098375 -270.603237) (xy 319.118265 -270.45598) (xy 319.14603 -270.310004)
			(xy 319.181591 -270.165727) (xy 319.224845 -270.023568) (xy 319.275667 -269.883935) (xy 319.333911 -269.747232)
			(xy 319.399409 -269.613852) (xy 319.471972 -269.48418) (xy 319.55139 -269.35859) (xy 319.637435 -269.237443)
			(xy 319.729859 -269.12109) (xy 319.828395 -269.009866) (xy 319.932759 -268.904091) (xy 320.042651 -268.804071)
			(xy 320.157752 -268.710093) (xy 320.277732 -268.622429) (xy 320.402245 -268.541332) (xy 320.530931 -268.467035)
			(xy 320.66342 -268.399753) (xy 320.799329 -268.339679) (xy 320.938267 -268.286987) (xy 321.079833 -268.241828)
			(xy 321.223619 -268.204333) (xy 321.36921 -268.174611) (xy 321.516186 -268.152746) (xy 321.664125 -268.138802)
			(xy 321.812598 -268.132818) (xy 321.961179 -268.134813) (xy 322.109438 -268.144781) (xy 322.256949 -268.162692)
			(xy 322.403285 -268.188495) (xy 322.548026 -268.222115) (xy 322.690753 -268.263457) (xy 322.831056 -268.3124)
			(xy 322.968529 -268.368803) (xy 323.102776 -268.432504) (xy 323.233411 -268.50332) (xy 323.360056 -268.581045)
			(xy 323.482346 -268.665456) (xy 323.599929 -268.756309) (xy 323.712466 -268.853343) (xy 323.819633 -268.956278)
			(xy 323.92112 -269.064817) (xy 324.016634 -269.178646) (xy 324.105901 -269.297439) (xy 324.188662 -269.420851)
			(xy 324.26468 -269.548529) (xy 324.333735 -269.680102) (xy 324.395628 -269.815193) (xy 324.450181 -269.95341)
			(xy 324.497236 -270.094357) (xy 324.536658 -270.237627) (xy 324.568332 -270.382806) (xy 324.592168 -270.529475)
			(xy 324.608097 -270.677213) (xy 324.616073 -270.825593) (xy 324.616572 -270.89989) (xy 375.182393 -270.89989)
			(xy 375.186382 -270.75135) (xy 375.198339 -270.603237) (xy 375.218229 -270.45598) (xy 375.245994 -270.310004)
			(xy 375.281555 -270.165727) (xy 375.324809 -270.023568) (xy 375.375631 -269.883935) (xy 375.433875 -269.747232)
			(xy 375.499373 -269.613852) (xy 375.571936 -269.48418) (xy 375.651354 -269.35859) (xy 375.737399 -269.237443)
			(xy 375.829823 -269.12109) (xy 375.928359 -269.009866) (xy 376.032723 -268.904091) (xy 376.142615 -268.804071)
			(xy 376.257716 -268.710093) (xy 376.377696 -268.622429) (xy 376.502209 -268.541332) (xy 376.630895 -268.467035)
			(xy 376.763384 -268.399753) (xy 376.899293 -268.339679) (xy 377.038231 -268.286987) (xy 377.179797 -268.241828)
			(xy 377.323583 -268.204333) (xy 377.469174 -268.174611) (xy 377.61615 -268.152746) (xy 377.764089 -268.138802)
			(xy 377.912562 -268.132818) (xy 378.061143 -268.134813) (xy 378.209402 -268.144781) (xy 378.356913 -268.162692)
			(xy 378.503249 -268.188495) (xy 378.64799 -268.222115) (xy 378.790717 -268.263457) (xy 378.93102 -268.3124)
			(xy 379.068493 -268.368803) (xy 379.20274 -268.432504) (xy 379.333375 -268.50332) (xy 379.46002 -268.581045)
			(xy 379.58231 -268.665456) (xy 379.699893 -268.756309) (xy 379.81243 -268.853343) (xy 379.919597 -268.956278)
			(xy 380.021084 -269.064817) (xy 380.116598 -269.178646) (xy 380.205865 -269.297439) (xy 380.288626 -269.420851)
			(xy 380.364644 -269.548529) (xy 380.433699 -269.680102) (xy 380.495592 -269.815193) (xy 380.550145 -269.95341)
			(xy 380.5972 -270.094357) (xy 380.636622 -270.237627) (xy 380.668296 -270.382806) (xy 380.692132 -270.529475)
			(xy 380.708061 -270.677213) (xy 380.716037 -270.825593) (xy 380.716536 -270.89989) (xy 435.182527 -270.89989)
			(xy 435.186516 -270.75135) (xy 435.198473 -270.603237) (xy 435.218363 -270.45598) (xy 435.246128 -270.310004)
			(xy 435.281689 -270.165727) (xy 435.324943 -270.023568) (xy 435.375765 -269.883935) (xy 435.434009 -269.747232)
			(xy 435.499507 -269.613852) (xy 435.57207 -269.48418) (xy 435.651488 -269.35859) (xy 435.737533 -269.237443)
			(xy 435.829957 -269.12109) (xy 435.928493 -269.009866) (xy 436.032857 -268.904091) (xy 436.142749 -268.804071)
			(xy 436.25785 -268.710093) (xy 436.37783 -268.622429) (xy 436.502343 -268.541332) (xy 436.631029 -268.467035)
			(xy 436.763518 -268.399753) (xy 436.899427 -268.339679) (xy 437.038365 -268.286987) (xy 437.179931 -268.241828)
			(xy 437.323717 -268.204333) (xy 437.469308 -268.174611) (xy 437.616284 -268.152746) (xy 437.764223 -268.138802)
			(xy 437.912696 -268.132818) (xy 438.061277 -268.134813) (xy 438.209536 -268.144781) (xy 438.357047 -268.162692)
			(xy 438.503383 -268.188495) (xy 438.648124 -268.222115) (xy 438.790851 -268.263457) (xy 438.931154 -268.3124)
			(xy 439.068627 -268.368803) (xy 439.202874 -268.432504) (xy 439.333509 -268.50332) (xy 439.460154 -268.581045)
			(xy 439.582444 -268.665456) (xy 439.700027 -268.756309) (xy 439.812564 -268.853343) (xy 439.919731 -268.956278)
			(xy 440.021218 -269.064817) (xy 440.116732 -269.178646) (xy 440.205999 -269.297439) (xy 440.28876 -269.420851)
			(xy 440.364778 -269.548529) (xy 440.433833 -269.680102) (xy 440.495726 -269.815193) (xy 440.550279 -269.95341)
			(xy 440.597334 -270.094357) (xy 440.636756 -270.237627) (xy 440.66843 -270.382806) (xy 440.692266 -270.529475)
			(xy 440.708195 -270.677213) (xy 440.716171 -270.825593) (xy 440.71667 -270.89989) (xy 440.716171 -270.974187)
			(xy 440.708195 -271.122567) (xy 440.692266 -271.270305) (xy 440.66843 -271.416974) (xy 440.636756 -271.562153)
			(xy 440.597334 -271.705423) (xy 440.550279 -271.84637) (xy 440.495726 -271.984587) (xy 440.433833 -272.119678)
			(xy 440.364778 -272.251251) (xy 440.28876 -272.378929) (xy 440.205999 -272.502341) (xy 440.116732 -272.621134)
			(xy 440.021218 -272.734963) (xy 439.919731 -272.843502) (xy 439.812564 -272.946437) (xy 439.700027 -273.043471)
			(xy 439.582444 -273.134324) (xy 439.460154 -273.218735) (xy 439.333509 -273.29646) (xy 439.202874 -273.367276)
			(xy 439.068627 -273.430977) (xy 438.931154 -273.48738) (xy 438.790851 -273.536323) (xy 438.648124 -273.577665)
			(xy 438.503383 -273.611285) (xy 438.357047 -273.637088) (xy 438.209536 -273.654999) (xy 438.061277 -273.664967)
			(xy 437.912696 -273.666962) (xy 437.764223 -273.660978) (xy 437.616284 -273.647034) (xy 437.469308 -273.625169)
			(xy 437.323717 -273.595447) (xy 437.179931 -273.557952) (xy 437.038365 -273.512793) (xy 436.899427 -273.460101)
			(xy 436.763518 -273.400027) (xy 436.631029 -273.332745) (xy 436.502343 -273.258448) (xy 436.37783 -273.177351)
			(xy 436.25785 -273.089687) (xy 436.142749 -272.995709) (xy 436.032857 -272.895689) (xy 435.928493 -272.789914)
			(xy 435.829957 -272.67869) (xy 435.737533 -272.562337) (xy 435.651488 -272.44119) (xy 435.57207 -272.3156)
			(xy 435.499507 -272.185928) (xy 435.434009 -272.052548) (xy 435.375765 -271.915845) (xy 435.324943 -271.776212)
			(xy 435.281689 -271.634053) (xy 435.246128 -271.489776) (xy 435.218363 -271.3438) (xy 435.198473 -271.196543)
			(xy 435.186516 -271.04843) (xy 435.182527 -270.89989) (xy 380.716536 -270.89989) (xy 380.716037 -270.974187)
			(xy 380.708061 -271.122567) (xy 380.692132 -271.270305) (xy 380.668296 -271.416974) (xy 380.636622 -271.562153)
			(xy 380.5972 -271.705423) (xy 380.550145 -271.84637) (xy 380.495592 -271.984587) (xy 380.433699 -272.119678)
			(xy 380.364644 -272.251251) (xy 380.288626 -272.378929) (xy 380.205865 -272.502341) (xy 380.116598 -272.621134)
			(xy 380.021084 -272.734963) (xy 379.919597 -272.843502) (xy 379.81243 -272.946437) (xy 379.699893 -273.043471)
			(xy 379.627012 -273.099784) (xy 392.443982 -273.099784) (xy 392.447942 -273.05073) (xy 392.459719 -273.002946)
			(xy 392.47901 -272.95767) (xy 392.505313 -272.916074) (xy 392.537948 -272.879237) (xy 392.576069 -272.848112)
			(xy 392.61869 -272.823505) (xy 392.664706 -272.806053) (xy 392.712925 -272.796209) (xy 392.7621 -272.794228)
			(xy 392.810955 -272.80016) (xy 392.858226 -272.813852) (xy 392.902688 -272.83495) (xy 392.943191 -272.862906)
			(xy 392.978684 -272.896998) (xy 393.008249 -272.936342) (xy 393.03112 -272.979919) (xy 393.046704 -273.0266)
			(xy 393.054599 -273.075177) (xy 393.055094 -273.099784) (xy 394.344156 -273.099784) (xy 394.348116 -273.05073)
			(xy 394.359893 -273.002946) (xy 394.379184 -272.95767) (xy 394.405487 -272.916074) (xy 394.438122 -272.879237)
			(xy 394.476243 -272.848112) (xy 394.518864 -272.823505) (xy 394.56488 -272.806053) (xy 394.613099 -272.796209)
			(xy 394.662274 -272.794228) (xy 394.711129 -272.80016) (xy 394.7584 -272.813852) (xy 394.802862 -272.83495)
			(xy 394.843365 -272.862906) (xy 394.878858 -272.896998) (xy 394.908423 -272.936342) (xy 394.931294 -272.979919)
			(xy 394.946878 -273.0266) (xy 394.954773 -273.075177) (xy 394.955268 -273.099784) (xy 396.244076 -273.099784)
			(xy 396.248036 -273.05073) (xy 396.259813 -273.002946) (xy 396.279104 -272.95767) (xy 396.305407 -272.916074)
			(xy 396.338042 -272.879237) (xy 396.376163 -272.848112) (xy 396.418784 -272.823505) (xy 396.4648 -272.806053)
			(xy 396.513019 -272.796209) (xy 396.562194 -272.794228) (xy 396.611049 -272.80016) (xy 396.65832 -272.813852)
			(xy 396.702782 -272.83495) (xy 396.743285 -272.862906) (xy 396.778778 -272.896998) (xy 396.808343 -272.936342)
			(xy 396.831214 -272.979919) (xy 396.846798 -273.0266) (xy 396.854693 -273.075177) (xy 396.855188 -273.099784)
			(xy 398.143996 -273.099784) (xy 398.147956 -273.05073) (xy 398.159733 -273.002946) (xy 398.179024 -272.95767)
			(xy 398.205327 -272.916074) (xy 398.237962 -272.879237) (xy 398.276083 -272.848112) (xy 398.318704 -272.823505)
			(xy 398.36472 -272.806053) (xy 398.412939 -272.796209) (xy 398.462114 -272.794228) (xy 398.510969 -272.80016)
			(xy 398.55824 -272.813852) (xy 398.602702 -272.83495) (xy 398.643205 -272.862906) (xy 398.678698 -272.896998)
			(xy 398.708263 -272.936342) (xy 398.731134 -272.979919) (xy 398.746718 -273.0266) (xy 398.754613 -273.075177)
			(xy 398.755108 -273.099784) (xy 400.04417 -273.099784) (xy 400.04813 -273.05073) (xy 400.059907 -273.002946)
			(xy 400.079198 -272.95767) (xy 400.105501 -272.916074) (xy 400.138136 -272.879237) (xy 400.176257 -272.848112)
			(xy 400.218878 -272.823505) (xy 400.264894 -272.806053) (xy 400.313113 -272.796209) (xy 400.362288 -272.794228)
			(xy 400.411143 -272.80016) (xy 400.458414 -272.813852) (xy 400.502876 -272.83495) (xy 400.543379 -272.862906)
			(xy 400.578872 -272.896998) (xy 400.608437 -272.936342) (xy 400.631308 -272.979919) (xy 400.646892 -273.0266)
			(xy 400.654787 -273.075177) (xy 400.655282 -273.099784) (xy 401.94409 -273.099784) (xy 401.94805 -273.05073)
			(xy 401.959827 -273.002946) (xy 401.979118 -272.95767) (xy 402.005421 -272.916074) (xy 402.038056 -272.879237)
			(xy 402.076177 -272.848112) (xy 402.118798 -272.823505) (xy 402.164814 -272.806053) (xy 402.213033 -272.796209)
			(xy 402.262208 -272.794228) (xy 402.311063 -272.80016) (xy 402.358334 -272.813852) (xy 402.402796 -272.83495)
			(xy 402.443299 -272.862906) (xy 402.478792 -272.896998) (xy 402.508357 -272.936342) (xy 402.531228 -272.979919)
			(xy 402.546812 -273.0266) (xy 402.554707 -273.075177) (xy 402.555202 -273.099784) (xy 403.84401 -273.099784)
			(xy 403.84797 -273.05073) (xy 403.859747 -273.002946) (xy 403.879038 -272.95767) (xy 403.905341 -272.916074)
			(xy 403.937976 -272.879237) (xy 403.976097 -272.848112) (xy 404.018718 -272.823505) (xy 404.064734 -272.806053)
			(xy 404.112953 -272.796209) (xy 404.162128 -272.794228) (xy 404.210983 -272.80016) (xy 404.258254 -272.813852)
			(xy 404.302716 -272.83495) (xy 404.343219 -272.862906) (xy 404.378712 -272.896998) (xy 404.408277 -272.936342)
			(xy 404.431148 -272.979919) (xy 404.446732 -273.0266) (xy 404.454627 -273.075177) (xy 404.455122 -273.099784)
			(xy 405.744184 -273.099784) (xy 405.748144 -273.05073) (xy 405.759921 -273.002946) (xy 405.779212 -272.95767)
			(xy 405.805515 -272.916074) (xy 405.83815 -272.879237) (xy 405.876271 -272.848112) (xy 405.918892 -272.823505)
			(xy 405.964908 -272.806053) (xy 406.013127 -272.796209) (xy 406.062302 -272.794228) (xy 406.111157 -272.80016)
			(xy 406.158428 -272.813852) (xy 406.20289 -272.83495) (xy 406.243393 -272.862906) (xy 406.278886 -272.896998)
			(xy 406.308451 -272.936342) (xy 406.331322 -272.979919) (xy 406.346906 -273.0266) (xy 406.354801 -273.075177)
			(xy 406.355296 -273.099784) (xy 406.354801 -273.124391) (xy 406.346906 -273.172968) (xy 406.331322 -273.219649)
			(xy 406.308451 -273.263226) (xy 406.278886 -273.30257) (xy 406.243393 -273.336662) (xy 406.20289 -273.364618)
			(xy 406.158428 -273.385716) (xy 406.111157 -273.399408) (xy 406.062302 -273.40534) (xy 406.013127 -273.403359)
			(xy 405.964908 -273.393515) (xy 405.918892 -273.376063) (xy 405.876271 -273.351456) (xy 405.83815 -273.320331)
			(xy 405.805515 -273.283494) (xy 405.779212 -273.241898) (xy 405.759921 -273.196622) (xy 405.748144 -273.148838)
			(xy 405.744184 -273.099784) (xy 404.455122 -273.099784) (xy 404.454627 -273.124391) (xy 404.446732 -273.172968)
			(xy 404.431148 -273.219649) (xy 404.408277 -273.263226) (xy 404.378712 -273.30257) (xy 404.343219 -273.336662)
			(xy 404.302716 -273.364618) (xy 404.258254 -273.385716) (xy 404.210983 -273.399408) (xy 404.162128 -273.40534)
			(xy 404.112953 -273.403359) (xy 404.064734 -273.393515) (xy 404.018718 -273.376063) (xy 403.976097 -273.351456)
			(xy 403.937976 -273.320331) (xy 403.905341 -273.283494) (xy 403.879038 -273.241898) (xy 403.859747 -273.196622)
			(xy 403.84797 -273.148838) (xy 403.84401 -273.099784) (xy 402.555202 -273.099784) (xy 402.554707 -273.124391)
			(xy 402.546812 -273.172968) (xy 402.531228 -273.219649) (xy 402.508357 -273.263226) (xy 402.478792 -273.30257)
			(xy 402.443299 -273.336662) (xy 402.402796 -273.364618) (xy 402.358334 -273.385716) (xy 402.311063 -273.399408)
			(xy 402.262208 -273.40534) (xy 402.213033 -273.403359) (xy 402.164814 -273.393515) (xy 402.118798 -273.376063)
			(xy 402.076177 -273.351456) (xy 402.038056 -273.320331) (xy 402.005421 -273.283494) (xy 401.979118 -273.241898)
			(xy 401.959827 -273.196622) (xy 401.94805 -273.148838) (xy 401.94409 -273.099784) (xy 400.655282 -273.099784)
			(xy 400.654787 -273.124391) (xy 400.646892 -273.172968) (xy 400.631308 -273.219649) (xy 400.608437 -273.263226)
			(xy 400.578872 -273.30257) (xy 400.543379 -273.336662) (xy 400.502876 -273.364618) (xy 400.458414 -273.385716)
			(xy 400.411143 -273.399408) (xy 400.362288 -273.40534) (xy 400.313113 -273.403359) (xy 400.264894 -273.393515)
			(xy 400.218878 -273.376063) (xy 400.176257 -273.351456) (xy 400.138136 -273.320331) (xy 400.105501 -273.283494)
			(xy 400.079198 -273.241898) (xy 400.059907 -273.196622) (xy 400.04813 -273.148838) (xy 400.04417 -273.099784)
			(xy 398.755108 -273.099784) (xy 398.754613 -273.124391) (xy 398.746718 -273.172968) (xy 398.731134 -273.219649)
			(xy 398.708263 -273.263226) (xy 398.678698 -273.30257) (xy 398.643205 -273.336662) (xy 398.602702 -273.364618)
			(xy 398.55824 -273.385716) (xy 398.510969 -273.399408) (xy 398.462114 -273.40534) (xy 398.412939 -273.403359)
			(xy 398.36472 -273.393515) (xy 398.318704 -273.376063) (xy 398.276083 -273.351456) (xy 398.237962 -273.320331)
			(xy 398.205327 -273.283494) (xy 398.179024 -273.241898) (xy 398.159733 -273.196622) (xy 398.147956 -273.148838)
			(xy 398.143996 -273.099784) (xy 396.855188 -273.099784) (xy 396.854693 -273.124391) (xy 396.846798 -273.172968)
			(xy 396.831214 -273.219649) (xy 396.808343 -273.263226) (xy 396.778778 -273.30257) (xy 396.743285 -273.336662)
			(xy 396.702782 -273.364618) (xy 396.65832 -273.385716) (xy 396.611049 -273.399408) (xy 396.562194 -273.40534)
			(xy 396.513019 -273.403359) (xy 396.4648 -273.393515) (xy 396.418784 -273.376063) (xy 396.376163 -273.351456)
			(xy 396.338042 -273.320331) (xy 396.305407 -273.283494) (xy 396.279104 -273.241898) (xy 396.259813 -273.196622)
			(xy 396.248036 -273.148838) (xy 396.244076 -273.099784) (xy 394.955268 -273.099784) (xy 394.954773 -273.124391)
			(xy 394.946878 -273.172968) (xy 394.931294 -273.219649) (xy 394.908423 -273.263226) (xy 394.878858 -273.30257)
			(xy 394.843365 -273.336662) (xy 394.802862 -273.364618) (xy 394.7584 -273.385716) (xy 394.711129 -273.399408)
			(xy 394.662274 -273.40534) (xy 394.613099 -273.403359) (xy 394.56488 -273.393515) (xy 394.518864 -273.376063)
			(xy 394.476243 -273.351456) (xy 394.438122 -273.320331) (xy 394.405487 -273.283494) (xy 394.379184 -273.241898)
			(xy 394.359893 -273.196622) (xy 394.348116 -273.148838) (xy 394.344156 -273.099784) (xy 393.055094 -273.099784)
			(xy 393.054599 -273.124391) (xy 393.046704 -273.172968) (xy 393.03112 -273.219649) (xy 393.008249 -273.263226)
			(xy 392.978684 -273.30257) (xy 392.943191 -273.336662) (xy 392.902688 -273.364618) (xy 392.858226 -273.385716)
			(xy 392.810955 -273.399408) (xy 392.7621 -273.40534) (xy 392.712925 -273.403359) (xy 392.664706 -273.393515)
			(xy 392.61869 -273.376063) (xy 392.576069 -273.351456) (xy 392.537948 -273.320331) (xy 392.505313 -273.283494)
			(xy 392.47901 -273.241898) (xy 392.459719 -273.196622) (xy 392.447942 -273.148838) (xy 392.443982 -273.099784)
			(xy 379.627012 -273.099784) (xy 379.58231 -273.134324) (xy 379.46002 -273.218735) (xy 379.333375 -273.29646)
			(xy 379.20274 -273.367276) (xy 379.068493 -273.430977) (xy 378.93102 -273.48738) (xy 378.790717 -273.536323)
			(xy 378.64799 -273.577665) (xy 378.503249 -273.611285) (xy 378.356913 -273.637088) (xy 378.209402 -273.654999)
			(xy 378.061143 -273.664967) (xy 377.912562 -273.666962) (xy 377.764089 -273.660978) (xy 377.61615 -273.647034)
			(xy 377.469174 -273.625169) (xy 377.323583 -273.595447) (xy 377.179797 -273.557952) (xy 377.038231 -273.512793)
			(xy 376.899293 -273.460101) (xy 376.763384 -273.400027) (xy 376.630895 -273.332745) (xy 376.502209 -273.258448)
			(xy 376.377696 -273.177351) (xy 376.257716 -273.089687) (xy 376.142615 -272.995709) (xy 376.032723 -272.895689)
			(xy 375.928359 -272.789914) (xy 375.829823 -272.67869) (xy 375.737399 -272.562337) (xy 375.651354 -272.44119)
			(xy 375.571936 -272.3156) (xy 375.499373 -272.185928) (xy 375.433875 -272.052548) (xy 375.375631 -271.915845)
			(xy 375.324809 -271.776212) (xy 375.281555 -271.634053) (xy 375.245994 -271.489776) (xy 375.218229 -271.3438)
			(xy 375.198339 -271.196543) (xy 375.186382 -271.04843) (xy 375.182393 -270.89989) (xy 324.616572 -270.89989)
			(xy 324.616073 -270.974187) (xy 324.608097 -271.122567) (xy 324.592168 -271.270305) (xy 324.568332 -271.416974)
			(xy 324.536658 -271.562153) (xy 324.497236 -271.705423) (xy 324.450181 -271.84637) (xy 324.395628 -271.984587)
			(xy 324.333735 -272.119678) (xy 324.26468 -272.251251) (xy 324.188662 -272.378929) (xy 324.105901 -272.502341)
			(xy 324.016634 -272.621134) (xy 323.92112 -272.734963) (xy 323.819633 -272.843502) (xy 323.712466 -272.946437)
			(xy 323.599929 -273.043471) (xy 323.482346 -273.134324) (xy 323.360056 -273.218735) (xy 323.233411 -273.29646)
			(xy 323.102776 -273.367276) (xy 322.968529 -273.430977) (xy 322.831056 -273.48738) (xy 322.690753 -273.536323)
			(xy 322.548026 -273.577665) (xy 322.403285 -273.611285) (xy 322.256949 -273.637088) (xy 322.109438 -273.654999)
			(xy 321.961179 -273.664967) (xy 321.812598 -273.666962) (xy 321.664125 -273.660978) (xy 321.516186 -273.647034)
			(xy 321.36921 -273.625169) (xy 321.223619 -273.595447) (xy 321.079833 -273.557952) (xy 320.938267 -273.512793)
			(xy 320.799329 -273.460101) (xy 320.66342 -273.400027) (xy 320.530931 -273.332745) (xy 320.402245 -273.258448)
			(xy 320.277732 -273.177351) (xy 320.157752 -273.089687) (xy 320.042651 -272.995709) (xy 319.932759 -272.895689)
			(xy 319.828395 -272.789914) (xy 319.729859 -272.67869) (xy 319.637435 -272.562337) (xy 319.55139 -272.44119)
			(xy 319.471972 -272.3156) (xy 319.399409 -272.185928) (xy 319.333911 -272.052548) (xy 319.275667 -271.915845)
			(xy 319.224845 -271.776212) (xy 319.181591 -271.634053) (xy 319.14603 -271.489776) (xy 319.118265 -271.3438)
			(xy 319.098375 -271.196543) (xy 319.086418 -271.04843) (xy 319.082429 -270.89989) (xy 264.616692 -270.89989)
			(xy 264.616193 -270.974187) (xy 264.608217 -271.122567) (xy 264.592288 -271.270305) (xy 264.568452 -271.416974)
			(xy 264.536778 -271.562153) (xy 264.497356 -271.705423) (xy 264.450301 -271.84637) (xy 264.395748 -271.984587)
			(xy 264.333855 -272.119678) (xy 264.2648 -272.251251) (xy 264.188782 -272.378929) (xy 264.106021 -272.502341)
			(xy 264.016754 -272.621134) (xy 263.92124 -272.734963) (xy 263.819753 -272.843502) (xy 263.712586 -272.946437)
			(xy 263.600049 -273.043471) (xy 263.527168 -273.099784) (xy 276.343884 -273.099784) (xy 276.347844 -273.05073)
			(xy 276.359621 -273.002946) (xy 276.378912 -272.95767) (xy 276.405215 -272.916074) (xy 276.43785 -272.879237)
			(xy 276.475971 -272.848112) (xy 276.518592 -272.823505) (xy 276.564608 -272.806053) (xy 276.612827 -272.796209)
			(xy 276.662002 -272.794228) (xy 276.710857 -272.80016) (xy 276.758128 -272.813852) (xy 276.80259 -272.83495)
			(xy 276.843093 -272.862906) (xy 276.878586 -272.896998) (xy 276.908151 -272.936342) (xy 276.931022 -272.979919)
			(xy 276.946606 -273.0266) (xy 276.954501 -273.075177) (xy 276.954996 -273.099784) (xy 278.244058 -273.099784)
			(xy 278.248018 -273.05073) (xy 278.259795 -273.002946) (xy 278.279086 -272.95767) (xy 278.305389 -272.916074)
			(xy 278.338024 -272.879237) (xy 278.376145 -272.848112) (xy 278.418766 -272.823505) (xy 278.464782 -272.806053)
			(xy 278.513001 -272.796209) (xy 278.562176 -272.794228) (xy 278.611031 -272.80016) (xy 278.658302 -272.813852)
			(xy 278.702764 -272.83495) (xy 278.743267 -272.862906) (xy 278.77876 -272.896998) (xy 278.808325 -272.936342)
			(xy 278.831196 -272.979919) (xy 278.84678 -273.0266) (xy 278.854675 -273.075177) (xy 278.85517 -273.099784)
			(xy 280.143978 -273.099784) (xy 280.147938 -273.05073) (xy 280.159715 -273.002946) (xy 280.179006 -272.95767)
			(xy 280.205309 -272.916074) (xy 280.237944 -272.879237) (xy 280.276065 -272.848112) (xy 280.318686 -272.823505)
			(xy 280.364702 -272.806053) (xy 280.412921 -272.796209) (xy 280.462096 -272.794228) (xy 280.510951 -272.80016)
			(xy 280.558222 -272.813852) (xy 280.602684 -272.83495) (xy 280.643187 -272.862906) (xy 280.67868 -272.896998)
			(xy 280.708245 -272.936342) (xy 280.731116 -272.979919) (xy 280.7467 -273.0266) (xy 280.754595 -273.075177)
			(xy 280.75509 -273.099784) (xy 282.043898 -273.099784) (xy 282.047858 -273.05073) (xy 282.059635 -273.002946)
			(xy 282.078926 -272.95767) (xy 282.105229 -272.916074) (xy 282.137864 -272.879237) (xy 282.175985 -272.848112)
			(xy 282.218606 -272.823505) (xy 282.264622 -272.806053) (xy 282.312841 -272.796209) (xy 282.362016 -272.794228)
			(xy 282.410871 -272.80016) (xy 282.458142 -272.813852) (xy 282.502604 -272.83495) (xy 282.543107 -272.862906)
			(xy 282.5786 -272.896998) (xy 282.608165 -272.936342) (xy 282.631036 -272.979919) (xy 282.64662 -273.0266)
			(xy 282.654515 -273.075177) (xy 282.65501 -273.099784) (xy 283.944072 -273.099784) (xy 283.948032 -273.05073)
			(xy 283.959809 -273.002946) (xy 283.9791 -272.95767) (xy 284.005403 -272.916074) (xy 284.038038 -272.879237)
			(xy 284.076159 -272.848112) (xy 284.11878 -272.823505) (xy 284.164796 -272.806053) (xy 284.213015 -272.796209)
			(xy 284.26219 -272.794228) (xy 284.311045 -272.80016) (xy 284.358316 -272.813852) (xy 284.402778 -272.83495)
			(xy 284.443281 -272.862906) (xy 284.478774 -272.896998) (xy 284.508339 -272.936342) (xy 284.53121 -272.979919)
			(xy 284.546794 -273.0266) (xy 284.554689 -273.075177) (xy 284.555184 -273.099784) (xy 285.843992 -273.099784)
			(xy 285.847952 -273.05073) (xy 285.859729 -273.002946) (xy 285.87902 -272.95767) (xy 285.905323 -272.916074)
			(xy 285.937958 -272.879237) (xy 285.976079 -272.848112) (xy 286.0187 -272.823505) (xy 286.064716 -272.806053)
			(xy 286.112935 -272.796209) (xy 286.16211 -272.794228) (xy 286.210965 -272.80016) (xy 286.258236 -272.813852)
			(xy 286.302698 -272.83495) (xy 286.343201 -272.862906) (xy 286.378694 -272.896998) (xy 286.408259 -272.936342)
			(xy 286.43113 -272.979919) (xy 286.446714 -273.0266) (xy 286.454609 -273.075177) (xy 286.455104 -273.099784)
			(xy 287.743912 -273.099784) (xy 287.747872 -273.05073) (xy 287.759649 -273.002946) (xy 287.77894 -272.95767)
			(xy 287.805243 -272.916074) (xy 287.837878 -272.879237) (xy 287.875999 -272.848112) (xy 287.91862 -272.823505)
			(xy 287.964636 -272.806053) (xy 288.012855 -272.796209) (xy 288.06203 -272.794228) (xy 288.110885 -272.80016)
			(xy 288.158156 -272.813852) (xy 288.202618 -272.83495) (xy 288.243121 -272.862906) (xy 288.278614 -272.896998)
			(xy 288.308179 -272.936342) (xy 288.33105 -272.979919) (xy 288.346634 -273.0266) (xy 288.354529 -273.075177)
			(xy 288.355024 -273.099784) (xy 289.644086 -273.099784) (xy 289.648046 -273.05073) (xy 289.659823 -273.002946)
			(xy 289.679114 -272.95767) (xy 289.705417 -272.916074) (xy 289.738052 -272.879237) (xy 289.776173 -272.848112)
			(xy 289.818794 -272.823505) (xy 289.86481 -272.806053) (xy 289.913029 -272.796209) (xy 289.962204 -272.794228)
			(xy 290.011059 -272.80016) (xy 290.05833 -272.813852) (xy 290.102792 -272.83495) (xy 290.143295 -272.862906)
			(xy 290.178788 -272.896998) (xy 290.208353 -272.936342) (xy 290.231224 -272.979919) (xy 290.246808 -273.0266)
			(xy 290.254703 -273.075177) (xy 290.255198 -273.099784) (xy 290.254703 -273.124391) (xy 290.246808 -273.172968)
			(xy 290.231224 -273.219649) (xy 290.208353 -273.263226) (xy 290.178788 -273.30257) (xy 290.143295 -273.336662)
			(xy 290.102792 -273.364618) (xy 290.05833 -273.385716) (xy 290.011059 -273.399408) (xy 289.962204 -273.40534)
			(xy 289.913029 -273.403359) (xy 289.86481 -273.393515) (xy 289.818794 -273.376063) (xy 289.776173 -273.351456)
			(xy 289.738052 -273.320331) (xy 289.705417 -273.283494) (xy 289.679114 -273.241898) (xy 289.659823 -273.196622)
			(xy 289.648046 -273.148838) (xy 289.644086 -273.099784) (xy 288.355024 -273.099784) (xy 288.354529 -273.124391)
			(xy 288.346634 -273.172968) (xy 288.33105 -273.219649) (xy 288.308179 -273.263226) (xy 288.278614 -273.30257)
			(xy 288.243121 -273.336662) (xy 288.202618 -273.364618) (xy 288.158156 -273.385716) (xy 288.110885 -273.399408)
			(xy 288.06203 -273.40534) (xy 288.012855 -273.403359) (xy 287.964636 -273.393515) (xy 287.91862 -273.376063)
			(xy 287.875999 -273.351456) (xy 287.837878 -273.320331) (xy 287.805243 -273.283494) (xy 287.77894 -273.241898)
			(xy 287.759649 -273.196622) (xy 287.747872 -273.148838) (xy 287.743912 -273.099784) (xy 286.455104 -273.099784)
			(xy 286.454609 -273.124391) (xy 286.446714 -273.172968) (xy 286.43113 -273.219649) (xy 286.408259 -273.263226)
			(xy 286.378694 -273.30257) (xy 286.343201 -273.336662) (xy 286.302698 -273.364618) (xy 286.258236 -273.385716)
			(xy 286.210965 -273.399408) (xy 286.16211 -273.40534) (xy 286.112935 -273.403359) (xy 286.064716 -273.393515)
			(xy 286.0187 -273.376063) (xy 285.976079 -273.351456) (xy 285.937958 -273.320331) (xy 285.905323 -273.283494)
			(xy 285.87902 -273.241898) (xy 285.859729 -273.196622) (xy 285.847952 -273.148838) (xy 285.843992 -273.099784)
			(xy 284.555184 -273.099784) (xy 284.554689 -273.124391) (xy 284.546794 -273.172968) (xy 284.53121 -273.219649)
			(xy 284.508339 -273.263226) (xy 284.478774 -273.30257) (xy 284.443281 -273.336662) (xy 284.402778 -273.364618)
			(xy 284.358316 -273.385716) (xy 284.311045 -273.399408) (xy 284.26219 -273.40534) (xy 284.213015 -273.403359)
			(xy 284.164796 -273.393515) (xy 284.11878 -273.376063) (xy 284.076159 -273.351456) (xy 284.038038 -273.320331)
			(xy 284.005403 -273.283494) (xy 283.9791 -273.241898) (xy 283.959809 -273.196622) (xy 283.948032 -273.148838)
			(xy 283.944072 -273.099784) (xy 282.65501 -273.099784) (xy 282.654515 -273.124391) (xy 282.64662 -273.172968)
			(xy 282.631036 -273.219649) (xy 282.608165 -273.263226) (xy 282.5786 -273.30257) (xy 282.543107 -273.336662)
			(xy 282.502604 -273.364618) (xy 282.458142 -273.385716) (xy 282.410871 -273.399408) (xy 282.362016 -273.40534)
			(xy 282.312841 -273.403359) (xy 282.264622 -273.393515) (xy 282.218606 -273.376063) (xy 282.175985 -273.351456)
			(xy 282.137864 -273.320331) (xy 282.105229 -273.283494) (xy 282.078926 -273.241898) (xy 282.059635 -273.196622)
			(xy 282.047858 -273.148838) (xy 282.043898 -273.099784) (xy 280.75509 -273.099784) (xy 280.754595 -273.124391)
			(xy 280.7467 -273.172968) (xy 280.731116 -273.219649) (xy 280.708245 -273.263226) (xy 280.67868 -273.30257)
			(xy 280.643187 -273.336662) (xy 280.602684 -273.364618) (xy 280.558222 -273.385716) (xy 280.510951 -273.399408)
			(xy 280.462096 -273.40534) (xy 280.412921 -273.403359) (xy 280.364702 -273.393515) (xy 280.318686 -273.376063)
			(xy 280.276065 -273.351456) (xy 280.237944 -273.320331) (xy 280.205309 -273.283494) (xy 280.179006 -273.241898)
			(xy 280.159715 -273.196622) (xy 280.147938 -273.148838) (xy 280.143978 -273.099784) (xy 278.85517 -273.099784)
			(xy 278.854675 -273.124391) (xy 278.84678 -273.172968) (xy 278.831196 -273.219649) (xy 278.808325 -273.263226)
			(xy 278.77876 -273.30257) (xy 278.743267 -273.336662) (xy 278.702764 -273.364618) (xy 278.658302 -273.385716)
			(xy 278.611031 -273.399408) (xy 278.562176 -273.40534) (xy 278.513001 -273.403359) (xy 278.464782 -273.393515)
			(xy 278.418766 -273.376063) (xy 278.376145 -273.351456) (xy 278.338024 -273.320331) (xy 278.305389 -273.283494)
			(xy 278.279086 -273.241898) (xy 278.259795 -273.196622) (xy 278.248018 -273.148838) (xy 278.244058 -273.099784)
			(xy 276.954996 -273.099784) (xy 276.954501 -273.124391) (xy 276.946606 -273.172968) (xy 276.931022 -273.219649)
			(xy 276.908151 -273.263226) (xy 276.878586 -273.30257) (xy 276.843093 -273.336662) (xy 276.80259 -273.364618)
			(xy 276.758128 -273.385716) (xy 276.710857 -273.399408) (xy 276.662002 -273.40534) (xy 276.612827 -273.403359)
			(xy 276.564608 -273.393515) (xy 276.518592 -273.376063) (xy 276.475971 -273.351456) (xy 276.43785 -273.320331)
			(xy 276.405215 -273.283494) (xy 276.378912 -273.241898) (xy 276.359621 -273.196622) (xy 276.347844 -273.148838)
			(xy 276.343884 -273.099784) (xy 263.527168 -273.099784) (xy 263.482466 -273.134324) (xy 263.360176 -273.218735)
			(xy 263.233531 -273.29646) (xy 263.102896 -273.367276) (xy 262.968649 -273.430977) (xy 262.831176 -273.48738)
			(xy 262.690873 -273.536323) (xy 262.548146 -273.577665) (xy 262.403405 -273.611285) (xy 262.257069 -273.637088)
			(xy 262.109558 -273.654999) (xy 261.961299 -273.664967) (xy 261.812718 -273.666962) (xy 261.664245 -273.660978)
			(xy 261.516306 -273.647034) (xy 261.36933 -273.625169) (xy 261.223739 -273.595447) (xy 261.079953 -273.557952)
			(xy 260.938387 -273.512793) (xy 260.799449 -273.460101) (xy 260.66354 -273.400027) (xy 260.531051 -273.332745)
			(xy 260.402365 -273.258448) (xy 260.277852 -273.177351) (xy 260.157872 -273.089687) (xy 260.042771 -272.995709)
			(xy 259.932879 -272.895689) (xy 259.828515 -272.789914) (xy 259.729979 -272.67869) (xy 259.637555 -272.562337)
			(xy 259.55151 -272.44119) (xy 259.472092 -272.3156) (xy 259.399529 -272.185928) (xy 259.334031 -272.052548)
			(xy 259.275787 -271.915845) (xy 259.224965 -271.776212) (xy 259.181711 -271.634053) (xy 259.14615 -271.489776)
			(xy 259.118385 -271.3438) (xy 259.098495 -271.196543) (xy 259.086538 -271.04843) (xy 259.082549 -270.89989)
			(xy 208.516474 -270.89989) (xy 208.515975 -270.974187) (xy 208.507999 -271.122567) (xy 208.49207 -271.270305)
			(xy 208.468234 -271.416974) (xy 208.43656 -271.562153) (xy 208.397138 -271.705423) (xy 208.350083 -271.84637)
			(xy 208.29553 -271.984587) (xy 208.233637 -272.119678) (xy 208.164582 -272.251251) (xy 208.088564 -272.378929)
			(xy 208.005803 -272.502341) (xy 207.916536 -272.621134) (xy 207.821022 -272.734963) (xy 207.719535 -272.843502)
			(xy 207.612368 -272.946437) (xy 207.499831 -273.043471) (xy 207.382248 -273.134324) (xy 207.259958 -273.218735)
			(xy 207.133313 -273.29646) (xy 207.002678 -273.367276) (xy 206.868431 -273.430977) (xy 206.730958 -273.48738)
			(xy 206.590655 -273.536323) (xy 206.447928 -273.577665) (xy 206.303187 -273.611285) (xy 206.156851 -273.637088)
			(xy 206.00934 -273.654999) (xy 205.861081 -273.664967) (xy 205.7125 -273.666962) (xy 205.564027 -273.660978)
			(xy 205.416088 -273.647034) (xy 205.269112 -273.625169) (xy 205.123521 -273.595447) (xy 204.979735 -273.557952)
			(xy 204.838169 -273.512793) (xy 204.699231 -273.460101) (xy 204.563322 -273.400027) (xy 204.430833 -273.332745)
			(xy 204.302147 -273.258448) (xy 204.177634 -273.177351) (xy 204.057654 -273.089687) (xy 203.942553 -272.995709)
			(xy 203.832661 -272.895689) (xy 203.728297 -272.789914) (xy 203.629761 -272.67869) (xy 203.537337 -272.562337)
			(xy 203.451292 -272.44119) (xy 203.371874 -272.3156) (xy 203.299311 -272.185928) (xy 203.233813 -272.052548)
			(xy 203.175569 -271.915845) (xy 203.124747 -271.776212) (xy 203.081493 -271.634053) (xy 203.045932 -271.489776)
			(xy 203.018167 -271.3438) (xy 202.998277 -271.196543) (xy 202.98632 -271.04843) (xy 202.982331 -270.89989)
			(xy 148.516594 -270.89989) (xy 148.516095 -270.974187) (xy 148.508119 -271.122567) (xy 148.49219 -271.270305)
			(xy 148.468354 -271.416974) (xy 148.43668 -271.562153) (xy 148.397258 -271.705423) (xy 148.350203 -271.84637)
			(xy 148.29565 -271.984587) (xy 148.233757 -272.119678) (xy 148.164702 -272.251251) (xy 148.088684 -272.378929)
			(xy 148.005923 -272.502341) (xy 147.916656 -272.621134) (xy 147.821142 -272.734963) (xy 147.719655 -272.843502)
			(xy 147.612488 -272.946437) (xy 147.499951 -273.043471) (xy 147.42707 -273.099784) (xy 160.24404 -273.099784)
			(xy 160.248 -273.05073) (xy 160.259777 -273.002946) (xy 160.279068 -272.95767) (xy 160.305371 -272.916074)
			(xy 160.338006 -272.879237) (xy 160.376127 -272.848112) (xy 160.418748 -272.823505) (xy 160.464764 -272.806053)
			(xy 160.512983 -272.796209) (xy 160.562158 -272.794228) (xy 160.611013 -272.80016) (xy 160.658284 -272.813852)
			(xy 160.702746 -272.83495) (xy 160.743249 -272.862906) (xy 160.778742 -272.896998) (xy 160.808307 -272.936342)
			(xy 160.831178 -272.979919) (xy 160.846762 -273.0266) (xy 160.854657 -273.075177) (xy 160.855152 -273.099784)
			(xy 162.144214 -273.099784) (xy 162.148174 -273.05073) (xy 162.159951 -273.002946) (xy 162.179242 -272.95767)
			(xy 162.205545 -272.916074) (xy 162.23818 -272.879237) (xy 162.276301 -272.848112) (xy 162.318922 -272.823505)
			(xy 162.364938 -272.806053) (xy 162.413157 -272.796209) (xy 162.462332 -272.794228) (xy 162.511187 -272.80016)
			(xy 162.558458 -272.813852) (xy 162.60292 -272.83495) (xy 162.643423 -272.862906) (xy 162.678916 -272.896998)
			(xy 162.708481 -272.936342) (xy 162.731352 -272.979919) (xy 162.746936 -273.0266) (xy 162.754831 -273.075177)
			(xy 162.755326 -273.099784) (xy 164.044134 -273.099784) (xy 164.048094 -273.05073) (xy 164.059871 -273.002946)
			(xy 164.079162 -272.95767) (xy 164.105465 -272.916074) (xy 164.1381 -272.879237) (xy 164.176221 -272.848112)
			(xy 164.218842 -272.823505) (xy 164.264858 -272.806053) (xy 164.313077 -272.796209) (xy 164.362252 -272.794228)
			(xy 164.411107 -272.80016) (xy 164.458378 -272.813852) (xy 164.50284 -272.83495) (xy 164.543343 -272.862906)
			(xy 164.578836 -272.896998) (xy 164.608401 -272.936342) (xy 164.631272 -272.979919) (xy 164.646856 -273.0266)
			(xy 164.654751 -273.075177) (xy 164.655246 -273.099784) (xy 165.944054 -273.099784) (xy 165.948014 -273.05073)
			(xy 165.959791 -273.002946) (xy 165.979082 -272.95767) (xy 166.005385 -272.916074) (xy 166.03802 -272.879237)
			(xy 166.076141 -272.848112) (xy 166.118762 -272.823505) (xy 166.164778 -272.806053) (xy 166.212997 -272.796209)
			(xy 166.262172 -272.794228) (xy 166.311027 -272.80016) (xy 166.358298 -272.813852) (xy 166.40276 -272.83495)
			(xy 166.443263 -272.862906) (xy 166.478756 -272.896998) (xy 166.508321 -272.936342) (xy 166.531192 -272.979919)
			(xy 166.546776 -273.0266) (xy 166.554671 -273.075177) (xy 166.555166 -273.099784) (xy 167.844228 -273.099784)
			(xy 167.848188 -273.05073) (xy 167.859965 -273.002946) (xy 167.879256 -272.95767) (xy 167.905559 -272.916074)
			(xy 167.938194 -272.879237) (xy 167.976315 -272.848112) (xy 168.018936 -272.823505) (xy 168.064952 -272.806053)
			(xy 168.113171 -272.796209) (xy 168.162346 -272.794228) (xy 168.211201 -272.80016) (xy 168.258472 -272.813852)
			(xy 168.302934 -272.83495) (xy 168.343437 -272.862906) (xy 168.37893 -272.896998) (xy 168.408495 -272.936342)
			(xy 168.431366 -272.979919) (xy 168.44695 -273.0266) (xy 168.454845 -273.075177) (xy 168.45534 -273.099784)
			(xy 169.744148 -273.099784) (xy 169.748108 -273.05073) (xy 169.759885 -273.002946) (xy 169.779176 -272.95767)
			(xy 169.805479 -272.916074) (xy 169.838114 -272.879237) (xy 169.876235 -272.848112) (xy 169.918856 -272.823505)
			(xy 169.964872 -272.806053) (xy 170.013091 -272.796209) (xy 170.062266 -272.794228) (xy 170.111121 -272.80016)
			(xy 170.158392 -272.813852) (xy 170.202854 -272.83495) (xy 170.243357 -272.862906) (xy 170.27885 -272.896998)
			(xy 170.308415 -272.936342) (xy 170.331286 -272.979919) (xy 170.34687 -273.0266) (xy 170.354765 -273.075177)
			(xy 170.35526 -273.099784) (xy 171.644068 -273.099784) (xy 171.648028 -273.05073) (xy 171.659805 -273.002946)
			(xy 171.679096 -272.95767) (xy 171.705399 -272.916074) (xy 171.738034 -272.879237) (xy 171.776155 -272.848112)
			(xy 171.818776 -272.823505) (xy 171.864792 -272.806053) (xy 171.913011 -272.796209) (xy 171.962186 -272.794228)
			(xy 172.011041 -272.80016) (xy 172.058312 -272.813852) (xy 172.102774 -272.83495) (xy 172.143277 -272.862906)
			(xy 172.17877 -272.896998) (xy 172.208335 -272.936342) (xy 172.231206 -272.979919) (xy 172.24679 -273.0266)
			(xy 172.254685 -273.075177) (xy 172.25518 -273.099784) (xy 173.544242 -273.099784) (xy 173.548202 -273.05073)
			(xy 173.559979 -273.002946) (xy 173.57927 -272.95767) (xy 173.605573 -272.916074) (xy 173.638208 -272.879237)
			(xy 173.676329 -272.848112) (xy 173.71895 -272.823505) (xy 173.764966 -272.806053) (xy 173.813185 -272.796209)
			(xy 173.86236 -272.794228) (xy 173.911215 -272.80016) (xy 173.958486 -272.813852) (xy 174.002948 -272.83495)
			(xy 174.043451 -272.862906) (xy 174.078944 -272.896998) (xy 174.108509 -272.936342) (xy 174.13138 -272.979919)
			(xy 174.146964 -273.0266) (xy 174.154859 -273.075177) (xy 174.155354 -273.099784) (xy 174.154859 -273.124391)
			(xy 174.146964 -273.172968) (xy 174.13138 -273.219649) (xy 174.108509 -273.263226) (xy 174.078944 -273.30257)
			(xy 174.043451 -273.336662) (xy 174.002948 -273.364618) (xy 173.958486 -273.385716) (xy 173.911215 -273.399408)
			(xy 173.86236 -273.40534) (xy 173.813185 -273.403359) (xy 173.764966 -273.393515) (xy 173.71895 -273.376063)
			(xy 173.676329 -273.351456) (xy 173.638208 -273.320331) (xy 173.605573 -273.283494) (xy 173.57927 -273.241898)
			(xy 173.559979 -273.196622) (xy 173.548202 -273.148838) (xy 173.544242 -273.099784) (xy 172.25518 -273.099784)
			(xy 172.254685 -273.124391) (xy 172.24679 -273.172968) (xy 172.231206 -273.219649) (xy 172.208335 -273.263226)
			(xy 172.17877 -273.30257) (xy 172.143277 -273.336662) (xy 172.102774 -273.364618) (xy 172.058312 -273.385716)
			(xy 172.011041 -273.399408) (xy 171.962186 -273.40534) (xy 171.913011 -273.403359) (xy 171.864792 -273.393515)
			(xy 171.818776 -273.376063) (xy 171.776155 -273.351456) (xy 171.738034 -273.320331) (xy 171.705399 -273.283494)
			(xy 171.679096 -273.241898) (xy 171.659805 -273.196622) (xy 171.648028 -273.148838) (xy 171.644068 -273.099784)
			(xy 170.35526 -273.099784) (xy 170.354765 -273.124391) (xy 170.34687 -273.172968) (xy 170.331286 -273.219649)
			(xy 170.308415 -273.263226) (xy 170.27885 -273.30257) (xy 170.243357 -273.336662) (xy 170.202854 -273.364618)
			(xy 170.158392 -273.385716) (xy 170.111121 -273.399408) (xy 170.062266 -273.40534) (xy 170.013091 -273.403359)
			(xy 169.964872 -273.393515) (xy 169.918856 -273.376063) (xy 169.876235 -273.351456) (xy 169.838114 -273.320331)
			(xy 169.805479 -273.283494) (xy 169.779176 -273.241898) (xy 169.759885 -273.196622) (xy 169.748108 -273.148838)
			(xy 169.744148 -273.099784) (xy 168.45534 -273.099784) (xy 168.454845 -273.124391) (xy 168.44695 -273.172968)
			(xy 168.431366 -273.219649) (xy 168.408495 -273.263226) (xy 168.37893 -273.30257) (xy 168.343437 -273.336662)
			(xy 168.302934 -273.364618) (xy 168.258472 -273.385716) (xy 168.211201 -273.399408) (xy 168.162346 -273.40534)
			(xy 168.113171 -273.403359) (xy 168.064952 -273.393515) (xy 168.018936 -273.376063) (xy 167.976315 -273.351456)
			(xy 167.938194 -273.320331) (xy 167.905559 -273.283494) (xy 167.879256 -273.241898) (xy 167.859965 -273.196622)
			(xy 167.848188 -273.148838) (xy 167.844228 -273.099784) (xy 166.555166 -273.099784) (xy 166.554671 -273.124391)
			(xy 166.546776 -273.172968) (xy 166.531192 -273.219649) (xy 166.508321 -273.263226) (xy 166.478756 -273.30257)
			(xy 166.443263 -273.336662) (xy 166.40276 -273.364618) (xy 166.358298 -273.385716) (xy 166.311027 -273.399408)
			(xy 166.262172 -273.40534) (xy 166.212997 -273.403359) (xy 166.164778 -273.393515) (xy 166.118762 -273.376063)
			(xy 166.076141 -273.351456) (xy 166.03802 -273.320331) (xy 166.005385 -273.283494) (xy 165.979082 -273.241898)
			(xy 165.959791 -273.196622) (xy 165.948014 -273.148838) (xy 165.944054 -273.099784) (xy 164.655246 -273.099784)
			(xy 164.654751 -273.124391) (xy 164.646856 -273.172968) (xy 164.631272 -273.219649) (xy 164.608401 -273.263226)
			(xy 164.578836 -273.30257) (xy 164.543343 -273.336662) (xy 164.50284 -273.364618) (xy 164.458378 -273.385716)
			(xy 164.411107 -273.399408) (xy 164.362252 -273.40534) (xy 164.313077 -273.403359) (xy 164.264858 -273.393515)
			(xy 164.218842 -273.376063) (xy 164.176221 -273.351456) (xy 164.1381 -273.320331) (xy 164.105465 -273.283494)
			(xy 164.079162 -273.241898) (xy 164.059871 -273.196622) (xy 164.048094 -273.148838) (xy 164.044134 -273.099784)
			(xy 162.755326 -273.099784) (xy 162.754831 -273.124391) (xy 162.746936 -273.172968) (xy 162.731352 -273.219649)
			(xy 162.708481 -273.263226) (xy 162.678916 -273.30257) (xy 162.643423 -273.336662) (xy 162.60292 -273.364618)
			(xy 162.558458 -273.385716) (xy 162.511187 -273.399408) (xy 162.462332 -273.40534) (xy 162.413157 -273.403359)
			(xy 162.364938 -273.393515) (xy 162.318922 -273.376063) (xy 162.276301 -273.351456) (xy 162.23818 -273.320331)
			(xy 162.205545 -273.283494) (xy 162.179242 -273.241898) (xy 162.159951 -273.196622) (xy 162.148174 -273.148838)
			(xy 162.144214 -273.099784) (xy 160.855152 -273.099784) (xy 160.854657 -273.124391) (xy 160.846762 -273.172968)
			(xy 160.831178 -273.219649) (xy 160.808307 -273.263226) (xy 160.778742 -273.30257) (xy 160.743249 -273.336662)
			(xy 160.702746 -273.364618) (xy 160.658284 -273.385716) (xy 160.611013 -273.399408) (xy 160.562158 -273.40534)
			(xy 160.512983 -273.403359) (xy 160.464764 -273.393515) (xy 160.418748 -273.376063) (xy 160.376127 -273.351456)
			(xy 160.338006 -273.320331) (xy 160.305371 -273.283494) (xy 160.279068 -273.241898) (xy 160.259777 -273.196622)
			(xy 160.248 -273.148838) (xy 160.24404 -273.099784) (xy 147.42707 -273.099784) (xy 147.382368 -273.134324)
			(xy 147.260078 -273.218735) (xy 147.133433 -273.29646) (xy 147.002798 -273.367276) (xy 146.868551 -273.430977)
			(xy 146.731078 -273.48738) (xy 146.590775 -273.536323) (xy 146.448048 -273.577665) (xy 146.303307 -273.611285)
			(xy 146.156971 -273.637088) (xy 146.00946 -273.654999) (xy 145.861201 -273.664967) (xy 145.71262 -273.666962)
			(xy 145.564147 -273.660978) (xy 145.416208 -273.647034) (xy 145.269232 -273.625169) (xy 145.123641 -273.595447)
			(xy 144.979855 -273.557952) (xy 144.838289 -273.512793) (xy 144.699351 -273.460101) (xy 144.563442 -273.400027)
			(xy 144.430953 -273.332745) (xy 144.302267 -273.258448) (xy 144.177754 -273.177351) (xy 144.057774 -273.089687)
			(xy 143.942673 -272.995709) (xy 143.832781 -272.895689) (xy 143.728417 -272.789914) (xy 143.629881 -272.67869)
			(xy 143.537457 -272.562337) (xy 143.451412 -272.44119) (xy 143.371994 -272.3156) (xy 143.299431 -272.185928)
			(xy 143.233933 -272.052548) (xy 143.175689 -271.915845) (xy 143.124867 -271.776212) (xy 143.081613 -271.634053)
			(xy 143.046052 -271.489776) (xy 143.018287 -271.3438) (xy 142.998397 -271.196543) (xy 142.98644 -271.04843)
			(xy 142.982451 -270.89989) (xy 92.41663 -270.89989) (xy 92.416131 -270.974187) (xy 92.408155 -271.122567)
			(xy 92.392226 -271.270305) (xy 92.36839 -271.416974) (xy 92.336716 -271.562153) (xy 92.297294 -271.705423)
			(xy 92.250239 -271.84637) (xy 92.195686 -271.984587) (xy 92.133793 -272.119678) (xy 92.064738 -272.251251)
			(xy 91.98872 -272.378929) (xy 91.905959 -272.502341) (xy 91.816692 -272.621134) (xy 91.721178 -272.734963)
			(xy 91.619691 -272.843502) (xy 91.512524 -272.946437) (xy 91.399987 -273.043471) (xy 91.282404 -273.134324)
			(xy 91.160114 -273.218735) (xy 91.033469 -273.29646) (xy 90.902834 -273.367276) (xy 90.768587 -273.430977)
			(xy 90.631114 -273.48738) (xy 90.490811 -273.536323) (xy 90.348084 -273.577665) (xy 90.203343 -273.611285)
			(xy 90.057007 -273.637088) (xy 89.909496 -273.654999) (xy 89.761237 -273.664967) (xy 89.612656 -273.666962)
			(xy 89.464183 -273.660978) (xy 89.316244 -273.647034) (xy 89.169268 -273.625169) (xy 89.023677 -273.595447)
			(xy 88.879891 -273.557952) (xy 88.738325 -273.512793) (xy 88.599387 -273.460101) (xy 88.463478 -273.400027)
			(xy 88.330989 -273.332745) (xy 88.202303 -273.258448) (xy 88.07779 -273.177351) (xy 87.95781 -273.089687)
			(xy 87.842709 -272.995709) (xy 87.732817 -272.895689) (xy 87.628453 -272.789914) (xy 87.529917 -272.67869)
			(xy 87.437493 -272.562337) (xy 87.351448 -272.44119) (xy 87.27203 -272.3156) (xy 87.199467 -272.185928)
			(xy 87.133969 -272.052548) (xy 87.075725 -271.915845) (xy 87.024903 -271.776212) (xy 86.981649 -271.634053)
			(xy 86.946088 -271.489776) (xy 86.918323 -271.3438) (xy 86.898433 -271.196543) (xy 86.886476 -271.04843)
			(xy 86.882487 -270.89989) (xy 32.416496 -270.89989) (xy 32.415997 -270.974187) (xy 32.408021 -271.122567)
			(xy 32.392092 -271.270305) (xy 32.368256 -271.416974) (xy 32.336582 -271.562153) (xy 32.29716 -271.705423)
			(xy 32.250105 -271.84637) (xy 32.195552 -271.984587) (xy 32.133659 -272.119678) (xy 32.064604 -272.251251)
			(xy 31.988586 -272.378929) (xy 31.905825 -272.502341) (xy 31.816558 -272.621134) (xy 31.721044 -272.734963)
			(xy 31.619557 -272.843502) (xy 31.51239 -272.946437) (xy 31.399853 -273.043471) (xy 31.326972 -273.099784)
			(xy 44.143942 -273.099784) (xy 44.147902 -273.05073) (xy 44.159679 -273.002946) (xy 44.17897 -272.95767)
			(xy 44.205273 -272.916074) (xy 44.237908 -272.879237) (xy 44.276029 -272.848112) (xy 44.31865 -272.823505)
			(xy 44.364666 -272.806053) (xy 44.412885 -272.796209) (xy 44.46206 -272.794228) (xy 44.510915 -272.80016)
			(xy 44.558186 -272.813852) (xy 44.602648 -272.83495) (xy 44.643151 -272.862906) (xy 44.678644 -272.896998)
			(xy 44.708209 -272.936342) (xy 44.73108 -272.979919) (xy 44.746664 -273.0266) (xy 44.754559 -273.075177)
			(xy 44.755054 -273.099784) (xy 46.044116 -273.099784) (xy 46.048076 -273.05073) (xy 46.059853 -273.002946)
			(xy 46.079144 -272.95767) (xy 46.105447 -272.916074) (xy 46.138082 -272.879237) (xy 46.176203 -272.848112)
			(xy 46.218824 -272.823505) (xy 46.26484 -272.806053) (xy 46.313059 -272.796209) (xy 46.362234 -272.794228)
			(xy 46.411089 -272.80016) (xy 46.45836 -272.813852) (xy 46.502822 -272.83495) (xy 46.543325 -272.862906)
			(xy 46.578818 -272.896998) (xy 46.608383 -272.936342) (xy 46.631254 -272.979919) (xy 46.646838 -273.0266)
			(xy 46.654733 -273.075177) (xy 46.655228 -273.099784) (xy 47.944036 -273.099784) (xy 47.947996 -273.05073)
			(xy 47.959773 -273.002946) (xy 47.979064 -272.95767) (xy 48.005367 -272.916074) (xy 48.038002 -272.879237)
			(xy 48.076123 -272.848112) (xy 48.118744 -272.823505) (xy 48.16476 -272.806053) (xy 48.212979 -272.796209)
			(xy 48.262154 -272.794228) (xy 48.311009 -272.80016) (xy 48.35828 -272.813852) (xy 48.402742 -272.83495)
			(xy 48.443245 -272.862906) (xy 48.478738 -272.896998) (xy 48.508303 -272.936342) (xy 48.531174 -272.979919)
			(xy 48.546758 -273.0266) (xy 48.554653 -273.075177) (xy 48.555148 -273.099784) (xy 49.843956 -273.099784)
			(xy 49.847916 -273.05073) (xy 49.859693 -273.002946) (xy 49.878984 -272.95767) (xy 49.905287 -272.916074)
			(xy 49.937922 -272.879237) (xy 49.976043 -272.848112) (xy 50.018664 -272.823505) (xy 50.06468 -272.806053)
			(xy 50.112899 -272.796209) (xy 50.162074 -272.794228) (xy 50.210929 -272.80016) (xy 50.2582 -272.813852)
			(xy 50.302662 -272.83495) (xy 50.343165 -272.862906) (xy 50.378658 -272.896998) (xy 50.408223 -272.936342)
			(xy 50.431094 -272.979919) (xy 50.446678 -273.0266) (xy 50.454573 -273.075177) (xy 50.455068 -273.099784)
			(xy 51.74413 -273.099784) (xy 51.74809 -273.05073) (xy 51.759867 -273.002946) (xy 51.779158 -272.95767)
			(xy 51.805461 -272.916074) (xy 51.838096 -272.879237) (xy 51.876217 -272.848112) (xy 51.918838 -272.823505)
			(xy 51.964854 -272.806053) (xy 52.013073 -272.796209) (xy 52.062248 -272.794228) (xy 52.111103 -272.80016)
			(xy 52.158374 -272.813852) (xy 52.202836 -272.83495) (xy 52.243339 -272.862906) (xy 52.278832 -272.896998)
			(xy 52.308397 -272.936342) (xy 52.331268 -272.979919) (xy 52.346852 -273.0266) (xy 52.354747 -273.075177)
			(xy 52.355242 -273.099784) (xy 53.64405 -273.099784) (xy 53.64801 -273.05073) (xy 53.659787 -273.002946)
			(xy 53.679078 -272.95767) (xy 53.705381 -272.916074) (xy 53.738016 -272.879237) (xy 53.776137 -272.848112)
			(xy 53.818758 -272.823505) (xy 53.864774 -272.806053) (xy 53.912993 -272.796209) (xy 53.962168 -272.794228)
			(xy 54.011023 -272.80016) (xy 54.058294 -272.813852) (xy 54.102756 -272.83495) (xy 54.143259 -272.862906)
			(xy 54.178752 -272.896998) (xy 54.208317 -272.936342) (xy 54.231188 -272.979919) (xy 54.246772 -273.0266)
			(xy 54.254667 -273.075177) (xy 54.255162 -273.099784) (xy 55.54397 -273.099784) (xy 55.54793 -273.05073)
			(xy 55.559707 -273.002946) (xy 55.578998 -272.95767) (xy 55.605301 -272.916074) (xy 55.637936 -272.879237)
			(xy 55.676057 -272.848112) (xy 55.718678 -272.823505) (xy 55.764694 -272.806053) (xy 55.812913 -272.796209)
			(xy 55.862088 -272.794228) (xy 55.910943 -272.80016) (xy 55.958214 -272.813852) (xy 56.002676 -272.83495)
			(xy 56.043179 -272.862906) (xy 56.078672 -272.896998) (xy 56.108237 -272.936342) (xy 56.131108 -272.979919)
			(xy 56.146692 -273.0266) (xy 56.154587 -273.075177) (xy 56.155082 -273.099784) (xy 57.444144 -273.099784)
			(xy 57.448104 -273.05073) (xy 57.459881 -273.002946) (xy 57.479172 -272.95767) (xy 57.505475 -272.916074)
			(xy 57.53811 -272.879237) (xy 57.576231 -272.848112) (xy 57.618852 -272.823505) (xy 57.664868 -272.806053)
			(xy 57.713087 -272.796209) (xy 57.762262 -272.794228) (xy 57.811117 -272.80016) (xy 57.858388 -272.813852)
			(xy 57.90285 -272.83495) (xy 57.943353 -272.862906) (xy 57.978846 -272.896998) (xy 58.008411 -272.936342)
			(xy 58.031282 -272.979919) (xy 58.046866 -273.0266) (xy 58.054761 -273.075177) (xy 58.055256 -273.099784)
			(xy 58.054761 -273.124391) (xy 58.046866 -273.172968) (xy 58.031282 -273.219649) (xy 58.008411 -273.263226)
			(xy 57.978846 -273.30257) (xy 57.943353 -273.336662) (xy 57.90285 -273.364618) (xy 57.858388 -273.385716)
			(xy 57.811117 -273.399408) (xy 57.762262 -273.40534) (xy 57.713087 -273.403359) (xy 57.664868 -273.393515)
			(xy 57.618852 -273.376063) (xy 57.576231 -273.351456) (xy 57.53811 -273.320331) (xy 57.505475 -273.283494)
			(xy 57.479172 -273.241898) (xy 57.459881 -273.196622) (xy 57.448104 -273.148838) (xy 57.444144 -273.099784)
			(xy 56.155082 -273.099784) (xy 56.154587 -273.124391) (xy 56.146692 -273.172968) (xy 56.131108 -273.219649)
			(xy 56.108237 -273.263226) (xy 56.078672 -273.30257) (xy 56.043179 -273.336662) (xy 56.002676 -273.364618)
			(xy 55.958214 -273.385716) (xy 55.910943 -273.399408) (xy 55.862088 -273.40534) (xy 55.812913 -273.403359)
			(xy 55.764694 -273.393515) (xy 55.718678 -273.376063) (xy 55.676057 -273.351456) (xy 55.637936 -273.320331)
			(xy 55.605301 -273.283494) (xy 55.578998 -273.241898) (xy 55.559707 -273.196622) (xy 55.54793 -273.148838)
			(xy 55.54397 -273.099784) (xy 54.255162 -273.099784) (xy 54.254667 -273.124391) (xy 54.246772 -273.172968)
			(xy 54.231188 -273.219649) (xy 54.208317 -273.263226) (xy 54.178752 -273.30257) (xy 54.143259 -273.336662)
			(xy 54.102756 -273.364618) (xy 54.058294 -273.385716) (xy 54.011023 -273.399408) (xy 53.962168 -273.40534)
			(xy 53.912993 -273.403359) (xy 53.864774 -273.393515) (xy 53.818758 -273.376063) (xy 53.776137 -273.351456)
			(xy 53.738016 -273.320331) (xy 53.705381 -273.283494) (xy 53.679078 -273.241898) (xy 53.659787 -273.196622)
			(xy 53.64801 -273.148838) (xy 53.64405 -273.099784) (xy 52.355242 -273.099784) (xy 52.354747 -273.124391)
			(xy 52.346852 -273.172968) (xy 52.331268 -273.219649) (xy 52.308397 -273.263226) (xy 52.278832 -273.30257)
			(xy 52.243339 -273.336662) (xy 52.202836 -273.364618) (xy 52.158374 -273.385716) (xy 52.111103 -273.399408)
			(xy 52.062248 -273.40534) (xy 52.013073 -273.403359) (xy 51.964854 -273.393515) (xy 51.918838 -273.376063)
			(xy 51.876217 -273.351456) (xy 51.838096 -273.320331) (xy 51.805461 -273.283494) (xy 51.779158 -273.241898)
			(xy 51.759867 -273.196622) (xy 51.74809 -273.148838) (xy 51.74413 -273.099784) (xy 50.455068 -273.099784)
			(xy 50.454573 -273.124391) (xy 50.446678 -273.172968) (xy 50.431094 -273.219649) (xy 50.408223 -273.263226)
			(xy 50.378658 -273.30257) (xy 50.343165 -273.336662) (xy 50.302662 -273.364618) (xy 50.2582 -273.385716)
			(xy 50.210929 -273.399408) (xy 50.162074 -273.40534) (xy 50.112899 -273.403359) (xy 50.06468 -273.393515)
			(xy 50.018664 -273.376063) (xy 49.976043 -273.351456) (xy 49.937922 -273.320331) (xy 49.905287 -273.283494)
			(xy 49.878984 -273.241898) (xy 49.859693 -273.196622) (xy 49.847916 -273.148838) (xy 49.843956 -273.099784)
			(xy 48.555148 -273.099784) (xy 48.554653 -273.124391) (xy 48.546758 -273.172968) (xy 48.531174 -273.219649)
			(xy 48.508303 -273.263226) (xy 48.478738 -273.30257) (xy 48.443245 -273.336662) (xy 48.402742 -273.364618)
			(xy 48.35828 -273.385716) (xy 48.311009 -273.399408) (xy 48.262154 -273.40534) (xy 48.212979 -273.403359)
			(xy 48.16476 -273.393515) (xy 48.118744 -273.376063) (xy 48.076123 -273.351456) (xy 48.038002 -273.320331)
			(xy 48.005367 -273.283494) (xy 47.979064 -273.241898) (xy 47.959773 -273.196622) (xy 47.947996 -273.148838)
			(xy 47.944036 -273.099784) (xy 46.655228 -273.099784) (xy 46.654733 -273.124391) (xy 46.646838 -273.172968)
			(xy 46.631254 -273.219649) (xy 46.608383 -273.263226) (xy 46.578818 -273.30257) (xy 46.543325 -273.336662)
			(xy 46.502822 -273.364618) (xy 46.45836 -273.385716) (xy 46.411089 -273.399408) (xy 46.362234 -273.40534)
			(xy 46.313059 -273.403359) (xy 46.26484 -273.393515) (xy 46.218824 -273.376063) (xy 46.176203 -273.351456)
			(xy 46.138082 -273.320331) (xy 46.105447 -273.283494) (xy 46.079144 -273.241898) (xy 46.059853 -273.196622)
			(xy 46.048076 -273.148838) (xy 46.044116 -273.099784) (xy 44.755054 -273.099784) (xy 44.754559 -273.124391)
			(xy 44.746664 -273.172968) (xy 44.73108 -273.219649) (xy 44.708209 -273.263226) (xy 44.678644 -273.30257)
			(xy 44.643151 -273.336662) (xy 44.602648 -273.364618) (xy 44.558186 -273.385716) (xy 44.510915 -273.399408)
			(xy 44.46206 -273.40534) (xy 44.412885 -273.403359) (xy 44.364666 -273.393515) (xy 44.31865 -273.376063)
			(xy 44.276029 -273.351456) (xy 44.237908 -273.320331) (xy 44.205273 -273.283494) (xy 44.17897 -273.241898)
			(xy 44.159679 -273.196622) (xy 44.147902 -273.148838) (xy 44.143942 -273.099784) (xy 31.326972 -273.099784)
			(xy 31.28227 -273.134324) (xy 31.15998 -273.218735) (xy 31.033335 -273.29646) (xy 30.9027 -273.367276)
			(xy 30.768453 -273.430977) (xy 30.63098 -273.48738) (xy 30.490677 -273.536323) (xy 30.34795 -273.577665)
			(xy 30.203209 -273.611285) (xy 30.056873 -273.637088) (xy 29.909362 -273.654999) (xy 29.761103 -273.664967)
			(xy 29.612522 -273.666962) (xy 29.464049 -273.660978) (xy 29.31611 -273.647034) (xy 29.169134 -273.625169)
			(xy 29.023543 -273.595447) (xy 28.879757 -273.557952) (xy 28.738191 -273.512793) (xy 28.599253 -273.460101)
			(xy 28.463344 -273.400027) (xy 28.330855 -273.332745) (xy 28.202169 -273.258448) (xy 28.077656 -273.177351)
			(xy 27.957676 -273.089687) (xy 27.842575 -272.995709) (xy 27.732683 -272.895689) (xy 27.628319 -272.789914)
			(xy 27.529783 -272.67869) (xy 27.437359 -272.562337) (xy 27.351314 -272.44119) (xy 27.271896 -272.3156)
			(xy 27.199333 -272.185928) (xy 27.133835 -272.052548) (xy 27.075591 -271.915845) (xy 27.024769 -271.776212)
			(xy 26.981515 -271.634053) (xy 26.945954 -271.489776) (xy 26.918189 -271.3438) (xy 26.898299 -271.196543)
			(xy 26.886342 -271.04843) (xy 26.882353 -270.89989) (xy 0.508 -270.89989) (xy 0.508 -274.049744)
			(xy 44.143942 -274.049744) (xy 44.147902 -274.00069) (xy 44.159679 -273.952906) (xy 44.17897 -273.90763)
			(xy 44.205273 -273.866034) (xy 44.237908 -273.829197) (xy 44.276029 -273.798072) (xy 44.31865 -273.773465)
			(xy 44.364666 -273.756013) (xy 44.412885 -273.746169) (xy 44.46206 -273.744188) (xy 44.510915 -273.75012)
			(xy 44.558186 -273.763812) (xy 44.602648 -273.78491) (xy 44.643151 -273.812866) (xy 44.678644 -273.846958)
			(xy 44.708209 -273.886302) (xy 44.73108 -273.929879) (xy 44.746664 -273.97656) (xy 44.754559 -274.025137)
			(xy 44.755054 -274.049744) (xy 46.044116 -274.049744) (xy 46.048076 -274.00069) (xy 46.059853 -273.952906)
			(xy 46.079144 -273.90763) (xy 46.105447 -273.866034) (xy 46.138082 -273.829197) (xy 46.176203 -273.798072)
			(xy 46.218824 -273.773465) (xy 46.26484 -273.756013) (xy 46.313059 -273.746169) (xy 46.362234 -273.744188)
			(xy 46.411089 -273.75012) (xy 46.45836 -273.763812) (xy 46.502822 -273.78491) (xy 46.543325 -273.812866)
			(xy 46.578818 -273.846958) (xy 46.608383 -273.886302) (xy 46.631254 -273.929879) (xy 46.646838 -273.97656)
			(xy 46.654733 -274.025137) (xy 46.655228 -274.049744) (xy 47.944036 -274.049744) (xy 47.947996 -274.00069)
			(xy 47.959773 -273.952906) (xy 47.979064 -273.90763) (xy 48.005367 -273.866034) (xy 48.038002 -273.829197)
			(xy 48.076123 -273.798072) (xy 48.118744 -273.773465) (xy 48.16476 -273.756013) (xy 48.212979 -273.746169)
			(xy 48.262154 -273.744188) (xy 48.311009 -273.75012) (xy 48.35828 -273.763812) (xy 48.402742 -273.78491)
			(xy 48.443245 -273.812866) (xy 48.478738 -273.846958) (xy 48.508303 -273.886302) (xy 48.531174 -273.929879)
			(xy 48.546758 -273.97656) (xy 48.554653 -274.025137) (xy 48.555148 -274.049744) (xy 49.843956 -274.049744)
			(xy 49.847916 -274.00069) (xy 49.859693 -273.952906) (xy 49.878984 -273.90763) (xy 49.905287 -273.866034)
			(xy 49.937922 -273.829197) (xy 49.976043 -273.798072) (xy 50.018664 -273.773465) (xy 50.06468 -273.756013)
			(xy 50.112899 -273.746169) (xy 50.162074 -273.744188) (xy 50.210929 -273.75012) (xy 50.2582 -273.763812)
			(xy 50.302662 -273.78491) (xy 50.343165 -273.812866) (xy 50.378658 -273.846958) (xy 50.408223 -273.886302)
			(xy 50.431094 -273.929879) (xy 50.446678 -273.97656) (xy 50.454573 -274.025137) (xy 50.455068 -274.049744)
			(xy 51.74413 -274.049744) (xy 51.74809 -274.00069) (xy 51.759867 -273.952906) (xy 51.779158 -273.90763)
			(xy 51.805461 -273.866034) (xy 51.838096 -273.829197) (xy 51.876217 -273.798072) (xy 51.918838 -273.773465)
			(xy 51.964854 -273.756013) (xy 52.013073 -273.746169) (xy 52.062248 -273.744188) (xy 52.111103 -273.75012)
			(xy 52.158374 -273.763812) (xy 52.202836 -273.78491) (xy 52.243339 -273.812866) (xy 52.278832 -273.846958)
			(xy 52.308397 -273.886302) (xy 52.331268 -273.929879) (xy 52.346852 -273.97656) (xy 52.354747 -274.025137)
			(xy 52.355242 -274.049744) (xy 53.64405 -274.049744) (xy 53.64801 -274.00069) (xy 53.659787 -273.952906)
			(xy 53.679078 -273.90763) (xy 53.705381 -273.866034) (xy 53.738016 -273.829197) (xy 53.776137 -273.798072)
			(xy 53.818758 -273.773465) (xy 53.864774 -273.756013) (xy 53.912993 -273.746169) (xy 53.962168 -273.744188)
			(xy 54.011023 -273.75012) (xy 54.058294 -273.763812) (xy 54.102756 -273.78491) (xy 54.143259 -273.812866)
			(xy 54.178752 -273.846958) (xy 54.208317 -273.886302) (xy 54.231188 -273.929879) (xy 54.246772 -273.97656)
			(xy 54.254667 -274.025137) (xy 54.255162 -274.049744) (xy 55.54397 -274.049744) (xy 55.54793 -274.00069)
			(xy 55.559707 -273.952906) (xy 55.578998 -273.90763) (xy 55.605301 -273.866034) (xy 55.637936 -273.829197)
			(xy 55.676057 -273.798072) (xy 55.718678 -273.773465) (xy 55.764694 -273.756013) (xy 55.812913 -273.746169)
			(xy 55.862088 -273.744188) (xy 55.910943 -273.75012) (xy 55.958214 -273.763812) (xy 56.002676 -273.78491)
			(xy 56.043179 -273.812866) (xy 56.078672 -273.846958) (xy 56.108237 -273.886302) (xy 56.131108 -273.929879)
			(xy 56.146692 -273.97656) (xy 56.154587 -274.025137) (xy 56.155082 -274.049744) (xy 57.444144 -274.049744)
			(xy 57.448104 -274.00069) (xy 57.459881 -273.952906) (xy 57.479172 -273.90763) (xy 57.505475 -273.866034)
			(xy 57.53811 -273.829197) (xy 57.576231 -273.798072) (xy 57.618852 -273.773465) (xy 57.664868 -273.756013)
			(xy 57.713087 -273.746169) (xy 57.762262 -273.744188) (xy 57.811117 -273.75012) (xy 57.858388 -273.763812)
			(xy 57.90285 -273.78491) (xy 57.943353 -273.812866) (xy 57.978846 -273.846958) (xy 58.008411 -273.886302)
			(xy 58.031282 -273.929879) (xy 58.046866 -273.97656) (xy 58.054761 -274.025137) (xy 58.055256 -274.049744)
			(xy 160.24404 -274.049744) (xy 160.248 -274.00069) (xy 160.259777 -273.952906) (xy 160.279068 -273.90763)
			(xy 160.305371 -273.866034) (xy 160.338006 -273.829197) (xy 160.376127 -273.798072) (xy 160.418748 -273.773465)
			(xy 160.464764 -273.756013) (xy 160.512983 -273.746169) (xy 160.562158 -273.744188) (xy 160.611013 -273.75012)
			(xy 160.658284 -273.763812) (xy 160.702746 -273.78491) (xy 160.743249 -273.812866) (xy 160.778742 -273.846958)
			(xy 160.808307 -273.886302) (xy 160.831178 -273.929879) (xy 160.846762 -273.97656) (xy 160.854657 -274.025137)
			(xy 160.855152 -274.049744) (xy 162.144214 -274.049744) (xy 162.148174 -274.00069) (xy 162.159951 -273.952906)
			(xy 162.179242 -273.90763) (xy 162.205545 -273.866034) (xy 162.23818 -273.829197) (xy 162.276301 -273.798072)
			(xy 162.318922 -273.773465) (xy 162.364938 -273.756013) (xy 162.413157 -273.746169) (xy 162.462332 -273.744188)
			(xy 162.511187 -273.75012) (xy 162.558458 -273.763812) (xy 162.60292 -273.78491) (xy 162.643423 -273.812866)
			(xy 162.678916 -273.846958) (xy 162.708481 -273.886302) (xy 162.731352 -273.929879) (xy 162.746936 -273.97656)
			(xy 162.754831 -274.025137) (xy 162.755326 -274.049744) (xy 164.044134 -274.049744) (xy 164.048094 -274.00069)
			(xy 164.059871 -273.952906) (xy 164.079162 -273.90763) (xy 164.105465 -273.866034) (xy 164.1381 -273.829197)
			(xy 164.176221 -273.798072) (xy 164.218842 -273.773465) (xy 164.264858 -273.756013) (xy 164.313077 -273.746169)
			(xy 164.362252 -273.744188) (xy 164.411107 -273.75012) (xy 164.458378 -273.763812) (xy 164.50284 -273.78491)
			(xy 164.543343 -273.812866) (xy 164.578836 -273.846958) (xy 164.608401 -273.886302) (xy 164.631272 -273.929879)
			(xy 164.646856 -273.97656) (xy 164.654751 -274.025137) (xy 164.655246 -274.049744) (xy 165.944054 -274.049744)
			(xy 165.948014 -274.00069) (xy 165.959791 -273.952906) (xy 165.979082 -273.90763) (xy 166.005385 -273.866034)
			(xy 166.03802 -273.829197) (xy 166.076141 -273.798072) (xy 166.118762 -273.773465) (xy 166.164778 -273.756013)
			(xy 166.212997 -273.746169) (xy 166.262172 -273.744188) (xy 166.311027 -273.75012) (xy 166.358298 -273.763812)
			(xy 166.40276 -273.78491) (xy 166.443263 -273.812866) (xy 166.478756 -273.846958) (xy 166.508321 -273.886302)
			(xy 166.531192 -273.929879) (xy 166.546776 -273.97656) (xy 166.554671 -274.025137) (xy 166.555166 -274.049744)
			(xy 167.844228 -274.049744) (xy 167.848188 -274.00069) (xy 167.859965 -273.952906) (xy 167.879256 -273.90763)
			(xy 167.905559 -273.866034) (xy 167.938194 -273.829197) (xy 167.976315 -273.798072) (xy 168.018936 -273.773465)
			(xy 168.064952 -273.756013) (xy 168.113171 -273.746169) (xy 168.162346 -273.744188) (xy 168.211201 -273.75012)
			(xy 168.258472 -273.763812) (xy 168.302934 -273.78491) (xy 168.343437 -273.812866) (xy 168.37893 -273.846958)
			(xy 168.408495 -273.886302) (xy 168.431366 -273.929879) (xy 168.44695 -273.97656) (xy 168.454845 -274.025137)
			(xy 168.45534 -274.049744) (xy 169.744148 -274.049744) (xy 169.748108 -274.00069) (xy 169.759885 -273.952906)
			(xy 169.779176 -273.90763) (xy 169.805479 -273.866034) (xy 169.838114 -273.829197) (xy 169.876235 -273.798072)
			(xy 169.918856 -273.773465) (xy 169.964872 -273.756013) (xy 170.013091 -273.746169) (xy 170.062266 -273.744188)
			(xy 170.111121 -273.75012) (xy 170.158392 -273.763812) (xy 170.202854 -273.78491) (xy 170.243357 -273.812866)
			(xy 170.27885 -273.846958) (xy 170.308415 -273.886302) (xy 170.331286 -273.929879) (xy 170.34687 -273.97656)
			(xy 170.354765 -274.025137) (xy 170.35526 -274.049744) (xy 171.644068 -274.049744) (xy 171.648028 -274.00069)
			(xy 171.659805 -273.952906) (xy 171.679096 -273.90763) (xy 171.705399 -273.866034) (xy 171.738034 -273.829197)
			(xy 171.776155 -273.798072) (xy 171.818776 -273.773465) (xy 171.864792 -273.756013) (xy 171.913011 -273.746169)
			(xy 171.962186 -273.744188) (xy 172.011041 -273.75012) (xy 172.058312 -273.763812) (xy 172.102774 -273.78491)
			(xy 172.143277 -273.812866) (xy 172.17877 -273.846958) (xy 172.208335 -273.886302) (xy 172.231206 -273.929879)
			(xy 172.24679 -273.97656) (xy 172.254685 -274.025137) (xy 172.25518 -274.049744) (xy 173.544242 -274.049744)
			(xy 173.548202 -274.00069) (xy 173.559979 -273.952906) (xy 173.57927 -273.90763) (xy 173.605573 -273.866034)
			(xy 173.638208 -273.829197) (xy 173.676329 -273.798072) (xy 173.71895 -273.773465) (xy 173.764966 -273.756013)
			(xy 173.813185 -273.746169) (xy 173.86236 -273.744188) (xy 173.911215 -273.75012) (xy 173.958486 -273.763812)
			(xy 174.002948 -273.78491) (xy 174.043451 -273.812866) (xy 174.078944 -273.846958) (xy 174.108509 -273.886302)
			(xy 174.13138 -273.929879) (xy 174.146964 -273.97656) (xy 174.154859 -274.025137) (xy 174.155354 -274.049744)
			(xy 276.343884 -274.049744) (xy 276.347844 -274.00069) (xy 276.359621 -273.952906) (xy 276.378912 -273.90763)
			(xy 276.405215 -273.866034) (xy 276.43785 -273.829197) (xy 276.475971 -273.798072) (xy 276.518592 -273.773465)
			(xy 276.564608 -273.756013) (xy 276.612827 -273.746169) (xy 276.662002 -273.744188) (xy 276.710857 -273.75012)
			(xy 276.758128 -273.763812) (xy 276.80259 -273.78491) (xy 276.843093 -273.812866) (xy 276.878586 -273.846958)
			(xy 276.908151 -273.886302) (xy 276.931022 -273.929879) (xy 276.946606 -273.97656) (xy 276.954501 -274.025137)
			(xy 276.954996 -274.049744) (xy 278.244058 -274.049744) (xy 278.248018 -274.00069) (xy 278.259795 -273.952906)
			(xy 278.279086 -273.90763) (xy 278.305389 -273.866034) (xy 278.338024 -273.829197) (xy 278.376145 -273.798072)
			(xy 278.418766 -273.773465) (xy 278.464782 -273.756013) (xy 278.513001 -273.746169) (xy 278.562176 -273.744188)
			(xy 278.611031 -273.75012) (xy 278.658302 -273.763812) (xy 278.702764 -273.78491) (xy 278.743267 -273.812866)
			(xy 278.77876 -273.846958) (xy 278.808325 -273.886302) (xy 278.831196 -273.929879) (xy 278.84678 -273.97656)
			(xy 278.854675 -274.025137) (xy 278.85517 -274.049744) (xy 280.143978 -274.049744) (xy 280.147938 -274.00069)
			(xy 280.159715 -273.952906) (xy 280.179006 -273.90763) (xy 280.205309 -273.866034) (xy 280.237944 -273.829197)
			(xy 280.276065 -273.798072) (xy 280.318686 -273.773465) (xy 280.364702 -273.756013) (xy 280.412921 -273.746169)
			(xy 280.462096 -273.744188) (xy 280.510951 -273.75012) (xy 280.558222 -273.763812) (xy 280.602684 -273.78491)
			(xy 280.643187 -273.812866) (xy 280.67868 -273.846958) (xy 280.708245 -273.886302) (xy 280.731116 -273.929879)
			(xy 280.7467 -273.97656) (xy 280.754595 -274.025137) (xy 280.75509 -274.049744) (xy 282.043898 -274.049744)
			(xy 282.047858 -274.00069) (xy 282.059635 -273.952906) (xy 282.078926 -273.90763) (xy 282.105229 -273.866034)
			(xy 282.137864 -273.829197) (xy 282.175985 -273.798072) (xy 282.218606 -273.773465) (xy 282.264622 -273.756013)
			(xy 282.312841 -273.746169) (xy 282.362016 -273.744188) (xy 282.410871 -273.75012) (xy 282.458142 -273.763812)
			(xy 282.502604 -273.78491) (xy 282.543107 -273.812866) (xy 282.5786 -273.846958) (xy 282.608165 -273.886302)
			(xy 282.631036 -273.929879) (xy 282.64662 -273.97656) (xy 282.654515 -274.025137) (xy 282.65501 -274.049744)
			(xy 283.944072 -274.049744) (xy 283.948032 -274.00069) (xy 283.959809 -273.952906) (xy 283.9791 -273.90763)
			(xy 284.005403 -273.866034) (xy 284.038038 -273.829197) (xy 284.076159 -273.798072) (xy 284.11878 -273.773465)
			(xy 284.164796 -273.756013) (xy 284.213015 -273.746169) (xy 284.26219 -273.744188) (xy 284.311045 -273.75012)
			(xy 284.358316 -273.763812) (xy 284.402778 -273.78491) (xy 284.443281 -273.812866) (xy 284.478774 -273.846958)
			(xy 284.508339 -273.886302) (xy 284.53121 -273.929879) (xy 284.546794 -273.97656) (xy 284.554689 -274.025137)
			(xy 284.555184 -274.049744) (xy 285.843992 -274.049744) (xy 285.847952 -274.00069) (xy 285.859729 -273.952906)
			(xy 285.87902 -273.90763) (xy 285.905323 -273.866034) (xy 285.937958 -273.829197) (xy 285.976079 -273.798072)
			(xy 286.0187 -273.773465) (xy 286.064716 -273.756013) (xy 286.112935 -273.746169) (xy 286.16211 -273.744188)
			(xy 286.210965 -273.75012) (xy 286.258236 -273.763812) (xy 286.302698 -273.78491) (xy 286.343201 -273.812866)
			(xy 286.378694 -273.846958) (xy 286.408259 -273.886302) (xy 286.43113 -273.929879) (xy 286.446714 -273.97656)
			(xy 286.454609 -274.025137) (xy 286.455104 -274.049744) (xy 287.743912 -274.049744) (xy 287.747872 -274.00069)
			(xy 287.759649 -273.952906) (xy 287.77894 -273.90763) (xy 287.805243 -273.866034) (xy 287.837878 -273.829197)
			(xy 287.875999 -273.798072) (xy 287.91862 -273.773465) (xy 287.964636 -273.756013) (xy 288.012855 -273.746169)
			(xy 288.06203 -273.744188) (xy 288.110885 -273.75012) (xy 288.158156 -273.763812) (xy 288.202618 -273.78491)
			(xy 288.243121 -273.812866) (xy 288.278614 -273.846958) (xy 288.308179 -273.886302) (xy 288.33105 -273.929879)
			(xy 288.346634 -273.97656) (xy 288.354529 -274.025137) (xy 288.355024 -274.049744) (xy 289.644086 -274.049744)
			(xy 289.648046 -274.00069) (xy 289.659823 -273.952906) (xy 289.679114 -273.90763) (xy 289.705417 -273.866034)
			(xy 289.738052 -273.829197) (xy 289.776173 -273.798072) (xy 289.818794 -273.773465) (xy 289.86481 -273.756013)
			(xy 289.913029 -273.746169) (xy 289.962204 -273.744188) (xy 290.011059 -273.75012) (xy 290.05833 -273.763812)
			(xy 290.102792 -273.78491) (xy 290.143295 -273.812866) (xy 290.178788 -273.846958) (xy 290.208353 -273.886302)
			(xy 290.231224 -273.929879) (xy 290.246808 -273.97656) (xy 290.254703 -274.025137) (xy 290.255198 -274.049744)
			(xy 392.443982 -274.049744) (xy 392.447942 -274.00069) (xy 392.459719 -273.952906) (xy 392.47901 -273.90763)
			(xy 392.505313 -273.866034) (xy 392.537948 -273.829197) (xy 392.576069 -273.798072) (xy 392.61869 -273.773465)
			(xy 392.664706 -273.756013) (xy 392.712925 -273.746169) (xy 392.7621 -273.744188) (xy 392.810955 -273.75012)
			(xy 392.858226 -273.763812) (xy 392.902688 -273.78491) (xy 392.943191 -273.812866) (xy 392.978684 -273.846958)
			(xy 393.008249 -273.886302) (xy 393.03112 -273.929879) (xy 393.046704 -273.97656) (xy 393.054599 -274.025137)
			(xy 393.055094 -274.049744) (xy 394.344156 -274.049744) (xy 394.348116 -274.00069) (xy 394.359893 -273.952906)
			(xy 394.379184 -273.90763) (xy 394.405487 -273.866034) (xy 394.438122 -273.829197) (xy 394.476243 -273.798072)
			(xy 394.518864 -273.773465) (xy 394.56488 -273.756013) (xy 394.613099 -273.746169) (xy 394.662274 -273.744188)
			(xy 394.711129 -273.75012) (xy 394.7584 -273.763812) (xy 394.802862 -273.78491) (xy 394.843365 -273.812866)
			(xy 394.878858 -273.846958) (xy 394.908423 -273.886302) (xy 394.931294 -273.929879) (xy 394.946878 -273.97656)
			(xy 394.954773 -274.025137) (xy 394.955268 -274.049744) (xy 396.244076 -274.049744) (xy 396.248036 -274.00069)
			(xy 396.259813 -273.952906) (xy 396.279104 -273.90763) (xy 396.305407 -273.866034) (xy 396.338042 -273.829197)
			(xy 396.376163 -273.798072) (xy 396.418784 -273.773465) (xy 396.4648 -273.756013) (xy 396.513019 -273.746169)
			(xy 396.562194 -273.744188) (xy 396.611049 -273.75012) (xy 396.65832 -273.763812) (xy 396.702782 -273.78491)
			(xy 396.743285 -273.812866) (xy 396.778778 -273.846958) (xy 396.808343 -273.886302) (xy 396.831214 -273.929879)
			(xy 396.846798 -273.97656) (xy 396.854693 -274.025137) (xy 396.855188 -274.049744) (xy 398.143996 -274.049744)
			(xy 398.147956 -274.00069) (xy 398.159733 -273.952906) (xy 398.179024 -273.90763) (xy 398.205327 -273.866034)
			(xy 398.237962 -273.829197) (xy 398.276083 -273.798072) (xy 398.318704 -273.773465) (xy 398.36472 -273.756013)
			(xy 398.412939 -273.746169) (xy 398.462114 -273.744188) (xy 398.510969 -273.75012) (xy 398.55824 -273.763812)
			(xy 398.602702 -273.78491) (xy 398.643205 -273.812866) (xy 398.678698 -273.846958) (xy 398.708263 -273.886302)
			(xy 398.731134 -273.929879) (xy 398.746718 -273.97656) (xy 398.754613 -274.025137) (xy 398.755108 -274.049744)
			(xy 400.04417 -274.049744) (xy 400.04813 -274.00069) (xy 400.059907 -273.952906) (xy 400.079198 -273.90763)
			(xy 400.105501 -273.866034) (xy 400.138136 -273.829197) (xy 400.176257 -273.798072) (xy 400.218878 -273.773465)
			(xy 400.264894 -273.756013) (xy 400.313113 -273.746169) (xy 400.362288 -273.744188) (xy 400.411143 -273.75012)
			(xy 400.458414 -273.763812) (xy 400.502876 -273.78491) (xy 400.543379 -273.812866) (xy 400.578872 -273.846958)
			(xy 400.608437 -273.886302) (xy 400.631308 -273.929879) (xy 400.646892 -273.97656) (xy 400.654787 -274.025137)
			(xy 400.655282 -274.049744) (xy 401.94409 -274.049744) (xy 401.94805 -274.00069) (xy 401.959827 -273.952906)
			(xy 401.979118 -273.90763) (xy 402.005421 -273.866034) (xy 402.038056 -273.829197) (xy 402.076177 -273.798072)
			(xy 402.118798 -273.773465) (xy 402.164814 -273.756013) (xy 402.213033 -273.746169) (xy 402.262208 -273.744188)
			(xy 402.311063 -273.75012) (xy 402.358334 -273.763812) (xy 402.402796 -273.78491) (xy 402.443299 -273.812866)
			(xy 402.478792 -273.846958) (xy 402.508357 -273.886302) (xy 402.531228 -273.929879) (xy 402.546812 -273.97656)
			(xy 402.554707 -274.025137) (xy 402.555202 -274.049744) (xy 403.84401 -274.049744) (xy 403.84797 -274.00069)
			(xy 403.859747 -273.952906) (xy 403.879038 -273.90763) (xy 403.905341 -273.866034) (xy 403.937976 -273.829197)
			(xy 403.976097 -273.798072) (xy 404.018718 -273.773465) (xy 404.064734 -273.756013) (xy 404.112953 -273.746169)
			(xy 404.162128 -273.744188) (xy 404.210983 -273.75012) (xy 404.258254 -273.763812) (xy 404.302716 -273.78491)
			(xy 404.343219 -273.812866) (xy 404.378712 -273.846958) (xy 404.408277 -273.886302) (xy 404.431148 -273.929879)
			(xy 404.446732 -273.97656) (xy 404.454627 -274.025137) (xy 404.455122 -274.049744) (xy 405.744184 -274.049744)
			(xy 405.748144 -274.00069) (xy 405.759921 -273.952906) (xy 405.779212 -273.90763) (xy 405.805515 -273.866034)
			(xy 405.83815 -273.829197) (xy 405.876271 -273.798072) (xy 405.918892 -273.773465) (xy 405.964908 -273.756013)
			(xy 406.013127 -273.746169) (xy 406.062302 -273.744188) (xy 406.111157 -273.75012) (xy 406.158428 -273.763812)
			(xy 406.20289 -273.78491) (xy 406.243393 -273.812866) (xy 406.278886 -273.846958) (xy 406.308451 -273.886302)
			(xy 406.331322 -273.929879) (xy 406.346906 -273.97656) (xy 406.354801 -274.025137) (xy 406.355296 -274.049744)
			(xy 406.354801 -274.074351) (xy 406.346906 -274.122928) (xy 406.331322 -274.169609) (xy 406.308451 -274.213186)
			(xy 406.278886 -274.25253) (xy 406.243393 -274.286622) (xy 406.20289 -274.314578) (xy 406.158428 -274.335676)
			(xy 406.111157 -274.349368) (xy 406.062302 -274.3553) (xy 406.013127 -274.353319) (xy 405.964908 -274.343475)
			(xy 405.918892 -274.326023) (xy 405.876271 -274.301416) (xy 405.83815 -274.270291) (xy 405.805515 -274.233454)
			(xy 405.779212 -274.191858) (xy 405.759921 -274.146582) (xy 405.748144 -274.098798) (xy 405.744184 -274.049744)
			(xy 404.455122 -274.049744) (xy 404.454627 -274.074351) (xy 404.446732 -274.122928) (xy 404.431148 -274.169609)
			(xy 404.408277 -274.213186) (xy 404.378712 -274.25253) (xy 404.343219 -274.286622) (xy 404.302716 -274.314578)
			(xy 404.258254 -274.335676) (xy 404.210983 -274.349368) (xy 404.162128 -274.3553) (xy 404.112953 -274.353319)
			(xy 404.064734 -274.343475) (xy 404.018718 -274.326023) (xy 403.976097 -274.301416) (xy 403.937976 -274.270291)
			(xy 403.905341 -274.233454) (xy 403.879038 -274.191858) (xy 403.859747 -274.146582) (xy 403.84797 -274.098798)
			(xy 403.84401 -274.049744) (xy 402.555202 -274.049744) (xy 402.554707 -274.074351) (xy 402.546812 -274.122928)
			(xy 402.531228 -274.169609) (xy 402.508357 -274.213186) (xy 402.478792 -274.25253) (xy 402.443299 -274.286622)
			(xy 402.402796 -274.314578) (xy 402.358334 -274.335676) (xy 402.311063 -274.349368) (xy 402.262208 -274.3553)
			(xy 402.213033 -274.353319) (xy 402.164814 -274.343475) (xy 402.118798 -274.326023) (xy 402.076177 -274.301416)
			(xy 402.038056 -274.270291) (xy 402.005421 -274.233454) (xy 401.979118 -274.191858) (xy 401.959827 -274.146582)
			(xy 401.94805 -274.098798) (xy 401.94409 -274.049744) (xy 400.655282 -274.049744) (xy 400.654787 -274.074351)
			(xy 400.646892 -274.122928) (xy 400.631308 -274.169609) (xy 400.608437 -274.213186) (xy 400.578872 -274.25253)
			(xy 400.543379 -274.286622) (xy 400.502876 -274.314578) (xy 400.458414 -274.335676) (xy 400.411143 -274.349368)
			(xy 400.362288 -274.3553) (xy 400.313113 -274.353319) (xy 400.264894 -274.343475) (xy 400.218878 -274.326023)
			(xy 400.176257 -274.301416) (xy 400.138136 -274.270291) (xy 400.105501 -274.233454) (xy 400.079198 -274.191858)
			(xy 400.059907 -274.146582) (xy 400.04813 -274.098798) (xy 400.04417 -274.049744) (xy 398.755108 -274.049744)
			(xy 398.754613 -274.074351) (xy 398.746718 -274.122928) (xy 398.731134 -274.169609) (xy 398.708263 -274.213186)
			(xy 398.678698 -274.25253) (xy 398.643205 -274.286622) (xy 398.602702 -274.314578) (xy 398.55824 -274.335676)
			(xy 398.510969 -274.349368) (xy 398.462114 -274.3553) (xy 398.412939 -274.353319) (xy 398.36472 -274.343475)
			(xy 398.318704 -274.326023) (xy 398.276083 -274.301416) (xy 398.237962 -274.270291) (xy 398.205327 -274.233454)
			(xy 398.179024 -274.191858) (xy 398.159733 -274.146582) (xy 398.147956 -274.098798) (xy 398.143996 -274.049744)
			(xy 396.855188 -274.049744) (xy 396.854693 -274.074351) (xy 396.846798 -274.122928) (xy 396.831214 -274.169609)
			(xy 396.808343 -274.213186) (xy 396.778778 -274.25253) (xy 396.743285 -274.286622) (xy 396.702782 -274.314578)
			(xy 396.65832 -274.335676) (xy 396.611049 -274.349368) (xy 396.562194 -274.3553) (xy 396.513019 -274.353319)
			(xy 396.4648 -274.343475) (xy 396.418784 -274.326023) (xy 396.376163 -274.301416) (xy 396.338042 -274.270291)
			(xy 396.305407 -274.233454) (xy 396.279104 -274.191858) (xy 396.259813 -274.146582) (xy 396.248036 -274.098798)
			(xy 396.244076 -274.049744) (xy 394.955268 -274.049744) (xy 394.954773 -274.074351) (xy 394.946878 -274.122928)
			(xy 394.931294 -274.169609) (xy 394.908423 -274.213186) (xy 394.878858 -274.25253) (xy 394.843365 -274.286622)
			(xy 394.802862 -274.314578) (xy 394.7584 -274.335676) (xy 394.711129 -274.349368) (xy 394.662274 -274.3553)
			(xy 394.613099 -274.353319) (xy 394.56488 -274.343475) (xy 394.518864 -274.326023) (xy 394.476243 -274.301416)
			(xy 394.438122 -274.270291) (xy 394.405487 -274.233454) (xy 394.379184 -274.191858) (xy 394.359893 -274.146582)
			(xy 394.348116 -274.098798) (xy 394.344156 -274.049744) (xy 393.055094 -274.049744) (xy 393.054599 -274.074351)
			(xy 393.046704 -274.122928) (xy 393.03112 -274.169609) (xy 393.008249 -274.213186) (xy 392.978684 -274.25253)
			(xy 392.943191 -274.286622) (xy 392.902688 -274.314578) (xy 392.858226 -274.335676) (xy 392.810955 -274.349368)
			(xy 392.7621 -274.3553) (xy 392.712925 -274.353319) (xy 392.664706 -274.343475) (xy 392.61869 -274.326023)
			(xy 392.576069 -274.301416) (xy 392.537948 -274.270291) (xy 392.505313 -274.233454) (xy 392.47901 -274.191858)
			(xy 392.459719 -274.146582) (xy 392.447942 -274.098798) (xy 392.443982 -274.049744) (xy 290.255198 -274.049744)
			(xy 290.254703 -274.074351) (xy 290.246808 -274.122928) (xy 290.231224 -274.169609) (xy 290.208353 -274.213186)
			(xy 290.178788 -274.25253) (xy 290.143295 -274.286622) (xy 290.102792 -274.314578) (xy 290.05833 -274.335676)
			(xy 290.011059 -274.349368) (xy 289.962204 -274.3553) (xy 289.913029 -274.353319) (xy 289.86481 -274.343475)
			(xy 289.818794 -274.326023) (xy 289.776173 -274.301416) (xy 289.738052 -274.270291) (xy 289.705417 -274.233454)
			(xy 289.679114 -274.191858) (xy 289.659823 -274.146582) (xy 289.648046 -274.098798) (xy 289.644086 -274.049744)
			(xy 288.355024 -274.049744) (xy 288.354529 -274.074351) (xy 288.346634 -274.122928) (xy 288.33105 -274.169609)
			(xy 288.308179 -274.213186) (xy 288.278614 -274.25253) (xy 288.243121 -274.286622) (xy 288.202618 -274.314578)
			(xy 288.158156 -274.335676) (xy 288.110885 -274.349368) (xy 288.06203 -274.3553) (xy 288.012855 -274.353319)
			(xy 287.964636 -274.343475) (xy 287.91862 -274.326023) (xy 287.875999 -274.301416) (xy 287.837878 -274.270291)
			(xy 287.805243 -274.233454) (xy 287.77894 -274.191858) (xy 287.759649 -274.146582) (xy 287.747872 -274.098798)
			(xy 287.743912 -274.049744) (xy 286.455104 -274.049744) (xy 286.454609 -274.074351) (xy 286.446714 -274.122928)
			(xy 286.43113 -274.169609) (xy 286.408259 -274.213186) (xy 286.378694 -274.25253) (xy 286.343201 -274.286622)
			(xy 286.302698 -274.314578) (xy 286.258236 -274.335676) (xy 286.210965 -274.349368) (xy 286.16211 -274.3553)
			(xy 286.112935 -274.353319) (xy 286.064716 -274.343475) (xy 286.0187 -274.326023) (xy 285.976079 -274.301416)
			(xy 285.937958 -274.270291) (xy 285.905323 -274.233454) (xy 285.87902 -274.191858) (xy 285.859729 -274.146582)
			(xy 285.847952 -274.098798) (xy 285.843992 -274.049744) (xy 284.555184 -274.049744) (xy 284.554689 -274.074351)
			(xy 284.546794 -274.122928) (xy 284.53121 -274.169609) (xy 284.508339 -274.213186) (xy 284.478774 -274.25253)
			(xy 284.443281 -274.286622) (xy 284.402778 -274.314578) (xy 284.358316 -274.335676) (xy 284.311045 -274.349368)
			(xy 284.26219 -274.3553) (xy 284.213015 -274.353319) (xy 284.164796 -274.343475) (xy 284.11878 -274.326023)
			(xy 284.076159 -274.301416) (xy 284.038038 -274.270291) (xy 284.005403 -274.233454) (xy 283.9791 -274.191858)
			(xy 283.959809 -274.146582) (xy 283.948032 -274.098798) (xy 283.944072 -274.049744) (xy 282.65501 -274.049744)
			(xy 282.654515 -274.074351) (xy 282.64662 -274.122928) (xy 282.631036 -274.169609) (xy 282.608165 -274.213186)
			(xy 282.5786 -274.25253) (xy 282.543107 -274.286622) (xy 282.502604 -274.314578) (xy 282.458142 -274.335676)
			(xy 282.410871 -274.349368) (xy 282.362016 -274.3553) (xy 282.312841 -274.353319) (xy 282.264622 -274.343475)
			(xy 282.218606 -274.326023) (xy 282.175985 -274.301416) (xy 282.137864 -274.270291) (xy 282.105229 -274.233454)
			(xy 282.078926 -274.191858) (xy 282.059635 -274.146582) (xy 282.047858 -274.098798) (xy 282.043898 -274.049744)
			(xy 280.75509 -274.049744) (xy 280.754595 -274.074351) (xy 280.7467 -274.122928) (xy 280.731116 -274.169609)
			(xy 280.708245 -274.213186) (xy 280.67868 -274.25253) (xy 280.643187 -274.286622) (xy 280.602684 -274.314578)
			(xy 280.558222 -274.335676) (xy 280.510951 -274.349368) (xy 280.462096 -274.3553) (xy 280.412921 -274.353319)
			(xy 280.364702 -274.343475) (xy 280.318686 -274.326023) (xy 280.276065 -274.301416) (xy 280.237944 -274.270291)
			(xy 280.205309 -274.233454) (xy 280.179006 -274.191858) (xy 280.159715 -274.146582) (xy 280.147938 -274.098798)
			(xy 280.143978 -274.049744) (xy 278.85517 -274.049744) (xy 278.854675 -274.074351) (xy 278.84678 -274.122928)
			(xy 278.831196 -274.169609) (xy 278.808325 -274.213186) (xy 278.77876 -274.25253) (xy 278.743267 -274.286622)
			(xy 278.702764 -274.314578) (xy 278.658302 -274.335676) (xy 278.611031 -274.349368) (xy 278.562176 -274.3553)
			(xy 278.513001 -274.353319) (xy 278.464782 -274.343475) (xy 278.418766 -274.326023) (xy 278.376145 -274.301416)
			(xy 278.338024 -274.270291) (xy 278.305389 -274.233454) (xy 278.279086 -274.191858) (xy 278.259795 -274.146582)
			(xy 278.248018 -274.098798) (xy 278.244058 -274.049744) (xy 276.954996 -274.049744) (xy 276.954501 -274.074351)
			(xy 276.946606 -274.122928) (xy 276.931022 -274.169609) (xy 276.908151 -274.213186) (xy 276.878586 -274.25253)
			(xy 276.843093 -274.286622) (xy 276.80259 -274.314578) (xy 276.758128 -274.335676) (xy 276.710857 -274.349368)
			(xy 276.662002 -274.3553) (xy 276.612827 -274.353319) (xy 276.564608 -274.343475) (xy 276.518592 -274.326023)
			(xy 276.475971 -274.301416) (xy 276.43785 -274.270291) (xy 276.405215 -274.233454) (xy 276.378912 -274.191858)
			(xy 276.359621 -274.146582) (xy 276.347844 -274.098798) (xy 276.343884 -274.049744) (xy 174.155354 -274.049744)
			(xy 174.154859 -274.074351) (xy 174.146964 -274.122928) (xy 174.13138 -274.169609) (xy 174.108509 -274.213186)
			(xy 174.078944 -274.25253) (xy 174.043451 -274.286622) (xy 174.002948 -274.314578) (xy 173.958486 -274.335676)
			(xy 173.911215 -274.349368) (xy 173.86236 -274.3553) (xy 173.813185 -274.353319) (xy 173.764966 -274.343475)
			(xy 173.71895 -274.326023) (xy 173.676329 -274.301416) (xy 173.638208 -274.270291) (xy 173.605573 -274.233454)
			(xy 173.57927 -274.191858) (xy 173.559979 -274.146582) (xy 173.548202 -274.098798) (xy 173.544242 -274.049744)
			(xy 172.25518 -274.049744) (xy 172.254685 -274.074351) (xy 172.24679 -274.122928) (xy 172.231206 -274.169609)
			(xy 172.208335 -274.213186) (xy 172.17877 -274.25253) (xy 172.143277 -274.286622) (xy 172.102774 -274.314578)
			(xy 172.058312 -274.335676) (xy 172.011041 -274.349368) (xy 171.962186 -274.3553) (xy 171.913011 -274.353319)
			(xy 171.864792 -274.343475) (xy 171.818776 -274.326023) (xy 171.776155 -274.301416) (xy 171.738034 -274.270291)
			(xy 171.705399 -274.233454) (xy 171.679096 -274.191858) (xy 171.659805 -274.146582) (xy 171.648028 -274.098798)
			(xy 171.644068 -274.049744) (xy 170.35526 -274.049744) (xy 170.354765 -274.074351) (xy 170.34687 -274.122928)
			(xy 170.331286 -274.169609) (xy 170.308415 -274.213186) (xy 170.27885 -274.25253) (xy 170.243357 -274.286622)
			(xy 170.202854 -274.314578) (xy 170.158392 -274.335676) (xy 170.111121 -274.349368) (xy 170.062266 -274.3553)
			(xy 170.013091 -274.353319) (xy 169.964872 -274.343475) (xy 169.918856 -274.326023) (xy 169.876235 -274.301416)
			(xy 169.838114 -274.270291) (xy 169.805479 -274.233454) (xy 169.779176 -274.191858) (xy 169.759885 -274.146582)
			(xy 169.748108 -274.098798) (xy 169.744148 -274.049744) (xy 168.45534 -274.049744) (xy 168.454845 -274.074351)
			(xy 168.44695 -274.122928) (xy 168.431366 -274.169609) (xy 168.408495 -274.213186) (xy 168.37893 -274.25253)
			(xy 168.343437 -274.286622) (xy 168.302934 -274.314578) (xy 168.258472 -274.335676) (xy 168.211201 -274.349368)
			(xy 168.162346 -274.3553) (xy 168.113171 -274.353319) (xy 168.064952 -274.343475) (xy 168.018936 -274.326023)
			(xy 167.976315 -274.301416) (xy 167.938194 -274.270291) (xy 167.905559 -274.233454) (xy 167.879256 -274.191858)
			(xy 167.859965 -274.146582) (xy 167.848188 -274.098798) (xy 167.844228 -274.049744) (xy 166.555166 -274.049744)
			(xy 166.554671 -274.074351) (xy 166.546776 -274.122928) (xy 166.531192 -274.169609) (xy 166.508321 -274.213186)
			(xy 166.478756 -274.25253) (xy 166.443263 -274.286622) (xy 166.40276 -274.314578) (xy 166.358298 -274.335676)
			(xy 166.311027 -274.349368) (xy 166.262172 -274.3553) (xy 166.212997 -274.353319) (xy 166.164778 -274.343475)
			(xy 166.118762 -274.326023) (xy 166.076141 -274.301416) (xy 166.03802 -274.270291) (xy 166.005385 -274.233454)
			(xy 165.979082 -274.191858) (xy 165.959791 -274.146582) (xy 165.948014 -274.098798) (xy 165.944054 -274.049744)
			(xy 164.655246 -274.049744) (xy 164.654751 -274.074351) (xy 164.646856 -274.122928) (xy 164.631272 -274.169609)
			(xy 164.608401 -274.213186) (xy 164.578836 -274.25253) (xy 164.543343 -274.286622) (xy 164.50284 -274.314578)
			(xy 164.458378 -274.335676) (xy 164.411107 -274.349368) (xy 164.362252 -274.3553) (xy 164.313077 -274.353319)
			(xy 164.264858 -274.343475) (xy 164.218842 -274.326023) (xy 164.176221 -274.301416) (xy 164.1381 -274.270291)
			(xy 164.105465 -274.233454) (xy 164.079162 -274.191858) (xy 164.059871 -274.146582) (xy 164.048094 -274.098798)
			(xy 164.044134 -274.049744) (xy 162.755326 -274.049744) (xy 162.754831 -274.074351) (xy 162.746936 -274.122928)
			(xy 162.731352 -274.169609) (xy 162.708481 -274.213186) (xy 162.678916 -274.25253) (xy 162.643423 -274.286622)
			(xy 162.60292 -274.314578) (xy 162.558458 -274.335676) (xy 162.511187 -274.349368) (xy 162.462332 -274.3553)
			(xy 162.413157 -274.353319) (xy 162.364938 -274.343475) (xy 162.318922 -274.326023) (xy 162.276301 -274.301416)
			(xy 162.23818 -274.270291) (xy 162.205545 -274.233454) (xy 162.179242 -274.191858) (xy 162.159951 -274.146582)
			(xy 162.148174 -274.098798) (xy 162.144214 -274.049744) (xy 160.855152 -274.049744) (xy 160.854657 -274.074351)
			(xy 160.846762 -274.122928) (xy 160.831178 -274.169609) (xy 160.808307 -274.213186) (xy 160.778742 -274.25253)
			(xy 160.743249 -274.286622) (xy 160.702746 -274.314578) (xy 160.658284 -274.335676) (xy 160.611013 -274.349368)
			(xy 160.562158 -274.3553) (xy 160.512983 -274.353319) (xy 160.464764 -274.343475) (xy 160.418748 -274.326023)
			(xy 160.376127 -274.301416) (xy 160.338006 -274.270291) (xy 160.305371 -274.233454) (xy 160.279068 -274.191858)
			(xy 160.259777 -274.146582) (xy 160.248 -274.098798) (xy 160.24404 -274.049744) (xy 58.055256 -274.049744)
			(xy 58.054761 -274.074351) (xy 58.046866 -274.122928) (xy 58.031282 -274.169609) (xy 58.008411 -274.213186)
			(xy 57.978846 -274.25253) (xy 57.943353 -274.286622) (xy 57.90285 -274.314578) (xy 57.858388 -274.335676)
			(xy 57.811117 -274.349368) (xy 57.762262 -274.3553) (xy 57.713087 -274.353319) (xy 57.664868 -274.343475)
			(xy 57.618852 -274.326023) (xy 57.576231 -274.301416) (xy 57.53811 -274.270291) (xy 57.505475 -274.233454)
			(xy 57.479172 -274.191858) (xy 57.459881 -274.146582) (xy 57.448104 -274.098798) (xy 57.444144 -274.049744)
			(xy 56.155082 -274.049744) (xy 56.154587 -274.074351) (xy 56.146692 -274.122928) (xy 56.131108 -274.169609)
			(xy 56.108237 -274.213186) (xy 56.078672 -274.25253) (xy 56.043179 -274.286622) (xy 56.002676 -274.314578)
			(xy 55.958214 -274.335676) (xy 55.910943 -274.349368) (xy 55.862088 -274.3553) (xy 55.812913 -274.353319)
			(xy 55.764694 -274.343475) (xy 55.718678 -274.326023) (xy 55.676057 -274.301416) (xy 55.637936 -274.270291)
			(xy 55.605301 -274.233454) (xy 55.578998 -274.191858) (xy 55.559707 -274.146582) (xy 55.54793 -274.098798)
			(xy 55.54397 -274.049744) (xy 54.255162 -274.049744) (xy 54.254667 -274.074351) (xy 54.246772 -274.122928)
			(xy 54.231188 -274.169609) (xy 54.208317 -274.213186) (xy 54.178752 -274.25253) (xy 54.143259 -274.286622)
			(xy 54.102756 -274.314578) (xy 54.058294 -274.335676) (xy 54.011023 -274.349368) (xy 53.962168 -274.3553)
			(xy 53.912993 -274.353319) (xy 53.864774 -274.343475) (xy 53.818758 -274.326023) (xy 53.776137 -274.301416)
			(xy 53.738016 -274.270291) (xy 53.705381 -274.233454) (xy 53.679078 -274.191858) (xy 53.659787 -274.146582)
			(xy 53.64801 -274.098798) (xy 53.64405 -274.049744) (xy 52.355242 -274.049744) (xy 52.354747 -274.074351)
			(xy 52.346852 -274.122928) (xy 52.331268 -274.169609) (xy 52.308397 -274.213186) (xy 52.278832 -274.25253)
			(xy 52.243339 -274.286622) (xy 52.202836 -274.314578) (xy 52.158374 -274.335676) (xy 52.111103 -274.349368)
			(xy 52.062248 -274.3553) (xy 52.013073 -274.353319) (xy 51.964854 -274.343475) (xy 51.918838 -274.326023)
			(xy 51.876217 -274.301416) (xy 51.838096 -274.270291) (xy 51.805461 -274.233454) (xy 51.779158 -274.191858)
			(xy 51.759867 -274.146582) (xy 51.74809 -274.098798) (xy 51.74413 -274.049744) (xy 50.455068 -274.049744)
			(xy 50.454573 -274.074351) (xy 50.446678 -274.122928) (xy 50.431094 -274.169609) (xy 50.408223 -274.213186)
			(xy 50.378658 -274.25253) (xy 50.343165 -274.286622) (xy 50.302662 -274.314578) (xy 50.2582 -274.335676)
			(xy 50.210929 -274.349368) (xy 50.162074 -274.3553) (xy 50.112899 -274.353319) (xy 50.06468 -274.343475)
			(xy 50.018664 -274.326023) (xy 49.976043 -274.301416) (xy 49.937922 -274.270291) (xy 49.905287 -274.233454)
			(xy 49.878984 -274.191858) (xy 49.859693 -274.146582) (xy 49.847916 -274.098798) (xy 49.843956 -274.049744)
			(xy 48.555148 -274.049744) (xy 48.554653 -274.074351) (xy 48.546758 -274.122928) (xy 48.531174 -274.169609)
			(xy 48.508303 -274.213186) (xy 48.478738 -274.25253) (xy 48.443245 -274.286622) (xy 48.402742 -274.314578)
			(xy 48.35828 -274.335676) (xy 48.311009 -274.349368) (xy 48.262154 -274.3553) (xy 48.212979 -274.353319)
			(xy 48.16476 -274.343475) (xy 48.118744 -274.326023) (xy 48.076123 -274.301416) (xy 48.038002 -274.270291)
			(xy 48.005367 -274.233454) (xy 47.979064 -274.191858) (xy 47.959773 -274.146582) (xy 47.947996 -274.098798)
			(xy 47.944036 -274.049744) (xy 46.655228 -274.049744) (xy 46.654733 -274.074351) (xy 46.646838 -274.122928)
			(xy 46.631254 -274.169609) (xy 46.608383 -274.213186) (xy 46.578818 -274.25253) (xy 46.543325 -274.286622)
			(xy 46.502822 -274.314578) (xy 46.45836 -274.335676) (xy 46.411089 -274.349368) (xy 46.362234 -274.3553)
			(xy 46.313059 -274.353319) (xy 46.26484 -274.343475) (xy 46.218824 -274.326023) (xy 46.176203 -274.301416)
			(xy 46.138082 -274.270291) (xy 46.105447 -274.233454) (xy 46.079144 -274.191858) (xy 46.059853 -274.146582)
			(xy 46.048076 -274.098798) (xy 46.044116 -274.049744) (xy 44.755054 -274.049744) (xy 44.754559 -274.074351)
			(xy 44.746664 -274.122928) (xy 44.73108 -274.169609) (xy 44.708209 -274.213186) (xy 44.678644 -274.25253)
			(xy 44.643151 -274.286622) (xy 44.602648 -274.314578) (xy 44.558186 -274.335676) (xy 44.510915 -274.349368)
			(xy 44.46206 -274.3553) (xy 44.412885 -274.353319) (xy 44.364666 -274.343475) (xy 44.31865 -274.326023)
			(xy 44.276029 -274.301416) (xy 44.237908 -274.270291) (xy 44.205273 -274.233454) (xy 44.17897 -274.191858)
			(xy 44.159679 -274.146582) (xy 44.147902 -274.098798) (xy 44.143942 -274.049744) (xy 0.508 -274.049744)
			(xy 0.508 -274.999958) (xy 45.094156 -274.999958) (xy 45.098116 -274.950904) (xy 45.109893 -274.90312)
			(xy 45.129184 -274.857844) (xy 45.155487 -274.816248) (xy 45.188122 -274.779411) (xy 45.226243 -274.748286)
			(xy 45.268864 -274.723679) (xy 45.31488 -274.706227) (xy 45.363099 -274.696383) (xy 45.412274 -274.694402)
			(xy 45.461129 -274.700334) (xy 45.5084 -274.714026) (xy 45.552862 -274.735124) (xy 45.593365 -274.76308)
			(xy 45.628858 -274.797172) (xy 45.658423 -274.836516) (xy 45.681294 -274.880093) (xy 45.696878 -274.926774)
			(xy 45.704773 -274.975351) (xy 45.705268 -274.999958) (xy 46.994076 -274.999958) (xy 46.998036 -274.950904)
			(xy 47.009813 -274.90312) (xy 47.029104 -274.857844) (xy 47.055407 -274.816248) (xy 47.088042 -274.779411)
			(xy 47.126163 -274.748286) (xy 47.168784 -274.723679) (xy 47.2148 -274.706227) (xy 47.263019 -274.696383)
			(xy 47.312194 -274.694402) (xy 47.361049 -274.700334) (xy 47.40832 -274.714026) (xy 47.452782 -274.735124)
			(xy 47.493285 -274.76308) (xy 47.528778 -274.797172) (xy 47.558343 -274.836516) (xy 47.581214 -274.880093)
			(xy 47.596798 -274.926774) (xy 47.604693 -274.975351) (xy 47.605188 -274.999958) (xy 48.893996 -274.999958)
			(xy 48.897956 -274.950904) (xy 48.909733 -274.90312) (xy 48.929024 -274.857844) (xy 48.955327 -274.816248)
			(xy 48.987962 -274.779411) (xy 49.026083 -274.748286) (xy 49.068704 -274.723679) (xy 49.11472 -274.706227)
			(xy 49.162939 -274.696383) (xy 49.212114 -274.694402) (xy 49.260969 -274.700334) (xy 49.30824 -274.714026)
			(xy 49.352702 -274.735124) (xy 49.393205 -274.76308) (xy 49.428698 -274.797172) (xy 49.458263 -274.836516)
			(xy 49.481134 -274.880093) (xy 49.496718 -274.926774) (xy 49.504613 -274.975351) (xy 49.505108 -274.999958)
			(xy 50.79417 -274.999958) (xy 50.79813 -274.950904) (xy 50.809907 -274.90312) (xy 50.829198 -274.857844)
			(xy 50.855501 -274.816248) (xy 50.888136 -274.779411) (xy 50.926257 -274.748286) (xy 50.968878 -274.723679)
			(xy 51.014894 -274.706227) (xy 51.063113 -274.696383) (xy 51.112288 -274.694402) (xy 51.161143 -274.700334)
			(xy 51.208414 -274.714026) (xy 51.252876 -274.735124) (xy 51.293379 -274.76308) (xy 51.328872 -274.797172)
			(xy 51.358437 -274.836516) (xy 51.381308 -274.880093) (xy 51.396892 -274.926774) (xy 51.404787 -274.975351)
			(xy 51.405282 -274.999958) (xy 52.69409 -274.999958) (xy 52.69805 -274.950904) (xy 52.709827 -274.90312)
			(xy 52.729118 -274.857844) (xy 52.755421 -274.816248) (xy 52.788056 -274.779411) (xy 52.826177 -274.748286)
			(xy 52.868798 -274.723679) (xy 52.914814 -274.706227) (xy 52.963033 -274.696383) (xy 53.012208 -274.694402)
			(xy 53.061063 -274.700334) (xy 53.108334 -274.714026) (xy 53.152796 -274.735124) (xy 53.193299 -274.76308)
			(xy 53.228792 -274.797172) (xy 53.258357 -274.836516) (xy 53.281228 -274.880093) (xy 53.296812 -274.926774)
			(xy 53.304707 -274.975351) (xy 53.305202 -274.999958) (xy 54.59401 -274.999958) (xy 54.59797 -274.950904)
			(xy 54.609747 -274.90312) (xy 54.629038 -274.857844) (xy 54.655341 -274.816248) (xy 54.687976 -274.779411)
			(xy 54.726097 -274.748286) (xy 54.768718 -274.723679) (xy 54.814734 -274.706227) (xy 54.862953 -274.696383)
			(xy 54.912128 -274.694402) (xy 54.960983 -274.700334) (xy 55.008254 -274.714026) (xy 55.052716 -274.735124)
			(xy 55.093219 -274.76308) (xy 55.128712 -274.797172) (xy 55.158277 -274.836516) (xy 55.181148 -274.880093)
			(xy 55.196732 -274.926774) (xy 55.204627 -274.975351) (xy 55.205122 -274.999958) (xy 56.494184 -274.999958)
			(xy 56.498144 -274.950904) (xy 56.509921 -274.90312) (xy 56.529212 -274.857844) (xy 56.555515 -274.816248)
			(xy 56.58815 -274.779411) (xy 56.626271 -274.748286) (xy 56.668892 -274.723679) (xy 56.714908 -274.706227)
			(xy 56.763127 -274.696383) (xy 56.812302 -274.694402) (xy 56.861157 -274.700334) (xy 56.908428 -274.714026)
			(xy 56.95289 -274.735124) (xy 56.993393 -274.76308) (xy 57.028886 -274.797172) (xy 57.058451 -274.836516)
			(xy 57.081322 -274.880093) (xy 57.096906 -274.926774) (xy 57.104801 -274.975351) (xy 57.105296 -274.999958)
			(xy 58.394104 -274.999958) (xy 58.398064 -274.950904) (xy 58.409841 -274.90312) (xy 58.429132 -274.857844)
			(xy 58.455435 -274.816248) (xy 58.48807 -274.779411) (xy 58.526191 -274.748286) (xy 58.568812 -274.723679)
			(xy 58.614828 -274.706227) (xy 58.663047 -274.696383) (xy 58.712222 -274.694402) (xy 58.761077 -274.700334)
			(xy 58.808348 -274.714026) (xy 58.85281 -274.735124) (xy 58.893313 -274.76308) (xy 58.928806 -274.797172)
			(xy 58.958371 -274.836516) (xy 58.981242 -274.880093) (xy 58.996826 -274.926774) (xy 59.004721 -274.975351)
			(xy 59.005216 -274.999958) (xy 161.194254 -274.999958) (xy 161.198214 -274.950904) (xy 161.209991 -274.90312)
			(xy 161.229282 -274.857844) (xy 161.255585 -274.816248) (xy 161.28822 -274.779411) (xy 161.326341 -274.748286)
			(xy 161.368962 -274.723679) (xy 161.414978 -274.706227) (xy 161.463197 -274.696383) (xy 161.512372 -274.694402)
			(xy 161.561227 -274.700334) (xy 161.608498 -274.714026) (xy 161.65296 -274.735124) (xy 161.693463 -274.76308)
			(xy 161.728956 -274.797172) (xy 161.758521 -274.836516) (xy 161.781392 -274.880093) (xy 161.796976 -274.926774)
			(xy 161.804871 -274.975351) (xy 161.805366 -274.999958) (xy 163.094174 -274.999958) (xy 163.098134 -274.950904)
			(xy 163.109911 -274.90312) (xy 163.129202 -274.857844) (xy 163.155505 -274.816248) (xy 163.18814 -274.779411)
			(xy 163.226261 -274.748286) (xy 163.268882 -274.723679) (xy 163.314898 -274.706227) (xy 163.363117 -274.696383)
			(xy 163.412292 -274.694402) (xy 163.461147 -274.700334) (xy 163.508418 -274.714026) (xy 163.55288 -274.735124)
			(xy 163.593383 -274.76308) (xy 163.628876 -274.797172) (xy 163.658441 -274.836516) (xy 163.681312 -274.880093)
			(xy 163.696896 -274.926774) (xy 163.704791 -274.975351) (xy 163.705286 -274.999958) (xy 164.994094 -274.999958)
			(xy 164.998054 -274.950904) (xy 165.009831 -274.90312) (xy 165.029122 -274.857844) (xy 165.055425 -274.816248)
			(xy 165.08806 -274.779411) (xy 165.126181 -274.748286) (xy 165.168802 -274.723679) (xy 165.214818 -274.706227)
			(xy 165.263037 -274.696383) (xy 165.312212 -274.694402) (xy 165.361067 -274.700334) (xy 165.408338 -274.714026)
			(xy 165.4528 -274.735124) (xy 165.493303 -274.76308) (xy 165.528796 -274.797172) (xy 165.558361 -274.836516)
			(xy 165.581232 -274.880093) (xy 165.596816 -274.926774) (xy 165.604711 -274.975351) (xy 165.605206 -274.999958)
			(xy 166.894268 -274.999958) (xy 166.898228 -274.950904) (xy 166.910005 -274.90312) (xy 166.929296 -274.857844)
			(xy 166.955599 -274.816248) (xy 166.988234 -274.779411) (xy 167.026355 -274.748286) (xy 167.068976 -274.723679)
			(xy 167.114992 -274.706227) (xy 167.163211 -274.696383) (xy 167.212386 -274.694402) (xy 167.261241 -274.700334)
			(xy 167.308512 -274.714026) (xy 167.352974 -274.735124) (xy 167.393477 -274.76308) (xy 167.42897 -274.797172)
			(xy 167.458535 -274.836516) (xy 167.481406 -274.880093) (xy 167.49699 -274.926774) (xy 167.504885 -274.975351)
			(xy 167.50538 -274.999958) (xy 168.794188 -274.999958) (xy 168.798148 -274.950904) (xy 168.809925 -274.90312)
			(xy 168.829216 -274.857844) (xy 168.855519 -274.816248) (xy 168.888154 -274.779411) (xy 168.926275 -274.748286)
			(xy 168.968896 -274.723679) (xy 169.014912 -274.706227) (xy 169.063131 -274.696383) (xy 169.112306 -274.694402)
			(xy 169.161161 -274.700334) (xy 169.208432 -274.714026) (xy 169.252894 -274.735124) (xy 169.293397 -274.76308)
			(xy 169.32889 -274.797172) (xy 169.358455 -274.836516) (xy 169.381326 -274.880093) (xy 169.39691 -274.926774)
			(xy 169.404805 -274.975351) (xy 169.4053 -274.999958) (xy 170.694108 -274.999958) (xy 170.698068 -274.950904)
			(xy 170.709845 -274.90312) (xy 170.729136 -274.857844) (xy 170.755439 -274.816248) (xy 170.788074 -274.779411)
			(xy 170.826195 -274.748286) (xy 170.868816 -274.723679) (xy 170.914832 -274.706227) (xy 170.963051 -274.696383)
			(xy 171.012226 -274.694402) (xy 171.061081 -274.700334) (xy 171.108352 -274.714026) (xy 171.152814 -274.735124)
			(xy 171.193317 -274.76308) (xy 171.22881 -274.797172) (xy 171.258375 -274.836516) (xy 171.281246 -274.880093)
			(xy 171.29683 -274.926774) (xy 171.304725 -274.975351) (xy 171.30522 -274.999958) (xy 172.594282 -274.999958)
			(xy 172.598242 -274.950904) (xy 172.610019 -274.90312) (xy 172.62931 -274.857844) (xy 172.655613 -274.816248)
			(xy 172.688248 -274.779411) (xy 172.726369 -274.748286) (xy 172.76899 -274.723679) (xy 172.815006 -274.706227)
			(xy 172.863225 -274.696383) (xy 172.9124 -274.694402) (xy 172.961255 -274.700334) (xy 173.008526 -274.714026)
			(xy 173.052988 -274.735124) (xy 173.093491 -274.76308) (xy 173.128984 -274.797172) (xy 173.158549 -274.836516)
			(xy 173.18142 -274.880093) (xy 173.197004 -274.926774) (xy 173.204899 -274.975351) (xy 173.205394 -274.999958)
			(xy 174.494202 -274.999958) (xy 174.498162 -274.950904) (xy 174.509939 -274.90312) (xy 174.52923 -274.857844)
			(xy 174.555533 -274.816248) (xy 174.588168 -274.779411) (xy 174.626289 -274.748286) (xy 174.66891 -274.723679)
			(xy 174.714926 -274.706227) (xy 174.763145 -274.696383) (xy 174.81232 -274.694402) (xy 174.861175 -274.700334)
			(xy 174.908446 -274.714026) (xy 174.952908 -274.735124) (xy 174.993411 -274.76308) (xy 175.028904 -274.797172)
			(xy 175.058469 -274.836516) (xy 175.08134 -274.880093) (xy 175.096924 -274.926774) (xy 175.104819 -274.975351)
			(xy 175.105314 -274.999958) (xy 277.294098 -274.999958) (xy 277.298058 -274.950904) (xy 277.309835 -274.90312)
			(xy 277.329126 -274.857844) (xy 277.355429 -274.816248) (xy 277.388064 -274.779411) (xy 277.426185 -274.748286)
			(xy 277.468806 -274.723679) (xy 277.514822 -274.706227) (xy 277.563041 -274.696383) (xy 277.612216 -274.694402)
			(xy 277.661071 -274.700334) (xy 277.708342 -274.714026) (xy 277.752804 -274.735124) (xy 277.793307 -274.76308)
			(xy 277.8288 -274.797172) (xy 277.858365 -274.836516) (xy 277.881236 -274.880093) (xy 277.89682 -274.926774)
			(xy 277.904715 -274.975351) (xy 277.90521 -274.999958) (xy 279.194018 -274.999958) (xy 279.197978 -274.950904)
			(xy 279.209755 -274.90312) (xy 279.229046 -274.857844) (xy 279.255349 -274.816248) (xy 279.287984 -274.779411)
			(xy 279.326105 -274.748286) (xy 279.368726 -274.723679) (xy 279.414742 -274.706227) (xy 279.462961 -274.696383)
			(xy 279.512136 -274.694402) (xy 279.560991 -274.700334) (xy 279.608262 -274.714026) (xy 279.652724 -274.735124)
			(xy 279.693227 -274.76308) (xy 279.72872 -274.797172) (xy 279.758285 -274.836516) (xy 279.781156 -274.880093)
			(xy 279.79674 -274.926774) (xy 279.804635 -274.975351) (xy 279.80513 -274.999958) (xy 281.093938 -274.999958)
			(xy 281.097898 -274.950904) (xy 281.109675 -274.90312) (xy 281.128966 -274.857844) (xy 281.155269 -274.816248)
			(xy 281.187904 -274.779411) (xy 281.226025 -274.748286) (xy 281.268646 -274.723679) (xy 281.314662 -274.706227)
			(xy 281.362881 -274.696383) (xy 281.412056 -274.694402) (xy 281.460911 -274.700334) (xy 281.508182 -274.714026)
			(xy 281.552644 -274.735124) (xy 281.593147 -274.76308) (xy 281.62864 -274.797172) (xy 281.658205 -274.836516)
			(xy 281.681076 -274.880093) (xy 281.69666 -274.926774) (xy 281.704555 -274.975351) (xy 281.70505 -274.999958)
			(xy 282.994112 -274.999958) (xy 282.998072 -274.950904) (xy 283.009849 -274.90312) (xy 283.02914 -274.857844)
			(xy 283.055443 -274.816248) (xy 283.088078 -274.779411) (xy 283.126199 -274.748286) (xy 283.16882 -274.723679)
			(xy 283.214836 -274.706227) (xy 283.263055 -274.696383) (xy 283.31223 -274.694402) (xy 283.361085 -274.700334)
			(xy 283.408356 -274.714026) (xy 283.452818 -274.735124) (xy 283.493321 -274.76308) (xy 283.528814 -274.797172)
			(xy 283.558379 -274.836516) (xy 283.58125 -274.880093) (xy 283.596834 -274.926774) (xy 283.604729 -274.975351)
			(xy 283.605224 -274.999958) (xy 284.894032 -274.999958) (xy 284.897992 -274.950904) (xy 284.909769 -274.90312)
			(xy 284.92906 -274.857844) (xy 284.955363 -274.816248) (xy 284.987998 -274.779411) (xy 285.026119 -274.748286)
			(xy 285.06874 -274.723679) (xy 285.114756 -274.706227) (xy 285.162975 -274.696383) (xy 285.21215 -274.694402)
			(xy 285.261005 -274.700334) (xy 285.308276 -274.714026) (xy 285.352738 -274.735124) (xy 285.393241 -274.76308)
			(xy 285.428734 -274.797172) (xy 285.458299 -274.836516) (xy 285.48117 -274.880093) (xy 285.496754 -274.926774)
			(xy 285.504649 -274.975351) (xy 285.505144 -274.999958) (xy 286.793952 -274.999958) (xy 286.797912 -274.950904)
			(xy 286.809689 -274.90312) (xy 286.82898 -274.857844) (xy 286.855283 -274.816248) (xy 286.887918 -274.779411)
			(xy 286.926039 -274.748286) (xy 286.96866 -274.723679) (xy 287.014676 -274.706227) (xy 287.062895 -274.696383)
			(xy 287.11207 -274.694402) (xy 287.160925 -274.700334) (xy 287.208196 -274.714026) (xy 287.252658 -274.735124)
			(xy 287.293161 -274.76308) (xy 287.328654 -274.797172) (xy 287.358219 -274.836516) (xy 287.38109 -274.880093)
			(xy 287.396674 -274.926774) (xy 287.404569 -274.975351) (xy 287.405064 -274.999958) (xy 288.694126 -274.999958)
			(xy 288.698086 -274.950904) (xy 288.709863 -274.90312) (xy 288.729154 -274.857844) (xy 288.755457 -274.816248)
			(xy 288.788092 -274.779411) (xy 288.826213 -274.748286) (xy 288.868834 -274.723679) (xy 288.91485 -274.706227)
			(xy 288.963069 -274.696383) (xy 289.012244 -274.694402) (xy 289.061099 -274.700334) (xy 289.10837 -274.714026)
			(xy 289.152832 -274.735124) (xy 289.193335 -274.76308) (xy 289.228828 -274.797172) (xy 289.258393 -274.836516)
			(xy 289.281264 -274.880093) (xy 289.296848 -274.926774) (xy 289.304743 -274.975351) (xy 289.305238 -274.999958)
			(xy 290.594046 -274.999958) (xy 290.598006 -274.950904) (xy 290.609783 -274.90312) (xy 290.629074 -274.857844)
			(xy 290.655377 -274.816248) (xy 290.688012 -274.779411) (xy 290.726133 -274.748286) (xy 290.768754 -274.723679)
			(xy 290.81477 -274.706227) (xy 290.862989 -274.696383) (xy 290.912164 -274.694402) (xy 290.961019 -274.700334)
			(xy 291.00829 -274.714026) (xy 291.052752 -274.735124) (xy 291.093255 -274.76308) (xy 291.128748 -274.797172)
			(xy 291.158313 -274.836516) (xy 291.181184 -274.880093) (xy 291.196768 -274.926774) (xy 291.204663 -274.975351)
			(xy 291.205158 -274.999958) (xy 393.394196 -274.999958) (xy 393.398156 -274.950904) (xy 393.409933 -274.90312)
			(xy 393.429224 -274.857844) (xy 393.455527 -274.816248) (xy 393.488162 -274.779411) (xy 393.526283 -274.748286)
			(xy 393.568904 -274.723679) (xy 393.61492 -274.706227) (xy 393.663139 -274.696383) (xy 393.712314 -274.694402)
			(xy 393.761169 -274.700334) (xy 393.80844 -274.714026) (xy 393.852902 -274.735124) (xy 393.893405 -274.76308)
			(xy 393.928898 -274.797172) (xy 393.958463 -274.836516) (xy 393.981334 -274.880093) (xy 393.996918 -274.926774)
			(xy 394.004813 -274.975351) (xy 394.005308 -274.999958) (xy 395.294116 -274.999958) (xy 395.298076 -274.950904)
			(xy 395.309853 -274.90312) (xy 395.329144 -274.857844) (xy 395.355447 -274.816248) (xy 395.388082 -274.779411)
			(xy 395.426203 -274.748286) (xy 395.468824 -274.723679) (xy 395.51484 -274.706227) (xy 395.563059 -274.696383)
			(xy 395.612234 -274.694402) (xy 395.661089 -274.700334) (xy 395.70836 -274.714026) (xy 395.752822 -274.735124)
			(xy 395.793325 -274.76308) (xy 395.828818 -274.797172) (xy 395.858383 -274.836516) (xy 395.881254 -274.880093)
			(xy 395.896838 -274.926774) (xy 395.904733 -274.975351) (xy 395.905228 -274.999958) (xy 397.194036 -274.999958)
			(xy 397.197996 -274.950904) (xy 397.209773 -274.90312) (xy 397.229064 -274.857844) (xy 397.255367 -274.816248)
			(xy 397.288002 -274.779411) (xy 397.326123 -274.748286) (xy 397.368744 -274.723679) (xy 397.41476 -274.706227)
			(xy 397.462979 -274.696383) (xy 397.512154 -274.694402) (xy 397.561009 -274.700334) (xy 397.60828 -274.714026)
			(xy 397.652742 -274.735124) (xy 397.693245 -274.76308) (xy 397.728738 -274.797172) (xy 397.758303 -274.836516)
			(xy 397.781174 -274.880093) (xy 397.796758 -274.926774) (xy 397.804653 -274.975351) (xy 397.805148 -274.999958)
			(xy 399.09421 -274.999958) (xy 399.09817 -274.950904) (xy 399.109947 -274.90312) (xy 399.129238 -274.857844)
			(xy 399.155541 -274.816248) (xy 399.188176 -274.779411) (xy 399.226297 -274.748286) (xy 399.268918 -274.723679)
			(xy 399.314934 -274.706227) (xy 399.363153 -274.696383) (xy 399.412328 -274.694402) (xy 399.461183 -274.700334)
			(xy 399.508454 -274.714026) (xy 399.552916 -274.735124) (xy 399.593419 -274.76308) (xy 399.628912 -274.797172)
			(xy 399.658477 -274.836516) (xy 399.681348 -274.880093) (xy 399.696932 -274.926774) (xy 399.704827 -274.975351)
			(xy 399.705322 -274.999958) (xy 400.99413 -274.999958) (xy 400.99809 -274.950904) (xy 401.009867 -274.90312)
			(xy 401.029158 -274.857844) (xy 401.055461 -274.816248) (xy 401.088096 -274.779411) (xy 401.126217 -274.748286)
			(xy 401.168838 -274.723679) (xy 401.214854 -274.706227) (xy 401.263073 -274.696383) (xy 401.312248 -274.694402)
			(xy 401.361103 -274.700334) (xy 401.408374 -274.714026) (xy 401.452836 -274.735124) (xy 401.493339 -274.76308)
			(xy 401.528832 -274.797172) (xy 401.558397 -274.836516) (xy 401.581268 -274.880093) (xy 401.596852 -274.926774)
			(xy 401.604747 -274.975351) (xy 401.605242 -274.999958) (xy 402.89405 -274.999958) (xy 402.89801 -274.950904)
			(xy 402.909787 -274.90312) (xy 402.929078 -274.857844) (xy 402.955381 -274.816248) (xy 402.988016 -274.779411)
			(xy 403.026137 -274.748286) (xy 403.068758 -274.723679) (xy 403.114774 -274.706227) (xy 403.162993 -274.696383)
			(xy 403.212168 -274.694402) (xy 403.261023 -274.700334) (xy 403.308294 -274.714026) (xy 403.352756 -274.735124)
			(xy 403.393259 -274.76308) (xy 403.428752 -274.797172) (xy 403.458317 -274.836516) (xy 403.481188 -274.880093)
			(xy 403.496772 -274.926774) (xy 403.504667 -274.975351) (xy 403.505162 -274.999958) (xy 404.794224 -274.999958)
			(xy 404.798184 -274.950904) (xy 404.809961 -274.90312) (xy 404.829252 -274.857844) (xy 404.855555 -274.816248)
			(xy 404.88819 -274.779411) (xy 404.926311 -274.748286) (xy 404.968932 -274.723679) (xy 405.014948 -274.706227)
			(xy 405.063167 -274.696383) (xy 405.112342 -274.694402) (xy 405.161197 -274.700334) (xy 405.208468 -274.714026)
			(xy 405.25293 -274.735124) (xy 405.293433 -274.76308) (xy 405.328926 -274.797172) (xy 405.358491 -274.836516)
			(xy 405.381362 -274.880093) (xy 405.396946 -274.926774) (xy 405.404841 -274.975351) (xy 405.405336 -274.999958)
			(xy 406.694144 -274.999958) (xy 406.698104 -274.950904) (xy 406.709881 -274.90312) (xy 406.729172 -274.857844)
			(xy 406.755475 -274.816248) (xy 406.78811 -274.779411) (xy 406.826231 -274.748286) (xy 406.868852 -274.723679)
			(xy 406.914868 -274.706227) (xy 406.963087 -274.696383) (xy 407.012262 -274.694402) (xy 407.061117 -274.700334)
			(xy 407.108388 -274.714026) (xy 407.15285 -274.735124) (xy 407.193353 -274.76308) (xy 407.228846 -274.797172)
			(xy 407.258411 -274.836516) (xy 407.281282 -274.880093) (xy 407.296866 -274.926774) (xy 407.304761 -274.975351)
			(xy 407.305256 -274.999958) (xy 407.304761 -275.024565) (xy 407.296866 -275.073142) (xy 407.281282 -275.119823)
			(xy 407.258411 -275.1634) (xy 407.228846 -275.202744) (xy 407.193353 -275.236836) (xy 407.15285 -275.264792)
			(xy 407.108388 -275.28589) (xy 407.061117 -275.299582) (xy 407.012262 -275.305514) (xy 406.963087 -275.303533)
			(xy 406.914868 -275.293689) (xy 406.868852 -275.276237) (xy 406.826231 -275.25163) (xy 406.78811 -275.220505)
			(xy 406.755475 -275.183668) (xy 406.729172 -275.142072) (xy 406.709881 -275.096796) (xy 406.698104 -275.049012)
			(xy 406.694144 -274.999958) (xy 405.405336 -274.999958) (xy 405.404841 -275.024565) (xy 405.396946 -275.073142)
			(xy 405.381362 -275.119823) (xy 405.358491 -275.1634) (xy 405.328926 -275.202744) (xy 405.293433 -275.236836)
			(xy 405.25293 -275.264792) (xy 405.208468 -275.28589) (xy 405.161197 -275.299582) (xy 405.112342 -275.305514)
			(xy 405.063167 -275.303533) (xy 405.014948 -275.293689) (xy 404.968932 -275.276237) (xy 404.926311 -275.25163)
			(xy 404.88819 -275.220505) (xy 404.855555 -275.183668) (xy 404.829252 -275.142072) (xy 404.809961 -275.096796)
			(xy 404.798184 -275.049012) (xy 404.794224 -274.999958) (xy 403.505162 -274.999958) (xy 403.504667 -275.024565)
			(xy 403.496772 -275.073142) (xy 403.481188 -275.119823) (xy 403.458317 -275.1634) (xy 403.428752 -275.202744)
			(xy 403.393259 -275.236836) (xy 403.352756 -275.264792) (xy 403.308294 -275.28589) (xy 403.261023 -275.299582)
			(xy 403.212168 -275.305514) (xy 403.162993 -275.303533) (xy 403.114774 -275.293689) (xy 403.068758 -275.276237)
			(xy 403.026137 -275.25163) (xy 402.988016 -275.220505) (xy 402.955381 -275.183668) (xy 402.929078 -275.142072)
			(xy 402.909787 -275.096796) (xy 402.89801 -275.049012) (xy 402.89405 -274.999958) (xy 401.605242 -274.999958)
			(xy 401.604747 -275.024565) (xy 401.596852 -275.073142) (xy 401.581268 -275.119823) (xy 401.558397 -275.1634)
			(xy 401.528832 -275.202744) (xy 401.493339 -275.236836) (xy 401.452836 -275.264792) (xy 401.408374 -275.28589)
			(xy 401.361103 -275.299582) (xy 401.312248 -275.305514) (xy 401.263073 -275.303533) (xy 401.214854 -275.293689)
			(xy 401.168838 -275.276237) (xy 401.126217 -275.25163) (xy 401.088096 -275.220505) (xy 401.055461 -275.183668)
			(xy 401.029158 -275.142072) (xy 401.009867 -275.096796) (xy 400.99809 -275.049012) (xy 400.99413 -274.999958)
			(xy 399.705322 -274.999958) (xy 399.704827 -275.024565) (xy 399.696932 -275.073142) (xy 399.681348 -275.119823)
			(xy 399.658477 -275.1634) (xy 399.628912 -275.202744) (xy 399.593419 -275.236836) (xy 399.552916 -275.264792)
			(xy 399.508454 -275.28589) (xy 399.461183 -275.299582) (xy 399.412328 -275.305514) (xy 399.363153 -275.303533)
			(xy 399.314934 -275.293689) (xy 399.268918 -275.276237) (xy 399.226297 -275.25163) (xy 399.188176 -275.220505)
			(xy 399.155541 -275.183668) (xy 399.129238 -275.142072) (xy 399.109947 -275.096796) (xy 399.09817 -275.049012)
			(xy 399.09421 -274.999958) (xy 397.805148 -274.999958) (xy 397.804653 -275.024565) (xy 397.796758 -275.073142)
			(xy 397.781174 -275.119823) (xy 397.758303 -275.1634) (xy 397.728738 -275.202744) (xy 397.693245 -275.236836)
			(xy 397.652742 -275.264792) (xy 397.60828 -275.28589) (xy 397.561009 -275.299582) (xy 397.512154 -275.305514)
			(xy 397.462979 -275.303533) (xy 397.41476 -275.293689) (xy 397.368744 -275.276237) (xy 397.326123 -275.25163)
			(xy 397.288002 -275.220505) (xy 397.255367 -275.183668) (xy 397.229064 -275.142072) (xy 397.209773 -275.096796)
			(xy 397.197996 -275.049012) (xy 397.194036 -274.999958) (xy 395.905228 -274.999958) (xy 395.904733 -275.024565)
			(xy 395.896838 -275.073142) (xy 395.881254 -275.119823) (xy 395.858383 -275.1634) (xy 395.828818 -275.202744)
			(xy 395.793325 -275.236836) (xy 395.752822 -275.264792) (xy 395.70836 -275.28589) (xy 395.661089 -275.299582)
			(xy 395.612234 -275.305514) (xy 395.563059 -275.303533) (xy 395.51484 -275.293689) (xy 395.468824 -275.276237)
			(xy 395.426203 -275.25163) (xy 395.388082 -275.220505) (xy 395.355447 -275.183668) (xy 395.329144 -275.142072)
			(xy 395.309853 -275.096796) (xy 395.298076 -275.049012) (xy 395.294116 -274.999958) (xy 394.005308 -274.999958)
			(xy 394.004813 -275.024565) (xy 393.996918 -275.073142) (xy 393.981334 -275.119823) (xy 393.958463 -275.1634)
			(xy 393.928898 -275.202744) (xy 393.893405 -275.236836) (xy 393.852902 -275.264792) (xy 393.80844 -275.28589)
			(xy 393.761169 -275.299582) (xy 393.712314 -275.305514) (xy 393.663139 -275.303533) (xy 393.61492 -275.293689)
			(xy 393.568904 -275.276237) (xy 393.526283 -275.25163) (xy 393.488162 -275.220505) (xy 393.455527 -275.183668)
			(xy 393.429224 -275.142072) (xy 393.409933 -275.096796) (xy 393.398156 -275.049012) (xy 393.394196 -274.999958)
			(xy 291.205158 -274.999958) (xy 291.204663 -275.024565) (xy 291.196768 -275.073142) (xy 291.181184 -275.119823)
			(xy 291.158313 -275.1634) (xy 291.128748 -275.202744) (xy 291.093255 -275.236836) (xy 291.052752 -275.264792)
			(xy 291.00829 -275.28589) (xy 290.961019 -275.299582) (xy 290.912164 -275.305514) (xy 290.862989 -275.303533)
			(xy 290.81477 -275.293689) (xy 290.768754 -275.276237) (xy 290.726133 -275.25163) (xy 290.688012 -275.220505)
			(xy 290.655377 -275.183668) (xy 290.629074 -275.142072) (xy 290.609783 -275.096796) (xy 290.598006 -275.049012)
			(xy 290.594046 -274.999958) (xy 289.305238 -274.999958) (xy 289.304743 -275.024565) (xy 289.296848 -275.073142)
			(xy 289.281264 -275.119823) (xy 289.258393 -275.1634) (xy 289.228828 -275.202744) (xy 289.193335 -275.236836)
			(xy 289.152832 -275.264792) (xy 289.10837 -275.28589) (xy 289.061099 -275.299582) (xy 289.012244 -275.305514)
			(xy 288.963069 -275.303533) (xy 288.91485 -275.293689) (xy 288.868834 -275.276237) (xy 288.826213 -275.25163)
			(xy 288.788092 -275.220505) (xy 288.755457 -275.183668) (xy 288.729154 -275.142072) (xy 288.709863 -275.096796)
			(xy 288.698086 -275.049012) (xy 288.694126 -274.999958) (xy 287.405064 -274.999958) (xy 287.404569 -275.024565)
			(xy 287.396674 -275.073142) (xy 287.38109 -275.119823) (xy 287.358219 -275.1634) (xy 287.328654 -275.202744)
			(xy 287.293161 -275.236836) (xy 287.252658 -275.264792) (xy 287.208196 -275.28589) (xy 287.160925 -275.299582)
			(xy 287.11207 -275.305514) (xy 287.062895 -275.303533) (xy 287.014676 -275.293689) (xy 286.96866 -275.276237)
			(xy 286.926039 -275.25163) (xy 286.887918 -275.220505) (xy 286.855283 -275.183668) (xy 286.82898 -275.142072)
			(xy 286.809689 -275.096796) (xy 286.797912 -275.049012) (xy 286.793952 -274.999958) (xy 285.505144 -274.999958)
			(xy 285.504649 -275.024565) (xy 285.496754 -275.073142) (xy 285.48117 -275.119823) (xy 285.458299 -275.1634)
			(xy 285.428734 -275.202744) (xy 285.393241 -275.236836) (xy 285.352738 -275.264792) (xy 285.308276 -275.28589)
			(xy 285.261005 -275.299582) (xy 285.21215 -275.305514) (xy 285.162975 -275.303533) (xy 285.114756 -275.293689)
			(xy 285.06874 -275.276237) (xy 285.026119 -275.25163) (xy 284.987998 -275.220505) (xy 284.955363 -275.183668)
			(xy 284.92906 -275.142072) (xy 284.909769 -275.096796) (xy 284.897992 -275.049012) (xy 284.894032 -274.999958)
			(xy 283.605224 -274.999958) (xy 283.604729 -275.024565) (xy 283.596834 -275.073142) (xy 283.58125 -275.119823)
			(xy 283.558379 -275.1634) (xy 283.528814 -275.202744) (xy 283.493321 -275.236836) (xy 283.452818 -275.264792)
			(xy 283.408356 -275.28589) (xy 283.361085 -275.299582) (xy 283.31223 -275.305514) (xy 283.263055 -275.303533)
			(xy 283.214836 -275.293689) (xy 283.16882 -275.276237) (xy 283.126199 -275.25163) (xy 283.088078 -275.220505)
			(xy 283.055443 -275.183668) (xy 283.02914 -275.142072) (xy 283.009849 -275.096796) (xy 282.998072 -275.049012)
			(xy 282.994112 -274.999958) (xy 281.70505 -274.999958) (xy 281.704555 -275.024565) (xy 281.69666 -275.073142)
			(xy 281.681076 -275.119823) (xy 281.658205 -275.1634) (xy 281.62864 -275.202744) (xy 281.593147 -275.236836)
			(xy 281.552644 -275.264792) (xy 281.508182 -275.28589) (xy 281.460911 -275.299582) (xy 281.412056 -275.305514)
			(xy 281.362881 -275.303533) (xy 281.314662 -275.293689) (xy 281.268646 -275.276237) (xy 281.226025 -275.25163)
			(xy 281.187904 -275.220505) (xy 281.155269 -275.183668) (xy 281.128966 -275.142072) (xy 281.109675 -275.096796)
			(xy 281.097898 -275.049012) (xy 281.093938 -274.999958) (xy 279.80513 -274.999958) (xy 279.804635 -275.024565)
			(xy 279.79674 -275.073142) (xy 279.781156 -275.119823) (xy 279.758285 -275.1634) (xy 279.72872 -275.202744)
			(xy 279.693227 -275.236836) (xy 279.652724 -275.264792) (xy 279.608262 -275.28589) (xy 279.560991 -275.299582)
			(xy 279.512136 -275.305514) (xy 279.462961 -275.303533) (xy 279.414742 -275.293689) (xy 279.368726 -275.276237)
			(xy 279.326105 -275.25163) (xy 279.287984 -275.220505) (xy 279.255349 -275.183668) (xy 279.229046 -275.142072)
			(xy 279.209755 -275.096796) (xy 279.197978 -275.049012) (xy 279.194018 -274.999958) (xy 277.90521 -274.999958)
			(xy 277.904715 -275.024565) (xy 277.89682 -275.073142) (xy 277.881236 -275.119823) (xy 277.858365 -275.1634)
			(xy 277.8288 -275.202744) (xy 277.793307 -275.236836) (xy 277.752804 -275.264792) (xy 277.708342 -275.28589)
			(xy 277.661071 -275.299582) (xy 277.612216 -275.305514) (xy 277.563041 -275.303533) (xy 277.514822 -275.293689)
			(xy 277.468806 -275.276237) (xy 277.426185 -275.25163) (xy 277.388064 -275.220505) (xy 277.355429 -275.183668)
			(xy 277.329126 -275.142072) (xy 277.309835 -275.096796) (xy 277.298058 -275.049012) (xy 277.294098 -274.999958)
			(xy 175.105314 -274.999958) (xy 175.104819 -275.024565) (xy 175.096924 -275.073142) (xy 175.08134 -275.119823)
			(xy 175.058469 -275.1634) (xy 175.028904 -275.202744) (xy 174.993411 -275.236836) (xy 174.952908 -275.264792)
			(xy 174.908446 -275.28589) (xy 174.861175 -275.299582) (xy 174.81232 -275.305514) (xy 174.763145 -275.303533)
			(xy 174.714926 -275.293689) (xy 174.66891 -275.276237) (xy 174.626289 -275.25163) (xy 174.588168 -275.220505)
			(xy 174.555533 -275.183668) (xy 174.52923 -275.142072) (xy 174.509939 -275.096796) (xy 174.498162 -275.049012)
			(xy 174.494202 -274.999958) (xy 173.205394 -274.999958) (xy 173.204899 -275.024565) (xy 173.197004 -275.073142)
			(xy 173.18142 -275.119823) (xy 173.158549 -275.1634) (xy 173.128984 -275.202744) (xy 173.093491 -275.236836)
			(xy 173.052988 -275.264792) (xy 173.008526 -275.28589) (xy 172.961255 -275.299582) (xy 172.9124 -275.305514)
			(xy 172.863225 -275.303533) (xy 172.815006 -275.293689) (xy 172.76899 -275.276237) (xy 172.726369 -275.25163)
			(xy 172.688248 -275.220505) (xy 172.655613 -275.183668) (xy 172.62931 -275.142072) (xy 172.610019 -275.096796)
			(xy 172.598242 -275.049012) (xy 172.594282 -274.999958) (xy 171.30522 -274.999958) (xy 171.304725 -275.024565)
			(xy 171.29683 -275.073142) (xy 171.281246 -275.119823) (xy 171.258375 -275.1634) (xy 171.22881 -275.202744)
			(xy 171.193317 -275.236836) (xy 171.152814 -275.264792) (xy 171.108352 -275.28589) (xy 171.061081 -275.299582)
			(xy 171.012226 -275.305514) (xy 170.963051 -275.303533) (xy 170.914832 -275.293689) (xy 170.868816 -275.276237)
			(xy 170.826195 -275.25163) (xy 170.788074 -275.220505) (xy 170.755439 -275.183668) (xy 170.729136 -275.142072)
			(xy 170.709845 -275.096796) (xy 170.698068 -275.049012) (xy 170.694108 -274.999958) (xy 169.4053 -274.999958)
			(xy 169.404805 -275.024565) (xy 169.39691 -275.073142) (xy 169.381326 -275.119823) (xy 169.358455 -275.1634)
			(xy 169.32889 -275.202744) (xy 169.293397 -275.236836) (xy 169.252894 -275.264792) (xy 169.208432 -275.28589)
			(xy 169.161161 -275.299582) (xy 169.112306 -275.305514) (xy 169.063131 -275.303533) (xy 169.014912 -275.293689)
			(xy 168.968896 -275.276237) (xy 168.926275 -275.25163) (xy 168.888154 -275.220505) (xy 168.855519 -275.183668)
			(xy 168.829216 -275.142072) (xy 168.809925 -275.096796) (xy 168.798148 -275.049012) (xy 168.794188 -274.999958)
			(xy 167.50538 -274.999958) (xy 167.504885 -275.024565) (xy 167.49699 -275.073142) (xy 167.481406 -275.119823)
			(xy 167.458535 -275.1634) (xy 167.42897 -275.202744) (xy 167.393477 -275.236836) (xy 167.352974 -275.264792)
			(xy 167.308512 -275.28589) (xy 167.261241 -275.299582) (xy 167.212386 -275.305514) (xy 167.163211 -275.303533)
			(xy 167.114992 -275.293689) (xy 167.068976 -275.276237) (xy 167.026355 -275.25163) (xy 166.988234 -275.220505)
			(xy 166.955599 -275.183668) (xy 166.929296 -275.142072) (xy 166.910005 -275.096796) (xy 166.898228 -275.049012)
			(xy 166.894268 -274.999958) (xy 165.605206 -274.999958) (xy 165.604711 -275.024565) (xy 165.596816 -275.073142)
			(xy 165.581232 -275.119823) (xy 165.558361 -275.1634) (xy 165.528796 -275.202744) (xy 165.493303 -275.236836)
			(xy 165.4528 -275.264792) (xy 165.408338 -275.28589) (xy 165.361067 -275.299582) (xy 165.312212 -275.305514)
			(xy 165.263037 -275.303533) (xy 165.214818 -275.293689) (xy 165.168802 -275.276237) (xy 165.126181 -275.25163)
			(xy 165.08806 -275.220505) (xy 165.055425 -275.183668) (xy 165.029122 -275.142072) (xy 165.009831 -275.096796)
			(xy 164.998054 -275.049012) (xy 164.994094 -274.999958) (xy 163.705286 -274.999958) (xy 163.704791 -275.024565)
			(xy 163.696896 -275.073142) (xy 163.681312 -275.119823) (xy 163.658441 -275.1634) (xy 163.628876 -275.202744)
			(xy 163.593383 -275.236836) (xy 163.55288 -275.264792) (xy 163.508418 -275.28589) (xy 163.461147 -275.299582)
			(xy 163.412292 -275.305514) (xy 163.363117 -275.303533) (xy 163.314898 -275.293689) (xy 163.268882 -275.276237)
			(xy 163.226261 -275.25163) (xy 163.18814 -275.220505) (xy 163.155505 -275.183668) (xy 163.129202 -275.142072)
			(xy 163.109911 -275.096796) (xy 163.098134 -275.049012) (xy 163.094174 -274.999958) (xy 161.805366 -274.999958)
			(xy 161.804871 -275.024565) (xy 161.796976 -275.073142) (xy 161.781392 -275.119823) (xy 161.758521 -275.1634)
			(xy 161.728956 -275.202744) (xy 161.693463 -275.236836) (xy 161.65296 -275.264792) (xy 161.608498 -275.28589)
			(xy 161.561227 -275.299582) (xy 161.512372 -275.305514) (xy 161.463197 -275.303533) (xy 161.414978 -275.293689)
			(xy 161.368962 -275.276237) (xy 161.326341 -275.25163) (xy 161.28822 -275.220505) (xy 161.255585 -275.183668)
			(xy 161.229282 -275.142072) (xy 161.209991 -275.096796) (xy 161.198214 -275.049012) (xy 161.194254 -274.999958)
			(xy 59.005216 -274.999958) (xy 59.004721 -275.024565) (xy 58.996826 -275.073142) (xy 58.981242 -275.119823)
			(xy 58.958371 -275.1634) (xy 58.928806 -275.202744) (xy 58.893313 -275.236836) (xy 58.85281 -275.264792)
			(xy 58.808348 -275.28589) (xy 58.761077 -275.299582) (xy 58.712222 -275.305514) (xy 58.663047 -275.303533)
			(xy 58.614828 -275.293689) (xy 58.568812 -275.276237) (xy 58.526191 -275.25163) (xy 58.48807 -275.220505)
			(xy 58.455435 -275.183668) (xy 58.429132 -275.142072) (xy 58.409841 -275.096796) (xy 58.398064 -275.049012)
			(xy 58.394104 -274.999958) (xy 57.105296 -274.999958) (xy 57.104801 -275.024565) (xy 57.096906 -275.073142)
			(xy 57.081322 -275.119823) (xy 57.058451 -275.1634) (xy 57.028886 -275.202744) (xy 56.993393 -275.236836)
			(xy 56.95289 -275.264792) (xy 56.908428 -275.28589) (xy 56.861157 -275.299582) (xy 56.812302 -275.305514)
			(xy 56.763127 -275.303533) (xy 56.714908 -275.293689) (xy 56.668892 -275.276237) (xy 56.626271 -275.25163)
			(xy 56.58815 -275.220505) (xy 56.555515 -275.183668) (xy 56.529212 -275.142072) (xy 56.509921 -275.096796)
			(xy 56.498144 -275.049012) (xy 56.494184 -274.999958) (xy 55.205122 -274.999958) (xy 55.204627 -275.024565)
			(xy 55.196732 -275.073142) (xy 55.181148 -275.119823) (xy 55.158277 -275.1634) (xy 55.128712 -275.202744)
			(xy 55.093219 -275.236836) (xy 55.052716 -275.264792) (xy 55.008254 -275.28589) (xy 54.960983 -275.299582)
			(xy 54.912128 -275.305514) (xy 54.862953 -275.303533) (xy 54.814734 -275.293689) (xy 54.768718 -275.276237)
			(xy 54.726097 -275.25163) (xy 54.687976 -275.220505) (xy 54.655341 -275.183668) (xy 54.629038 -275.142072)
			(xy 54.609747 -275.096796) (xy 54.59797 -275.049012) (xy 54.59401 -274.999958) (xy 53.305202 -274.999958)
			(xy 53.304707 -275.024565) (xy 53.296812 -275.073142) (xy 53.281228 -275.119823) (xy 53.258357 -275.1634)
			(xy 53.228792 -275.202744) (xy 53.193299 -275.236836) (xy 53.152796 -275.264792) (xy 53.108334 -275.28589)
			(xy 53.061063 -275.299582) (xy 53.012208 -275.305514) (xy 52.963033 -275.303533) (xy 52.914814 -275.293689)
			(xy 52.868798 -275.276237) (xy 52.826177 -275.25163) (xy 52.788056 -275.220505) (xy 52.755421 -275.183668)
			(xy 52.729118 -275.142072) (xy 52.709827 -275.096796) (xy 52.69805 -275.049012) (xy 52.69409 -274.999958)
			(xy 51.405282 -274.999958) (xy 51.404787 -275.024565) (xy 51.396892 -275.073142) (xy 51.381308 -275.119823)
			(xy 51.358437 -275.1634) (xy 51.328872 -275.202744) (xy 51.293379 -275.236836) (xy 51.252876 -275.264792)
			(xy 51.208414 -275.28589) (xy 51.161143 -275.299582) (xy 51.112288 -275.305514) (xy 51.063113 -275.303533)
			(xy 51.014894 -275.293689) (xy 50.968878 -275.276237) (xy 50.926257 -275.25163) (xy 50.888136 -275.220505)
			(xy 50.855501 -275.183668) (xy 50.829198 -275.142072) (xy 50.809907 -275.096796) (xy 50.79813 -275.049012)
			(xy 50.79417 -274.999958) (xy 49.505108 -274.999958) (xy 49.504613 -275.024565) (xy 49.496718 -275.073142)
			(xy 49.481134 -275.119823) (xy 49.458263 -275.1634) (xy 49.428698 -275.202744) (xy 49.393205 -275.236836)
			(xy 49.352702 -275.264792) (xy 49.30824 -275.28589) (xy 49.260969 -275.299582) (xy 49.212114 -275.305514)
			(xy 49.162939 -275.303533) (xy 49.11472 -275.293689) (xy 49.068704 -275.276237) (xy 49.026083 -275.25163)
			(xy 48.987962 -275.220505) (xy 48.955327 -275.183668) (xy 48.929024 -275.142072) (xy 48.909733 -275.096796)
			(xy 48.897956 -275.049012) (xy 48.893996 -274.999958) (xy 47.605188 -274.999958) (xy 47.604693 -275.024565)
			(xy 47.596798 -275.073142) (xy 47.581214 -275.119823) (xy 47.558343 -275.1634) (xy 47.528778 -275.202744)
			(xy 47.493285 -275.236836) (xy 47.452782 -275.264792) (xy 47.40832 -275.28589) (xy 47.361049 -275.299582)
			(xy 47.312194 -275.305514) (xy 47.263019 -275.303533) (xy 47.2148 -275.293689) (xy 47.168784 -275.276237)
			(xy 47.126163 -275.25163) (xy 47.088042 -275.220505) (xy 47.055407 -275.183668) (xy 47.029104 -275.142072)
			(xy 47.009813 -275.096796) (xy 46.998036 -275.049012) (xy 46.994076 -274.999958) (xy 45.705268 -274.999958)
			(xy 45.704773 -275.024565) (xy 45.696878 -275.073142) (xy 45.681294 -275.119823) (xy 45.658423 -275.1634)
			(xy 45.628858 -275.202744) (xy 45.593365 -275.236836) (xy 45.552862 -275.264792) (xy 45.5084 -275.28589)
			(xy 45.461129 -275.299582) (xy 45.412274 -275.305514) (xy 45.363099 -275.303533) (xy 45.31488 -275.293689)
			(xy 45.268864 -275.276237) (xy 45.226243 -275.25163) (xy 45.188122 -275.220505) (xy 45.155487 -275.183668)
			(xy 45.129184 -275.142072) (xy 45.109893 -275.096796) (xy 45.098116 -275.049012) (xy 45.094156 -274.999958)
			(xy 0.508 -274.999958) (xy 0.508 -275.949918) (xy 45.094156 -275.949918) (xy 45.098116 -275.900864)
			(xy 45.109893 -275.85308) (xy 45.129184 -275.807804) (xy 45.155487 -275.766208) (xy 45.188122 -275.729371)
			(xy 45.226243 -275.698246) (xy 45.268864 -275.673639) (xy 45.31488 -275.656187) (xy 45.363099 -275.646343)
			(xy 45.412274 -275.644362) (xy 45.461129 -275.650294) (xy 45.5084 -275.663986) (xy 45.552862 -275.685084)
			(xy 45.593365 -275.71304) (xy 45.628858 -275.747132) (xy 45.658423 -275.786476) (xy 45.681294 -275.830053)
			(xy 45.696878 -275.876734) (xy 45.704773 -275.925311) (xy 45.705268 -275.949918) (xy 46.994076 -275.949918)
			(xy 46.998036 -275.900864) (xy 47.009813 -275.85308) (xy 47.029104 -275.807804) (xy 47.055407 -275.766208)
			(xy 47.088042 -275.729371) (xy 47.126163 -275.698246) (xy 47.168784 -275.673639) (xy 47.2148 -275.656187)
			(xy 47.263019 -275.646343) (xy 47.312194 -275.644362) (xy 47.361049 -275.650294) (xy 47.40832 -275.663986)
			(xy 47.452782 -275.685084) (xy 47.493285 -275.71304) (xy 47.528778 -275.747132) (xy 47.558343 -275.786476)
			(xy 47.581214 -275.830053) (xy 47.596798 -275.876734) (xy 47.604693 -275.925311) (xy 47.605188 -275.949918)
			(xy 48.893996 -275.949918) (xy 48.897956 -275.900864) (xy 48.909733 -275.85308) (xy 48.929024 -275.807804)
			(xy 48.955327 -275.766208) (xy 48.987962 -275.729371) (xy 49.026083 -275.698246) (xy 49.068704 -275.673639)
			(xy 49.11472 -275.656187) (xy 49.162939 -275.646343) (xy 49.212114 -275.644362) (xy 49.260969 -275.650294)
			(xy 49.30824 -275.663986) (xy 49.352702 -275.685084) (xy 49.393205 -275.71304) (xy 49.428698 -275.747132)
			(xy 49.458263 -275.786476) (xy 49.481134 -275.830053) (xy 49.496718 -275.876734) (xy 49.504613 -275.925311)
			(xy 49.505108 -275.949918) (xy 50.79417 -275.949918) (xy 50.79813 -275.900864) (xy 50.809907 -275.85308)
			(xy 50.829198 -275.807804) (xy 50.855501 -275.766208) (xy 50.888136 -275.729371) (xy 50.926257 -275.698246)
			(xy 50.968878 -275.673639) (xy 51.014894 -275.656187) (xy 51.063113 -275.646343) (xy 51.112288 -275.644362)
			(xy 51.161143 -275.650294) (xy 51.208414 -275.663986) (xy 51.252876 -275.685084) (xy 51.293379 -275.71304)
			(xy 51.328872 -275.747132) (xy 51.358437 -275.786476) (xy 51.381308 -275.830053) (xy 51.396892 -275.876734)
			(xy 51.404787 -275.925311) (xy 51.405282 -275.949918) (xy 52.69409 -275.949918) (xy 52.69805 -275.900864)
			(xy 52.709827 -275.85308) (xy 52.729118 -275.807804) (xy 52.755421 -275.766208) (xy 52.788056 -275.729371)
			(xy 52.826177 -275.698246) (xy 52.868798 -275.673639) (xy 52.914814 -275.656187) (xy 52.963033 -275.646343)
			(xy 53.012208 -275.644362) (xy 53.061063 -275.650294) (xy 53.108334 -275.663986) (xy 53.152796 -275.685084)
			(xy 53.193299 -275.71304) (xy 53.228792 -275.747132) (xy 53.258357 -275.786476) (xy 53.281228 -275.830053)
			(xy 53.296812 -275.876734) (xy 53.304707 -275.925311) (xy 53.305202 -275.949918) (xy 54.59401 -275.949918)
			(xy 54.59797 -275.900864) (xy 54.609747 -275.85308) (xy 54.629038 -275.807804) (xy 54.655341 -275.766208)
			(xy 54.687976 -275.729371) (xy 54.726097 -275.698246) (xy 54.768718 -275.673639) (xy 54.814734 -275.656187)
			(xy 54.862953 -275.646343) (xy 54.912128 -275.644362) (xy 54.960983 -275.650294) (xy 55.008254 -275.663986)
			(xy 55.052716 -275.685084) (xy 55.093219 -275.71304) (xy 55.128712 -275.747132) (xy 55.158277 -275.786476)
			(xy 55.181148 -275.830053) (xy 55.196732 -275.876734) (xy 55.204627 -275.925311) (xy 55.205122 -275.949918)
			(xy 56.494184 -275.949918) (xy 56.498144 -275.900864) (xy 56.509921 -275.85308) (xy 56.529212 -275.807804)
			(xy 56.555515 -275.766208) (xy 56.58815 -275.729371) (xy 56.626271 -275.698246) (xy 56.668892 -275.673639)
			(xy 56.714908 -275.656187) (xy 56.763127 -275.646343) (xy 56.812302 -275.644362) (xy 56.861157 -275.650294)
			(xy 56.908428 -275.663986) (xy 56.95289 -275.685084) (xy 56.993393 -275.71304) (xy 57.028886 -275.747132)
			(xy 57.058451 -275.786476) (xy 57.081322 -275.830053) (xy 57.096906 -275.876734) (xy 57.104801 -275.925311)
			(xy 57.105296 -275.949918) (xy 58.394104 -275.949918) (xy 58.398064 -275.900864) (xy 58.409841 -275.85308)
			(xy 58.429132 -275.807804) (xy 58.455435 -275.766208) (xy 58.48807 -275.729371) (xy 58.526191 -275.698246)
			(xy 58.568812 -275.673639) (xy 58.614828 -275.656187) (xy 58.663047 -275.646343) (xy 58.712222 -275.644362)
			(xy 58.761077 -275.650294) (xy 58.808348 -275.663986) (xy 58.85281 -275.685084) (xy 58.893313 -275.71304)
			(xy 58.928806 -275.747132) (xy 58.958371 -275.786476) (xy 58.981242 -275.830053) (xy 58.996826 -275.876734)
			(xy 59.004721 -275.925311) (xy 59.005216 -275.949918) (xy 161.194254 -275.949918) (xy 161.198214 -275.900864)
			(xy 161.209991 -275.85308) (xy 161.229282 -275.807804) (xy 161.255585 -275.766208) (xy 161.28822 -275.729371)
			(xy 161.326341 -275.698246) (xy 161.368962 -275.673639) (xy 161.414978 -275.656187) (xy 161.463197 -275.646343)
			(xy 161.512372 -275.644362) (xy 161.561227 -275.650294) (xy 161.608498 -275.663986) (xy 161.65296 -275.685084)
			(xy 161.693463 -275.71304) (xy 161.728956 -275.747132) (xy 161.758521 -275.786476) (xy 161.781392 -275.830053)
			(xy 161.796976 -275.876734) (xy 161.804871 -275.925311) (xy 161.805366 -275.949918) (xy 163.094174 -275.949918)
			(xy 163.098134 -275.900864) (xy 163.109911 -275.85308) (xy 163.129202 -275.807804) (xy 163.155505 -275.766208)
			(xy 163.18814 -275.729371) (xy 163.226261 -275.698246) (xy 163.268882 -275.673639) (xy 163.314898 -275.656187)
			(xy 163.363117 -275.646343) (xy 163.412292 -275.644362) (xy 163.461147 -275.650294) (xy 163.508418 -275.663986)
			(xy 163.55288 -275.685084) (xy 163.593383 -275.71304) (xy 163.628876 -275.747132) (xy 163.658441 -275.786476)
			(xy 163.681312 -275.830053) (xy 163.696896 -275.876734) (xy 163.704791 -275.925311) (xy 163.705286 -275.949918)
			(xy 164.994094 -275.949918) (xy 164.998054 -275.900864) (xy 165.009831 -275.85308) (xy 165.029122 -275.807804)
			(xy 165.055425 -275.766208) (xy 165.08806 -275.729371) (xy 165.126181 -275.698246) (xy 165.168802 -275.673639)
			(xy 165.214818 -275.656187) (xy 165.263037 -275.646343) (xy 165.312212 -275.644362) (xy 165.361067 -275.650294)
			(xy 165.408338 -275.663986) (xy 165.4528 -275.685084) (xy 165.493303 -275.71304) (xy 165.528796 -275.747132)
			(xy 165.558361 -275.786476) (xy 165.581232 -275.830053) (xy 165.596816 -275.876734) (xy 165.604711 -275.925311)
			(xy 165.605206 -275.949918) (xy 166.894268 -275.949918) (xy 166.898228 -275.900864) (xy 166.910005 -275.85308)
			(xy 166.929296 -275.807804) (xy 166.955599 -275.766208) (xy 166.988234 -275.729371) (xy 167.026355 -275.698246)
			(xy 167.068976 -275.673639) (xy 167.114992 -275.656187) (xy 167.163211 -275.646343) (xy 167.212386 -275.644362)
			(xy 167.261241 -275.650294) (xy 167.308512 -275.663986) (xy 167.352974 -275.685084) (xy 167.393477 -275.71304)
			(xy 167.42897 -275.747132) (xy 167.458535 -275.786476) (xy 167.481406 -275.830053) (xy 167.49699 -275.876734)
			(xy 167.504885 -275.925311) (xy 167.50538 -275.949918) (xy 168.794188 -275.949918) (xy 168.798148 -275.900864)
			(xy 168.809925 -275.85308) (xy 168.829216 -275.807804) (xy 168.855519 -275.766208) (xy 168.888154 -275.729371)
			(xy 168.926275 -275.698246) (xy 168.968896 -275.673639) (xy 169.014912 -275.656187) (xy 169.063131 -275.646343)
			(xy 169.112306 -275.644362) (xy 169.161161 -275.650294) (xy 169.208432 -275.663986) (xy 169.252894 -275.685084)
			(xy 169.293397 -275.71304) (xy 169.32889 -275.747132) (xy 169.358455 -275.786476) (xy 169.381326 -275.830053)
			(xy 169.39691 -275.876734) (xy 169.404805 -275.925311) (xy 169.4053 -275.949918) (xy 170.694108 -275.949918)
			(xy 170.698068 -275.900864) (xy 170.709845 -275.85308) (xy 170.729136 -275.807804) (xy 170.755439 -275.766208)
			(xy 170.788074 -275.729371) (xy 170.826195 -275.698246) (xy 170.868816 -275.673639) (xy 170.914832 -275.656187)
			(xy 170.963051 -275.646343) (xy 171.012226 -275.644362) (xy 171.061081 -275.650294) (xy 171.108352 -275.663986)
			(xy 171.152814 -275.685084) (xy 171.193317 -275.71304) (xy 171.22881 -275.747132) (xy 171.258375 -275.786476)
			(xy 171.281246 -275.830053) (xy 171.29683 -275.876734) (xy 171.304725 -275.925311) (xy 171.30522 -275.949918)
			(xy 172.594282 -275.949918) (xy 172.598242 -275.900864) (xy 172.610019 -275.85308) (xy 172.62931 -275.807804)
			(xy 172.655613 -275.766208) (xy 172.688248 -275.729371) (xy 172.726369 -275.698246) (xy 172.76899 -275.673639)
			(xy 172.815006 -275.656187) (xy 172.863225 -275.646343) (xy 172.9124 -275.644362) (xy 172.961255 -275.650294)
			(xy 173.008526 -275.663986) (xy 173.052988 -275.685084) (xy 173.093491 -275.71304) (xy 173.128984 -275.747132)
			(xy 173.158549 -275.786476) (xy 173.18142 -275.830053) (xy 173.197004 -275.876734) (xy 173.204899 -275.925311)
			(xy 173.205394 -275.949918) (xy 174.494202 -275.949918) (xy 174.498162 -275.900864) (xy 174.509939 -275.85308)
			(xy 174.52923 -275.807804) (xy 174.555533 -275.766208) (xy 174.588168 -275.729371) (xy 174.626289 -275.698246)
			(xy 174.66891 -275.673639) (xy 174.714926 -275.656187) (xy 174.763145 -275.646343) (xy 174.81232 -275.644362)
			(xy 174.861175 -275.650294) (xy 174.908446 -275.663986) (xy 174.952908 -275.685084) (xy 174.993411 -275.71304)
			(xy 175.028904 -275.747132) (xy 175.058469 -275.786476) (xy 175.08134 -275.830053) (xy 175.096924 -275.876734)
			(xy 175.104819 -275.925311) (xy 175.105314 -275.949918) (xy 277.294098 -275.949918) (xy 277.298058 -275.900864)
			(xy 277.309835 -275.85308) (xy 277.329126 -275.807804) (xy 277.355429 -275.766208) (xy 277.388064 -275.729371)
			(xy 277.426185 -275.698246) (xy 277.468806 -275.673639) (xy 277.514822 -275.656187) (xy 277.563041 -275.646343)
			(xy 277.612216 -275.644362) (xy 277.661071 -275.650294) (xy 277.708342 -275.663986) (xy 277.752804 -275.685084)
			(xy 277.793307 -275.71304) (xy 277.8288 -275.747132) (xy 277.858365 -275.786476) (xy 277.881236 -275.830053)
			(xy 277.89682 -275.876734) (xy 277.904715 -275.925311) (xy 277.90521 -275.949918) (xy 279.194018 -275.949918)
			(xy 279.197978 -275.900864) (xy 279.209755 -275.85308) (xy 279.229046 -275.807804) (xy 279.255349 -275.766208)
			(xy 279.287984 -275.729371) (xy 279.326105 -275.698246) (xy 279.368726 -275.673639) (xy 279.414742 -275.656187)
			(xy 279.462961 -275.646343) (xy 279.512136 -275.644362) (xy 279.560991 -275.650294) (xy 279.608262 -275.663986)
			(xy 279.652724 -275.685084) (xy 279.693227 -275.71304) (xy 279.72872 -275.747132) (xy 279.758285 -275.786476)
			(xy 279.781156 -275.830053) (xy 279.79674 -275.876734) (xy 279.804635 -275.925311) (xy 279.80513 -275.949918)
			(xy 281.093938 -275.949918) (xy 281.097898 -275.900864) (xy 281.109675 -275.85308) (xy 281.128966 -275.807804)
			(xy 281.155269 -275.766208) (xy 281.187904 -275.729371) (xy 281.226025 -275.698246) (xy 281.268646 -275.673639)
			(xy 281.314662 -275.656187) (xy 281.362881 -275.646343) (xy 281.412056 -275.644362) (xy 281.460911 -275.650294)
			(xy 281.508182 -275.663986) (xy 281.552644 -275.685084) (xy 281.593147 -275.71304) (xy 281.62864 -275.747132)
			(xy 281.658205 -275.786476) (xy 281.681076 -275.830053) (xy 281.69666 -275.876734) (xy 281.704555 -275.925311)
			(xy 281.70505 -275.949918) (xy 282.994112 -275.949918) (xy 282.998072 -275.900864) (xy 283.009849 -275.85308)
			(xy 283.02914 -275.807804) (xy 283.055443 -275.766208) (xy 283.088078 -275.729371) (xy 283.126199 -275.698246)
			(xy 283.16882 -275.673639) (xy 283.214836 -275.656187) (xy 283.263055 -275.646343) (xy 283.31223 -275.644362)
			(xy 283.361085 -275.650294) (xy 283.408356 -275.663986) (xy 283.452818 -275.685084) (xy 283.493321 -275.71304)
			(xy 283.528814 -275.747132) (xy 283.558379 -275.786476) (xy 283.58125 -275.830053) (xy 283.596834 -275.876734)
			(xy 283.604729 -275.925311) (xy 283.605224 -275.949918) (xy 284.894032 -275.949918) (xy 284.897992 -275.900864)
			(xy 284.909769 -275.85308) (xy 284.92906 -275.807804) (xy 284.955363 -275.766208) (xy 284.987998 -275.729371)
			(xy 285.026119 -275.698246) (xy 285.06874 -275.673639) (xy 285.114756 -275.656187) (xy 285.162975 -275.646343)
			(xy 285.21215 -275.644362) (xy 285.261005 -275.650294) (xy 285.308276 -275.663986) (xy 285.352738 -275.685084)
			(xy 285.393241 -275.71304) (xy 285.428734 -275.747132) (xy 285.458299 -275.786476) (xy 285.48117 -275.830053)
			(xy 285.496754 -275.876734) (xy 285.504649 -275.925311) (xy 285.505144 -275.949918) (xy 286.793952 -275.949918)
			(xy 286.797912 -275.900864) (xy 286.809689 -275.85308) (xy 286.82898 -275.807804) (xy 286.855283 -275.766208)
			(xy 286.887918 -275.729371) (xy 286.926039 -275.698246) (xy 286.96866 -275.673639) (xy 287.014676 -275.656187)
			(xy 287.062895 -275.646343) (xy 287.11207 -275.644362) (xy 287.160925 -275.650294) (xy 287.208196 -275.663986)
			(xy 287.252658 -275.685084) (xy 287.293161 -275.71304) (xy 287.328654 -275.747132) (xy 287.358219 -275.786476)
			(xy 287.38109 -275.830053) (xy 287.396674 -275.876734) (xy 287.404569 -275.925311) (xy 287.405064 -275.949918)
			(xy 288.694126 -275.949918) (xy 288.698086 -275.900864) (xy 288.709863 -275.85308) (xy 288.729154 -275.807804)
			(xy 288.755457 -275.766208) (xy 288.788092 -275.729371) (xy 288.826213 -275.698246) (xy 288.868834 -275.673639)
			(xy 288.91485 -275.656187) (xy 288.963069 -275.646343) (xy 289.012244 -275.644362) (xy 289.061099 -275.650294)
			(xy 289.10837 -275.663986) (xy 289.152832 -275.685084) (xy 289.193335 -275.71304) (xy 289.228828 -275.747132)
			(xy 289.258393 -275.786476) (xy 289.281264 -275.830053) (xy 289.296848 -275.876734) (xy 289.304743 -275.925311)
			(xy 289.305238 -275.949918) (xy 290.594046 -275.949918) (xy 290.598006 -275.900864) (xy 290.609783 -275.85308)
			(xy 290.629074 -275.807804) (xy 290.655377 -275.766208) (xy 290.688012 -275.729371) (xy 290.726133 -275.698246)
			(xy 290.768754 -275.673639) (xy 290.81477 -275.656187) (xy 290.862989 -275.646343) (xy 290.912164 -275.644362)
			(xy 290.961019 -275.650294) (xy 291.00829 -275.663986) (xy 291.052752 -275.685084) (xy 291.093255 -275.71304)
			(xy 291.128748 -275.747132) (xy 291.158313 -275.786476) (xy 291.181184 -275.830053) (xy 291.196768 -275.876734)
			(xy 291.204663 -275.925311) (xy 291.205158 -275.949918) (xy 393.394196 -275.949918) (xy 393.398156 -275.900864)
			(xy 393.409933 -275.85308) (xy 393.429224 -275.807804) (xy 393.455527 -275.766208) (xy 393.488162 -275.729371)
			(xy 393.526283 -275.698246) (xy 393.568904 -275.673639) (xy 393.61492 -275.656187) (xy 393.663139 -275.646343)
			(xy 393.712314 -275.644362) (xy 393.761169 -275.650294) (xy 393.80844 -275.663986) (xy 393.852902 -275.685084)
			(xy 393.893405 -275.71304) (xy 393.928898 -275.747132) (xy 393.958463 -275.786476) (xy 393.981334 -275.830053)
			(xy 393.996918 -275.876734) (xy 394.004813 -275.925311) (xy 394.005308 -275.949918) (xy 395.294116 -275.949918)
			(xy 395.298076 -275.900864) (xy 395.309853 -275.85308) (xy 395.329144 -275.807804) (xy 395.355447 -275.766208)
			(xy 395.388082 -275.729371) (xy 395.426203 -275.698246) (xy 395.468824 -275.673639) (xy 395.51484 -275.656187)
			(xy 395.563059 -275.646343) (xy 395.612234 -275.644362) (xy 395.661089 -275.650294) (xy 395.70836 -275.663986)
			(xy 395.752822 -275.685084) (xy 395.793325 -275.71304) (xy 395.828818 -275.747132) (xy 395.858383 -275.786476)
			(xy 395.881254 -275.830053) (xy 395.896838 -275.876734) (xy 395.904733 -275.925311) (xy 395.905228 -275.949918)
			(xy 397.194036 -275.949918) (xy 397.197996 -275.900864) (xy 397.209773 -275.85308) (xy 397.229064 -275.807804)
			(xy 397.255367 -275.766208) (xy 397.288002 -275.729371) (xy 397.326123 -275.698246) (xy 397.368744 -275.673639)
			(xy 397.41476 -275.656187) (xy 397.462979 -275.646343) (xy 397.512154 -275.644362) (xy 397.561009 -275.650294)
			(xy 397.60828 -275.663986) (xy 397.652742 -275.685084) (xy 397.693245 -275.71304) (xy 397.728738 -275.747132)
			(xy 397.758303 -275.786476) (xy 397.781174 -275.830053) (xy 397.796758 -275.876734) (xy 397.804653 -275.925311)
			(xy 397.805148 -275.949918) (xy 399.09421 -275.949918) (xy 399.09817 -275.900864) (xy 399.109947 -275.85308)
			(xy 399.129238 -275.807804) (xy 399.155541 -275.766208) (xy 399.188176 -275.729371) (xy 399.226297 -275.698246)
			(xy 399.268918 -275.673639) (xy 399.314934 -275.656187) (xy 399.363153 -275.646343) (xy 399.412328 -275.644362)
			(xy 399.461183 -275.650294) (xy 399.508454 -275.663986) (xy 399.552916 -275.685084) (xy 399.593419 -275.71304)
			(xy 399.628912 -275.747132) (xy 399.658477 -275.786476) (xy 399.681348 -275.830053) (xy 399.696932 -275.876734)
			(xy 399.704827 -275.925311) (xy 399.705322 -275.949918) (xy 400.99413 -275.949918) (xy 400.99809 -275.900864)
			(xy 401.009867 -275.85308) (xy 401.029158 -275.807804) (xy 401.055461 -275.766208) (xy 401.088096 -275.729371)
			(xy 401.126217 -275.698246) (xy 401.168838 -275.673639) (xy 401.214854 -275.656187) (xy 401.263073 -275.646343)
			(xy 401.312248 -275.644362) (xy 401.361103 -275.650294) (xy 401.408374 -275.663986) (xy 401.452836 -275.685084)
			(xy 401.493339 -275.71304) (xy 401.528832 -275.747132) (xy 401.558397 -275.786476) (xy 401.581268 -275.830053)
			(xy 401.596852 -275.876734) (xy 401.604747 -275.925311) (xy 401.605242 -275.949918) (xy 402.89405 -275.949918)
			(xy 402.89801 -275.900864) (xy 402.909787 -275.85308) (xy 402.929078 -275.807804) (xy 402.955381 -275.766208)
			(xy 402.988016 -275.729371) (xy 403.026137 -275.698246) (xy 403.068758 -275.673639) (xy 403.114774 -275.656187)
			(xy 403.162993 -275.646343) (xy 403.212168 -275.644362) (xy 403.261023 -275.650294) (xy 403.308294 -275.663986)
			(xy 403.352756 -275.685084) (xy 403.393259 -275.71304) (xy 403.428752 -275.747132) (xy 403.458317 -275.786476)
			(xy 403.481188 -275.830053) (xy 403.496772 -275.876734) (xy 403.504667 -275.925311) (xy 403.505162 -275.949918)
			(xy 404.794224 -275.949918) (xy 404.798184 -275.900864) (xy 404.809961 -275.85308) (xy 404.829252 -275.807804)
			(xy 404.855555 -275.766208) (xy 404.88819 -275.729371) (xy 404.926311 -275.698246) (xy 404.968932 -275.673639)
			(xy 405.014948 -275.656187) (xy 405.063167 -275.646343) (xy 405.112342 -275.644362) (xy 405.161197 -275.650294)
			(xy 405.208468 -275.663986) (xy 405.25293 -275.685084) (xy 405.293433 -275.71304) (xy 405.328926 -275.747132)
			(xy 405.358491 -275.786476) (xy 405.381362 -275.830053) (xy 405.396946 -275.876734) (xy 405.404841 -275.925311)
			(xy 405.405336 -275.949918) (xy 406.694144 -275.949918) (xy 406.698104 -275.900864) (xy 406.709881 -275.85308)
			(xy 406.729172 -275.807804) (xy 406.755475 -275.766208) (xy 406.78811 -275.729371) (xy 406.826231 -275.698246)
			(xy 406.868852 -275.673639) (xy 406.914868 -275.656187) (xy 406.963087 -275.646343) (xy 407.012262 -275.644362)
			(xy 407.061117 -275.650294) (xy 407.108388 -275.663986) (xy 407.15285 -275.685084) (xy 407.193353 -275.71304)
			(xy 407.228846 -275.747132) (xy 407.258411 -275.786476) (xy 407.281282 -275.830053) (xy 407.296866 -275.876734)
			(xy 407.304761 -275.925311) (xy 407.305256 -275.949918) (xy 407.304761 -275.974525) (xy 407.296866 -276.023102)
			(xy 407.281282 -276.069783) (xy 407.258411 -276.11336) (xy 407.228846 -276.152704) (xy 407.193353 -276.186796)
			(xy 407.15285 -276.214752) (xy 407.108388 -276.23585) (xy 407.061117 -276.249542) (xy 407.012262 -276.255474)
			(xy 406.963087 -276.253493) (xy 406.914868 -276.243649) (xy 406.868852 -276.226197) (xy 406.826231 -276.20159)
			(xy 406.78811 -276.170465) (xy 406.755475 -276.133628) (xy 406.729172 -276.092032) (xy 406.709881 -276.046756)
			(xy 406.698104 -275.998972) (xy 406.694144 -275.949918) (xy 405.405336 -275.949918) (xy 405.404841 -275.974525)
			(xy 405.396946 -276.023102) (xy 405.381362 -276.069783) (xy 405.358491 -276.11336) (xy 405.328926 -276.152704)
			(xy 405.293433 -276.186796) (xy 405.25293 -276.214752) (xy 405.208468 -276.23585) (xy 405.161197 -276.249542)
			(xy 405.112342 -276.255474) (xy 405.063167 -276.253493) (xy 405.014948 -276.243649) (xy 404.968932 -276.226197)
			(xy 404.926311 -276.20159) (xy 404.88819 -276.170465) (xy 404.855555 -276.133628) (xy 404.829252 -276.092032)
			(xy 404.809961 -276.046756) (xy 404.798184 -275.998972) (xy 404.794224 -275.949918) (xy 403.505162 -275.949918)
			(xy 403.504667 -275.974525) (xy 403.496772 -276.023102) (xy 403.481188 -276.069783) (xy 403.458317 -276.11336)
			(xy 403.428752 -276.152704) (xy 403.393259 -276.186796) (xy 403.352756 -276.214752) (xy 403.308294 -276.23585)
			(xy 403.261023 -276.249542) (xy 403.212168 -276.255474) (xy 403.162993 -276.253493) (xy 403.114774 -276.243649)
			(xy 403.068758 -276.226197) (xy 403.026137 -276.20159) (xy 402.988016 -276.170465) (xy 402.955381 -276.133628)
			(xy 402.929078 -276.092032) (xy 402.909787 -276.046756) (xy 402.89801 -275.998972) (xy 402.89405 -275.949918)
			(xy 401.605242 -275.949918) (xy 401.604747 -275.974525) (xy 401.596852 -276.023102) (xy 401.581268 -276.069783)
			(xy 401.558397 -276.11336) (xy 401.528832 -276.152704) (xy 401.493339 -276.186796) (xy 401.452836 -276.214752)
			(xy 401.408374 -276.23585) (xy 401.361103 -276.249542) (xy 401.312248 -276.255474) (xy 401.263073 -276.253493)
			(xy 401.214854 -276.243649) (xy 401.168838 -276.226197) (xy 401.126217 -276.20159) (xy 401.088096 -276.170465)
			(xy 401.055461 -276.133628) (xy 401.029158 -276.092032) (xy 401.009867 -276.046756) (xy 400.99809 -275.998972)
			(xy 400.99413 -275.949918) (xy 399.705322 -275.949918) (xy 399.704827 -275.974525) (xy 399.696932 -276.023102)
			(xy 399.681348 -276.069783) (xy 399.658477 -276.11336) (xy 399.628912 -276.152704) (xy 399.593419 -276.186796)
			(xy 399.552916 -276.214752) (xy 399.508454 -276.23585) (xy 399.461183 -276.249542) (xy 399.412328 -276.255474)
			(xy 399.363153 -276.253493) (xy 399.314934 -276.243649) (xy 399.268918 -276.226197) (xy 399.226297 -276.20159)
			(xy 399.188176 -276.170465) (xy 399.155541 -276.133628) (xy 399.129238 -276.092032) (xy 399.109947 -276.046756)
			(xy 399.09817 -275.998972) (xy 399.09421 -275.949918) (xy 397.805148 -275.949918) (xy 397.804653 -275.974525)
			(xy 397.796758 -276.023102) (xy 397.781174 -276.069783) (xy 397.758303 -276.11336) (xy 397.728738 -276.152704)
			(xy 397.693245 -276.186796) (xy 397.652742 -276.214752) (xy 397.60828 -276.23585) (xy 397.561009 -276.249542)
			(xy 397.512154 -276.255474) (xy 397.462979 -276.253493) (xy 397.41476 -276.243649) (xy 397.368744 -276.226197)
			(xy 397.326123 -276.20159) (xy 397.288002 -276.170465) (xy 397.255367 -276.133628) (xy 397.229064 -276.092032)
			(xy 397.209773 -276.046756) (xy 397.197996 -275.998972) (xy 397.194036 -275.949918) (xy 395.905228 -275.949918)
			(xy 395.904733 -275.974525) (xy 395.896838 -276.023102) (xy 395.881254 -276.069783) (xy 395.858383 -276.11336)
			(xy 395.828818 -276.152704) (xy 395.793325 -276.186796) (xy 395.752822 -276.214752) (xy 395.70836 -276.23585)
			(xy 395.661089 -276.249542) (xy 395.612234 -276.255474) (xy 395.563059 -276.253493) (xy 395.51484 -276.243649)
			(xy 395.468824 -276.226197) (xy 395.426203 -276.20159) (xy 395.388082 -276.170465) (xy 395.355447 -276.133628)
			(xy 395.329144 -276.092032) (xy 395.309853 -276.046756) (xy 395.298076 -275.998972) (xy 395.294116 -275.949918)
			(xy 394.005308 -275.949918) (xy 394.004813 -275.974525) (xy 393.996918 -276.023102) (xy 393.981334 -276.069783)
			(xy 393.958463 -276.11336) (xy 393.928898 -276.152704) (xy 393.893405 -276.186796) (xy 393.852902 -276.214752)
			(xy 393.80844 -276.23585) (xy 393.761169 -276.249542) (xy 393.712314 -276.255474) (xy 393.663139 -276.253493)
			(xy 393.61492 -276.243649) (xy 393.568904 -276.226197) (xy 393.526283 -276.20159) (xy 393.488162 -276.170465)
			(xy 393.455527 -276.133628) (xy 393.429224 -276.092032) (xy 393.409933 -276.046756) (xy 393.398156 -275.998972)
			(xy 393.394196 -275.949918) (xy 291.205158 -275.949918) (xy 291.204663 -275.974525) (xy 291.196768 -276.023102)
			(xy 291.181184 -276.069783) (xy 291.158313 -276.11336) (xy 291.128748 -276.152704) (xy 291.093255 -276.186796)
			(xy 291.052752 -276.214752) (xy 291.00829 -276.23585) (xy 290.961019 -276.249542) (xy 290.912164 -276.255474)
			(xy 290.862989 -276.253493) (xy 290.81477 -276.243649) (xy 290.768754 -276.226197) (xy 290.726133 -276.20159)
			(xy 290.688012 -276.170465) (xy 290.655377 -276.133628) (xy 290.629074 -276.092032) (xy 290.609783 -276.046756)
			(xy 290.598006 -275.998972) (xy 290.594046 -275.949918) (xy 289.305238 -275.949918) (xy 289.304743 -275.974525)
			(xy 289.296848 -276.023102) (xy 289.281264 -276.069783) (xy 289.258393 -276.11336) (xy 289.228828 -276.152704)
			(xy 289.193335 -276.186796) (xy 289.152832 -276.214752) (xy 289.10837 -276.23585) (xy 289.061099 -276.249542)
			(xy 289.012244 -276.255474) (xy 288.963069 -276.253493) (xy 288.91485 -276.243649) (xy 288.868834 -276.226197)
			(xy 288.826213 -276.20159) (xy 288.788092 -276.170465) (xy 288.755457 -276.133628) (xy 288.729154 -276.092032)
			(xy 288.709863 -276.046756) (xy 288.698086 -275.998972) (xy 288.694126 -275.949918) (xy 287.405064 -275.949918)
			(xy 287.404569 -275.974525) (xy 287.396674 -276.023102) (xy 287.38109 -276.069783) (xy 287.358219 -276.11336)
			(xy 287.328654 -276.152704) (xy 287.293161 -276.186796) (xy 287.252658 -276.214752) (xy 287.208196 -276.23585)
			(xy 287.160925 -276.249542) (xy 287.11207 -276.255474) (xy 287.062895 -276.253493) (xy 287.014676 -276.243649)
			(xy 286.96866 -276.226197) (xy 286.926039 -276.20159) (xy 286.887918 -276.170465) (xy 286.855283 -276.133628)
			(xy 286.82898 -276.092032) (xy 286.809689 -276.046756) (xy 286.797912 -275.998972) (xy 286.793952 -275.949918)
			(xy 285.505144 -275.949918) (xy 285.504649 -275.974525) (xy 285.496754 -276.023102) (xy 285.48117 -276.069783)
			(xy 285.458299 -276.11336) (xy 285.428734 -276.152704) (xy 285.393241 -276.186796) (xy 285.352738 -276.214752)
			(xy 285.308276 -276.23585) (xy 285.261005 -276.249542) (xy 285.21215 -276.255474) (xy 285.162975 -276.253493)
			(xy 285.114756 -276.243649) (xy 285.06874 -276.226197) (xy 285.026119 -276.20159) (xy 284.987998 -276.170465)
			(xy 284.955363 -276.133628) (xy 284.92906 -276.092032) (xy 284.909769 -276.046756) (xy 284.897992 -275.998972)
			(xy 284.894032 -275.949918) (xy 283.605224 -275.949918) (xy 283.604729 -275.974525) (xy 283.596834 -276.023102)
			(xy 283.58125 -276.069783) (xy 283.558379 -276.11336) (xy 283.528814 -276.152704) (xy 283.493321 -276.186796)
			(xy 283.452818 -276.214752) (xy 283.408356 -276.23585) (xy 283.361085 -276.249542) (xy 283.31223 -276.255474)
			(xy 283.263055 -276.253493) (xy 283.214836 -276.243649) (xy 283.16882 -276.226197) (xy 283.126199 -276.20159)
			(xy 283.088078 -276.170465) (xy 283.055443 -276.133628) (xy 283.02914 -276.092032) (xy 283.009849 -276.046756)
			(xy 282.998072 -275.998972) (xy 282.994112 -275.949918) (xy 281.70505 -275.949918) (xy 281.704555 -275.974525)
			(xy 281.69666 -276.023102) (xy 281.681076 -276.069783) (xy 281.658205 -276.11336) (xy 281.62864 -276.152704)
			(xy 281.593147 -276.186796) (xy 281.552644 -276.214752) (xy 281.508182 -276.23585) (xy 281.460911 -276.249542)
			(xy 281.412056 -276.255474) (xy 281.362881 -276.253493) (xy 281.314662 -276.243649) (xy 281.268646 -276.226197)
			(xy 281.226025 -276.20159) (xy 281.187904 -276.170465) (xy 281.155269 -276.133628) (xy 281.128966 -276.092032)
			(xy 281.109675 -276.046756) (xy 281.097898 -275.998972) (xy 281.093938 -275.949918) (xy 279.80513 -275.949918)
			(xy 279.804635 -275.974525) (xy 279.79674 -276.023102) (xy 279.781156 -276.069783) (xy 279.758285 -276.11336)
			(xy 279.72872 -276.152704) (xy 279.693227 -276.186796) (xy 279.652724 -276.214752) (xy 279.608262 -276.23585)
			(xy 279.560991 -276.249542) (xy 279.512136 -276.255474) (xy 279.462961 -276.253493) (xy 279.414742 -276.243649)
			(xy 279.368726 -276.226197) (xy 279.326105 -276.20159) (xy 279.287984 -276.170465) (xy 279.255349 -276.133628)
			(xy 279.229046 -276.092032) (xy 279.209755 -276.046756) (xy 279.197978 -275.998972) (xy 279.194018 -275.949918)
			(xy 277.90521 -275.949918) (xy 277.904715 -275.974525) (xy 277.89682 -276.023102) (xy 277.881236 -276.069783)
			(xy 277.858365 -276.11336) (xy 277.8288 -276.152704) (xy 277.793307 -276.186796) (xy 277.752804 -276.214752)
			(xy 277.708342 -276.23585) (xy 277.661071 -276.249542) (xy 277.612216 -276.255474) (xy 277.563041 -276.253493)
			(xy 277.514822 -276.243649) (xy 277.468806 -276.226197) (xy 277.426185 -276.20159) (xy 277.388064 -276.170465)
			(xy 277.355429 -276.133628) (xy 277.329126 -276.092032) (xy 277.309835 -276.046756) (xy 277.298058 -275.998972)
			(xy 277.294098 -275.949918) (xy 175.105314 -275.949918) (xy 175.104819 -275.974525) (xy 175.096924 -276.023102)
			(xy 175.08134 -276.069783) (xy 175.058469 -276.11336) (xy 175.028904 -276.152704) (xy 174.993411 -276.186796)
			(xy 174.952908 -276.214752) (xy 174.908446 -276.23585) (xy 174.861175 -276.249542) (xy 174.81232 -276.255474)
			(xy 174.763145 -276.253493) (xy 174.714926 -276.243649) (xy 174.66891 -276.226197) (xy 174.626289 -276.20159)
			(xy 174.588168 -276.170465) (xy 174.555533 -276.133628) (xy 174.52923 -276.092032) (xy 174.509939 -276.046756)
			(xy 174.498162 -275.998972) (xy 174.494202 -275.949918) (xy 173.205394 -275.949918) (xy 173.204899 -275.974525)
			(xy 173.197004 -276.023102) (xy 173.18142 -276.069783) (xy 173.158549 -276.11336) (xy 173.128984 -276.152704)
			(xy 173.093491 -276.186796) (xy 173.052988 -276.214752) (xy 173.008526 -276.23585) (xy 172.961255 -276.249542)
			(xy 172.9124 -276.255474) (xy 172.863225 -276.253493) (xy 172.815006 -276.243649) (xy 172.76899 -276.226197)
			(xy 172.726369 -276.20159) (xy 172.688248 -276.170465) (xy 172.655613 -276.133628) (xy 172.62931 -276.092032)
			(xy 172.610019 -276.046756) (xy 172.598242 -275.998972) (xy 172.594282 -275.949918) (xy 171.30522 -275.949918)
			(xy 171.304725 -275.974525) (xy 171.29683 -276.023102) (xy 171.281246 -276.069783) (xy 171.258375 -276.11336)
			(xy 171.22881 -276.152704) (xy 171.193317 -276.186796) (xy 171.152814 -276.214752) (xy 171.108352 -276.23585)
			(xy 171.061081 -276.249542) (xy 171.012226 -276.255474) (xy 170.963051 -276.253493) (xy 170.914832 -276.243649)
			(xy 170.868816 -276.226197) (xy 170.826195 -276.20159) (xy 170.788074 -276.170465) (xy 170.755439 -276.133628)
			(xy 170.729136 -276.092032) (xy 170.709845 -276.046756) (xy 170.698068 -275.998972) (xy 170.694108 -275.949918)
			(xy 169.4053 -275.949918) (xy 169.404805 -275.974525) (xy 169.39691 -276.023102) (xy 169.381326 -276.069783)
			(xy 169.358455 -276.11336) (xy 169.32889 -276.152704) (xy 169.293397 -276.186796) (xy 169.252894 -276.214752)
			(xy 169.208432 -276.23585) (xy 169.161161 -276.249542) (xy 169.112306 -276.255474) (xy 169.063131 -276.253493)
			(xy 169.014912 -276.243649) (xy 168.968896 -276.226197) (xy 168.926275 -276.20159) (xy 168.888154 -276.170465)
			(xy 168.855519 -276.133628) (xy 168.829216 -276.092032) (xy 168.809925 -276.046756) (xy 168.798148 -275.998972)
			(xy 168.794188 -275.949918) (xy 167.50538 -275.949918) (xy 167.504885 -275.974525) (xy 167.49699 -276.023102)
			(xy 167.481406 -276.069783) (xy 167.458535 -276.11336) (xy 167.42897 -276.152704) (xy 167.393477 -276.186796)
			(xy 167.352974 -276.214752) (xy 167.308512 -276.23585) (xy 167.261241 -276.249542) (xy 167.212386 -276.255474)
			(xy 167.163211 -276.253493) (xy 167.114992 -276.243649) (xy 167.068976 -276.226197) (xy 167.026355 -276.20159)
			(xy 166.988234 -276.170465) (xy 166.955599 -276.133628) (xy 166.929296 -276.092032) (xy 166.910005 -276.046756)
			(xy 166.898228 -275.998972) (xy 166.894268 -275.949918) (xy 165.605206 -275.949918) (xy 165.604711 -275.974525)
			(xy 165.596816 -276.023102) (xy 165.581232 -276.069783) (xy 165.558361 -276.11336) (xy 165.528796 -276.152704)
			(xy 165.493303 -276.186796) (xy 165.4528 -276.214752) (xy 165.408338 -276.23585) (xy 165.361067 -276.249542)
			(xy 165.312212 -276.255474) (xy 165.263037 -276.253493) (xy 165.214818 -276.243649) (xy 165.168802 -276.226197)
			(xy 165.126181 -276.20159) (xy 165.08806 -276.170465) (xy 165.055425 -276.133628) (xy 165.029122 -276.092032)
			(xy 165.009831 -276.046756) (xy 164.998054 -275.998972) (xy 164.994094 -275.949918) (xy 163.705286 -275.949918)
			(xy 163.704791 -275.974525) (xy 163.696896 -276.023102) (xy 163.681312 -276.069783) (xy 163.658441 -276.11336)
			(xy 163.628876 -276.152704) (xy 163.593383 -276.186796) (xy 163.55288 -276.214752) (xy 163.508418 -276.23585)
			(xy 163.461147 -276.249542) (xy 163.412292 -276.255474) (xy 163.363117 -276.253493) (xy 163.314898 -276.243649)
			(xy 163.268882 -276.226197) (xy 163.226261 -276.20159) (xy 163.18814 -276.170465) (xy 163.155505 -276.133628)
			(xy 163.129202 -276.092032) (xy 163.109911 -276.046756) (xy 163.098134 -275.998972) (xy 163.094174 -275.949918)
			(xy 161.805366 -275.949918) (xy 161.804871 -275.974525) (xy 161.796976 -276.023102) (xy 161.781392 -276.069783)
			(xy 161.758521 -276.11336) (xy 161.728956 -276.152704) (xy 161.693463 -276.186796) (xy 161.65296 -276.214752)
			(xy 161.608498 -276.23585) (xy 161.561227 -276.249542) (xy 161.512372 -276.255474) (xy 161.463197 -276.253493)
			(xy 161.414978 -276.243649) (xy 161.368962 -276.226197) (xy 161.326341 -276.20159) (xy 161.28822 -276.170465)
			(xy 161.255585 -276.133628) (xy 161.229282 -276.092032) (xy 161.209991 -276.046756) (xy 161.198214 -275.998972)
			(xy 161.194254 -275.949918) (xy 59.005216 -275.949918) (xy 59.004721 -275.974525) (xy 58.996826 -276.023102)
			(xy 58.981242 -276.069783) (xy 58.958371 -276.11336) (xy 58.928806 -276.152704) (xy 58.893313 -276.186796)
			(xy 58.85281 -276.214752) (xy 58.808348 -276.23585) (xy 58.761077 -276.249542) (xy 58.712222 -276.255474)
			(xy 58.663047 -276.253493) (xy 58.614828 -276.243649) (xy 58.568812 -276.226197) (xy 58.526191 -276.20159)
			(xy 58.48807 -276.170465) (xy 58.455435 -276.133628) (xy 58.429132 -276.092032) (xy 58.409841 -276.046756)
			(xy 58.398064 -275.998972) (xy 58.394104 -275.949918) (xy 57.105296 -275.949918) (xy 57.104801 -275.974525)
			(xy 57.096906 -276.023102) (xy 57.081322 -276.069783) (xy 57.058451 -276.11336) (xy 57.028886 -276.152704)
			(xy 56.993393 -276.186796) (xy 56.95289 -276.214752) (xy 56.908428 -276.23585) (xy 56.861157 -276.249542)
			(xy 56.812302 -276.255474) (xy 56.763127 -276.253493) (xy 56.714908 -276.243649) (xy 56.668892 -276.226197)
			(xy 56.626271 -276.20159) (xy 56.58815 -276.170465) (xy 56.555515 -276.133628) (xy 56.529212 -276.092032)
			(xy 56.509921 -276.046756) (xy 56.498144 -275.998972) (xy 56.494184 -275.949918) (xy 55.205122 -275.949918)
			(xy 55.204627 -275.974525) (xy 55.196732 -276.023102) (xy 55.181148 -276.069783) (xy 55.158277 -276.11336)
			(xy 55.128712 -276.152704) (xy 55.093219 -276.186796) (xy 55.052716 -276.214752) (xy 55.008254 -276.23585)
			(xy 54.960983 -276.249542) (xy 54.912128 -276.255474) (xy 54.862953 -276.253493) (xy 54.814734 -276.243649)
			(xy 54.768718 -276.226197) (xy 54.726097 -276.20159) (xy 54.687976 -276.170465) (xy 54.655341 -276.133628)
			(xy 54.629038 -276.092032) (xy 54.609747 -276.046756) (xy 54.59797 -275.998972) (xy 54.59401 -275.949918)
			(xy 53.305202 -275.949918) (xy 53.304707 -275.974525) (xy 53.296812 -276.023102) (xy 53.281228 -276.069783)
			(xy 53.258357 -276.11336) (xy 53.228792 -276.152704) (xy 53.193299 -276.186796) (xy 53.152796 -276.214752)
			(xy 53.108334 -276.23585) (xy 53.061063 -276.249542) (xy 53.012208 -276.255474) (xy 52.963033 -276.253493)
			(xy 52.914814 -276.243649) (xy 52.868798 -276.226197) (xy 52.826177 -276.20159) (xy 52.788056 -276.170465)
			(xy 52.755421 -276.133628) (xy 52.729118 -276.092032) (xy 52.709827 -276.046756) (xy 52.69805 -275.998972)
			(xy 52.69409 -275.949918) (xy 51.405282 -275.949918) (xy 51.404787 -275.974525) (xy 51.396892 -276.023102)
			(xy 51.381308 -276.069783) (xy 51.358437 -276.11336) (xy 51.328872 -276.152704) (xy 51.293379 -276.186796)
			(xy 51.252876 -276.214752) (xy 51.208414 -276.23585) (xy 51.161143 -276.249542) (xy 51.112288 -276.255474)
			(xy 51.063113 -276.253493) (xy 51.014894 -276.243649) (xy 50.968878 -276.226197) (xy 50.926257 -276.20159)
			(xy 50.888136 -276.170465) (xy 50.855501 -276.133628) (xy 50.829198 -276.092032) (xy 50.809907 -276.046756)
			(xy 50.79813 -275.998972) (xy 50.79417 -275.949918) (xy 49.505108 -275.949918) (xy 49.504613 -275.974525)
			(xy 49.496718 -276.023102) (xy 49.481134 -276.069783) (xy 49.458263 -276.11336) (xy 49.428698 -276.152704)
			(xy 49.393205 -276.186796) (xy 49.352702 -276.214752) (xy 49.30824 -276.23585) (xy 49.260969 -276.249542)
			(xy 49.212114 -276.255474) (xy 49.162939 -276.253493) (xy 49.11472 -276.243649) (xy 49.068704 -276.226197)
			(xy 49.026083 -276.20159) (xy 48.987962 -276.170465) (xy 48.955327 -276.133628) (xy 48.929024 -276.092032)
			(xy 48.909733 -276.046756) (xy 48.897956 -275.998972) (xy 48.893996 -275.949918) (xy 47.605188 -275.949918)
			(xy 47.604693 -275.974525) (xy 47.596798 -276.023102) (xy 47.581214 -276.069783) (xy 47.558343 -276.11336)
			(xy 47.528778 -276.152704) (xy 47.493285 -276.186796) (xy 47.452782 -276.214752) (xy 47.40832 -276.23585)
			(xy 47.361049 -276.249542) (xy 47.312194 -276.255474) (xy 47.263019 -276.253493) (xy 47.2148 -276.243649)
			(xy 47.168784 -276.226197) (xy 47.126163 -276.20159) (xy 47.088042 -276.170465) (xy 47.055407 -276.133628)
			(xy 47.029104 -276.092032) (xy 47.009813 -276.046756) (xy 46.998036 -275.998972) (xy 46.994076 -275.949918)
			(xy 45.705268 -275.949918) (xy 45.704773 -275.974525) (xy 45.696878 -276.023102) (xy 45.681294 -276.069783)
			(xy 45.658423 -276.11336) (xy 45.628858 -276.152704) (xy 45.593365 -276.186796) (xy 45.552862 -276.214752)
			(xy 45.5084 -276.23585) (xy 45.461129 -276.249542) (xy 45.412274 -276.255474) (xy 45.363099 -276.253493)
			(xy 45.31488 -276.243649) (xy 45.268864 -276.226197) (xy 45.226243 -276.20159) (xy 45.188122 -276.170465)
			(xy 45.155487 -276.133628) (xy 45.129184 -276.092032) (xy 45.109893 -276.046756) (xy 45.098116 -275.998972)
			(xy 45.094156 -275.949918) (xy 0.508 -275.949918) (xy 0.508 -276.899878) (xy 81.19416 -276.899878)
			(xy 81.19812 -276.850824) (xy 81.209897 -276.80304) (xy 81.229188 -276.757764) (xy 81.255491 -276.716168)
			(xy 81.288126 -276.679331) (xy 81.326247 -276.648206) (xy 81.368868 -276.623599) (xy 81.414884 -276.606147)
			(xy 81.463103 -276.596303) (xy 81.512278 -276.594322) (xy 81.561133 -276.600254) (xy 81.608404 -276.613946)
			(xy 81.652866 -276.635044) (xy 81.693369 -276.663) (xy 81.728862 -276.697092) (xy 81.758427 -276.736436)
			(xy 81.781298 -276.780013) (xy 81.796882 -276.826694) (xy 81.804777 -276.875271) (xy 81.805272 -276.899878)
			(xy 82.14412 -276.899878) (xy 82.14808 -276.850824) (xy 82.159857 -276.80304) (xy 82.179148 -276.757764)
			(xy 82.205451 -276.716168) (xy 82.238086 -276.679331) (xy 82.276207 -276.648206) (xy 82.318828 -276.623599)
			(xy 82.364844 -276.606147) (xy 82.413063 -276.596303) (xy 82.462238 -276.594322) (xy 82.511093 -276.600254)
			(xy 82.558364 -276.613946) (xy 82.602826 -276.635044) (xy 82.643329 -276.663) (xy 82.678822 -276.697092)
			(xy 82.708387 -276.736436) (xy 82.731258 -276.780013) (xy 82.746842 -276.826694) (xy 82.754737 -276.875271)
			(xy 82.755232 -276.899878) (xy 197.294258 -276.899878) (xy 197.298218 -276.850824) (xy 197.309995 -276.80304)
			(xy 197.329286 -276.757764) (xy 197.355589 -276.716168) (xy 197.388224 -276.679331) (xy 197.426345 -276.648206)
			(xy 197.468966 -276.623599) (xy 197.514982 -276.606147) (xy 197.563201 -276.596303) (xy 197.612376 -276.594322)
			(xy 197.661231 -276.600254) (xy 197.708502 -276.613946) (xy 197.752964 -276.635044) (xy 197.793467 -276.663)
			(xy 197.82896 -276.697092) (xy 197.858525 -276.736436) (xy 197.881396 -276.780013) (xy 197.89698 -276.826694)
			(xy 197.904875 -276.875271) (xy 197.90537 -276.899878) (xy 198.244218 -276.899878) (xy 198.248178 -276.850824)
			(xy 198.259955 -276.80304) (xy 198.279246 -276.757764) (xy 198.305549 -276.716168) (xy 198.338184 -276.679331)
			(xy 198.376305 -276.648206) (xy 198.418926 -276.623599) (xy 198.464942 -276.606147) (xy 198.513161 -276.596303)
			(xy 198.562336 -276.594322) (xy 198.611191 -276.600254) (xy 198.658462 -276.613946) (xy 198.702924 -276.635044)
			(xy 198.743427 -276.663) (xy 198.77892 -276.697092) (xy 198.808485 -276.736436) (xy 198.831356 -276.780013)
			(xy 198.84694 -276.826694) (xy 198.854835 -276.875271) (xy 198.85533 -276.899878) (xy 313.394102 -276.899878)
			(xy 313.398062 -276.850824) (xy 313.409839 -276.80304) (xy 313.42913 -276.757764) (xy 313.455433 -276.716168)
			(xy 313.488068 -276.679331) (xy 313.526189 -276.648206) (xy 313.56881 -276.623599) (xy 313.614826 -276.606147)
			(xy 313.663045 -276.596303) (xy 313.71222 -276.594322) (xy 313.761075 -276.600254) (xy 313.808346 -276.613946)
			(xy 313.852808 -276.635044) (xy 313.893311 -276.663) (xy 313.928804 -276.697092) (xy 313.958369 -276.736436)
			(xy 313.98124 -276.780013) (xy 313.996824 -276.826694) (xy 314.004719 -276.875271) (xy 314.005214 -276.899878)
			(xy 314.344062 -276.899878) (xy 314.348022 -276.850824) (xy 314.359799 -276.80304) (xy 314.37909 -276.757764)
			(xy 314.405393 -276.716168) (xy 314.438028 -276.679331) (xy 314.476149 -276.648206) (xy 314.51877 -276.623599)
			(xy 314.564786 -276.606147) (xy 314.613005 -276.596303) (xy 314.66218 -276.594322) (xy 314.711035 -276.600254)
			(xy 314.758306 -276.613946) (xy 314.802768 -276.635044) (xy 314.843271 -276.663) (xy 314.878764 -276.697092)
			(xy 314.908329 -276.736436) (xy 314.9312 -276.780013) (xy 314.946784 -276.826694) (xy 314.954679 -276.875271)
			(xy 314.955174 -276.899878) (xy 429.4942 -276.899878) (xy 429.49816 -276.850824) (xy 429.509937 -276.80304)
			(xy 429.529228 -276.757764) (xy 429.555531 -276.716168) (xy 429.588166 -276.679331) (xy 429.626287 -276.648206)
			(xy 429.668908 -276.623599) (xy 429.714924 -276.606147) (xy 429.763143 -276.596303) (xy 429.812318 -276.594322)
			(xy 429.861173 -276.600254) (xy 429.908444 -276.613946) (xy 429.952906 -276.635044) (xy 429.993409 -276.663)
			(xy 430.028902 -276.697092) (xy 430.058467 -276.736436) (xy 430.081338 -276.780013) (xy 430.096922 -276.826694)
			(xy 430.104817 -276.875271) (xy 430.105312 -276.899878) (xy 430.44416 -276.899878) (xy 430.44812 -276.850824)
			(xy 430.459897 -276.80304) (xy 430.479188 -276.757764) (xy 430.505491 -276.716168) (xy 430.538126 -276.679331)
			(xy 430.576247 -276.648206) (xy 430.618868 -276.623599) (xy 430.664884 -276.606147) (xy 430.713103 -276.596303)
			(xy 430.762278 -276.594322) (xy 430.811133 -276.600254) (xy 430.858404 -276.613946) (xy 430.902866 -276.635044)
			(xy 430.943369 -276.663) (xy 430.978862 -276.697092) (xy 431.008427 -276.736436) (xy 431.031298 -276.780013)
			(xy 431.046882 -276.826694) (xy 431.054777 -276.875271) (xy 431.055272 -276.899878) (xy 431.054777 -276.924485)
			(xy 431.046882 -276.973062) (xy 431.031298 -277.019743) (xy 431.008427 -277.06332) (xy 430.978862 -277.102664)
			(xy 430.943369 -277.136756) (xy 430.902866 -277.164712) (xy 430.858404 -277.18581) (xy 430.811133 -277.199502)
			(xy 430.762278 -277.205434) (xy 430.713103 -277.203453) (xy 430.664884 -277.193609) (xy 430.618868 -277.176157)
			(xy 430.576247 -277.15155) (xy 430.538126 -277.120425) (xy 430.505491 -277.083588) (xy 430.479188 -277.041992)
			(xy 430.459897 -276.996716) (xy 430.44812 -276.948932) (xy 430.44416 -276.899878) (xy 430.105312 -276.899878)
			(xy 430.104817 -276.924485) (xy 430.096922 -276.973062) (xy 430.081338 -277.019743) (xy 430.058467 -277.06332)
			(xy 430.028902 -277.102664) (xy 429.993409 -277.136756) (xy 429.952906 -277.164712) (xy 429.908444 -277.18581)
			(xy 429.861173 -277.199502) (xy 429.812318 -277.205434) (xy 429.763143 -277.203453) (xy 429.714924 -277.193609)
			(xy 429.668908 -277.176157) (xy 429.626287 -277.15155) (xy 429.588166 -277.120425) (xy 429.555531 -277.083588)
			(xy 429.529228 -277.041992) (xy 429.509937 -276.996716) (xy 429.49816 -276.948932) (xy 429.4942 -276.899878)
			(xy 314.955174 -276.899878) (xy 314.954679 -276.924485) (xy 314.946784 -276.973062) (xy 314.9312 -277.019743)
			(xy 314.908329 -277.06332) (xy 314.878764 -277.102664) (xy 314.843271 -277.136756) (xy 314.802768 -277.164712)
			(xy 314.758306 -277.18581) (xy 314.711035 -277.199502) (xy 314.66218 -277.205434) (xy 314.613005 -277.203453)
			(xy 314.564786 -277.193609) (xy 314.51877 -277.176157) (xy 314.476149 -277.15155) (xy 314.438028 -277.120425)
			(xy 314.405393 -277.083588) (xy 314.37909 -277.041992) (xy 314.359799 -276.996716) (xy 314.348022 -276.948932)
			(xy 314.344062 -276.899878) (xy 314.005214 -276.899878) (xy 314.004719 -276.924485) (xy 313.996824 -276.973062)
			(xy 313.98124 -277.019743) (xy 313.958369 -277.06332) (xy 313.928804 -277.102664) (xy 313.893311 -277.136756)
			(xy 313.852808 -277.164712) (xy 313.808346 -277.18581) (xy 313.761075 -277.199502) (xy 313.71222 -277.205434)
			(xy 313.663045 -277.203453) (xy 313.614826 -277.193609) (xy 313.56881 -277.176157) (xy 313.526189 -277.15155)
			(xy 313.488068 -277.120425) (xy 313.455433 -277.083588) (xy 313.42913 -277.041992) (xy 313.409839 -276.996716)
			(xy 313.398062 -276.948932) (xy 313.394102 -276.899878) (xy 198.85533 -276.899878) (xy 198.854835 -276.924485)
			(xy 198.84694 -276.973062) (xy 198.831356 -277.019743) (xy 198.808485 -277.06332) (xy 198.77892 -277.102664)
			(xy 198.743427 -277.136756) (xy 198.702924 -277.164712) (xy 198.658462 -277.18581) (xy 198.611191 -277.199502)
			(xy 198.562336 -277.205434) (xy 198.513161 -277.203453) (xy 198.464942 -277.193609) (xy 198.418926 -277.176157)
			(xy 198.376305 -277.15155) (xy 198.338184 -277.120425) (xy 198.305549 -277.083588) (xy 198.279246 -277.041992)
			(xy 198.259955 -276.996716) (xy 198.248178 -276.948932) (xy 198.244218 -276.899878) (xy 197.90537 -276.899878)
			(xy 197.904875 -276.924485) (xy 197.89698 -276.973062) (xy 197.881396 -277.019743) (xy 197.858525 -277.06332)
			(xy 197.82896 -277.102664) (xy 197.793467 -277.136756) (xy 197.752964 -277.164712) (xy 197.708502 -277.18581)
			(xy 197.661231 -277.199502) (xy 197.612376 -277.205434) (xy 197.563201 -277.203453) (xy 197.514982 -277.193609)
			(xy 197.468966 -277.176157) (xy 197.426345 -277.15155) (xy 197.388224 -277.120425) (xy 197.355589 -277.083588)
			(xy 197.329286 -277.041992) (xy 197.309995 -276.996716) (xy 197.298218 -276.948932) (xy 197.294258 -276.899878)
			(xy 82.755232 -276.899878) (xy 82.754737 -276.924485) (xy 82.746842 -276.973062) (xy 82.731258 -277.019743)
			(xy 82.708387 -277.06332) (xy 82.678822 -277.102664) (xy 82.643329 -277.136756) (xy 82.602826 -277.164712)
			(xy 82.558364 -277.18581) (xy 82.511093 -277.199502) (xy 82.462238 -277.205434) (xy 82.413063 -277.203453)
			(xy 82.364844 -277.193609) (xy 82.318828 -277.176157) (xy 82.276207 -277.15155) (xy 82.238086 -277.120425)
			(xy 82.205451 -277.083588) (xy 82.179148 -277.041992) (xy 82.159857 -276.996716) (xy 82.14808 -276.948932)
			(xy 82.14412 -276.899878) (xy 81.805272 -276.899878) (xy 81.804777 -276.924485) (xy 81.796882 -276.973062)
			(xy 81.781298 -277.019743) (xy 81.758427 -277.06332) (xy 81.728862 -277.102664) (xy 81.693369 -277.136756)
			(xy 81.652866 -277.164712) (xy 81.608404 -277.18581) (xy 81.561133 -277.199502) (xy 81.512278 -277.205434)
			(xy 81.463103 -277.203453) (xy 81.414884 -277.193609) (xy 81.368868 -277.176157) (xy 81.326247 -277.15155)
			(xy 81.288126 -277.120425) (xy 81.255491 -277.083588) (xy 81.229188 -277.041992) (xy 81.209897 -276.996716)
			(xy 81.19812 -276.948932) (xy 81.19416 -276.899878) (xy 0.508 -276.899878) (xy 0.508 -277.849838)
			(xy 44.143942 -277.849838) (xy 44.147902 -277.800784) (xy 44.159679 -277.753) (xy 44.17897 -277.707724)
			(xy 44.205273 -277.666128) (xy 44.237908 -277.629291) (xy 44.276029 -277.598166) (xy 44.31865 -277.573559)
			(xy 44.364666 -277.556107) (xy 44.412885 -277.546263) (xy 44.46206 -277.544282) (xy 44.510915 -277.550214)
			(xy 44.558186 -277.563906) (xy 44.602648 -277.585004) (xy 44.643151 -277.61296) (xy 44.678644 -277.647052)
			(xy 44.708209 -277.686396) (xy 44.73108 -277.729973) (xy 44.746664 -277.776654) (xy 44.754559 -277.825231)
			(xy 44.755054 -277.849838) (xy 46.044116 -277.849838) (xy 46.048076 -277.800784) (xy 46.059853 -277.753)
			(xy 46.079144 -277.707724) (xy 46.105447 -277.666128) (xy 46.138082 -277.629291) (xy 46.176203 -277.598166)
			(xy 46.218824 -277.573559) (xy 46.26484 -277.556107) (xy 46.313059 -277.546263) (xy 46.362234 -277.544282)
			(xy 46.411089 -277.550214) (xy 46.45836 -277.563906) (xy 46.502822 -277.585004) (xy 46.543325 -277.61296)
			(xy 46.578818 -277.647052) (xy 46.608383 -277.686396) (xy 46.631254 -277.729973) (xy 46.646838 -277.776654)
			(xy 46.654733 -277.825231) (xy 46.655228 -277.849838) (xy 47.944036 -277.849838) (xy 47.947996 -277.800784)
			(xy 47.959773 -277.753) (xy 47.979064 -277.707724) (xy 48.005367 -277.666128) (xy 48.038002 -277.629291)
			(xy 48.076123 -277.598166) (xy 48.118744 -277.573559) (xy 48.16476 -277.556107) (xy 48.212979 -277.546263)
			(xy 48.262154 -277.544282) (xy 48.311009 -277.550214) (xy 48.35828 -277.563906) (xy 48.402742 -277.585004)
			(xy 48.443245 -277.61296) (xy 48.478738 -277.647052) (xy 48.508303 -277.686396) (xy 48.531174 -277.729973)
			(xy 48.546758 -277.776654) (xy 48.554653 -277.825231) (xy 48.555148 -277.849838) (xy 49.843956 -277.849838)
			(xy 49.847916 -277.800784) (xy 49.859693 -277.753) (xy 49.878984 -277.707724) (xy 49.905287 -277.666128)
			(xy 49.937922 -277.629291) (xy 49.976043 -277.598166) (xy 50.018664 -277.573559) (xy 50.06468 -277.556107)
			(xy 50.112899 -277.546263) (xy 50.162074 -277.544282) (xy 50.210929 -277.550214) (xy 50.2582 -277.563906)
			(xy 50.302662 -277.585004) (xy 50.343165 -277.61296) (xy 50.378658 -277.647052) (xy 50.408223 -277.686396)
			(xy 50.431094 -277.729973) (xy 50.446678 -277.776654) (xy 50.454573 -277.825231) (xy 50.455068 -277.849838)
			(xy 51.74413 -277.849838) (xy 51.74809 -277.800784) (xy 51.759867 -277.753) (xy 51.779158 -277.707724)
			(xy 51.805461 -277.666128) (xy 51.838096 -277.629291) (xy 51.876217 -277.598166) (xy 51.918838 -277.573559)
			(xy 51.964854 -277.556107) (xy 52.013073 -277.546263) (xy 52.062248 -277.544282) (xy 52.111103 -277.550214)
			(xy 52.158374 -277.563906) (xy 52.202836 -277.585004) (xy 52.243339 -277.61296) (xy 52.278832 -277.647052)
			(xy 52.308397 -277.686396) (xy 52.331268 -277.729973) (xy 52.346852 -277.776654) (xy 52.354747 -277.825231)
			(xy 52.355242 -277.849838) (xy 53.64405 -277.849838) (xy 53.64801 -277.800784) (xy 53.659787 -277.753)
			(xy 53.679078 -277.707724) (xy 53.705381 -277.666128) (xy 53.738016 -277.629291) (xy 53.776137 -277.598166)
			(xy 53.818758 -277.573559) (xy 53.864774 -277.556107) (xy 53.912993 -277.546263) (xy 53.962168 -277.544282)
			(xy 54.011023 -277.550214) (xy 54.058294 -277.563906) (xy 54.102756 -277.585004) (xy 54.143259 -277.61296)
			(xy 54.178752 -277.647052) (xy 54.208317 -277.686396) (xy 54.231188 -277.729973) (xy 54.246772 -277.776654)
			(xy 54.254667 -277.825231) (xy 54.255162 -277.849838) (xy 55.54397 -277.849838) (xy 55.54793 -277.800784)
			(xy 55.559707 -277.753) (xy 55.578998 -277.707724) (xy 55.605301 -277.666128) (xy 55.637936 -277.629291)
			(xy 55.676057 -277.598166) (xy 55.718678 -277.573559) (xy 55.764694 -277.556107) (xy 55.812913 -277.546263)
			(xy 55.862088 -277.544282) (xy 55.910943 -277.550214) (xy 55.958214 -277.563906) (xy 56.002676 -277.585004)
			(xy 56.043179 -277.61296) (xy 56.078672 -277.647052) (xy 56.108237 -277.686396) (xy 56.131108 -277.729973)
			(xy 56.146692 -277.776654) (xy 56.154587 -277.825231) (xy 56.155082 -277.849838) (xy 57.444144 -277.849838)
			(xy 57.448104 -277.800784) (xy 57.459881 -277.753) (xy 57.479172 -277.707724) (xy 57.505475 -277.666128)
			(xy 57.53811 -277.629291) (xy 57.576231 -277.598166) (xy 57.618852 -277.573559) (xy 57.664868 -277.556107)
			(xy 57.713087 -277.546263) (xy 57.762262 -277.544282) (xy 57.811117 -277.550214) (xy 57.858388 -277.563906)
			(xy 57.90285 -277.585004) (xy 57.943353 -277.61296) (xy 57.978846 -277.647052) (xy 58.008411 -277.686396)
			(xy 58.031282 -277.729973) (xy 58.046866 -277.776654) (xy 58.054761 -277.825231) (xy 58.055256 -277.849838)
			(xy 59.34381 -277.849838) (xy 59.34777 -277.800784) (xy 59.359547 -277.753) (xy 59.378838 -277.707724)
			(xy 59.405141 -277.666128) (xy 59.437776 -277.629291) (xy 59.475897 -277.598166) (xy 59.518518 -277.573559)
			(xy 59.564534 -277.556107) (xy 59.612753 -277.546263) (xy 59.661928 -277.544282) (xy 59.710783 -277.550214)
			(xy 59.758054 -277.563906) (xy 59.802516 -277.585004) (xy 59.843019 -277.61296) (xy 59.878512 -277.647052)
			(xy 59.908077 -277.686396) (xy 59.930948 -277.729973) (xy 59.946532 -277.776654) (xy 59.954427 -277.825231)
			(xy 59.954922 -277.849838) (xy 61.24373 -277.849838) (xy 61.24769 -277.800784) (xy 61.259467 -277.753)
			(xy 61.278758 -277.707724) (xy 61.305061 -277.666128) (xy 61.337696 -277.629291) (xy 61.375817 -277.598166)
			(xy 61.418438 -277.573559) (xy 61.464454 -277.556107) (xy 61.512673 -277.546263) (xy 61.561848 -277.544282)
			(xy 61.610703 -277.550214) (xy 61.657974 -277.563906) (xy 61.702436 -277.585004) (xy 61.742939 -277.61296)
			(xy 61.778432 -277.647052) (xy 61.807997 -277.686396) (xy 61.830868 -277.729973) (xy 61.846452 -277.776654)
			(xy 61.854347 -277.825231) (xy 61.854842 -277.849838) (xy 63.143904 -277.849838) (xy 63.147864 -277.800784)
			(xy 63.159641 -277.753) (xy 63.178932 -277.707724) (xy 63.205235 -277.666128) (xy 63.23787 -277.629291)
			(xy 63.275991 -277.598166) (xy 63.318612 -277.573559) (xy 63.364628 -277.556107) (xy 63.412847 -277.546263)
			(xy 63.462022 -277.544282) (xy 63.510877 -277.550214) (xy 63.558148 -277.563906) (xy 63.60261 -277.585004)
			(xy 63.643113 -277.61296) (xy 63.678606 -277.647052) (xy 63.708171 -277.686396) (xy 63.731042 -277.729973)
			(xy 63.746626 -277.776654) (xy 63.754521 -277.825231) (xy 63.755016 -277.849838) (xy 65.043824 -277.849838)
			(xy 65.047784 -277.800784) (xy 65.059561 -277.753) (xy 65.078852 -277.707724) (xy 65.105155 -277.666128)
			(xy 65.13779 -277.629291) (xy 65.175911 -277.598166) (xy 65.218532 -277.573559) (xy 65.264548 -277.556107)
			(xy 65.312767 -277.546263) (xy 65.361942 -277.544282) (xy 65.410797 -277.550214) (xy 65.458068 -277.563906)
			(xy 65.50253 -277.585004) (xy 65.543033 -277.61296) (xy 65.578526 -277.647052) (xy 65.608091 -277.686396)
			(xy 65.630962 -277.729973) (xy 65.646546 -277.776654) (xy 65.654441 -277.825231) (xy 65.654936 -277.849838)
			(xy 66.943744 -277.849838) (xy 66.947704 -277.800784) (xy 66.959481 -277.753) (xy 66.978772 -277.707724)
			(xy 67.005075 -277.666128) (xy 67.03771 -277.629291) (xy 67.075831 -277.598166) (xy 67.118452 -277.573559)
			(xy 67.164468 -277.556107) (xy 67.212687 -277.546263) (xy 67.261862 -277.544282) (xy 67.310717 -277.550214)
			(xy 67.357988 -277.563906) (xy 67.40245 -277.585004) (xy 67.442953 -277.61296) (xy 67.478446 -277.647052)
			(xy 67.508011 -277.686396) (xy 67.530882 -277.729973) (xy 67.546466 -277.776654) (xy 67.554361 -277.825231)
			(xy 67.554856 -277.849838) (xy 68.843918 -277.849838) (xy 68.847878 -277.800784) (xy 68.859655 -277.753)
			(xy 68.878946 -277.707724) (xy 68.905249 -277.666128) (xy 68.937884 -277.629291) (xy 68.976005 -277.598166)
			(xy 69.018626 -277.573559) (xy 69.064642 -277.556107) (xy 69.112861 -277.546263) (xy 69.162036 -277.544282)
			(xy 69.210891 -277.550214) (xy 69.258162 -277.563906) (xy 69.302624 -277.585004) (xy 69.343127 -277.61296)
			(xy 69.37862 -277.647052) (xy 69.408185 -277.686396) (xy 69.431056 -277.729973) (xy 69.44664 -277.776654)
			(xy 69.454535 -277.825231) (xy 69.45503 -277.849838) (xy 70.743838 -277.849838) (xy 70.747798 -277.800784)
			(xy 70.759575 -277.753) (xy 70.778866 -277.707724) (xy 70.805169 -277.666128) (xy 70.837804 -277.629291)
			(xy 70.875925 -277.598166) (xy 70.918546 -277.573559) (xy 70.964562 -277.556107) (xy 71.012781 -277.546263)
			(xy 71.061956 -277.544282) (xy 71.110811 -277.550214) (xy 71.158082 -277.563906) (xy 71.202544 -277.585004)
			(xy 71.243047 -277.61296) (xy 71.27854 -277.647052) (xy 71.308105 -277.686396) (xy 71.330976 -277.729973)
			(xy 71.34656 -277.776654) (xy 71.354455 -277.825231) (xy 71.35495 -277.849838) (xy 72.643758 -277.849838)
			(xy 72.647718 -277.800784) (xy 72.659495 -277.753) (xy 72.678786 -277.707724) (xy 72.705089 -277.666128)
			(xy 72.737724 -277.629291) (xy 72.775845 -277.598166) (xy 72.818466 -277.573559) (xy 72.864482 -277.556107)
			(xy 72.912701 -277.546263) (xy 72.961876 -277.544282) (xy 73.010731 -277.550214) (xy 73.058002 -277.563906)
			(xy 73.102464 -277.585004) (xy 73.142967 -277.61296) (xy 73.17846 -277.647052) (xy 73.208025 -277.686396)
			(xy 73.230896 -277.729973) (xy 73.24648 -277.776654) (xy 73.254375 -277.825231) (xy 73.25487 -277.849838)
			(xy 74.543932 -277.849838) (xy 74.547892 -277.800784) (xy 74.559669 -277.753) (xy 74.57896 -277.707724)
			(xy 74.605263 -277.666128) (xy 74.637898 -277.629291) (xy 74.676019 -277.598166) (xy 74.71864 -277.573559)
			(xy 74.764656 -277.556107) (xy 74.812875 -277.546263) (xy 74.86205 -277.544282) (xy 74.910905 -277.550214)
			(xy 74.958176 -277.563906) (xy 75.002638 -277.585004) (xy 75.043141 -277.61296) (xy 75.078634 -277.647052)
			(xy 75.108199 -277.686396) (xy 75.13107 -277.729973) (xy 75.146654 -277.776654) (xy 75.154549 -277.825231)
			(xy 75.155044 -277.849838) (xy 76.443852 -277.849838) (xy 76.447812 -277.800784) (xy 76.459589 -277.753)
			(xy 76.47888 -277.707724) (xy 76.505183 -277.666128) (xy 76.537818 -277.629291) (xy 76.575939 -277.598166)
			(xy 76.61856 -277.573559) (xy 76.664576 -277.556107) (xy 76.712795 -277.546263) (xy 76.76197 -277.544282)
			(xy 76.810825 -277.550214) (xy 76.858096 -277.563906) (xy 76.902558 -277.585004) (xy 76.943061 -277.61296)
			(xy 76.978554 -277.647052) (xy 77.008119 -277.686396) (xy 77.03099 -277.729973) (xy 77.046574 -277.776654)
			(xy 77.054469 -277.825231) (xy 77.054964 -277.849838) (xy 78.343772 -277.849838) (xy 78.347732 -277.800784)
			(xy 78.359509 -277.753) (xy 78.3788 -277.707724) (xy 78.405103 -277.666128) (xy 78.437738 -277.629291)
			(xy 78.475859 -277.598166) (xy 78.51848 -277.573559) (xy 78.564496 -277.556107) (xy 78.612715 -277.546263)
			(xy 78.66189 -277.544282) (xy 78.710745 -277.550214) (xy 78.758016 -277.563906) (xy 78.802478 -277.585004)
			(xy 78.842981 -277.61296) (xy 78.878474 -277.647052) (xy 78.908039 -277.686396) (xy 78.93091 -277.729973)
			(xy 78.946494 -277.776654) (xy 78.954389 -277.825231) (xy 78.954884 -277.849838) (xy 80.243946 -277.849838)
			(xy 80.247906 -277.800784) (xy 80.259683 -277.753) (xy 80.278974 -277.707724) (xy 80.305277 -277.666128)
			(xy 80.337912 -277.629291) (xy 80.376033 -277.598166) (xy 80.418654 -277.573559) (xy 80.46467 -277.556107)
			(xy 80.512889 -277.546263) (xy 80.562064 -277.544282) (xy 80.610919 -277.550214) (xy 80.65819 -277.563906)
			(xy 80.702652 -277.585004) (xy 80.743155 -277.61296) (xy 80.778648 -277.647052) (xy 80.808213 -277.686396)
			(xy 80.831084 -277.729973) (xy 80.846668 -277.776654) (xy 80.854563 -277.825231) (xy 80.855058 -277.849838)
			(xy 160.24404 -277.849838) (xy 160.248 -277.800784) (xy 160.259777 -277.753) (xy 160.279068 -277.707724)
			(xy 160.305371 -277.666128) (xy 160.338006 -277.629291) (xy 160.376127 -277.598166) (xy 160.418748 -277.573559)
			(xy 160.464764 -277.556107) (xy 160.512983 -277.546263) (xy 160.562158 -277.544282) (xy 160.611013 -277.550214)
			(xy 160.658284 -277.563906) (xy 160.702746 -277.585004) (xy 160.743249 -277.61296) (xy 160.778742 -277.647052)
			(xy 160.808307 -277.686396) (xy 160.831178 -277.729973) (xy 160.846762 -277.776654) (xy 160.854657 -277.825231)
			(xy 160.855152 -277.849838) (xy 162.144214 -277.849838) (xy 162.148174 -277.800784) (xy 162.159951 -277.753)
			(xy 162.179242 -277.707724) (xy 162.205545 -277.666128) (xy 162.23818 -277.629291) (xy 162.276301 -277.598166)
			(xy 162.318922 -277.573559) (xy 162.364938 -277.556107) (xy 162.413157 -277.546263) (xy 162.462332 -277.544282)
			(xy 162.511187 -277.550214) (xy 162.558458 -277.563906) (xy 162.60292 -277.585004) (xy 162.643423 -277.61296)
			(xy 162.678916 -277.647052) (xy 162.708481 -277.686396) (xy 162.731352 -277.729973) (xy 162.746936 -277.776654)
			(xy 162.754831 -277.825231) (xy 162.755326 -277.849838) (xy 164.044134 -277.849838) (xy 164.048094 -277.800784)
			(xy 164.059871 -277.753) (xy 164.079162 -277.707724) (xy 164.105465 -277.666128) (xy 164.1381 -277.629291)
			(xy 164.176221 -277.598166) (xy 164.218842 -277.573559) (xy 164.264858 -277.556107) (xy 164.313077 -277.546263)
			(xy 164.362252 -277.544282) (xy 164.411107 -277.550214) (xy 164.458378 -277.563906) (xy 164.50284 -277.585004)
			(xy 164.543343 -277.61296) (xy 164.578836 -277.647052) (xy 164.608401 -277.686396) (xy 164.631272 -277.729973)
			(xy 164.646856 -277.776654) (xy 164.654751 -277.825231) (xy 164.655246 -277.849838) (xy 165.944054 -277.849838)
			(xy 165.948014 -277.800784) (xy 165.959791 -277.753) (xy 165.979082 -277.707724) (xy 166.005385 -277.666128)
			(xy 166.03802 -277.629291) (xy 166.076141 -277.598166) (xy 166.118762 -277.573559) (xy 166.164778 -277.556107)
			(xy 166.212997 -277.546263) (xy 166.262172 -277.544282) (xy 166.311027 -277.550214) (xy 166.358298 -277.563906)
			(xy 166.40276 -277.585004) (xy 166.443263 -277.61296) (xy 166.478756 -277.647052) (xy 166.508321 -277.686396)
			(xy 166.531192 -277.729973) (xy 166.546776 -277.776654) (xy 166.554671 -277.825231) (xy 166.555166 -277.849838)
			(xy 167.844228 -277.849838) (xy 167.848188 -277.800784) (xy 167.859965 -277.753) (xy 167.879256 -277.707724)
			(xy 167.905559 -277.666128) (xy 167.938194 -277.629291) (xy 167.976315 -277.598166) (xy 168.018936 -277.573559)
			(xy 168.064952 -277.556107) (xy 168.113171 -277.546263) (xy 168.162346 -277.544282) (xy 168.211201 -277.550214)
			(xy 168.258472 -277.563906) (xy 168.302934 -277.585004) (xy 168.343437 -277.61296) (xy 168.37893 -277.647052)
			(xy 168.408495 -277.686396) (xy 168.431366 -277.729973) (xy 168.44695 -277.776654) (xy 168.454845 -277.825231)
			(xy 168.45534 -277.849838) (xy 169.744148 -277.849838) (xy 169.748108 -277.800784) (xy 169.759885 -277.753)
			(xy 169.779176 -277.707724) (xy 169.805479 -277.666128) (xy 169.838114 -277.629291) (xy 169.876235 -277.598166)
			(xy 169.918856 -277.573559) (xy 169.964872 -277.556107) (xy 170.013091 -277.546263) (xy 170.062266 -277.544282)
			(xy 170.111121 -277.550214) (xy 170.158392 -277.563906) (xy 170.202854 -277.585004) (xy 170.243357 -277.61296)
			(xy 170.27885 -277.647052) (xy 170.308415 -277.686396) (xy 170.331286 -277.729973) (xy 170.34687 -277.776654)
			(xy 170.354765 -277.825231) (xy 170.35526 -277.849838) (xy 171.644068 -277.849838) (xy 171.648028 -277.800784)
			(xy 171.659805 -277.753) (xy 171.679096 -277.707724) (xy 171.705399 -277.666128) (xy 171.738034 -277.629291)
			(xy 171.776155 -277.598166) (xy 171.818776 -277.573559) (xy 171.864792 -277.556107) (xy 171.913011 -277.546263)
			(xy 171.962186 -277.544282) (xy 172.011041 -277.550214) (xy 172.058312 -277.563906) (xy 172.102774 -277.585004)
			(xy 172.143277 -277.61296) (xy 172.17877 -277.647052) (xy 172.208335 -277.686396) (xy 172.231206 -277.729973)
			(xy 172.24679 -277.776654) (xy 172.254685 -277.825231) (xy 172.25518 -277.849838) (xy 173.544242 -277.849838)
			(xy 173.548202 -277.800784) (xy 173.559979 -277.753) (xy 173.57927 -277.707724) (xy 173.605573 -277.666128)
			(xy 173.638208 -277.629291) (xy 173.676329 -277.598166) (xy 173.71895 -277.573559) (xy 173.764966 -277.556107)
			(xy 173.813185 -277.546263) (xy 173.86236 -277.544282) (xy 173.911215 -277.550214) (xy 173.958486 -277.563906)
			(xy 174.002948 -277.585004) (xy 174.043451 -277.61296) (xy 174.078944 -277.647052) (xy 174.108509 -277.686396)
			(xy 174.13138 -277.729973) (xy 174.146964 -277.776654) (xy 174.154859 -277.825231) (xy 174.155354 -277.849838)
			(xy 175.443908 -277.849838) (xy 175.447868 -277.800784) (xy 175.459645 -277.753) (xy 175.478936 -277.707724)
			(xy 175.505239 -277.666128) (xy 175.537874 -277.629291) (xy 175.575995 -277.598166) (xy 175.618616 -277.573559)
			(xy 175.664632 -277.556107) (xy 175.712851 -277.546263) (xy 175.762026 -277.544282) (xy 175.810881 -277.550214)
			(xy 175.858152 -277.563906) (xy 175.902614 -277.585004) (xy 175.943117 -277.61296) (xy 175.97861 -277.647052)
			(xy 176.008175 -277.686396) (xy 176.031046 -277.729973) (xy 176.04663 -277.776654) (xy 176.054525 -277.825231)
			(xy 176.05502 -277.849838) (xy 177.343828 -277.849838) (xy 177.347788 -277.800784) (xy 177.359565 -277.753)
			(xy 177.378856 -277.707724) (xy 177.405159 -277.666128) (xy 177.437794 -277.629291) (xy 177.475915 -277.598166)
			(xy 177.518536 -277.573559) (xy 177.564552 -277.556107) (xy 177.612771 -277.546263) (xy 177.661946 -277.544282)
			(xy 177.710801 -277.550214) (xy 177.758072 -277.563906) (xy 177.802534 -277.585004) (xy 177.843037 -277.61296)
			(xy 177.87853 -277.647052) (xy 177.908095 -277.686396) (xy 177.930966 -277.729973) (xy 177.94655 -277.776654)
			(xy 177.954445 -277.825231) (xy 177.95494 -277.849838) (xy 179.244002 -277.849838) (xy 179.247962 -277.800784)
			(xy 179.259739 -277.753) (xy 179.27903 -277.707724) (xy 179.305333 -277.666128) (xy 179.337968 -277.629291)
			(xy 179.376089 -277.598166) (xy 179.41871 -277.573559) (xy 179.464726 -277.556107) (xy 179.512945 -277.546263)
			(xy 179.56212 -277.544282) (xy 179.610975 -277.550214) (xy 179.658246 -277.563906) (xy 179.702708 -277.585004)
			(xy 179.743211 -277.61296) (xy 179.778704 -277.647052) (xy 179.808269 -277.686396) (xy 179.83114 -277.729973)
			(xy 179.846724 -277.776654) (xy 179.854619 -277.825231) (xy 179.855114 -277.849838) (xy 181.143922 -277.849838)
			(xy 181.147882 -277.800784) (xy 181.159659 -277.753) (xy 181.17895 -277.707724) (xy 181.205253 -277.666128)
			(xy 181.237888 -277.629291) (xy 181.276009 -277.598166) (xy 181.31863 -277.573559) (xy 181.364646 -277.556107)
			(xy 181.412865 -277.546263) (xy 181.46204 -277.544282) (xy 181.510895 -277.550214) (xy 181.558166 -277.563906)
			(xy 181.602628 -277.585004) (xy 181.643131 -277.61296) (xy 181.678624 -277.647052) (xy 181.708189 -277.686396)
			(xy 181.73106 -277.729973) (xy 181.746644 -277.776654) (xy 181.754539 -277.825231) (xy 181.755034 -277.849838)
			(xy 183.043842 -277.849838) (xy 183.047802 -277.800784) (xy 183.059579 -277.753) (xy 183.07887 -277.707724)
			(xy 183.105173 -277.666128) (xy 183.137808 -277.629291) (xy 183.175929 -277.598166) (xy 183.21855 -277.573559)
			(xy 183.264566 -277.556107) (xy 183.312785 -277.546263) (xy 183.36196 -277.544282) (xy 183.410815 -277.550214)
			(xy 183.458086 -277.563906) (xy 183.502548 -277.585004) (xy 183.543051 -277.61296) (xy 183.578544 -277.647052)
			(xy 183.608109 -277.686396) (xy 183.63098 -277.729973) (xy 183.646564 -277.776654) (xy 183.654459 -277.825231)
			(xy 183.654954 -277.849838) (xy 184.944016 -277.849838) (xy 184.947976 -277.800784) (xy 184.959753 -277.753)
			(xy 184.979044 -277.707724) (xy 185.005347 -277.666128) (xy 185.037982 -277.629291) (xy 185.076103 -277.598166)
			(xy 185.118724 -277.573559) (xy 185.16474 -277.556107) (xy 185.212959 -277.546263) (xy 185.262134 -277.544282)
			(xy 185.310989 -277.550214) (xy 185.35826 -277.563906) (xy 185.402722 -277.585004) (xy 185.443225 -277.61296)
			(xy 185.478718 -277.647052) (xy 185.508283 -277.686396) (xy 185.531154 -277.729973) (xy 185.546738 -277.776654)
			(xy 185.554633 -277.825231) (xy 185.555128 -277.849838) (xy 186.843936 -277.849838) (xy 186.847896 -277.800784)
			(xy 186.859673 -277.753) (xy 186.878964 -277.707724) (xy 186.905267 -277.666128) (xy 186.937902 -277.629291)
			(xy 186.976023 -277.598166) (xy 187.018644 -277.573559) (xy 187.06466 -277.556107) (xy 187.112879 -277.546263)
			(xy 187.162054 -277.544282) (xy 187.210909 -277.550214) (xy 187.25818 -277.563906) (xy 187.302642 -277.585004)
			(xy 187.343145 -277.61296) (xy 187.378638 -277.647052) (xy 187.408203 -277.686396) (xy 187.431074 -277.729973)
			(xy 187.446658 -277.776654) (xy 187.454553 -277.825231) (xy 187.455048 -277.849838) (xy 188.743856 -277.849838)
			(xy 188.747816 -277.800784) (xy 188.759593 -277.753) (xy 188.778884 -277.707724) (xy 188.805187 -277.666128)
			(xy 188.837822 -277.629291) (xy 188.875943 -277.598166) (xy 188.918564 -277.573559) (xy 188.96458 -277.556107)
			(xy 189.012799 -277.546263) (xy 189.061974 -277.544282) (xy 189.110829 -277.550214) (xy 189.1581 -277.563906)
			(xy 189.202562 -277.585004) (xy 189.243065 -277.61296) (xy 189.278558 -277.647052) (xy 189.308123 -277.686396)
			(xy 189.330994 -277.729973) (xy 189.346578 -277.776654) (xy 189.354473 -277.825231) (xy 189.354968 -277.849838)
			(xy 190.64403 -277.849838) (xy 190.64799 -277.800784) (xy 190.659767 -277.753) (xy 190.679058 -277.707724)
			(xy 190.705361 -277.666128) (xy 190.737996 -277.629291) (xy 190.776117 -277.598166) (xy 190.818738 -277.573559)
			(xy 190.864754 -277.556107) (xy 190.912973 -277.546263) (xy 190.962148 -277.544282) (xy 191.011003 -277.550214)
			(xy 191.058274 -277.563906) (xy 191.102736 -277.585004) (xy 191.143239 -277.61296) (xy 191.178732 -277.647052)
			(xy 191.208297 -277.686396) (xy 191.231168 -277.729973) (xy 191.246752 -277.776654) (xy 191.254647 -277.825231)
			(xy 191.255142 -277.849838) (xy 192.54395 -277.849838) (xy 192.54791 -277.800784) (xy 192.559687 -277.753)
			(xy 192.578978 -277.707724) (xy 192.605281 -277.666128) (xy 192.637916 -277.629291) (xy 192.676037 -277.598166)
			(xy 192.718658 -277.573559) (xy 192.764674 -277.556107) (xy 192.812893 -277.546263) (xy 192.862068 -277.544282)
			(xy 192.910923 -277.550214) (xy 192.958194 -277.563906) (xy 193.002656 -277.585004) (xy 193.043159 -277.61296)
			(xy 193.078652 -277.647052) (xy 193.108217 -277.686396) (xy 193.131088 -277.729973) (xy 193.146672 -277.776654)
			(xy 193.154567 -277.825231) (xy 193.155062 -277.849838) (xy 194.44387 -277.849838) (xy 194.44783 -277.800784)
			(xy 194.459607 -277.753) (xy 194.478898 -277.707724) (xy 194.505201 -277.666128) (xy 194.537836 -277.629291)
			(xy 194.575957 -277.598166) (xy 194.618578 -277.573559) (xy 194.664594 -277.556107) (xy 194.712813 -277.546263)
			(xy 194.761988 -277.544282) (xy 194.810843 -277.550214) (xy 194.858114 -277.563906) (xy 194.902576 -277.585004)
			(xy 194.943079 -277.61296) (xy 194.978572 -277.647052) (xy 195.008137 -277.686396) (xy 195.031008 -277.729973)
			(xy 195.046592 -277.776654) (xy 195.054487 -277.825231) (xy 195.054982 -277.849838) (xy 196.344044 -277.849838)
			(xy 196.348004 -277.800784) (xy 196.359781 -277.753) (xy 196.379072 -277.707724) (xy 196.405375 -277.666128)
			(xy 196.43801 -277.629291) (xy 196.476131 -277.598166) (xy 196.518752 -277.573559) (xy 196.564768 -277.556107)
			(xy 196.612987 -277.546263) (xy 196.662162 -277.544282) (xy 196.711017 -277.550214) (xy 196.758288 -277.563906)
			(xy 196.80275 -277.585004) (xy 196.843253 -277.61296) (xy 196.878746 -277.647052) (xy 196.908311 -277.686396)
			(xy 196.931182 -277.729973) (xy 196.946766 -277.776654) (xy 196.954661 -277.825231) (xy 196.955156 -277.849838)
			(xy 276.343884 -277.849838) (xy 276.347844 -277.800784) (xy 276.359621 -277.753) (xy 276.378912 -277.707724)
			(xy 276.405215 -277.666128) (xy 276.43785 -277.629291) (xy 276.475971 -277.598166) (xy 276.518592 -277.573559)
			(xy 276.564608 -277.556107) (xy 276.612827 -277.546263) (xy 276.662002 -277.544282) (xy 276.710857 -277.550214)
			(xy 276.758128 -277.563906) (xy 276.80259 -277.585004) (xy 276.843093 -277.61296) (xy 276.878586 -277.647052)
			(xy 276.908151 -277.686396) (xy 276.931022 -277.729973) (xy 276.946606 -277.776654) (xy 276.954501 -277.825231)
			(xy 276.954996 -277.849838) (xy 278.244058 -277.849838) (xy 278.248018 -277.800784) (xy 278.259795 -277.753)
			(xy 278.279086 -277.707724) (xy 278.305389 -277.666128) (xy 278.338024 -277.629291) (xy 278.376145 -277.598166)
			(xy 278.418766 -277.573559) (xy 278.464782 -277.556107) (xy 278.513001 -277.546263) (xy 278.562176 -277.544282)
			(xy 278.611031 -277.550214) (xy 278.658302 -277.563906) (xy 278.702764 -277.585004) (xy 278.743267 -277.61296)
			(xy 278.77876 -277.647052) (xy 278.808325 -277.686396) (xy 278.831196 -277.729973) (xy 278.84678 -277.776654)
			(xy 278.854675 -277.825231) (xy 278.85517 -277.849838) (xy 280.143978 -277.849838) (xy 280.147938 -277.800784)
			(xy 280.159715 -277.753) (xy 280.179006 -277.707724) (xy 280.205309 -277.666128) (xy 280.237944 -277.629291)
			(xy 280.276065 -277.598166) (xy 280.318686 -277.573559) (xy 280.364702 -277.556107) (xy 280.412921 -277.546263)
			(xy 280.462096 -277.544282) (xy 280.510951 -277.550214) (xy 280.558222 -277.563906) (xy 280.602684 -277.585004)
			(xy 280.643187 -277.61296) (xy 280.67868 -277.647052) (xy 280.708245 -277.686396) (xy 280.731116 -277.729973)
			(xy 280.7467 -277.776654) (xy 280.754595 -277.825231) (xy 280.75509 -277.849838) (xy 282.043898 -277.849838)
			(xy 282.047858 -277.800784) (xy 282.059635 -277.753) (xy 282.078926 -277.707724) (xy 282.105229 -277.666128)
			(xy 282.137864 -277.629291) (xy 282.175985 -277.598166) (xy 282.218606 -277.573559) (xy 282.264622 -277.556107)
			(xy 282.312841 -277.546263) (xy 282.362016 -277.544282) (xy 282.410871 -277.550214) (xy 282.458142 -277.563906)
			(xy 282.502604 -277.585004) (xy 282.543107 -277.61296) (xy 282.5786 -277.647052) (xy 282.608165 -277.686396)
			(xy 282.631036 -277.729973) (xy 282.64662 -277.776654) (xy 282.654515 -277.825231) (xy 282.65501 -277.849838)
			(xy 283.944072 -277.849838) (xy 283.948032 -277.800784) (xy 283.959809 -277.753) (xy 283.9791 -277.707724)
			(xy 284.005403 -277.666128) (xy 284.038038 -277.629291) (xy 284.076159 -277.598166) (xy 284.11878 -277.573559)
			(xy 284.164796 -277.556107) (xy 284.213015 -277.546263) (xy 284.26219 -277.544282) (xy 284.311045 -277.550214)
			(xy 284.358316 -277.563906) (xy 284.402778 -277.585004) (xy 284.443281 -277.61296) (xy 284.478774 -277.647052)
			(xy 284.508339 -277.686396) (xy 284.53121 -277.729973) (xy 284.546794 -277.776654) (xy 284.554689 -277.825231)
			(xy 284.555184 -277.849838) (xy 285.843992 -277.849838) (xy 285.847952 -277.800784) (xy 285.859729 -277.753)
			(xy 285.87902 -277.707724) (xy 285.905323 -277.666128) (xy 285.937958 -277.629291) (xy 285.976079 -277.598166)
			(xy 286.0187 -277.573559) (xy 286.064716 -277.556107) (xy 286.112935 -277.546263) (xy 286.16211 -277.544282)
			(xy 286.210965 -277.550214) (xy 286.258236 -277.563906) (xy 286.302698 -277.585004) (xy 286.343201 -277.61296)
			(xy 286.378694 -277.647052) (xy 286.408259 -277.686396) (xy 286.43113 -277.729973) (xy 286.446714 -277.776654)
			(xy 286.454609 -277.825231) (xy 286.455104 -277.849838) (xy 287.743912 -277.849838) (xy 287.747872 -277.800784)
			(xy 287.759649 -277.753) (xy 287.77894 -277.707724) (xy 287.805243 -277.666128) (xy 287.837878 -277.629291)
			(xy 287.875999 -277.598166) (xy 287.91862 -277.573559) (xy 287.964636 -277.556107) (xy 288.012855 -277.546263)
			(xy 288.06203 -277.544282) (xy 288.110885 -277.550214) (xy 288.158156 -277.563906) (xy 288.202618 -277.585004)
			(xy 288.243121 -277.61296) (xy 288.278614 -277.647052) (xy 288.308179 -277.686396) (xy 288.33105 -277.729973)
			(xy 288.346634 -277.776654) (xy 288.354529 -277.825231) (xy 288.355024 -277.849838) (xy 289.644086 -277.849838)
			(xy 289.648046 -277.800784) (xy 289.659823 -277.753) (xy 289.679114 -277.707724) (xy 289.705417 -277.666128)
			(xy 289.738052 -277.629291) (xy 289.776173 -277.598166) (xy 289.818794 -277.573559) (xy 289.86481 -277.556107)
			(xy 289.913029 -277.546263) (xy 289.962204 -277.544282) (xy 290.011059 -277.550214) (xy 290.05833 -277.563906)
			(xy 290.102792 -277.585004) (xy 290.143295 -277.61296) (xy 290.178788 -277.647052) (xy 290.208353 -277.686396)
			(xy 290.231224 -277.729973) (xy 290.246808 -277.776654) (xy 290.254703 -277.825231) (xy 290.255198 -277.849838)
			(xy 291.543752 -277.849838) (xy 291.547712 -277.800784) (xy 291.559489 -277.753) (xy 291.57878 -277.707724)
			(xy 291.605083 -277.666128) (xy 291.637718 -277.629291) (xy 291.675839 -277.598166) (xy 291.71846 -277.573559)
			(xy 291.764476 -277.556107) (xy 291.812695 -277.546263) (xy 291.86187 -277.544282) (xy 291.910725 -277.550214)
			(xy 291.957996 -277.563906) (xy 292.002458 -277.585004) (xy 292.042961 -277.61296) (xy 292.078454 -277.647052)
			(xy 292.108019 -277.686396) (xy 292.13089 -277.729973) (xy 292.146474 -277.776654) (xy 292.154369 -277.825231)
			(xy 292.154864 -277.849838) (xy 293.443672 -277.849838) (xy 293.447632 -277.800784) (xy 293.459409 -277.753)
			(xy 293.4787 -277.707724) (xy 293.505003 -277.666128) (xy 293.537638 -277.629291) (xy 293.575759 -277.598166)
			(xy 293.61838 -277.573559) (xy 293.664396 -277.556107) (xy 293.712615 -277.546263) (xy 293.76179 -277.544282)
			(xy 293.810645 -277.550214) (xy 293.857916 -277.563906) (xy 293.902378 -277.585004) (xy 293.942881 -277.61296)
			(xy 293.978374 -277.647052) (xy 294.007939 -277.686396) (xy 294.03081 -277.729973) (xy 294.046394 -277.776654)
			(xy 294.054289 -277.825231) (xy 294.054784 -277.849838) (xy 295.343846 -277.849838) (xy 295.347806 -277.800784)
			(xy 295.359583 -277.753) (xy 295.378874 -277.707724) (xy 295.405177 -277.666128) (xy 295.437812 -277.629291)
			(xy 295.475933 -277.598166) (xy 295.518554 -277.573559) (xy 295.56457 -277.556107) (xy 295.612789 -277.546263)
			(xy 295.661964 -277.544282) (xy 295.710819 -277.550214) (xy 295.75809 -277.563906) (xy 295.802552 -277.585004)
			(xy 295.843055 -277.61296) (xy 295.878548 -277.647052) (xy 295.908113 -277.686396) (xy 295.930984 -277.729973)
			(xy 295.946568 -277.776654) (xy 295.954463 -277.825231) (xy 295.954958 -277.849838) (xy 297.243766 -277.849838)
			(xy 297.247726 -277.800784) (xy 297.259503 -277.753) (xy 297.278794 -277.707724) (xy 297.305097 -277.666128)
			(xy 297.337732 -277.629291) (xy 297.375853 -277.598166) (xy 297.418474 -277.573559) (xy 297.46449 -277.556107)
			(xy 297.512709 -277.546263) (xy 297.561884 -277.544282) (xy 297.610739 -277.550214) (xy 297.65801 -277.563906)
			(xy 297.702472 -277.585004) (xy 297.742975 -277.61296) (xy 297.778468 -277.647052) (xy 297.808033 -277.686396)
			(xy 297.830904 -277.729973) (xy 297.846488 -277.776654) (xy 297.854383 -277.825231) (xy 297.854878 -277.849838)
			(xy 299.143686 -277.849838) (xy 299.147646 -277.800784) (xy 299.159423 -277.753) (xy 299.178714 -277.707724)
			(xy 299.205017 -277.666128) (xy 299.237652 -277.629291) (xy 299.275773 -277.598166) (xy 299.318394 -277.573559)
			(xy 299.36441 -277.556107) (xy 299.412629 -277.546263) (xy 299.461804 -277.544282) (xy 299.510659 -277.550214)
			(xy 299.55793 -277.563906) (xy 299.602392 -277.585004) (xy 299.642895 -277.61296) (xy 299.678388 -277.647052)
			(xy 299.707953 -277.686396) (xy 299.730824 -277.729973) (xy 299.746408 -277.776654) (xy 299.754303 -277.825231)
			(xy 299.754798 -277.849838) (xy 301.04386 -277.849838) (xy 301.04782 -277.800784) (xy 301.059597 -277.753)
			(xy 301.078888 -277.707724) (xy 301.105191 -277.666128) (xy 301.137826 -277.629291) (xy 301.175947 -277.598166)
			(xy 301.218568 -277.573559) (xy 301.264584 -277.556107) (xy 301.312803 -277.546263) (xy 301.361978 -277.544282)
			(xy 301.410833 -277.550214) (xy 301.458104 -277.563906) (xy 301.502566 -277.585004) (xy 301.543069 -277.61296)
			(xy 301.578562 -277.647052) (xy 301.608127 -277.686396) (xy 301.630998 -277.729973) (xy 301.646582 -277.776654)
			(xy 301.654477 -277.825231) (xy 301.654972 -277.849838) (xy 302.94378 -277.849838) (xy 302.94774 -277.800784)
			(xy 302.959517 -277.753) (xy 302.978808 -277.707724) (xy 303.005111 -277.666128) (xy 303.037746 -277.629291)
			(xy 303.075867 -277.598166) (xy 303.118488 -277.573559) (xy 303.164504 -277.556107) (xy 303.212723 -277.546263)
			(xy 303.261898 -277.544282) (xy 303.310753 -277.550214) (xy 303.358024 -277.563906) (xy 303.402486 -277.585004)
			(xy 303.442989 -277.61296) (xy 303.478482 -277.647052) (xy 303.508047 -277.686396) (xy 303.530918 -277.729973)
			(xy 303.546502 -277.776654) (xy 303.554397 -277.825231) (xy 303.554892 -277.849838) (xy 304.8437 -277.849838)
			(xy 304.84766 -277.800784) (xy 304.859437 -277.753) (xy 304.878728 -277.707724) (xy 304.905031 -277.666128)
			(xy 304.937666 -277.629291) (xy 304.975787 -277.598166) (xy 305.018408 -277.573559) (xy 305.064424 -277.556107)
			(xy 305.112643 -277.546263) (xy 305.161818 -277.544282) (xy 305.210673 -277.550214) (xy 305.257944 -277.563906)
			(xy 305.302406 -277.585004) (xy 305.342909 -277.61296) (xy 305.378402 -277.647052) (xy 305.407967 -277.686396)
			(xy 305.430838 -277.729973) (xy 305.446422 -277.776654) (xy 305.454317 -277.825231) (xy 305.454812 -277.849838)
			(xy 306.743874 -277.849838) (xy 306.747834 -277.800784) (xy 306.759611 -277.753) (xy 306.778902 -277.707724)
			(xy 306.805205 -277.666128) (xy 306.83784 -277.629291) (xy 306.875961 -277.598166) (xy 306.918582 -277.573559)
			(xy 306.964598 -277.556107) (xy 307.012817 -277.546263) (xy 307.061992 -277.544282) (xy 307.110847 -277.550214)
			(xy 307.158118 -277.563906) (xy 307.20258 -277.585004) (xy 307.243083 -277.61296) (xy 307.278576 -277.647052)
			(xy 307.308141 -277.686396) (xy 307.331012 -277.729973) (xy 307.346596 -277.776654) (xy 307.354491 -277.825231)
			(xy 307.354986 -277.849838) (xy 308.643794 -277.849838) (xy 308.647754 -277.800784) (xy 308.659531 -277.753)
			(xy 308.678822 -277.707724) (xy 308.705125 -277.666128) (xy 308.73776 -277.629291) (xy 308.775881 -277.598166)
			(xy 308.818502 -277.573559) (xy 308.864518 -277.556107) (xy 308.912737 -277.546263) (xy 308.961912 -277.544282)
			(xy 309.010767 -277.550214) (xy 309.058038 -277.563906) (xy 309.1025 -277.585004) (xy 309.143003 -277.61296)
			(xy 309.178496 -277.647052) (xy 309.208061 -277.686396) (xy 309.230932 -277.729973) (xy 309.246516 -277.776654)
			(xy 309.254411 -277.825231) (xy 309.254906 -277.849838) (xy 310.543714 -277.849838) (xy 310.547674 -277.800784)
			(xy 310.559451 -277.753) (xy 310.578742 -277.707724) (xy 310.605045 -277.666128) (xy 310.63768 -277.629291)
			(xy 310.675801 -277.598166) (xy 310.718422 -277.573559) (xy 310.764438 -277.556107) (xy 310.812657 -277.546263)
			(xy 310.861832 -277.544282) (xy 310.910687 -277.550214) (xy 310.957958 -277.563906) (xy 311.00242 -277.585004)
			(xy 311.042923 -277.61296) (xy 311.078416 -277.647052) (xy 311.107981 -277.686396) (xy 311.130852 -277.729973)
			(xy 311.146436 -277.776654) (xy 311.154331 -277.825231) (xy 311.154826 -277.849838) (xy 312.443888 -277.849838)
			(xy 312.447848 -277.800784) (xy 312.459625 -277.753) (xy 312.478916 -277.707724) (xy 312.505219 -277.666128)
			(xy 312.537854 -277.629291) (xy 312.575975 -277.598166) (xy 312.618596 -277.573559) (xy 312.664612 -277.556107)
			(xy 312.712831 -277.546263) (xy 312.762006 -277.544282) (xy 312.810861 -277.550214) (xy 312.858132 -277.563906)
			(xy 312.902594 -277.585004) (xy 312.943097 -277.61296) (xy 312.97859 -277.647052) (xy 313.008155 -277.686396)
			(xy 313.031026 -277.729973) (xy 313.04661 -277.776654) (xy 313.054505 -277.825231) (xy 313.055 -277.849838)
			(xy 392.443982 -277.849838) (xy 392.447942 -277.800784) (xy 392.459719 -277.753) (xy 392.47901 -277.707724)
			(xy 392.505313 -277.666128) (xy 392.537948 -277.629291) (xy 392.576069 -277.598166) (xy 392.61869 -277.573559)
			(xy 392.664706 -277.556107) (xy 392.712925 -277.546263) (xy 392.7621 -277.544282) (xy 392.810955 -277.550214)
			(xy 392.858226 -277.563906) (xy 392.902688 -277.585004) (xy 392.943191 -277.61296) (xy 392.978684 -277.647052)
			(xy 393.008249 -277.686396) (xy 393.03112 -277.729973) (xy 393.046704 -277.776654) (xy 393.054599 -277.825231)
			(xy 393.055094 -277.849838) (xy 394.344156 -277.849838) (xy 394.348116 -277.800784) (xy 394.359893 -277.753)
			(xy 394.379184 -277.707724) (xy 394.405487 -277.666128) (xy 394.438122 -277.629291) (xy 394.476243 -277.598166)
			(xy 394.518864 -277.573559) (xy 394.56488 -277.556107) (xy 394.613099 -277.546263) (xy 394.662274 -277.544282)
			(xy 394.711129 -277.550214) (xy 394.7584 -277.563906) (xy 394.802862 -277.585004) (xy 394.843365 -277.61296)
			(xy 394.878858 -277.647052) (xy 394.908423 -277.686396) (xy 394.931294 -277.729973) (xy 394.946878 -277.776654)
			(xy 394.954773 -277.825231) (xy 394.955268 -277.849838) (xy 396.244076 -277.849838) (xy 396.248036 -277.800784)
			(xy 396.259813 -277.753) (xy 396.279104 -277.707724) (xy 396.305407 -277.666128) (xy 396.338042 -277.629291)
			(xy 396.376163 -277.598166) (xy 396.418784 -277.573559) (xy 396.4648 -277.556107) (xy 396.513019 -277.546263)
			(xy 396.562194 -277.544282) (xy 396.611049 -277.550214) (xy 396.65832 -277.563906) (xy 396.702782 -277.585004)
			(xy 396.743285 -277.61296) (xy 396.778778 -277.647052) (xy 396.808343 -277.686396) (xy 396.831214 -277.729973)
			(xy 396.846798 -277.776654) (xy 396.854693 -277.825231) (xy 396.855188 -277.849838) (xy 398.143996 -277.849838)
			(xy 398.147956 -277.800784) (xy 398.159733 -277.753) (xy 398.179024 -277.707724) (xy 398.205327 -277.666128)
			(xy 398.237962 -277.629291) (xy 398.276083 -277.598166) (xy 398.318704 -277.573559) (xy 398.36472 -277.556107)
			(xy 398.412939 -277.546263) (xy 398.462114 -277.544282) (xy 398.510969 -277.550214) (xy 398.55824 -277.563906)
			(xy 398.602702 -277.585004) (xy 398.643205 -277.61296) (xy 398.678698 -277.647052) (xy 398.708263 -277.686396)
			(xy 398.731134 -277.729973) (xy 398.746718 -277.776654) (xy 398.754613 -277.825231) (xy 398.755108 -277.849838)
			(xy 400.04417 -277.849838) (xy 400.04813 -277.800784) (xy 400.059907 -277.753) (xy 400.079198 -277.707724)
			(xy 400.105501 -277.666128) (xy 400.138136 -277.629291) (xy 400.176257 -277.598166) (xy 400.218878 -277.573559)
			(xy 400.264894 -277.556107) (xy 400.313113 -277.546263) (xy 400.362288 -277.544282) (xy 400.411143 -277.550214)
			(xy 400.458414 -277.563906) (xy 400.502876 -277.585004) (xy 400.543379 -277.61296) (xy 400.578872 -277.647052)
			(xy 400.608437 -277.686396) (xy 400.631308 -277.729973) (xy 400.646892 -277.776654) (xy 400.654787 -277.825231)
			(xy 400.655282 -277.849838) (xy 401.94409 -277.849838) (xy 401.94805 -277.800784) (xy 401.959827 -277.753)
			(xy 401.979118 -277.707724) (xy 402.005421 -277.666128) (xy 402.038056 -277.629291) (xy 402.076177 -277.598166)
			(xy 402.118798 -277.573559) (xy 402.164814 -277.556107) (xy 402.213033 -277.546263) (xy 402.262208 -277.544282)
			(xy 402.311063 -277.550214) (xy 402.358334 -277.563906) (xy 402.402796 -277.585004) (xy 402.443299 -277.61296)
			(xy 402.478792 -277.647052) (xy 402.508357 -277.686396) (xy 402.531228 -277.729973) (xy 402.546812 -277.776654)
			(xy 402.554707 -277.825231) (xy 402.555202 -277.849838) (xy 403.84401 -277.849838) (xy 403.84797 -277.800784)
			(xy 403.859747 -277.753) (xy 403.879038 -277.707724) (xy 403.905341 -277.666128) (xy 403.937976 -277.629291)
			(xy 403.976097 -277.598166) (xy 404.018718 -277.573559) (xy 404.064734 -277.556107) (xy 404.112953 -277.546263)
			(xy 404.162128 -277.544282) (xy 404.210983 -277.550214) (xy 404.258254 -277.563906) (xy 404.302716 -277.585004)
			(xy 404.343219 -277.61296) (xy 404.378712 -277.647052) (xy 404.408277 -277.686396) (xy 404.431148 -277.729973)
			(xy 404.446732 -277.776654) (xy 404.454627 -277.825231) (xy 404.455122 -277.849838) (xy 405.744184 -277.849838)
			(xy 405.748144 -277.800784) (xy 405.759921 -277.753) (xy 405.779212 -277.707724) (xy 405.805515 -277.666128)
			(xy 405.83815 -277.629291) (xy 405.876271 -277.598166) (xy 405.918892 -277.573559) (xy 405.964908 -277.556107)
			(xy 406.013127 -277.546263) (xy 406.062302 -277.544282) (xy 406.111157 -277.550214) (xy 406.158428 -277.563906)
			(xy 406.20289 -277.585004) (xy 406.243393 -277.61296) (xy 406.278886 -277.647052) (xy 406.308451 -277.686396)
			(xy 406.331322 -277.729973) (xy 406.346906 -277.776654) (xy 406.354801 -277.825231) (xy 406.355296 -277.849838)
			(xy 407.64385 -277.849838) (xy 407.64781 -277.800784) (xy 407.659587 -277.753) (xy 407.678878 -277.707724)
			(xy 407.705181 -277.666128) (xy 407.737816 -277.629291) (xy 407.775937 -277.598166) (xy 407.818558 -277.573559)
			(xy 407.864574 -277.556107) (xy 407.912793 -277.546263) (xy 407.961968 -277.544282) (xy 408.010823 -277.550214)
			(xy 408.058094 -277.563906) (xy 408.102556 -277.585004) (xy 408.143059 -277.61296) (xy 408.178552 -277.647052)
			(xy 408.208117 -277.686396) (xy 408.230988 -277.729973) (xy 408.246572 -277.776654) (xy 408.254467 -277.825231)
			(xy 408.254962 -277.849838) (xy 409.54377 -277.849838) (xy 409.54773 -277.800784) (xy 409.559507 -277.753)
			(xy 409.578798 -277.707724) (xy 409.605101 -277.666128) (xy 409.637736 -277.629291) (xy 409.675857 -277.598166)
			(xy 409.718478 -277.573559) (xy 409.764494 -277.556107) (xy 409.812713 -277.546263) (xy 409.861888 -277.544282)
			(xy 409.910743 -277.550214) (xy 409.958014 -277.563906) (xy 410.002476 -277.585004) (xy 410.042979 -277.61296)
			(xy 410.078472 -277.647052) (xy 410.108037 -277.686396) (xy 410.130908 -277.729973) (xy 410.146492 -277.776654)
			(xy 410.154387 -277.825231) (xy 410.154882 -277.849838) (xy 411.443944 -277.849838) (xy 411.447904 -277.800784)
			(xy 411.459681 -277.753) (xy 411.478972 -277.707724) (xy 411.505275 -277.666128) (xy 411.53791 -277.629291)
			(xy 411.576031 -277.598166) (xy 411.618652 -277.573559) (xy 411.664668 -277.556107) (xy 411.712887 -277.546263)
			(xy 411.762062 -277.544282) (xy 411.810917 -277.550214) (xy 411.858188 -277.563906) (xy 411.90265 -277.585004)
			(xy 411.943153 -277.61296) (xy 411.978646 -277.647052) (xy 412.008211 -277.686396) (xy 412.031082 -277.729973)
			(xy 412.046666 -277.776654) (xy 412.054561 -277.825231) (xy 412.055056 -277.849838) (xy 413.343864 -277.849838)
			(xy 413.347824 -277.800784) (xy 413.359601 -277.753) (xy 413.378892 -277.707724) (xy 413.405195 -277.666128)
			(xy 413.43783 -277.629291) (xy 413.475951 -277.598166) (xy 413.518572 -277.573559) (xy 413.564588 -277.556107)
			(xy 413.612807 -277.546263) (xy 413.661982 -277.544282) (xy 413.710837 -277.550214) (xy 413.758108 -277.563906)
			(xy 413.80257 -277.585004) (xy 413.843073 -277.61296) (xy 413.878566 -277.647052) (xy 413.908131 -277.686396)
			(xy 413.931002 -277.729973) (xy 413.946586 -277.776654) (xy 413.954481 -277.825231) (xy 413.954976 -277.849838)
			(xy 415.243784 -277.849838) (xy 415.247744 -277.800784) (xy 415.259521 -277.753) (xy 415.278812 -277.707724)
			(xy 415.305115 -277.666128) (xy 415.33775 -277.629291) (xy 415.375871 -277.598166) (xy 415.418492 -277.573559)
			(xy 415.464508 -277.556107) (xy 415.512727 -277.546263) (xy 415.561902 -277.544282) (xy 415.610757 -277.550214)
			(xy 415.658028 -277.563906) (xy 415.70249 -277.585004) (xy 415.742993 -277.61296) (xy 415.778486 -277.647052)
			(xy 415.808051 -277.686396) (xy 415.830922 -277.729973) (xy 415.846506 -277.776654) (xy 415.854401 -277.825231)
			(xy 415.854896 -277.849838) (xy 417.143958 -277.849838) (xy 417.147918 -277.800784) (xy 417.159695 -277.753)
			(xy 417.178986 -277.707724) (xy 417.205289 -277.666128) (xy 417.237924 -277.629291) (xy 417.276045 -277.598166)
			(xy 417.318666 -277.573559) (xy 417.364682 -277.556107) (xy 417.412901 -277.546263) (xy 417.462076 -277.544282)
			(xy 417.510931 -277.550214) (xy 417.558202 -277.563906) (xy 417.602664 -277.585004) (xy 417.643167 -277.61296)
			(xy 417.67866 -277.647052) (xy 417.708225 -277.686396) (xy 417.731096 -277.729973) (xy 417.74668 -277.776654)
			(xy 417.754575 -277.825231) (xy 417.75507 -277.849838) (xy 419.043878 -277.849838) (xy 419.047838 -277.800784)
			(xy 419.059615 -277.753) (xy 419.078906 -277.707724) (xy 419.105209 -277.666128) (xy 419.137844 -277.629291)
			(xy 419.175965 -277.598166) (xy 419.218586 -277.573559) (xy 419.264602 -277.556107) (xy 419.312821 -277.546263)
			(xy 419.361996 -277.544282) (xy 419.410851 -277.550214) (xy 419.458122 -277.563906) (xy 419.502584 -277.585004)
			(xy 419.543087 -277.61296) (xy 419.57858 -277.647052) (xy 419.608145 -277.686396) (xy 419.631016 -277.729973)
			(xy 419.6466 -277.776654) (xy 419.654495 -277.825231) (xy 419.65499 -277.849838) (xy 420.943798 -277.849838)
			(xy 420.947758 -277.800784) (xy 420.959535 -277.753) (xy 420.978826 -277.707724) (xy 421.005129 -277.666128)
			(xy 421.037764 -277.629291) (xy 421.075885 -277.598166) (xy 421.118506 -277.573559) (xy 421.164522 -277.556107)
			(xy 421.212741 -277.546263) (xy 421.261916 -277.544282) (xy 421.310771 -277.550214) (xy 421.358042 -277.563906)
			(xy 421.402504 -277.585004) (xy 421.443007 -277.61296) (xy 421.4785 -277.647052) (xy 421.508065 -277.686396)
			(xy 421.530936 -277.729973) (xy 421.54652 -277.776654) (xy 421.554415 -277.825231) (xy 421.55491 -277.849838)
			(xy 422.843972 -277.849838) (xy 422.847932 -277.800784) (xy 422.859709 -277.753) (xy 422.879 -277.707724)
			(xy 422.905303 -277.666128) (xy 422.937938 -277.629291) (xy 422.976059 -277.598166) (xy 423.01868 -277.573559)
			(xy 423.064696 -277.556107) (xy 423.112915 -277.546263) (xy 423.16209 -277.544282) (xy 423.210945 -277.550214)
			(xy 423.258216 -277.563906) (xy 423.302678 -277.585004) (xy 423.343181 -277.61296) (xy 423.378674 -277.647052)
			(xy 423.408239 -277.686396) (xy 423.43111 -277.729973) (xy 423.446694 -277.776654) (xy 423.454589 -277.825231)
			(xy 423.455084 -277.849838) (xy 424.743892 -277.849838) (xy 424.747852 -277.800784) (xy 424.759629 -277.753)
			(xy 424.77892 -277.707724) (xy 424.805223 -277.666128) (xy 424.837858 -277.629291) (xy 424.875979 -277.598166)
			(xy 424.9186 -277.573559) (xy 424.964616 -277.556107) (xy 425.012835 -277.546263) (xy 425.06201 -277.544282)
			(xy 425.110865 -277.550214) (xy 425.158136 -277.563906) (xy 425.202598 -277.585004) (xy 425.243101 -277.61296)
			(xy 425.278594 -277.647052) (xy 425.308159 -277.686396) (xy 425.33103 -277.729973) (xy 425.346614 -277.776654)
			(xy 425.354509 -277.825231) (xy 425.355004 -277.849838) (xy 426.643812 -277.849838) (xy 426.647772 -277.800784)
			(xy 426.659549 -277.753) (xy 426.67884 -277.707724) (xy 426.705143 -277.666128) (xy 426.737778 -277.629291)
			(xy 426.775899 -277.598166) (xy 426.81852 -277.573559) (xy 426.864536 -277.556107) (xy 426.912755 -277.546263)
			(xy 426.96193 -277.544282) (xy 427.010785 -277.550214) (xy 427.058056 -277.563906) (xy 427.102518 -277.585004)
			(xy 427.143021 -277.61296) (xy 427.178514 -277.647052) (xy 427.208079 -277.686396) (xy 427.23095 -277.729973)
			(xy 427.246534 -277.776654) (xy 427.254429 -277.825231) (xy 427.254924 -277.849838) (xy 428.543986 -277.849838)
			(xy 428.547946 -277.800784) (xy 428.559723 -277.753) (xy 428.579014 -277.707724) (xy 428.605317 -277.666128)
			(xy 428.637952 -277.629291) (xy 428.676073 -277.598166) (xy 428.718694 -277.573559) (xy 428.76471 -277.556107)
			(xy 428.812929 -277.546263) (xy 428.862104 -277.544282) (xy 428.910959 -277.550214) (xy 428.95823 -277.563906)
			(xy 429.002692 -277.585004) (xy 429.043195 -277.61296) (xy 429.078688 -277.647052) (xy 429.108253 -277.686396)
			(xy 429.131124 -277.729973) (xy 429.146708 -277.776654) (xy 429.154603 -277.825231) (xy 429.155098 -277.849838)
			(xy 429.154603 -277.874445) (xy 429.146708 -277.923022) (xy 429.131124 -277.969703) (xy 429.108253 -278.01328)
			(xy 429.078688 -278.052624) (xy 429.043195 -278.086716) (xy 429.002692 -278.114672) (xy 428.95823 -278.13577)
			(xy 428.910959 -278.149462) (xy 428.862104 -278.155394) (xy 428.812929 -278.153413) (xy 428.76471 -278.143569)
			(xy 428.718694 -278.126117) (xy 428.676073 -278.10151) (xy 428.637952 -278.070385) (xy 428.605317 -278.033548)
			(xy 428.579014 -277.991952) (xy 428.559723 -277.946676) (xy 428.547946 -277.898892) (xy 428.543986 -277.849838)
			(xy 427.254924 -277.849838) (xy 427.254429 -277.874445) (xy 427.246534 -277.923022) (xy 427.23095 -277.969703)
			(xy 427.208079 -278.01328) (xy 427.178514 -278.052624) (xy 427.143021 -278.086716) (xy 427.102518 -278.114672)
			(xy 427.058056 -278.13577) (xy 427.010785 -278.149462) (xy 426.96193 -278.155394) (xy 426.912755 -278.153413)
			(xy 426.864536 -278.143569) (xy 426.81852 -278.126117) (xy 426.775899 -278.10151) (xy 426.737778 -278.070385)
			(xy 426.705143 -278.033548) (xy 426.67884 -277.991952) (xy 426.659549 -277.946676) (xy 426.647772 -277.898892)
			(xy 426.643812 -277.849838) (xy 425.355004 -277.849838) (xy 425.354509 -277.874445) (xy 425.346614 -277.923022)
			(xy 425.33103 -277.969703) (xy 425.308159 -278.01328) (xy 425.278594 -278.052624) (xy 425.243101 -278.086716)
			(xy 425.202598 -278.114672) (xy 425.158136 -278.13577) (xy 425.110865 -278.149462) (xy 425.06201 -278.155394)
			(xy 425.012835 -278.153413) (xy 424.964616 -278.143569) (xy 424.9186 -278.126117) (xy 424.875979 -278.10151)
			(xy 424.837858 -278.070385) (xy 424.805223 -278.033548) (xy 424.77892 -277.991952) (xy 424.759629 -277.946676)
			(xy 424.747852 -277.898892) (xy 424.743892 -277.849838) (xy 423.455084 -277.849838) (xy 423.454589 -277.874445)
			(xy 423.446694 -277.923022) (xy 423.43111 -277.969703) (xy 423.408239 -278.01328) (xy 423.378674 -278.052624)
			(xy 423.343181 -278.086716) (xy 423.302678 -278.114672) (xy 423.258216 -278.13577) (xy 423.210945 -278.149462)
			(xy 423.16209 -278.155394) (xy 423.112915 -278.153413) (xy 423.064696 -278.143569) (xy 423.01868 -278.126117)
			(xy 422.976059 -278.10151) (xy 422.937938 -278.070385) (xy 422.905303 -278.033548) (xy 422.879 -277.991952)
			(xy 422.859709 -277.946676) (xy 422.847932 -277.898892) (xy 422.843972 -277.849838) (xy 421.55491 -277.849838)
			(xy 421.554415 -277.874445) (xy 421.54652 -277.923022) (xy 421.530936 -277.969703) (xy 421.508065 -278.01328)
			(xy 421.4785 -278.052624) (xy 421.443007 -278.086716) (xy 421.402504 -278.114672) (xy 421.358042 -278.13577)
			(xy 421.310771 -278.149462) (xy 421.261916 -278.155394) (xy 421.212741 -278.153413) (xy 421.164522 -278.143569)
			(xy 421.118506 -278.126117) (xy 421.075885 -278.10151) (xy 421.037764 -278.070385) (xy 421.005129 -278.033548)
			(xy 420.978826 -277.991952) (xy 420.959535 -277.946676) (xy 420.947758 -277.898892) (xy 420.943798 -277.849838)
			(xy 419.65499 -277.849838) (xy 419.654495 -277.874445) (xy 419.6466 -277.923022) (xy 419.631016 -277.969703)
			(xy 419.608145 -278.01328) (xy 419.57858 -278.052624) (xy 419.543087 -278.086716) (xy 419.502584 -278.114672)
			(xy 419.458122 -278.13577) (xy 419.410851 -278.149462) (xy 419.361996 -278.155394) (xy 419.312821 -278.153413)
			(xy 419.264602 -278.143569) (xy 419.218586 -278.126117) (xy 419.175965 -278.10151) (xy 419.137844 -278.070385)
			(xy 419.105209 -278.033548) (xy 419.078906 -277.991952) (xy 419.059615 -277.946676) (xy 419.047838 -277.898892)
			(xy 419.043878 -277.849838) (xy 417.75507 -277.849838) (xy 417.754575 -277.874445) (xy 417.74668 -277.923022)
			(xy 417.731096 -277.969703) (xy 417.708225 -278.01328) (xy 417.67866 -278.052624) (xy 417.643167 -278.086716)
			(xy 417.602664 -278.114672) (xy 417.558202 -278.13577) (xy 417.510931 -278.149462) (xy 417.462076 -278.155394)
			(xy 417.412901 -278.153413) (xy 417.364682 -278.143569) (xy 417.318666 -278.126117) (xy 417.276045 -278.10151)
			(xy 417.237924 -278.070385) (xy 417.205289 -278.033548) (xy 417.178986 -277.991952) (xy 417.159695 -277.946676)
			(xy 417.147918 -277.898892) (xy 417.143958 -277.849838) (xy 415.854896 -277.849838) (xy 415.854401 -277.874445)
			(xy 415.846506 -277.923022) (xy 415.830922 -277.969703) (xy 415.808051 -278.01328) (xy 415.778486 -278.052624)
			(xy 415.742993 -278.086716) (xy 415.70249 -278.114672) (xy 415.658028 -278.13577) (xy 415.610757 -278.149462)
			(xy 415.561902 -278.155394) (xy 415.512727 -278.153413) (xy 415.464508 -278.143569) (xy 415.418492 -278.126117)
			(xy 415.375871 -278.10151) (xy 415.33775 -278.070385) (xy 415.305115 -278.033548) (xy 415.278812 -277.991952)
			(xy 415.259521 -277.946676) (xy 415.247744 -277.898892) (xy 415.243784 -277.849838) (xy 413.954976 -277.849838)
			(xy 413.954481 -277.874445) (xy 413.946586 -277.923022) (xy 413.931002 -277.969703) (xy 413.908131 -278.01328)
			(xy 413.878566 -278.052624) (xy 413.843073 -278.086716) (xy 413.80257 -278.114672) (xy 413.758108 -278.13577)
			(xy 413.710837 -278.149462) (xy 413.661982 -278.155394) (xy 413.612807 -278.153413) (xy 413.564588 -278.143569)
			(xy 413.518572 -278.126117) (xy 413.475951 -278.10151) (xy 413.43783 -278.070385) (xy 413.405195 -278.033548)
			(xy 413.378892 -277.991952) (xy 413.359601 -277.946676) (xy 413.347824 -277.898892) (xy 413.343864 -277.849838)
			(xy 412.055056 -277.849838) (xy 412.054561 -277.874445) (xy 412.046666 -277.923022) (xy 412.031082 -277.969703)
			(xy 412.008211 -278.01328) (xy 411.978646 -278.052624) (xy 411.943153 -278.086716) (xy 411.90265 -278.114672)
			(xy 411.858188 -278.13577) (xy 411.810917 -278.149462) (xy 411.762062 -278.155394) (xy 411.712887 -278.153413)
			(xy 411.664668 -278.143569) (xy 411.618652 -278.126117) (xy 411.576031 -278.10151) (xy 411.53791 -278.070385)
			(xy 411.505275 -278.033548) (xy 411.478972 -277.991952) (xy 411.459681 -277.946676) (xy 411.447904 -277.898892)
			(xy 411.443944 -277.849838) (xy 410.154882 -277.849838) (xy 410.154387 -277.874445) (xy 410.146492 -277.923022)
			(xy 410.130908 -277.969703) (xy 410.108037 -278.01328) (xy 410.078472 -278.052624) (xy 410.042979 -278.086716)
			(xy 410.002476 -278.114672) (xy 409.958014 -278.13577) (xy 409.910743 -278.149462) (xy 409.861888 -278.155394)
			(xy 409.812713 -278.153413) (xy 409.764494 -278.143569) (xy 409.718478 -278.126117) (xy 409.675857 -278.10151)
			(xy 409.637736 -278.070385) (xy 409.605101 -278.033548) (xy 409.578798 -277.991952) (xy 409.559507 -277.946676)
			(xy 409.54773 -277.898892) (xy 409.54377 -277.849838) (xy 408.254962 -277.849838) (xy 408.254467 -277.874445)
			(xy 408.246572 -277.923022) (xy 408.230988 -277.969703) (xy 408.208117 -278.01328) (xy 408.178552 -278.052624)
			(xy 408.143059 -278.086716) (xy 408.102556 -278.114672) (xy 408.058094 -278.13577) (xy 408.010823 -278.149462)
			(xy 407.961968 -278.155394) (xy 407.912793 -278.153413) (xy 407.864574 -278.143569) (xy 407.818558 -278.126117)
			(xy 407.775937 -278.10151) (xy 407.737816 -278.070385) (xy 407.705181 -278.033548) (xy 407.678878 -277.991952)
			(xy 407.659587 -277.946676) (xy 407.64781 -277.898892) (xy 407.64385 -277.849838) (xy 406.355296 -277.849838)
			(xy 406.354801 -277.874445) (xy 406.346906 -277.923022) (xy 406.331322 -277.969703) (xy 406.308451 -278.01328)
			(xy 406.278886 -278.052624) (xy 406.243393 -278.086716) (xy 406.20289 -278.114672) (xy 406.158428 -278.13577)
			(xy 406.111157 -278.149462) (xy 406.062302 -278.155394) (xy 406.013127 -278.153413) (xy 405.964908 -278.143569)
			(xy 405.918892 -278.126117) (xy 405.876271 -278.10151) (xy 405.83815 -278.070385) (xy 405.805515 -278.033548)
			(xy 405.779212 -277.991952) (xy 405.759921 -277.946676) (xy 405.748144 -277.898892) (xy 405.744184 -277.849838)
			(xy 404.455122 -277.849838) (xy 404.454627 -277.874445) (xy 404.446732 -277.923022) (xy 404.431148 -277.969703)
			(xy 404.408277 -278.01328) (xy 404.378712 -278.052624) (xy 404.343219 -278.086716) (xy 404.302716 -278.114672)
			(xy 404.258254 -278.13577) (xy 404.210983 -278.149462) (xy 404.162128 -278.155394) (xy 404.112953 -278.153413)
			(xy 404.064734 -278.143569) (xy 404.018718 -278.126117) (xy 403.976097 -278.10151) (xy 403.937976 -278.070385)
			(xy 403.905341 -278.033548) (xy 403.879038 -277.991952) (xy 403.859747 -277.946676) (xy 403.84797 -277.898892)
			(xy 403.84401 -277.849838) (xy 402.555202 -277.849838) (xy 402.554707 -277.874445) (xy 402.546812 -277.923022)
			(xy 402.531228 -277.969703) (xy 402.508357 -278.01328) (xy 402.478792 -278.052624) (xy 402.443299 -278.086716)
			(xy 402.402796 -278.114672) (xy 402.358334 -278.13577) (xy 402.311063 -278.149462) (xy 402.262208 -278.155394)
			(xy 402.213033 -278.153413) (xy 402.164814 -278.143569) (xy 402.118798 -278.126117) (xy 402.076177 -278.10151)
			(xy 402.038056 -278.070385) (xy 402.005421 -278.033548) (xy 401.979118 -277.991952) (xy 401.959827 -277.946676)
			(xy 401.94805 -277.898892) (xy 401.94409 -277.849838) (xy 400.655282 -277.849838) (xy 400.654787 -277.874445)
			(xy 400.646892 -277.923022) (xy 400.631308 -277.969703) (xy 400.608437 -278.01328) (xy 400.578872 -278.052624)
			(xy 400.543379 -278.086716) (xy 400.502876 -278.114672) (xy 400.458414 -278.13577) (xy 400.411143 -278.149462)
			(xy 400.362288 -278.155394) (xy 400.313113 -278.153413) (xy 400.264894 -278.143569) (xy 400.218878 -278.126117)
			(xy 400.176257 -278.10151) (xy 400.138136 -278.070385) (xy 400.105501 -278.033548) (xy 400.079198 -277.991952)
			(xy 400.059907 -277.946676) (xy 400.04813 -277.898892) (xy 400.04417 -277.849838) (xy 398.755108 -277.849838)
			(xy 398.754613 -277.874445) (xy 398.746718 -277.923022) (xy 398.731134 -277.969703) (xy 398.708263 -278.01328)
			(xy 398.678698 -278.052624) (xy 398.643205 -278.086716) (xy 398.602702 -278.114672) (xy 398.55824 -278.13577)
			(xy 398.510969 -278.149462) (xy 398.462114 -278.155394) (xy 398.412939 -278.153413) (xy 398.36472 -278.143569)
			(xy 398.318704 -278.126117) (xy 398.276083 -278.10151) (xy 398.237962 -278.070385) (xy 398.205327 -278.033548)
			(xy 398.179024 -277.991952) (xy 398.159733 -277.946676) (xy 398.147956 -277.898892) (xy 398.143996 -277.849838)
			(xy 396.855188 -277.849838) (xy 396.854693 -277.874445) (xy 396.846798 -277.923022) (xy 396.831214 -277.969703)
			(xy 396.808343 -278.01328) (xy 396.778778 -278.052624) (xy 396.743285 -278.086716) (xy 396.702782 -278.114672)
			(xy 396.65832 -278.13577) (xy 396.611049 -278.149462) (xy 396.562194 -278.155394) (xy 396.513019 -278.153413)
			(xy 396.4648 -278.143569) (xy 396.418784 -278.126117) (xy 396.376163 -278.10151) (xy 396.338042 -278.070385)
			(xy 396.305407 -278.033548) (xy 396.279104 -277.991952) (xy 396.259813 -277.946676) (xy 396.248036 -277.898892)
			(xy 396.244076 -277.849838) (xy 394.955268 -277.849838) (xy 394.954773 -277.874445) (xy 394.946878 -277.923022)
			(xy 394.931294 -277.969703) (xy 394.908423 -278.01328) (xy 394.878858 -278.052624) (xy 394.843365 -278.086716)
			(xy 394.802862 -278.114672) (xy 394.7584 -278.13577) (xy 394.711129 -278.149462) (xy 394.662274 -278.155394)
			(xy 394.613099 -278.153413) (xy 394.56488 -278.143569) (xy 394.518864 -278.126117) (xy 394.476243 -278.10151)
			(xy 394.438122 -278.070385) (xy 394.405487 -278.033548) (xy 394.379184 -277.991952) (xy 394.359893 -277.946676)
			(xy 394.348116 -277.898892) (xy 394.344156 -277.849838) (xy 393.055094 -277.849838) (xy 393.054599 -277.874445)
			(xy 393.046704 -277.923022) (xy 393.03112 -277.969703) (xy 393.008249 -278.01328) (xy 392.978684 -278.052624)
			(xy 392.943191 -278.086716) (xy 392.902688 -278.114672) (xy 392.858226 -278.13577) (xy 392.810955 -278.149462)
			(xy 392.7621 -278.155394) (xy 392.712925 -278.153413) (xy 392.664706 -278.143569) (xy 392.61869 -278.126117)
			(xy 392.576069 -278.10151) (xy 392.537948 -278.070385) (xy 392.505313 -278.033548) (xy 392.47901 -277.991952)
			(xy 392.459719 -277.946676) (xy 392.447942 -277.898892) (xy 392.443982 -277.849838) (xy 313.055 -277.849838)
			(xy 313.054505 -277.874445) (xy 313.04661 -277.923022) (xy 313.031026 -277.969703) (xy 313.008155 -278.01328)
			(xy 312.97859 -278.052624) (xy 312.943097 -278.086716) (xy 312.902594 -278.114672) (xy 312.858132 -278.13577)
			(xy 312.810861 -278.149462) (xy 312.762006 -278.155394) (xy 312.712831 -278.153413) (xy 312.664612 -278.143569)
			(xy 312.618596 -278.126117) (xy 312.575975 -278.10151) (xy 312.537854 -278.070385) (xy 312.505219 -278.033548)
			(xy 312.478916 -277.991952) (xy 312.459625 -277.946676) (xy 312.447848 -277.898892) (xy 312.443888 -277.849838)
			(xy 311.154826 -277.849838) (xy 311.154331 -277.874445) (xy 311.146436 -277.923022) (xy 311.130852 -277.969703)
			(xy 311.107981 -278.01328) (xy 311.078416 -278.052624) (xy 311.042923 -278.086716) (xy 311.00242 -278.114672)
			(xy 310.957958 -278.13577) (xy 310.910687 -278.149462) (xy 310.861832 -278.155394) (xy 310.812657 -278.153413)
			(xy 310.764438 -278.143569) (xy 310.718422 -278.126117) (xy 310.675801 -278.10151) (xy 310.63768 -278.070385)
			(xy 310.605045 -278.033548) (xy 310.578742 -277.991952) (xy 310.559451 -277.946676) (xy 310.547674 -277.898892)
			(xy 310.543714 -277.849838) (xy 309.254906 -277.849838) (xy 309.254411 -277.874445) (xy 309.246516 -277.923022)
			(xy 309.230932 -277.969703) (xy 309.208061 -278.01328) (xy 309.178496 -278.052624) (xy 309.143003 -278.086716)
			(xy 309.1025 -278.114672) (xy 309.058038 -278.13577) (xy 309.010767 -278.149462) (xy 308.961912 -278.155394)
			(xy 308.912737 -278.153413) (xy 308.864518 -278.143569) (xy 308.818502 -278.126117) (xy 308.775881 -278.10151)
			(xy 308.73776 -278.070385) (xy 308.705125 -278.033548) (xy 308.678822 -277.991952) (xy 308.659531 -277.946676)
			(xy 308.647754 -277.898892) (xy 308.643794 -277.849838) (xy 307.354986 -277.849838) (xy 307.354491 -277.874445)
			(xy 307.346596 -277.923022) (xy 307.331012 -277.969703) (xy 307.308141 -278.01328) (xy 307.278576 -278.052624)
			(xy 307.243083 -278.086716) (xy 307.20258 -278.114672) (xy 307.158118 -278.13577) (xy 307.110847 -278.149462)
			(xy 307.061992 -278.155394) (xy 307.012817 -278.153413) (xy 306.964598 -278.143569) (xy 306.918582 -278.126117)
			(xy 306.875961 -278.10151) (xy 306.83784 -278.070385) (xy 306.805205 -278.033548) (xy 306.778902 -277.991952)
			(xy 306.759611 -277.946676) (xy 306.747834 -277.898892) (xy 306.743874 -277.849838) (xy 305.454812 -277.849838)
			(xy 305.454317 -277.874445) (xy 305.446422 -277.923022) (xy 305.430838 -277.969703) (xy 305.407967 -278.01328)
			(xy 305.378402 -278.052624) (xy 305.342909 -278.086716) (xy 305.302406 -278.114672) (xy 305.257944 -278.13577)
			(xy 305.210673 -278.149462) (xy 305.161818 -278.155394) (xy 305.112643 -278.153413) (xy 305.064424 -278.143569)
			(xy 305.018408 -278.126117) (xy 304.975787 -278.10151) (xy 304.937666 -278.070385) (xy 304.905031 -278.033548)
			(xy 304.878728 -277.991952) (xy 304.859437 -277.946676) (xy 304.84766 -277.898892) (xy 304.8437 -277.849838)
			(xy 303.554892 -277.849838) (xy 303.554397 -277.874445) (xy 303.546502 -277.923022) (xy 303.530918 -277.969703)
			(xy 303.508047 -278.01328) (xy 303.478482 -278.052624) (xy 303.442989 -278.086716) (xy 303.402486 -278.114672)
			(xy 303.358024 -278.13577) (xy 303.310753 -278.149462) (xy 303.261898 -278.155394) (xy 303.212723 -278.153413)
			(xy 303.164504 -278.143569) (xy 303.118488 -278.126117) (xy 303.075867 -278.10151) (xy 303.037746 -278.070385)
			(xy 303.005111 -278.033548) (xy 302.978808 -277.991952) (xy 302.959517 -277.946676) (xy 302.94774 -277.898892)
			(xy 302.94378 -277.849838) (xy 301.654972 -277.849838) (xy 301.654477 -277.874445) (xy 301.646582 -277.923022)
			(xy 301.630998 -277.969703) (xy 301.608127 -278.01328) (xy 301.578562 -278.052624) (xy 301.543069 -278.086716)
			(xy 301.502566 -278.114672) (xy 301.458104 -278.13577) (xy 301.410833 -278.149462) (xy 301.361978 -278.155394)
			(xy 301.312803 -278.153413) (xy 301.264584 -278.143569) (xy 301.218568 -278.126117) (xy 301.175947 -278.10151)
			(xy 301.137826 -278.070385) (xy 301.105191 -278.033548) (xy 301.078888 -277.991952) (xy 301.059597 -277.946676)
			(xy 301.04782 -277.898892) (xy 301.04386 -277.849838) (xy 299.754798 -277.849838) (xy 299.754303 -277.874445)
			(xy 299.746408 -277.923022) (xy 299.730824 -277.969703) (xy 299.707953 -278.01328) (xy 299.678388 -278.052624)
			(xy 299.642895 -278.086716) (xy 299.602392 -278.114672) (xy 299.55793 -278.13577) (xy 299.510659 -278.149462)
			(xy 299.461804 -278.155394) (xy 299.412629 -278.153413) (xy 299.36441 -278.143569) (xy 299.318394 -278.126117)
			(xy 299.275773 -278.10151) (xy 299.237652 -278.070385) (xy 299.205017 -278.033548) (xy 299.178714 -277.991952)
			(xy 299.159423 -277.946676) (xy 299.147646 -277.898892) (xy 299.143686 -277.849838) (xy 297.854878 -277.849838)
			(xy 297.854383 -277.874445) (xy 297.846488 -277.923022) (xy 297.830904 -277.969703) (xy 297.808033 -278.01328)
			(xy 297.778468 -278.052624) (xy 297.742975 -278.086716) (xy 297.702472 -278.114672) (xy 297.65801 -278.13577)
			(xy 297.610739 -278.149462) (xy 297.561884 -278.155394) (xy 297.512709 -278.153413) (xy 297.46449 -278.143569)
			(xy 297.418474 -278.126117) (xy 297.375853 -278.10151) (xy 297.337732 -278.070385) (xy 297.305097 -278.033548)
			(xy 297.278794 -277.991952) (xy 297.259503 -277.946676) (xy 297.247726 -277.898892) (xy 297.243766 -277.849838)
			(xy 295.954958 -277.849838) (xy 295.954463 -277.874445) (xy 295.946568 -277.923022) (xy 295.930984 -277.969703)
			(xy 295.908113 -278.01328) (xy 295.878548 -278.052624) (xy 295.843055 -278.086716) (xy 295.802552 -278.114672)
			(xy 295.75809 -278.13577) (xy 295.710819 -278.149462) (xy 295.661964 -278.155394) (xy 295.612789 -278.153413)
			(xy 295.56457 -278.143569) (xy 295.518554 -278.126117) (xy 295.475933 -278.10151) (xy 295.437812 -278.070385)
			(xy 295.405177 -278.033548) (xy 295.378874 -277.991952) (xy 295.359583 -277.946676) (xy 295.347806 -277.898892)
			(xy 295.343846 -277.849838) (xy 294.054784 -277.849838) (xy 294.054289 -277.874445) (xy 294.046394 -277.923022)
			(xy 294.03081 -277.969703) (xy 294.007939 -278.01328) (xy 293.978374 -278.052624) (xy 293.942881 -278.086716)
			(xy 293.902378 -278.114672) (xy 293.857916 -278.13577) (xy 293.810645 -278.149462) (xy 293.76179 -278.155394)
			(xy 293.712615 -278.153413) (xy 293.664396 -278.143569) (xy 293.61838 -278.126117) (xy 293.575759 -278.10151)
			(xy 293.537638 -278.070385) (xy 293.505003 -278.033548) (xy 293.4787 -277.991952) (xy 293.459409 -277.946676)
			(xy 293.447632 -277.898892) (xy 293.443672 -277.849838) (xy 292.154864 -277.849838) (xy 292.154369 -277.874445)
			(xy 292.146474 -277.923022) (xy 292.13089 -277.969703) (xy 292.108019 -278.01328) (xy 292.078454 -278.052624)
			(xy 292.042961 -278.086716) (xy 292.002458 -278.114672) (xy 291.957996 -278.13577) (xy 291.910725 -278.149462)
			(xy 291.86187 -278.155394) (xy 291.812695 -278.153413) (xy 291.764476 -278.143569) (xy 291.71846 -278.126117)
			(xy 291.675839 -278.10151) (xy 291.637718 -278.070385) (xy 291.605083 -278.033548) (xy 291.57878 -277.991952)
			(xy 291.559489 -277.946676) (xy 291.547712 -277.898892) (xy 291.543752 -277.849838) (xy 290.255198 -277.849838)
			(xy 290.254703 -277.874445) (xy 290.246808 -277.923022) (xy 290.231224 -277.969703) (xy 290.208353 -278.01328)
			(xy 290.178788 -278.052624) (xy 290.143295 -278.086716) (xy 290.102792 -278.114672) (xy 290.05833 -278.13577)
			(xy 290.011059 -278.149462) (xy 289.962204 -278.155394) (xy 289.913029 -278.153413) (xy 289.86481 -278.143569)
			(xy 289.818794 -278.126117) (xy 289.776173 -278.10151) (xy 289.738052 -278.070385) (xy 289.705417 -278.033548)
			(xy 289.679114 -277.991952) (xy 289.659823 -277.946676) (xy 289.648046 -277.898892) (xy 289.644086 -277.849838)
			(xy 288.355024 -277.849838) (xy 288.354529 -277.874445) (xy 288.346634 -277.923022) (xy 288.33105 -277.969703)
			(xy 288.308179 -278.01328) (xy 288.278614 -278.052624) (xy 288.243121 -278.086716) (xy 288.202618 -278.114672)
			(xy 288.158156 -278.13577) (xy 288.110885 -278.149462) (xy 288.06203 -278.155394) (xy 288.012855 -278.153413)
			(xy 287.964636 -278.143569) (xy 287.91862 -278.126117) (xy 287.875999 -278.10151) (xy 287.837878 -278.070385)
			(xy 287.805243 -278.033548) (xy 287.77894 -277.991952) (xy 287.759649 -277.946676) (xy 287.747872 -277.898892)
			(xy 287.743912 -277.849838) (xy 286.455104 -277.849838) (xy 286.454609 -277.874445) (xy 286.446714 -277.923022)
			(xy 286.43113 -277.969703) (xy 286.408259 -278.01328) (xy 286.378694 -278.052624) (xy 286.343201 -278.086716)
			(xy 286.302698 -278.114672) (xy 286.258236 -278.13577) (xy 286.210965 -278.149462) (xy 286.16211 -278.155394)
			(xy 286.112935 -278.153413) (xy 286.064716 -278.143569) (xy 286.0187 -278.126117) (xy 285.976079 -278.10151)
			(xy 285.937958 -278.070385) (xy 285.905323 -278.033548) (xy 285.87902 -277.991952) (xy 285.859729 -277.946676)
			(xy 285.847952 -277.898892) (xy 285.843992 -277.849838) (xy 284.555184 -277.849838) (xy 284.554689 -277.874445)
			(xy 284.546794 -277.923022) (xy 284.53121 -277.969703) (xy 284.508339 -278.01328) (xy 284.478774 -278.052624)
			(xy 284.443281 -278.086716) (xy 284.402778 -278.114672) (xy 284.358316 -278.13577) (xy 284.311045 -278.149462)
			(xy 284.26219 -278.155394) (xy 284.213015 -278.153413) (xy 284.164796 -278.143569) (xy 284.11878 -278.126117)
			(xy 284.076159 -278.10151) (xy 284.038038 -278.070385) (xy 284.005403 -278.033548) (xy 283.9791 -277.991952)
			(xy 283.959809 -277.946676) (xy 283.948032 -277.898892) (xy 283.944072 -277.849838) (xy 282.65501 -277.849838)
			(xy 282.654515 -277.874445) (xy 282.64662 -277.923022) (xy 282.631036 -277.969703) (xy 282.608165 -278.01328)
			(xy 282.5786 -278.052624) (xy 282.543107 -278.086716) (xy 282.502604 -278.114672) (xy 282.458142 -278.13577)
			(xy 282.410871 -278.149462) (xy 282.362016 -278.155394) (xy 282.312841 -278.153413) (xy 282.264622 -278.143569)
			(xy 282.218606 -278.126117) (xy 282.175985 -278.10151) (xy 282.137864 -278.070385) (xy 282.105229 -278.033548)
			(xy 282.078926 -277.991952) (xy 282.059635 -277.946676) (xy 282.047858 -277.898892) (xy 282.043898 -277.849838)
			(xy 280.75509 -277.849838) (xy 280.754595 -277.874445) (xy 280.7467 -277.923022) (xy 280.731116 -277.969703)
			(xy 280.708245 -278.01328) (xy 280.67868 -278.052624) (xy 280.643187 -278.086716) (xy 280.602684 -278.114672)
			(xy 280.558222 -278.13577) (xy 280.510951 -278.149462) (xy 280.462096 -278.155394) (xy 280.412921 -278.153413)
			(xy 280.364702 -278.143569) (xy 280.318686 -278.126117) (xy 280.276065 -278.10151) (xy 280.237944 -278.070385)
			(xy 280.205309 -278.033548) (xy 280.179006 -277.991952) (xy 280.159715 -277.946676) (xy 280.147938 -277.898892)
			(xy 280.143978 -277.849838) (xy 278.85517 -277.849838) (xy 278.854675 -277.874445) (xy 278.84678 -277.923022)
			(xy 278.831196 -277.969703) (xy 278.808325 -278.01328) (xy 278.77876 -278.052624) (xy 278.743267 -278.086716)
			(xy 278.702764 -278.114672) (xy 278.658302 -278.13577) (xy 278.611031 -278.149462) (xy 278.562176 -278.155394)
			(xy 278.513001 -278.153413) (xy 278.464782 -278.143569) (xy 278.418766 -278.126117) (xy 278.376145 -278.10151)
			(xy 278.338024 -278.070385) (xy 278.305389 -278.033548) (xy 278.279086 -277.991952) (xy 278.259795 -277.946676)
			(xy 278.248018 -277.898892) (xy 278.244058 -277.849838) (xy 276.954996 -277.849838) (xy 276.954501 -277.874445)
			(xy 276.946606 -277.923022) (xy 276.931022 -277.969703) (xy 276.908151 -278.01328) (xy 276.878586 -278.052624)
			(xy 276.843093 -278.086716) (xy 276.80259 -278.114672) (xy 276.758128 -278.13577) (xy 276.710857 -278.149462)
			(xy 276.662002 -278.155394) (xy 276.612827 -278.153413) (xy 276.564608 -278.143569) (xy 276.518592 -278.126117)
			(xy 276.475971 -278.10151) (xy 276.43785 -278.070385) (xy 276.405215 -278.033548) (xy 276.378912 -277.991952)
			(xy 276.359621 -277.946676) (xy 276.347844 -277.898892) (xy 276.343884 -277.849838) (xy 196.955156 -277.849838)
			(xy 196.954661 -277.874445) (xy 196.946766 -277.923022) (xy 196.931182 -277.969703) (xy 196.908311 -278.01328)
			(xy 196.878746 -278.052624) (xy 196.843253 -278.086716) (xy 196.80275 -278.114672) (xy 196.758288 -278.13577)
			(xy 196.711017 -278.149462) (xy 196.662162 -278.155394) (xy 196.612987 -278.153413) (xy 196.564768 -278.143569)
			(xy 196.518752 -278.126117) (xy 196.476131 -278.10151) (xy 196.43801 -278.070385) (xy 196.405375 -278.033548)
			(xy 196.379072 -277.991952) (xy 196.359781 -277.946676) (xy 196.348004 -277.898892) (xy 196.344044 -277.849838)
			(xy 195.054982 -277.849838) (xy 195.054487 -277.874445) (xy 195.046592 -277.923022) (xy 195.031008 -277.969703)
			(xy 195.008137 -278.01328) (xy 194.978572 -278.052624) (xy 194.943079 -278.086716) (xy 194.902576 -278.114672)
			(xy 194.858114 -278.13577) (xy 194.810843 -278.149462) (xy 194.761988 -278.155394) (xy 194.712813 -278.153413)
			(xy 194.664594 -278.143569) (xy 194.618578 -278.126117) (xy 194.575957 -278.10151) (xy 194.537836 -278.070385)
			(xy 194.505201 -278.033548) (xy 194.478898 -277.991952) (xy 194.459607 -277.946676) (xy 194.44783 -277.898892)
			(xy 194.44387 -277.849838) (xy 193.155062 -277.849838) (xy 193.154567 -277.874445) (xy 193.146672 -277.923022)
			(xy 193.131088 -277.969703) (xy 193.108217 -278.01328) (xy 193.078652 -278.052624) (xy 193.043159 -278.086716)
			(xy 193.002656 -278.114672) (xy 192.958194 -278.13577) (xy 192.910923 -278.149462) (xy 192.862068 -278.155394)
			(xy 192.812893 -278.153413) (xy 192.764674 -278.143569) (xy 192.718658 -278.126117) (xy 192.676037 -278.10151)
			(xy 192.637916 -278.070385) (xy 192.605281 -278.033548) (xy 192.578978 -277.991952) (xy 192.559687 -277.946676)
			(xy 192.54791 -277.898892) (xy 192.54395 -277.849838) (xy 191.255142 -277.849838) (xy 191.254647 -277.874445)
			(xy 191.246752 -277.923022) (xy 191.231168 -277.969703) (xy 191.208297 -278.01328) (xy 191.178732 -278.052624)
			(xy 191.143239 -278.086716) (xy 191.102736 -278.114672) (xy 191.058274 -278.13577) (xy 191.011003 -278.149462)
			(xy 190.962148 -278.155394) (xy 190.912973 -278.153413) (xy 190.864754 -278.143569) (xy 190.818738 -278.126117)
			(xy 190.776117 -278.10151) (xy 190.737996 -278.070385) (xy 190.705361 -278.033548) (xy 190.679058 -277.991952)
			(xy 190.659767 -277.946676) (xy 190.64799 -277.898892) (xy 190.64403 -277.849838) (xy 189.354968 -277.849838)
			(xy 189.354473 -277.874445) (xy 189.346578 -277.923022) (xy 189.330994 -277.969703) (xy 189.308123 -278.01328)
			(xy 189.278558 -278.052624) (xy 189.243065 -278.086716) (xy 189.202562 -278.114672) (xy 189.1581 -278.13577)
			(xy 189.110829 -278.149462) (xy 189.061974 -278.155394) (xy 189.012799 -278.153413) (xy 188.96458 -278.143569)
			(xy 188.918564 -278.126117) (xy 188.875943 -278.10151) (xy 188.837822 -278.070385) (xy 188.805187 -278.033548)
			(xy 188.778884 -277.991952) (xy 188.759593 -277.946676) (xy 188.747816 -277.898892) (xy 188.743856 -277.849838)
			(xy 187.455048 -277.849838) (xy 187.454553 -277.874445) (xy 187.446658 -277.923022) (xy 187.431074 -277.969703)
			(xy 187.408203 -278.01328) (xy 187.378638 -278.052624) (xy 187.343145 -278.086716) (xy 187.302642 -278.114672)
			(xy 187.25818 -278.13577) (xy 187.210909 -278.149462) (xy 187.162054 -278.155394) (xy 187.112879 -278.153413)
			(xy 187.06466 -278.143569) (xy 187.018644 -278.126117) (xy 186.976023 -278.10151) (xy 186.937902 -278.070385)
			(xy 186.905267 -278.033548) (xy 186.878964 -277.991952) (xy 186.859673 -277.946676) (xy 186.847896 -277.898892)
			(xy 186.843936 -277.849838) (xy 185.555128 -277.849838) (xy 185.554633 -277.874445) (xy 185.546738 -277.923022)
			(xy 185.531154 -277.969703) (xy 185.508283 -278.01328) (xy 185.478718 -278.052624) (xy 185.443225 -278.086716)
			(xy 185.402722 -278.114672) (xy 185.35826 -278.13577) (xy 185.310989 -278.149462) (xy 185.262134 -278.155394)
			(xy 185.212959 -278.153413) (xy 185.16474 -278.143569) (xy 185.118724 -278.126117) (xy 185.076103 -278.10151)
			(xy 185.037982 -278.070385) (xy 185.005347 -278.033548) (xy 184.979044 -277.991952) (xy 184.959753 -277.946676)
			(xy 184.947976 -277.898892) (xy 184.944016 -277.849838) (xy 183.654954 -277.849838) (xy 183.654459 -277.874445)
			(xy 183.646564 -277.923022) (xy 183.63098 -277.969703) (xy 183.608109 -278.01328) (xy 183.578544 -278.052624)
			(xy 183.543051 -278.086716) (xy 183.502548 -278.114672) (xy 183.458086 -278.13577) (xy 183.410815 -278.149462)
			(xy 183.36196 -278.155394) (xy 183.312785 -278.153413) (xy 183.264566 -278.143569) (xy 183.21855 -278.126117)
			(xy 183.175929 -278.10151) (xy 183.137808 -278.070385) (xy 183.105173 -278.033548) (xy 183.07887 -277.991952)
			(xy 183.059579 -277.946676) (xy 183.047802 -277.898892) (xy 183.043842 -277.849838) (xy 181.755034 -277.849838)
			(xy 181.754539 -277.874445) (xy 181.746644 -277.923022) (xy 181.73106 -277.969703) (xy 181.708189 -278.01328)
			(xy 181.678624 -278.052624) (xy 181.643131 -278.086716) (xy 181.602628 -278.114672) (xy 181.558166 -278.13577)
			(xy 181.510895 -278.149462) (xy 181.46204 -278.155394) (xy 181.412865 -278.153413) (xy 181.364646 -278.143569)
			(xy 181.31863 -278.126117) (xy 181.276009 -278.10151) (xy 181.237888 -278.070385) (xy 181.205253 -278.033548)
			(xy 181.17895 -277.991952) (xy 181.159659 -277.946676) (xy 181.147882 -277.898892) (xy 181.143922 -277.849838)
			(xy 179.855114 -277.849838) (xy 179.854619 -277.874445) (xy 179.846724 -277.923022) (xy 179.83114 -277.969703)
			(xy 179.808269 -278.01328) (xy 179.778704 -278.052624) (xy 179.743211 -278.086716) (xy 179.702708 -278.114672)
			(xy 179.658246 -278.13577) (xy 179.610975 -278.149462) (xy 179.56212 -278.155394) (xy 179.512945 -278.153413)
			(xy 179.464726 -278.143569) (xy 179.41871 -278.126117) (xy 179.376089 -278.10151) (xy 179.337968 -278.070385)
			(xy 179.305333 -278.033548) (xy 179.27903 -277.991952) (xy 179.259739 -277.946676) (xy 179.247962 -277.898892)
			(xy 179.244002 -277.849838) (xy 177.95494 -277.849838) (xy 177.954445 -277.874445) (xy 177.94655 -277.923022)
			(xy 177.930966 -277.969703) (xy 177.908095 -278.01328) (xy 177.87853 -278.052624) (xy 177.843037 -278.086716)
			(xy 177.802534 -278.114672) (xy 177.758072 -278.13577) (xy 177.710801 -278.149462) (xy 177.661946 -278.155394)
			(xy 177.612771 -278.153413) (xy 177.564552 -278.143569) (xy 177.518536 -278.126117) (xy 177.475915 -278.10151)
			(xy 177.437794 -278.070385) (xy 177.405159 -278.033548) (xy 177.378856 -277.991952) (xy 177.359565 -277.946676)
			(xy 177.347788 -277.898892) (xy 177.343828 -277.849838) (xy 176.05502 -277.849838) (xy 176.054525 -277.874445)
			(xy 176.04663 -277.923022) (xy 176.031046 -277.969703) (xy 176.008175 -278.01328) (xy 175.97861 -278.052624)
			(xy 175.943117 -278.086716) (xy 175.902614 -278.114672) (xy 175.858152 -278.13577) (xy 175.810881 -278.149462)
			(xy 175.762026 -278.155394) (xy 175.712851 -278.153413) (xy 175.664632 -278.143569) (xy 175.618616 -278.126117)
			(xy 175.575995 -278.10151) (xy 175.537874 -278.070385) (xy 175.505239 -278.033548) (xy 175.478936 -277.991952)
			(xy 175.459645 -277.946676) (xy 175.447868 -277.898892) (xy 175.443908 -277.849838) (xy 174.155354 -277.849838)
			(xy 174.154859 -277.874445) (xy 174.146964 -277.923022) (xy 174.13138 -277.969703) (xy 174.108509 -278.01328)
			(xy 174.078944 -278.052624) (xy 174.043451 -278.086716) (xy 174.002948 -278.114672) (xy 173.958486 -278.13577)
			(xy 173.911215 -278.149462) (xy 173.86236 -278.155394) (xy 173.813185 -278.153413) (xy 173.764966 -278.143569)
			(xy 173.71895 -278.126117) (xy 173.676329 -278.10151) (xy 173.638208 -278.070385) (xy 173.605573 -278.033548)
			(xy 173.57927 -277.991952) (xy 173.559979 -277.946676) (xy 173.548202 -277.898892) (xy 173.544242 -277.849838)
			(xy 172.25518 -277.849838) (xy 172.254685 -277.874445) (xy 172.24679 -277.923022) (xy 172.231206 -277.969703)
			(xy 172.208335 -278.01328) (xy 172.17877 -278.052624) (xy 172.143277 -278.086716) (xy 172.102774 -278.114672)
			(xy 172.058312 -278.13577) (xy 172.011041 -278.149462) (xy 171.962186 -278.155394) (xy 171.913011 -278.153413)
			(xy 171.864792 -278.143569) (xy 171.818776 -278.126117) (xy 171.776155 -278.10151) (xy 171.738034 -278.070385)
			(xy 171.705399 -278.033548) (xy 171.679096 -277.991952) (xy 171.659805 -277.946676) (xy 171.648028 -277.898892)
			(xy 171.644068 -277.849838) (xy 170.35526 -277.849838) (xy 170.354765 -277.874445) (xy 170.34687 -277.923022)
			(xy 170.331286 -277.969703) (xy 170.308415 -278.01328) (xy 170.27885 -278.052624) (xy 170.243357 -278.086716)
			(xy 170.202854 -278.114672) (xy 170.158392 -278.13577) (xy 170.111121 -278.149462) (xy 170.062266 -278.155394)
			(xy 170.013091 -278.153413) (xy 169.964872 -278.143569) (xy 169.918856 -278.126117) (xy 169.876235 -278.10151)
			(xy 169.838114 -278.070385) (xy 169.805479 -278.033548) (xy 169.779176 -277.991952) (xy 169.759885 -277.946676)
			(xy 169.748108 -277.898892) (xy 169.744148 -277.849838) (xy 168.45534 -277.849838) (xy 168.454845 -277.874445)
			(xy 168.44695 -277.923022) (xy 168.431366 -277.969703) (xy 168.408495 -278.01328) (xy 168.37893 -278.052624)
			(xy 168.343437 -278.086716) (xy 168.302934 -278.114672) (xy 168.258472 -278.13577) (xy 168.211201 -278.149462)
			(xy 168.162346 -278.155394) (xy 168.113171 -278.153413) (xy 168.064952 -278.143569) (xy 168.018936 -278.126117)
			(xy 167.976315 -278.10151) (xy 167.938194 -278.070385) (xy 167.905559 -278.033548) (xy 167.879256 -277.991952)
			(xy 167.859965 -277.946676) (xy 167.848188 -277.898892) (xy 167.844228 -277.849838) (xy 166.555166 -277.849838)
			(xy 166.554671 -277.874445) (xy 166.546776 -277.923022) (xy 166.531192 -277.969703) (xy 166.508321 -278.01328)
			(xy 166.478756 -278.052624) (xy 166.443263 -278.086716) (xy 166.40276 -278.114672) (xy 166.358298 -278.13577)
			(xy 166.311027 -278.149462) (xy 166.262172 -278.155394) (xy 166.212997 -278.153413) (xy 166.164778 -278.143569)
			(xy 166.118762 -278.126117) (xy 166.076141 -278.10151) (xy 166.03802 -278.070385) (xy 166.005385 -278.033548)
			(xy 165.979082 -277.991952) (xy 165.959791 -277.946676) (xy 165.948014 -277.898892) (xy 165.944054 -277.849838)
			(xy 164.655246 -277.849838) (xy 164.654751 -277.874445) (xy 164.646856 -277.923022) (xy 164.631272 -277.969703)
			(xy 164.608401 -278.01328) (xy 164.578836 -278.052624) (xy 164.543343 -278.086716) (xy 164.50284 -278.114672)
			(xy 164.458378 -278.13577) (xy 164.411107 -278.149462) (xy 164.362252 -278.155394) (xy 164.313077 -278.153413)
			(xy 164.264858 -278.143569) (xy 164.218842 -278.126117) (xy 164.176221 -278.10151) (xy 164.1381 -278.070385)
			(xy 164.105465 -278.033548) (xy 164.079162 -277.991952) (xy 164.059871 -277.946676) (xy 164.048094 -277.898892)
			(xy 164.044134 -277.849838) (xy 162.755326 -277.849838) (xy 162.754831 -277.874445) (xy 162.746936 -277.923022)
			(xy 162.731352 -277.969703) (xy 162.708481 -278.01328) (xy 162.678916 -278.052624) (xy 162.643423 -278.086716)
			(xy 162.60292 -278.114672) (xy 162.558458 -278.13577) (xy 162.511187 -278.149462) (xy 162.462332 -278.155394)
			(xy 162.413157 -278.153413) (xy 162.364938 -278.143569) (xy 162.318922 -278.126117) (xy 162.276301 -278.10151)
			(xy 162.23818 -278.070385) (xy 162.205545 -278.033548) (xy 162.179242 -277.991952) (xy 162.159951 -277.946676)
			(xy 162.148174 -277.898892) (xy 162.144214 -277.849838) (xy 160.855152 -277.849838) (xy 160.854657 -277.874445)
			(xy 160.846762 -277.923022) (xy 160.831178 -277.969703) (xy 160.808307 -278.01328) (xy 160.778742 -278.052624)
			(xy 160.743249 -278.086716) (xy 160.702746 -278.114672) (xy 160.658284 -278.13577) (xy 160.611013 -278.149462)
			(xy 160.562158 -278.155394) (xy 160.512983 -278.153413) (xy 160.464764 -278.143569) (xy 160.418748 -278.126117)
			(xy 160.376127 -278.10151) (xy 160.338006 -278.070385) (xy 160.305371 -278.033548) (xy 160.279068 -277.991952)
			(xy 160.259777 -277.946676) (xy 160.248 -277.898892) (xy 160.24404 -277.849838) (xy 80.855058 -277.849838)
			(xy 80.854563 -277.874445) (xy 80.846668 -277.923022) (xy 80.831084 -277.969703) (xy 80.808213 -278.01328)
			(xy 80.778648 -278.052624) (xy 80.743155 -278.086716) (xy 80.702652 -278.114672) (xy 80.65819 -278.13577)
			(xy 80.610919 -278.149462) (xy 80.562064 -278.155394) (xy 80.512889 -278.153413) (xy 80.46467 -278.143569)
			(xy 80.418654 -278.126117) (xy 80.376033 -278.10151) (xy 80.337912 -278.070385) (xy 80.305277 -278.033548)
			(xy 80.278974 -277.991952) (xy 80.259683 -277.946676) (xy 80.247906 -277.898892) (xy 80.243946 -277.849838)
			(xy 78.954884 -277.849838) (xy 78.954389 -277.874445) (xy 78.946494 -277.923022) (xy 78.93091 -277.969703)
			(xy 78.908039 -278.01328) (xy 78.878474 -278.052624) (xy 78.842981 -278.086716) (xy 78.802478 -278.114672)
			(xy 78.758016 -278.13577) (xy 78.710745 -278.149462) (xy 78.66189 -278.155394) (xy 78.612715 -278.153413)
			(xy 78.564496 -278.143569) (xy 78.51848 -278.126117) (xy 78.475859 -278.10151) (xy 78.437738 -278.070385)
			(xy 78.405103 -278.033548) (xy 78.3788 -277.991952) (xy 78.359509 -277.946676) (xy 78.347732 -277.898892)
			(xy 78.343772 -277.849838) (xy 77.054964 -277.849838) (xy 77.054469 -277.874445) (xy 77.046574 -277.923022)
			(xy 77.03099 -277.969703) (xy 77.008119 -278.01328) (xy 76.978554 -278.052624) (xy 76.943061 -278.086716)
			(xy 76.902558 -278.114672) (xy 76.858096 -278.13577) (xy 76.810825 -278.149462) (xy 76.76197 -278.155394)
			(xy 76.712795 -278.153413) (xy 76.664576 -278.143569) (xy 76.61856 -278.126117) (xy 76.575939 -278.10151)
			(xy 76.537818 -278.070385) (xy 76.505183 -278.033548) (xy 76.47888 -277.991952) (xy 76.459589 -277.946676)
			(xy 76.447812 -277.898892) (xy 76.443852 -277.849838) (xy 75.155044 -277.849838) (xy 75.154549 -277.874445)
			(xy 75.146654 -277.923022) (xy 75.13107 -277.969703) (xy 75.108199 -278.01328) (xy 75.078634 -278.052624)
			(xy 75.043141 -278.086716) (xy 75.002638 -278.114672) (xy 74.958176 -278.13577) (xy 74.910905 -278.149462)
			(xy 74.86205 -278.155394) (xy 74.812875 -278.153413) (xy 74.764656 -278.143569) (xy 74.71864 -278.126117)
			(xy 74.676019 -278.10151) (xy 74.637898 -278.070385) (xy 74.605263 -278.033548) (xy 74.57896 -277.991952)
			(xy 74.559669 -277.946676) (xy 74.547892 -277.898892) (xy 74.543932 -277.849838) (xy 73.25487 -277.849838)
			(xy 73.254375 -277.874445) (xy 73.24648 -277.923022) (xy 73.230896 -277.969703) (xy 73.208025 -278.01328)
			(xy 73.17846 -278.052624) (xy 73.142967 -278.086716) (xy 73.102464 -278.114672) (xy 73.058002 -278.13577)
			(xy 73.010731 -278.149462) (xy 72.961876 -278.155394) (xy 72.912701 -278.153413) (xy 72.864482 -278.143569)
			(xy 72.818466 -278.126117) (xy 72.775845 -278.10151) (xy 72.737724 -278.070385) (xy 72.705089 -278.033548)
			(xy 72.678786 -277.991952) (xy 72.659495 -277.946676) (xy 72.647718 -277.898892) (xy 72.643758 -277.849838)
			(xy 71.35495 -277.849838) (xy 71.354455 -277.874445) (xy 71.34656 -277.923022) (xy 71.330976 -277.969703)
			(xy 71.308105 -278.01328) (xy 71.27854 -278.052624) (xy 71.243047 -278.086716) (xy 71.202544 -278.114672)
			(xy 71.158082 -278.13577) (xy 71.110811 -278.149462) (xy 71.061956 -278.155394) (xy 71.012781 -278.153413)
			(xy 70.964562 -278.143569) (xy 70.918546 -278.126117) (xy 70.875925 -278.10151) (xy 70.837804 -278.070385)
			(xy 70.805169 -278.033548) (xy 70.778866 -277.991952) (xy 70.759575 -277.946676) (xy 70.747798 -277.898892)
			(xy 70.743838 -277.849838) (xy 69.45503 -277.849838) (xy 69.454535 -277.874445) (xy 69.44664 -277.923022)
			(xy 69.431056 -277.969703) (xy 69.408185 -278.01328) (xy 69.37862 -278.052624) (xy 69.343127 -278.086716)
			(xy 69.302624 -278.114672) (xy 69.258162 -278.13577) (xy 69.210891 -278.149462) (xy 69.162036 -278.155394)
			(xy 69.112861 -278.153413) (xy 69.064642 -278.143569) (xy 69.018626 -278.126117) (xy 68.976005 -278.10151)
			(xy 68.937884 -278.070385) (xy 68.905249 -278.033548) (xy 68.878946 -277.991952) (xy 68.859655 -277.946676)
			(xy 68.847878 -277.898892) (xy 68.843918 -277.849838) (xy 67.554856 -277.849838) (xy 67.554361 -277.874445)
			(xy 67.546466 -277.923022) (xy 67.530882 -277.969703) (xy 67.508011 -278.01328) (xy 67.478446 -278.052624)
			(xy 67.442953 -278.086716) (xy 67.40245 -278.114672) (xy 67.357988 -278.13577) (xy 67.310717 -278.149462)
			(xy 67.261862 -278.155394) (xy 67.212687 -278.153413) (xy 67.164468 -278.143569) (xy 67.118452 -278.126117)
			(xy 67.075831 -278.10151) (xy 67.03771 -278.070385) (xy 67.005075 -278.033548) (xy 66.978772 -277.991952)
			(xy 66.959481 -277.946676) (xy 66.947704 -277.898892) (xy 66.943744 -277.849838) (xy 65.654936 -277.849838)
			(xy 65.654441 -277.874445) (xy 65.646546 -277.923022) (xy 65.630962 -277.969703) (xy 65.608091 -278.01328)
			(xy 65.578526 -278.052624) (xy 65.543033 -278.086716) (xy 65.50253 -278.114672) (xy 65.458068 -278.13577)
			(xy 65.410797 -278.149462) (xy 65.361942 -278.155394) (xy 65.312767 -278.153413) (xy 65.264548 -278.143569)
			(xy 65.218532 -278.126117) (xy 65.175911 -278.10151) (xy 65.13779 -278.070385) (xy 65.105155 -278.033548)
			(xy 65.078852 -277.991952) (xy 65.059561 -277.946676) (xy 65.047784 -277.898892) (xy 65.043824 -277.849838)
			(xy 63.755016 -277.849838) (xy 63.754521 -277.874445) (xy 63.746626 -277.923022) (xy 63.731042 -277.969703)
			(xy 63.708171 -278.01328) (xy 63.678606 -278.052624) (xy 63.643113 -278.086716) (xy 63.60261 -278.114672)
			(xy 63.558148 -278.13577) (xy 63.510877 -278.149462) (xy 63.462022 -278.155394) (xy 63.412847 -278.153413)
			(xy 63.364628 -278.143569) (xy 63.318612 -278.126117) (xy 63.275991 -278.10151) (xy 63.23787 -278.070385)
			(xy 63.205235 -278.033548) (xy 63.178932 -277.991952) (xy 63.159641 -277.946676) (xy 63.147864 -277.898892)
			(xy 63.143904 -277.849838) (xy 61.854842 -277.849838) (xy 61.854347 -277.874445) (xy 61.846452 -277.923022)
			(xy 61.830868 -277.969703) (xy 61.807997 -278.01328) (xy 61.778432 -278.052624) (xy 61.742939 -278.086716)
			(xy 61.702436 -278.114672) (xy 61.657974 -278.13577) (xy 61.610703 -278.149462) (xy 61.561848 -278.155394)
			(xy 61.512673 -278.153413) (xy 61.464454 -278.143569) (xy 61.418438 -278.126117) (xy 61.375817 -278.10151)
			(xy 61.337696 -278.070385) (xy 61.305061 -278.033548) (xy 61.278758 -277.991952) (xy 61.259467 -277.946676)
			(xy 61.24769 -277.898892) (xy 61.24373 -277.849838) (xy 59.954922 -277.849838) (xy 59.954427 -277.874445)
			(xy 59.946532 -277.923022) (xy 59.930948 -277.969703) (xy 59.908077 -278.01328) (xy 59.878512 -278.052624)
			(xy 59.843019 -278.086716) (xy 59.802516 -278.114672) (xy 59.758054 -278.13577) (xy 59.710783 -278.149462)
			(xy 59.661928 -278.155394) (xy 59.612753 -278.153413) (xy 59.564534 -278.143569) (xy 59.518518 -278.126117)
			(xy 59.475897 -278.10151) (xy 59.437776 -278.070385) (xy 59.405141 -278.033548) (xy 59.378838 -277.991952)
			(xy 59.359547 -277.946676) (xy 59.34777 -277.898892) (xy 59.34381 -277.849838) (xy 58.055256 -277.849838)
			(xy 58.054761 -277.874445) (xy 58.046866 -277.923022) (xy 58.031282 -277.969703) (xy 58.008411 -278.01328)
			(xy 57.978846 -278.052624) (xy 57.943353 -278.086716) (xy 57.90285 -278.114672) (xy 57.858388 -278.13577)
			(xy 57.811117 -278.149462) (xy 57.762262 -278.155394) (xy 57.713087 -278.153413) (xy 57.664868 -278.143569)
			(xy 57.618852 -278.126117) (xy 57.576231 -278.10151) (xy 57.53811 -278.070385) (xy 57.505475 -278.033548)
			(xy 57.479172 -277.991952) (xy 57.459881 -277.946676) (xy 57.448104 -277.898892) (xy 57.444144 -277.849838)
			(xy 56.155082 -277.849838) (xy 56.154587 -277.874445) (xy 56.146692 -277.923022) (xy 56.131108 -277.969703)
			(xy 56.108237 -278.01328) (xy 56.078672 -278.052624) (xy 56.043179 -278.086716) (xy 56.002676 -278.114672)
			(xy 55.958214 -278.13577) (xy 55.910943 -278.149462) (xy 55.862088 -278.155394) (xy 55.812913 -278.153413)
			(xy 55.764694 -278.143569) (xy 55.718678 -278.126117) (xy 55.676057 -278.10151) (xy 55.637936 -278.070385)
			(xy 55.605301 -278.033548) (xy 55.578998 -277.991952) (xy 55.559707 -277.946676) (xy 55.54793 -277.898892)
			(xy 55.54397 -277.849838) (xy 54.255162 -277.849838) (xy 54.254667 -277.874445) (xy 54.246772 -277.923022)
			(xy 54.231188 -277.969703) (xy 54.208317 -278.01328) (xy 54.178752 -278.052624) (xy 54.143259 -278.086716)
			(xy 54.102756 -278.114672) (xy 54.058294 -278.13577) (xy 54.011023 -278.149462) (xy 53.962168 -278.155394)
			(xy 53.912993 -278.153413) (xy 53.864774 -278.143569) (xy 53.818758 -278.126117) (xy 53.776137 -278.10151)
			(xy 53.738016 -278.070385) (xy 53.705381 -278.033548) (xy 53.679078 -277.991952) (xy 53.659787 -277.946676)
			(xy 53.64801 -277.898892) (xy 53.64405 -277.849838) (xy 52.355242 -277.849838) (xy 52.354747 -277.874445)
			(xy 52.346852 -277.923022) (xy 52.331268 -277.969703) (xy 52.308397 -278.01328) (xy 52.278832 -278.052624)
			(xy 52.243339 -278.086716) (xy 52.202836 -278.114672) (xy 52.158374 -278.13577) (xy 52.111103 -278.149462)
			(xy 52.062248 -278.155394) (xy 52.013073 -278.153413) (xy 51.964854 -278.143569) (xy 51.918838 -278.126117)
			(xy 51.876217 -278.10151) (xy 51.838096 -278.070385) (xy 51.805461 -278.033548) (xy 51.779158 -277.991952)
			(xy 51.759867 -277.946676) (xy 51.74809 -277.898892) (xy 51.74413 -277.849838) (xy 50.455068 -277.849838)
			(xy 50.454573 -277.874445) (xy 50.446678 -277.923022) (xy 50.431094 -277.969703) (xy 50.408223 -278.01328)
			(xy 50.378658 -278.052624) (xy 50.343165 -278.086716) (xy 50.302662 -278.114672) (xy 50.2582 -278.13577)
			(xy 50.210929 -278.149462) (xy 50.162074 -278.155394) (xy 50.112899 -278.153413) (xy 50.06468 -278.143569)
			(xy 50.018664 -278.126117) (xy 49.976043 -278.10151) (xy 49.937922 -278.070385) (xy 49.905287 -278.033548)
			(xy 49.878984 -277.991952) (xy 49.859693 -277.946676) (xy 49.847916 -277.898892) (xy 49.843956 -277.849838)
			(xy 48.555148 -277.849838) (xy 48.554653 -277.874445) (xy 48.546758 -277.923022) (xy 48.531174 -277.969703)
			(xy 48.508303 -278.01328) (xy 48.478738 -278.052624) (xy 48.443245 -278.086716) (xy 48.402742 -278.114672)
			(xy 48.35828 -278.13577) (xy 48.311009 -278.149462) (xy 48.262154 -278.155394) (xy 48.212979 -278.153413)
			(xy 48.16476 -278.143569) (xy 48.118744 -278.126117) (xy 48.076123 -278.10151) (xy 48.038002 -278.070385)
			(xy 48.005367 -278.033548) (xy 47.979064 -277.991952) (xy 47.959773 -277.946676) (xy 47.947996 -277.898892)
			(xy 47.944036 -277.849838) (xy 46.655228 -277.849838) (xy 46.654733 -277.874445) (xy 46.646838 -277.923022)
			(xy 46.631254 -277.969703) (xy 46.608383 -278.01328) (xy 46.578818 -278.052624) (xy 46.543325 -278.086716)
			(xy 46.502822 -278.114672) (xy 46.45836 -278.13577) (xy 46.411089 -278.149462) (xy 46.362234 -278.155394)
			(xy 46.313059 -278.153413) (xy 46.26484 -278.143569) (xy 46.218824 -278.126117) (xy 46.176203 -278.10151)
			(xy 46.138082 -278.070385) (xy 46.105447 -278.033548) (xy 46.079144 -277.991952) (xy 46.059853 -277.946676)
			(xy 46.048076 -277.898892) (xy 46.044116 -277.849838) (xy 44.755054 -277.849838) (xy 44.754559 -277.874445)
			(xy 44.746664 -277.923022) (xy 44.73108 -277.969703) (xy 44.708209 -278.01328) (xy 44.678644 -278.052624)
			(xy 44.643151 -278.086716) (xy 44.602648 -278.114672) (xy 44.558186 -278.13577) (xy 44.510915 -278.149462)
			(xy 44.46206 -278.155394) (xy 44.412885 -278.153413) (xy 44.364666 -278.143569) (xy 44.31865 -278.126117)
			(xy 44.276029 -278.10151) (xy 44.237908 -278.070385) (xy 44.205273 -278.033548) (xy 44.17897 -277.991952)
			(xy 44.159679 -277.946676) (xy 44.147902 -277.898892) (xy 44.143942 -277.849838) (xy 0.508 -277.849838)
			(xy 0.508 -278.799798) (xy 44.143942 -278.799798) (xy 44.147902 -278.750744) (xy 44.159679 -278.70296)
			(xy 44.17897 -278.657684) (xy 44.205273 -278.616088) (xy 44.237908 -278.579251) (xy 44.276029 -278.548126)
			(xy 44.31865 -278.523519) (xy 44.364666 -278.506067) (xy 44.412885 -278.496223) (xy 44.46206 -278.494242)
			(xy 44.510915 -278.500174) (xy 44.558186 -278.513866) (xy 44.602648 -278.534964) (xy 44.643151 -278.56292)
			(xy 44.678644 -278.597012) (xy 44.708209 -278.636356) (xy 44.73108 -278.679933) (xy 44.746664 -278.726614)
			(xy 44.754559 -278.775191) (xy 44.755054 -278.799798) (xy 46.044116 -278.799798) (xy 46.048076 -278.750744)
			(xy 46.059853 -278.70296) (xy 46.079144 -278.657684) (xy 46.105447 -278.616088) (xy 46.138082 -278.579251)
			(xy 46.176203 -278.548126) (xy 46.218824 -278.523519) (xy 46.26484 -278.506067) (xy 46.313059 -278.496223)
			(xy 46.362234 -278.494242) (xy 46.411089 -278.500174) (xy 46.45836 -278.513866) (xy 46.502822 -278.534964)
			(xy 46.543325 -278.56292) (xy 46.578818 -278.597012) (xy 46.608383 -278.636356) (xy 46.631254 -278.679933)
			(xy 46.646838 -278.726614) (xy 46.654733 -278.775191) (xy 46.655228 -278.799798) (xy 47.944036 -278.799798)
			(xy 47.947996 -278.750744) (xy 47.959773 -278.70296) (xy 47.979064 -278.657684) (xy 48.005367 -278.616088)
			(xy 48.038002 -278.579251) (xy 48.076123 -278.548126) (xy 48.118744 -278.523519) (xy 48.16476 -278.506067)
			(xy 48.212979 -278.496223) (xy 48.262154 -278.494242) (xy 48.311009 -278.500174) (xy 48.35828 -278.513866)
			(xy 48.402742 -278.534964) (xy 48.443245 -278.56292) (xy 48.478738 -278.597012) (xy 48.508303 -278.636356)
			(xy 48.531174 -278.679933) (xy 48.546758 -278.726614) (xy 48.554653 -278.775191) (xy 48.555148 -278.799798)
			(xy 49.843956 -278.799798) (xy 49.847916 -278.750744) (xy 49.859693 -278.70296) (xy 49.878984 -278.657684)
			(xy 49.905287 -278.616088) (xy 49.937922 -278.579251) (xy 49.976043 -278.548126) (xy 50.018664 -278.523519)
			(xy 50.06468 -278.506067) (xy 50.112899 -278.496223) (xy 50.162074 -278.494242) (xy 50.210929 -278.500174)
			(xy 50.2582 -278.513866) (xy 50.302662 -278.534964) (xy 50.343165 -278.56292) (xy 50.378658 -278.597012)
			(xy 50.408223 -278.636356) (xy 50.431094 -278.679933) (xy 50.446678 -278.726614) (xy 50.454573 -278.775191)
			(xy 50.455068 -278.799798) (xy 51.74413 -278.799798) (xy 51.74809 -278.750744) (xy 51.759867 -278.70296)
			(xy 51.779158 -278.657684) (xy 51.805461 -278.616088) (xy 51.838096 -278.579251) (xy 51.876217 -278.548126)
			(xy 51.918838 -278.523519) (xy 51.964854 -278.506067) (xy 52.013073 -278.496223) (xy 52.062248 -278.494242)
			(xy 52.111103 -278.500174) (xy 52.158374 -278.513866) (xy 52.202836 -278.534964) (xy 52.243339 -278.56292)
			(xy 52.278832 -278.597012) (xy 52.308397 -278.636356) (xy 52.331268 -278.679933) (xy 52.346852 -278.726614)
			(xy 52.354747 -278.775191) (xy 52.355242 -278.799798) (xy 53.64405 -278.799798) (xy 53.64801 -278.750744)
			(xy 53.659787 -278.70296) (xy 53.679078 -278.657684) (xy 53.705381 -278.616088) (xy 53.738016 -278.579251)
			(xy 53.776137 -278.548126) (xy 53.818758 -278.523519) (xy 53.864774 -278.506067) (xy 53.912993 -278.496223)
			(xy 53.962168 -278.494242) (xy 54.011023 -278.500174) (xy 54.058294 -278.513866) (xy 54.102756 -278.534964)
			(xy 54.143259 -278.56292) (xy 54.178752 -278.597012) (xy 54.208317 -278.636356) (xy 54.231188 -278.679933)
			(xy 54.246772 -278.726614) (xy 54.254667 -278.775191) (xy 54.255162 -278.799798) (xy 55.54397 -278.799798)
			(xy 55.54793 -278.750744) (xy 55.559707 -278.70296) (xy 55.578998 -278.657684) (xy 55.605301 -278.616088)
			(xy 55.637936 -278.579251) (xy 55.676057 -278.548126) (xy 55.718678 -278.523519) (xy 55.764694 -278.506067)
			(xy 55.812913 -278.496223) (xy 55.862088 -278.494242) (xy 55.910943 -278.500174) (xy 55.958214 -278.513866)
			(xy 56.002676 -278.534964) (xy 56.043179 -278.56292) (xy 56.078672 -278.597012) (xy 56.108237 -278.636356)
			(xy 56.131108 -278.679933) (xy 56.146692 -278.726614) (xy 56.154587 -278.775191) (xy 56.155082 -278.799798)
			(xy 57.444144 -278.799798) (xy 57.448104 -278.750744) (xy 57.459881 -278.70296) (xy 57.479172 -278.657684)
			(xy 57.505475 -278.616088) (xy 57.53811 -278.579251) (xy 57.576231 -278.548126) (xy 57.618852 -278.523519)
			(xy 57.664868 -278.506067) (xy 57.713087 -278.496223) (xy 57.762262 -278.494242) (xy 57.811117 -278.500174)
			(xy 57.858388 -278.513866) (xy 57.90285 -278.534964) (xy 57.943353 -278.56292) (xy 57.978846 -278.597012)
			(xy 58.008411 -278.636356) (xy 58.031282 -278.679933) (xy 58.046866 -278.726614) (xy 58.054761 -278.775191)
			(xy 58.055256 -278.799798) (xy 59.34381 -278.799798) (xy 59.34777 -278.750744) (xy 59.359547 -278.70296)
			(xy 59.378838 -278.657684) (xy 59.405141 -278.616088) (xy 59.437776 -278.579251) (xy 59.475897 -278.548126)
			(xy 59.518518 -278.523519) (xy 59.564534 -278.506067) (xy 59.612753 -278.496223) (xy 59.661928 -278.494242)
			(xy 59.710783 -278.500174) (xy 59.758054 -278.513866) (xy 59.802516 -278.534964) (xy 59.843019 -278.56292)
			(xy 59.878512 -278.597012) (xy 59.908077 -278.636356) (xy 59.930948 -278.679933) (xy 59.946532 -278.726614)
			(xy 59.954427 -278.775191) (xy 59.954922 -278.799798) (xy 61.24373 -278.799798) (xy 61.24769 -278.750744)
			(xy 61.259467 -278.70296) (xy 61.278758 -278.657684) (xy 61.305061 -278.616088) (xy 61.337696 -278.579251)
			(xy 61.375817 -278.548126) (xy 61.418438 -278.523519) (xy 61.464454 -278.506067) (xy 61.512673 -278.496223)
			(xy 61.561848 -278.494242) (xy 61.610703 -278.500174) (xy 61.657974 -278.513866) (xy 61.702436 -278.534964)
			(xy 61.742939 -278.56292) (xy 61.778432 -278.597012) (xy 61.807997 -278.636356) (xy 61.830868 -278.679933)
			(xy 61.846452 -278.726614) (xy 61.854347 -278.775191) (xy 61.854842 -278.799798) (xy 63.143904 -278.799798)
			(xy 63.147864 -278.750744) (xy 63.159641 -278.70296) (xy 63.178932 -278.657684) (xy 63.205235 -278.616088)
			(xy 63.23787 -278.579251) (xy 63.275991 -278.548126) (xy 63.318612 -278.523519) (xy 63.364628 -278.506067)
			(xy 63.412847 -278.496223) (xy 63.462022 -278.494242) (xy 63.510877 -278.500174) (xy 63.558148 -278.513866)
			(xy 63.60261 -278.534964) (xy 63.643113 -278.56292) (xy 63.678606 -278.597012) (xy 63.708171 -278.636356)
			(xy 63.731042 -278.679933) (xy 63.746626 -278.726614) (xy 63.754521 -278.775191) (xy 63.755016 -278.799798)
			(xy 65.043824 -278.799798) (xy 65.047784 -278.750744) (xy 65.059561 -278.70296) (xy 65.078852 -278.657684)
			(xy 65.105155 -278.616088) (xy 65.13779 -278.579251) (xy 65.175911 -278.548126) (xy 65.218532 -278.523519)
			(xy 65.264548 -278.506067) (xy 65.312767 -278.496223) (xy 65.361942 -278.494242) (xy 65.410797 -278.500174)
			(xy 65.458068 -278.513866) (xy 65.50253 -278.534964) (xy 65.543033 -278.56292) (xy 65.578526 -278.597012)
			(xy 65.608091 -278.636356) (xy 65.630962 -278.679933) (xy 65.646546 -278.726614) (xy 65.654441 -278.775191)
			(xy 65.654936 -278.799798) (xy 66.943744 -278.799798) (xy 66.947704 -278.750744) (xy 66.959481 -278.70296)
			(xy 66.978772 -278.657684) (xy 67.005075 -278.616088) (xy 67.03771 -278.579251) (xy 67.075831 -278.548126)
			(xy 67.118452 -278.523519) (xy 67.164468 -278.506067) (xy 67.212687 -278.496223) (xy 67.261862 -278.494242)
			(xy 67.310717 -278.500174) (xy 67.357988 -278.513866) (xy 67.40245 -278.534964) (xy 67.442953 -278.56292)
			(xy 67.478446 -278.597012) (xy 67.508011 -278.636356) (xy 67.530882 -278.679933) (xy 67.546466 -278.726614)
			(xy 67.554361 -278.775191) (xy 67.554856 -278.799798) (xy 68.843918 -278.799798) (xy 68.847878 -278.750744)
			(xy 68.859655 -278.70296) (xy 68.878946 -278.657684) (xy 68.905249 -278.616088) (xy 68.937884 -278.579251)
			(xy 68.976005 -278.548126) (xy 69.018626 -278.523519) (xy 69.064642 -278.506067) (xy 69.112861 -278.496223)
			(xy 69.162036 -278.494242) (xy 69.210891 -278.500174) (xy 69.258162 -278.513866) (xy 69.302624 -278.534964)
			(xy 69.343127 -278.56292) (xy 69.37862 -278.597012) (xy 69.408185 -278.636356) (xy 69.431056 -278.679933)
			(xy 69.44664 -278.726614) (xy 69.454535 -278.775191) (xy 69.45503 -278.799798) (xy 70.743838 -278.799798)
			(xy 70.747798 -278.750744) (xy 70.759575 -278.70296) (xy 70.778866 -278.657684) (xy 70.805169 -278.616088)
			(xy 70.837804 -278.579251) (xy 70.875925 -278.548126) (xy 70.918546 -278.523519) (xy 70.964562 -278.506067)
			(xy 71.012781 -278.496223) (xy 71.061956 -278.494242) (xy 71.110811 -278.500174) (xy 71.158082 -278.513866)
			(xy 71.202544 -278.534964) (xy 71.243047 -278.56292) (xy 71.27854 -278.597012) (xy 71.308105 -278.636356)
			(xy 71.330976 -278.679933) (xy 71.34656 -278.726614) (xy 71.354455 -278.775191) (xy 71.35495 -278.799798)
			(xy 72.643758 -278.799798) (xy 72.647718 -278.750744) (xy 72.659495 -278.70296) (xy 72.678786 -278.657684)
			(xy 72.705089 -278.616088) (xy 72.737724 -278.579251) (xy 72.775845 -278.548126) (xy 72.818466 -278.523519)
			(xy 72.864482 -278.506067) (xy 72.912701 -278.496223) (xy 72.961876 -278.494242) (xy 73.010731 -278.500174)
			(xy 73.058002 -278.513866) (xy 73.102464 -278.534964) (xy 73.142967 -278.56292) (xy 73.17846 -278.597012)
			(xy 73.208025 -278.636356) (xy 73.230896 -278.679933) (xy 73.24648 -278.726614) (xy 73.254375 -278.775191)
			(xy 73.25487 -278.799798) (xy 74.543932 -278.799798) (xy 74.547892 -278.750744) (xy 74.559669 -278.70296)
			(xy 74.57896 -278.657684) (xy 74.605263 -278.616088) (xy 74.637898 -278.579251) (xy 74.676019 -278.548126)
			(xy 74.71864 -278.523519) (xy 74.764656 -278.506067) (xy 74.812875 -278.496223) (xy 74.86205 -278.494242)
			(xy 74.910905 -278.500174) (xy 74.958176 -278.513866) (xy 75.002638 -278.534964) (xy 75.043141 -278.56292)
			(xy 75.078634 -278.597012) (xy 75.108199 -278.636356) (xy 75.13107 -278.679933) (xy 75.146654 -278.726614)
			(xy 75.154549 -278.775191) (xy 75.155044 -278.799798) (xy 76.443852 -278.799798) (xy 76.447812 -278.750744)
			(xy 76.459589 -278.70296) (xy 76.47888 -278.657684) (xy 76.505183 -278.616088) (xy 76.537818 -278.579251)
			(xy 76.575939 -278.548126) (xy 76.61856 -278.523519) (xy 76.664576 -278.506067) (xy 76.712795 -278.496223)
			(xy 76.76197 -278.494242) (xy 76.810825 -278.500174) (xy 76.858096 -278.513866) (xy 76.902558 -278.534964)
			(xy 76.943061 -278.56292) (xy 76.978554 -278.597012) (xy 77.008119 -278.636356) (xy 77.03099 -278.679933)
			(xy 77.046574 -278.726614) (xy 77.054469 -278.775191) (xy 77.054964 -278.799798) (xy 78.343772 -278.799798)
			(xy 78.347732 -278.750744) (xy 78.359509 -278.70296) (xy 78.3788 -278.657684) (xy 78.405103 -278.616088)
			(xy 78.437738 -278.579251) (xy 78.475859 -278.548126) (xy 78.51848 -278.523519) (xy 78.564496 -278.506067)
			(xy 78.612715 -278.496223) (xy 78.66189 -278.494242) (xy 78.710745 -278.500174) (xy 78.758016 -278.513866)
			(xy 78.802478 -278.534964) (xy 78.842981 -278.56292) (xy 78.878474 -278.597012) (xy 78.908039 -278.636356)
			(xy 78.93091 -278.679933) (xy 78.946494 -278.726614) (xy 78.954389 -278.775191) (xy 78.954884 -278.799798)
			(xy 80.243946 -278.799798) (xy 80.247906 -278.750744) (xy 80.259683 -278.70296) (xy 80.278974 -278.657684)
			(xy 80.305277 -278.616088) (xy 80.337912 -278.579251) (xy 80.376033 -278.548126) (xy 80.418654 -278.523519)
			(xy 80.46467 -278.506067) (xy 80.512889 -278.496223) (xy 80.562064 -278.494242) (xy 80.610919 -278.500174)
			(xy 80.65819 -278.513866) (xy 80.702652 -278.534964) (xy 80.743155 -278.56292) (xy 80.778648 -278.597012)
			(xy 80.808213 -278.636356) (xy 80.831084 -278.679933) (xy 80.846668 -278.726614) (xy 80.854563 -278.775191)
			(xy 80.855058 -278.799798) (xy 160.24404 -278.799798) (xy 160.248 -278.750744) (xy 160.259777 -278.70296)
			(xy 160.279068 -278.657684) (xy 160.305371 -278.616088) (xy 160.338006 -278.579251) (xy 160.376127 -278.548126)
			(xy 160.418748 -278.523519) (xy 160.464764 -278.506067) (xy 160.512983 -278.496223) (xy 160.562158 -278.494242)
			(xy 160.611013 -278.500174) (xy 160.658284 -278.513866) (xy 160.702746 -278.534964) (xy 160.743249 -278.56292)
			(xy 160.778742 -278.597012) (xy 160.808307 -278.636356) (xy 160.831178 -278.679933) (xy 160.846762 -278.726614)
			(xy 160.854657 -278.775191) (xy 160.855152 -278.799798) (xy 162.144214 -278.799798) (xy 162.148174 -278.750744)
			(xy 162.159951 -278.70296) (xy 162.179242 -278.657684) (xy 162.205545 -278.616088) (xy 162.23818 -278.579251)
			(xy 162.276301 -278.548126) (xy 162.318922 -278.523519) (xy 162.364938 -278.506067) (xy 162.413157 -278.496223)
			(xy 162.462332 -278.494242) (xy 162.511187 -278.500174) (xy 162.558458 -278.513866) (xy 162.60292 -278.534964)
			(xy 162.643423 -278.56292) (xy 162.678916 -278.597012) (xy 162.708481 -278.636356) (xy 162.731352 -278.679933)
			(xy 162.746936 -278.726614) (xy 162.754831 -278.775191) (xy 162.755326 -278.799798) (xy 164.044134 -278.799798)
			(xy 164.048094 -278.750744) (xy 164.059871 -278.70296) (xy 164.079162 -278.657684) (xy 164.105465 -278.616088)
			(xy 164.1381 -278.579251) (xy 164.176221 -278.548126) (xy 164.218842 -278.523519) (xy 164.264858 -278.506067)
			(xy 164.313077 -278.496223) (xy 164.362252 -278.494242) (xy 164.411107 -278.500174) (xy 164.458378 -278.513866)
			(xy 164.50284 -278.534964) (xy 164.543343 -278.56292) (xy 164.578836 -278.597012) (xy 164.608401 -278.636356)
			(xy 164.631272 -278.679933) (xy 164.646856 -278.726614) (xy 164.654751 -278.775191) (xy 164.655246 -278.799798)
			(xy 165.944054 -278.799798) (xy 165.948014 -278.750744) (xy 165.959791 -278.70296) (xy 165.979082 -278.657684)
			(xy 166.005385 -278.616088) (xy 166.03802 -278.579251) (xy 166.076141 -278.548126) (xy 166.118762 -278.523519)
			(xy 166.164778 -278.506067) (xy 166.212997 -278.496223) (xy 166.262172 -278.494242) (xy 166.311027 -278.500174)
			(xy 166.358298 -278.513866) (xy 166.40276 -278.534964) (xy 166.443263 -278.56292) (xy 166.478756 -278.597012)
			(xy 166.508321 -278.636356) (xy 166.531192 -278.679933) (xy 166.546776 -278.726614) (xy 166.554671 -278.775191)
			(xy 166.555166 -278.799798) (xy 167.844228 -278.799798) (xy 167.848188 -278.750744) (xy 167.859965 -278.70296)
			(xy 167.879256 -278.657684) (xy 167.905559 -278.616088) (xy 167.938194 -278.579251) (xy 167.976315 -278.548126)
			(xy 168.018936 -278.523519) (xy 168.064952 -278.506067) (xy 168.113171 -278.496223) (xy 168.162346 -278.494242)
			(xy 168.211201 -278.500174) (xy 168.258472 -278.513866) (xy 168.302934 -278.534964) (xy 168.343437 -278.56292)
			(xy 168.37893 -278.597012) (xy 168.408495 -278.636356) (xy 168.431366 -278.679933) (xy 168.44695 -278.726614)
			(xy 168.454845 -278.775191) (xy 168.45534 -278.799798) (xy 169.744148 -278.799798) (xy 169.748108 -278.750744)
			(xy 169.759885 -278.70296) (xy 169.779176 -278.657684) (xy 169.805479 -278.616088) (xy 169.838114 -278.579251)
			(xy 169.876235 -278.548126) (xy 169.918856 -278.523519) (xy 169.964872 -278.506067) (xy 170.013091 -278.496223)
			(xy 170.062266 -278.494242) (xy 170.111121 -278.500174) (xy 170.158392 -278.513866) (xy 170.202854 -278.534964)
			(xy 170.243357 -278.56292) (xy 170.27885 -278.597012) (xy 170.308415 -278.636356) (xy 170.331286 -278.679933)
			(xy 170.34687 -278.726614) (xy 170.354765 -278.775191) (xy 170.35526 -278.799798) (xy 171.644068 -278.799798)
			(xy 171.648028 -278.750744) (xy 171.659805 -278.70296) (xy 171.679096 -278.657684) (xy 171.705399 -278.616088)
			(xy 171.738034 -278.579251) (xy 171.776155 -278.548126) (xy 171.818776 -278.523519) (xy 171.864792 -278.506067)
			(xy 171.913011 -278.496223) (xy 171.962186 -278.494242) (xy 172.011041 -278.500174) (xy 172.058312 -278.513866)
			(xy 172.102774 -278.534964) (xy 172.143277 -278.56292) (xy 172.17877 -278.597012) (xy 172.208335 -278.636356)
			(xy 172.231206 -278.679933) (xy 172.24679 -278.726614) (xy 172.254685 -278.775191) (xy 172.25518 -278.799798)
			(xy 173.544242 -278.799798) (xy 173.548202 -278.750744) (xy 173.559979 -278.70296) (xy 173.57927 -278.657684)
			(xy 173.605573 -278.616088) (xy 173.638208 -278.579251) (xy 173.676329 -278.548126) (xy 173.71895 -278.523519)
			(xy 173.764966 -278.506067) (xy 173.813185 -278.496223) (xy 173.86236 -278.494242) (xy 173.911215 -278.500174)
			(xy 173.958486 -278.513866) (xy 174.002948 -278.534964) (xy 174.043451 -278.56292) (xy 174.078944 -278.597012)
			(xy 174.108509 -278.636356) (xy 174.13138 -278.679933) (xy 174.146964 -278.726614) (xy 174.154859 -278.775191)
			(xy 174.155354 -278.799798) (xy 175.443908 -278.799798) (xy 175.447868 -278.750744) (xy 175.459645 -278.70296)
			(xy 175.478936 -278.657684) (xy 175.505239 -278.616088) (xy 175.537874 -278.579251) (xy 175.575995 -278.548126)
			(xy 175.618616 -278.523519) (xy 175.664632 -278.506067) (xy 175.712851 -278.496223) (xy 175.762026 -278.494242)
			(xy 175.810881 -278.500174) (xy 175.858152 -278.513866) (xy 175.902614 -278.534964) (xy 175.943117 -278.56292)
			(xy 175.97861 -278.597012) (xy 176.008175 -278.636356) (xy 176.031046 -278.679933) (xy 176.04663 -278.726614)
			(xy 176.054525 -278.775191) (xy 176.05502 -278.799798) (xy 177.343828 -278.799798) (xy 177.347788 -278.750744)
			(xy 177.359565 -278.70296) (xy 177.378856 -278.657684) (xy 177.405159 -278.616088) (xy 177.437794 -278.579251)
			(xy 177.475915 -278.548126) (xy 177.518536 -278.523519) (xy 177.564552 -278.506067) (xy 177.612771 -278.496223)
			(xy 177.661946 -278.494242) (xy 177.710801 -278.500174) (xy 177.758072 -278.513866) (xy 177.802534 -278.534964)
			(xy 177.843037 -278.56292) (xy 177.87853 -278.597012) (xy 177.908095 -278.636356) (xy 177.930966 -278.679933)
			(xy 177.94655 -278.726614) (xy 177.954445 -278.775191) (xy 177.95494 -278.799798) (xy 179.244002 -278.799798)
			(xy 179.247962 -278.750744) (xy 179.259739 -278.70296) (xy 179.27903 -278.657684) (xy 179.305333 -278.616088)
			(xy 179.337968 -278.579251) (xy 179.376089 -278.548126) (xy 179.41871 -278.523519) (xy 179.464726 -278.506067)
			(xy 179.512945 -278.496223) (xy 179.56212 -278.494242) (xy 179.610975 -278.500174) (xy 179.658246 -278.513866)
			(xy 179.702708 -278.534964) (xy 179.743211 -278.56292) (xy 179.778704 -278.597012) (xy 179.808269 -278.636356)
			(xy 179.83114 -278.679933) (xy 179.846724 -278.726614) (xy 179.854619 -278.775191) (xy 179.855114 -278.799798)
			(xy 181.143922 -278.799798) (xy 181.147882 -278.750744) (xy 181.159659 -278.70296) (xy 181.17895 -278.657684)
			(xy 181.205253 -278.616088) (xy 181.237888 -278.579251) (xy 181.276009 -278.548126) (xy 181.31863 -278.523519)
			(xy 181.364646 -278.506067) (xy 181.412865 -278.496223) (xy 181.46204 -278.494242) (xy 181.510895 -278.500174)
			(xy 181.558166 -278.513866) (xy 181.602628 -278.534964) (xy 181.643131 -278.56292) (xy 181.678624 -278.597012)
			(xy 181.708189 -278.636356) (xy 181.73106 -278.679933) (xy 181.746644 -278.726614) (xy 181.754539 -278.775191)
			(xy 181.755034 -278.799798) (xy 183.043842 -278.799798) (xy 183.047802 -278.750744) (xy 183.059579 -278.70296)
			(xy 183.07887 -278.657684) (xy 183.105173 -278.616088) (xy 183.137808 -278.579251) (xy 183.175929 -278.548126)
			(xy 183.21855 -278.523519) (xy 183.264566 -278.506067) (xy 183.312785 -278.496223) (xy 183.36196 -278.494242)
			(xy 183.410815 -278.500174) (xy 183.458086 -278.513866) (xy 183.502548 -278.534964) (xy 183.543051 -278.56292)
			(xy 183.578544 -278.597012) (xy 183.608109 -278.636356) (xy 183.63098 -278.679933) (xy 183.646564 -278.726614)
			(xy 183.654459 -278.775191) (xy 183.654954 -278.799798) (xy 184.944016 -278.799798) (xy 184.947976 -278.750744)
			(xy 184.959753 -278.70296) (xy 184.979044 -278.657684) (xy 185.005347 -278.616088) (xy 185.037982 -278.579251)
			(xy 185.076103 -278.548126) (xy 185.118724 -278.523519) (xy 185.16474 -278.506067) (xy 185.212959 -278.496223)
			(xy 185.262134 -278.494242) (xy 185.310989 -278.500174) (xy 185.35826 -278.513866) (xy 185.402722 -278.534964)
			(xy 185.443225 -278.56292) (xy 185.478718 -278.597012) (xy 185.508283 -278.636356) (xy 185.531154 -278.679933)
			(xy 185.546738 -278.726614) (xy 185.554633 -278.775191) (xy 185.555128 -278.799798) (xy 186.843936 -278.799798)
			(xy 186.847896 -278.750744) (xy 186.859673 -278.70296) (xy 186.878964 -278.657684) (xy 186.905267 -278.616088)
			(xy 186.937902 -278.579251) (xy 186.976023 -278.548126) (xy 187.018644 -278.523519) (xy 187.06466 -278.506067)
			(xy 187.112879 -278.496223) (xy 187.162054 -278.494242) (xy 187.210909 -278.500174) (xy 187.25818 -278.513866)
			(xy 187.302642 -278.534964) (xy 187.343145 -278.56292) (xy 187.378638 -278.597012) (xy 187.408203 -278.636356)
			(xy 187.431074 -278.679933) (xy 187.446658 -278.726614) (xy 187.454553 -278.775191) (xy 187.455048 -278.799798)
			(xy 188.743856 -278.799798) (xy 188.747816 -278.750744) (xy 188.759593 -278.70296) (xy 188.778884 -278.657684)
			(xy 188.805187 -278.616088) (xy 188.837822 -278.579251) (xy 188.875943 -278.548126) (xy 188.918564 -278.523519)
			(xy 188.96458 -278.506067) (xy 189.012799 -278.496223) (xy 189.061974 -278.494242) (xy 189.110829 -278.500174)
			(xy 189.1581 -278.513866) (xy 189.202562 -278.534964) (xy 189.243065 -278.56292) (xy 189.278558 -278.597012)
			(xy 189.308123 -278.636356) (xy 189.330994 -278.679933) (xy 189.346578 -278.726614) (xy 189.354473 -278.775191)
			(xy 189.354968 -278.799798) (xy 190.64403 -278.799798) (xy 190.64799 -278.750744) (xy 190.659767 -278.70296)
			(xy 190.679058 -278.657684) (xy 190.705361 -278.616088) (xy 190.737996 -278.579251) (xy 190.776117 -278.548126)
			(xy 190.818738 -278.523519) (xy 190.864754 -278.506067) (xy 190.912973 -278.496223) (xy 190.962148 -278.494242)
			(xy 191.011003 -278.500174) (xy 191.058274 -278.513866) (xy 191.102736 -278.534964) (xy 191.143239 -278.56292)
			(xy 191.178732 -278.597012) (xy 191.208297 -278.636356) (xy 191.231168 -278.679933) (xy 191.246752 -278.726614)
			(xy 191.254647 -278.775191) (xy 191.255142 -278.799798) (xy 192.54395 -278.799798) (xy 192.54791 -278.750744)
			(xy 192.559687 -278.70296) (xy 192.578978 -278.657684) (xy 192.605281 -278.616088) (xy 192.637916 -278.579251)
			(xy 192.676037 -278.548126) (xy 192.718658 -278.523519) (xy 192.764674 -278.506067) (xy 192.812893 -278.496223)
			(xy 192.862068 -278.494242) (xy 192.910923 -278.500174) (xy 192.958194 -278.513866) (xy 193.002656 -278.534964)
			(xy 193.043159 -278.56292) (xy 193.078652 -278.597012) (xy 193.108217 -278.636356) (xy 193.131088 -278.679933)
			(xy 193.146672 -278.726614) (xy 193.154567 -278.775191) (xy 193.155062 -278.799798) (xy 194.44387 -278.799798)
			(xy 194.44783 -278.750744) (xy 194.459607 -278.70296) (xy 194.478898 -278.657684) (xy 194.505201 -278.616088)
			(xy 194.537836 -278.579251) (xy 194.575957 -278.548126) (xy 194.618578 -278.523519) (xy 194.664594 -278.506067)
			(xy 194.712813 -278.496223) (xy 194.761988 -278.494242) (xy 194.810843 -278.500174) (xy 194.858114 -278.513866)
			(xy 194.902576 -278.534964) (xy 194.943079 -278.56292) (xy 194.978572 -278.597012) (xy 195.008137 -278.636356)
			(xy 195.031008 -278.679933) (xy 195.046592 -278.726614) (xy 195.054487 -278.775191) (xy 195.054982 -278.799798)
			(xy 196.344044 -278.799798) (xy 196.348004 -278.750744) (xy 196.359781 -278.70296) (xy 196.379072 -278.657684)
			(xy 196.405375 -278.616088) (xy 196.43801 -278.579251) (xy 196.476131 -278.548126) (xy 196.518752 -278.523519)
			(xy 196.564768 -278.506067) (xy 196.612987 -278.496223) (xy 196.662162 -278.494242) (xy 196.711017 -278.500174)
			(xy 196.758288 -278.513866) (xy 196.80275 -278.534964) (xy 196.843253 -278.56292) (xy 196.878746 -278.597012)
			(xy 196.908311 -278.636356) (xy 196.931182 -278.679933) (xy 196.946766 -278.726614) (xy 196.954661 -278.775191)
			(xy 196.955156 -278.799798) (xy 276.343884 -278.799798) (xy 276.347844 -278.750744) (xy 276.359621 -278.70296)
			(xy 276.378912 -278.657684) (xy 276.405215 -278.616088) (xy 276.43785 -278.579251) (xy 276.475971 -278.548126)
			(xy 276.518592 -278.523519) (xy 276.564608 -278.506067) (xy 276.612827 -278.496223) (xy 276.662002 -278.494242)
			(xy 276.710857 -278.500174) (xy 276.758128 -278.513866) (xy 276.80259 -278.534964) (xy 276.843093 -278.56292)
			(xy 276.878586 -278.597012) (xy 276.908151 -278.636356) (xy 276.931022 -278.679933) (xy 276.946606 -278.726614)
			(xy 276.954501 -278.775191) (xy 276.954996 -278.799798) (xy 278.244058 -278.799798) (xy 278.248018 -278.750744)
			(xy 278.259795 -278.70296) (xy 278.279086 -278.657684) (xy 278.305389 -278.616088) (xy 278.338024 -278.579251)
			(xy 278.376145 -278.548126) (xy 278.418766 -278.523519) (xy 278.464782 -278.506067) (xy 278.513001 -278.496223)
			(xy 278.562176 -278.494242) (xy 278.611031 -278.500174) (xy 278.658302 -278.513866) (xy 278.702764 -278.534964)
			(xy 278.743267 -278.56292) (xy 278.77876 -278.597012) (xy 278.808325 -278.636356) (xy 278.831196 -278.679933)
			(xy 278.84678 -278.726614) (xy 278.854675 -278.775191) (xy 278.85517 -278.799798) (xy 280.143978 -278.799798)
			(xy 280.147938 -278.750744) (xy 280.159715 -278.70296) (xy 280.179006 -278.657684) (xy 280.205309 -278.616088)
			(xy 280.237944 -278.579251) (xy 280.276065 -278.548126) (xy 280.318686 -278.523519) (xy 280.364702 -278.506067)
			(xy 280.412921 -278.496223) (xy 280.462096 -278.494242) (xy 280.510951 -278.500174) (xy 280.558222 -278.513866)
			(xy 280.602684 -278.534964) (xy 280.643187 -278.56292) (xy 280.67868 -278.597012) (xy 280.708245 -278.636356)
			(xy 280.731116 -278.679933) (xy 280.7467 -278.726614) (xy 280.754595 -278.775191) (xy 280.75509 -278.799798)
			(xy 282.043898 -278.799798) (xy 282.047858 -278.750744) (xy 282.059635 -278.70296) (xy 282.078926 -278.657684)
			(xy 282.105229 -278.616088) (xy 282.137864 -278.579251) (xy 282.175985 -278.548126) (xy 282.218606 -278.523519)
			(xy 282.264622 -278.506067) (xy 282.312841 -278.496223) (xy 282.362016 -278.494242) (xy 282.410871 -278.500174)
			(xy 282.458142 -278.513866) (xy 282.502604 -278.534964) (xy 282.543107 -278.56292) (xy 282.5786 -278.597012)
			(xy 282.608165 -278.636356) (xy 282.631036 -278.679933) (xy 282.64662 -278.726614) (xy 282.654515 -278.775191)
			(xy 282.65501 -278.799798) (xy 283.944072 -278.799798) (xy 283.948032 -278.750744) (xy 283.959809 -278.70296)
			(xy 283.9791 -278.657684) (xy 284.005403 -278.616088) (xy 284.038038 -278.579251) (xy 284.076159 -278.548126)
			(xy 284.11878 -278.523519) (xy 284.164796 -278.506067) (xy 284.213015 -278.496223) (xy 284.26219 -278.494242)
			(xy 284.311045 -278.500174) (xy 284.358316 -278.513866) (xy 284.402778 -278.534964) (xy 284.443281 -278.56292)
			(xy 284.478774 -278.597012) (xy 284.508339 -278.636356) (xy 284.53121 -278.679933) (xy 284.546794 -278.726614)
			(xy 284.554689 -278.775191) (xy 284.555184 -278.799798) (xy 285.843992 -278.799798) (xy 285.847952 -278.750744)
			(xy 285.859729 -278.70296) (xy 285.87902 -278.657684) (xy 285.905323 -278.616088) (xy 285.937958 -278.579251)
			(xy 285.976079 -278.548126) (xy 286.0187 -278.523519) (xy 286.064716 -278.506067) (xy 286.112935 -278.496223)
			(xy 286.16211 -278.494242) (xy 286.210965 -278.500174) (xy 286.258236 -278.513866) (xy 286.302698 -278.534964)
			(xy 286.343201 -278.56292) (xy 286.378694 -278.597012) (xy 286.408259 -278.636356) (xy 286.43113 -278.679933)
			(xy 286.446714 -278.726614) (xy 286.454609 -278.775191) (xy 286.455104 -278.799798) (xy 287.743912 -278.799798)
			(xy 287.747872 -278.750744) (xy 287.759649 -278.70296) (xy 287.77894 -278.657684) (xy 287.805243 -278.616088)
			(xy 287.837878 -278.579251) (xy 287.875999 -278.548126) (xy 287.91862 -278.523519) (xy 287.964636 -278.506067)
			(xy 288.012855 -278.496223) (xy 288.06203 -278.494242) (xy 288.110885 -278.500174) (xy 288.158156 -278.513866)
			(xy 288.202618 -278.534964) (xy 288.243121 -278.56292) (xy 288.278614 -278.597012) (xy 288.308179 -278.636356)
			(xy 288.33105 -278.679933) (xy 288.346634 -278.726614) (xy 288.354529 -278.775191) (xy 288.355024 -278.799798)
			(xy 289.644086 -278.799798) (xy 289.648046 -278.750744) (xy 289.659823 -278.70296) (xy 289.679114 -278.657684)
			(xy 289.705417 -278.616088) (xy 289.738052 -278.579251) (xy 289.776173 -278.548126) (xy 289.818794 -278.523519)
			(xy 289.86481 -278.506067) (xy 289.913029 -278.496223) (xy 289.962204 -278.494242) (xy 290.011059 -278.500174)
			(xy 290.05833 -278.513866) (xy 290.102792 -278.534964) (xy 290.143295 -278.56292) (xy 290.178788 -278.597012)
			(xy 290.208353 -278.636356) (xy 290.231224 -278.679933) (xy 290.246808 -278.726614) (xy 290.254703 -278.775191)
			(xy 290.255198 -278.799798) (xy 291.543752 -278.799798) (xy 291.547712 -278.750744) (xy 291.559489 -278.70296)
			(xy 291.57878 -278.657684) (xy 291.605083 -278.616088) (xy 291.637718 -278.579251) (xy 291.675839 -278.548126)
			(xy 291.71846 -278.523519) (xy 291.764476 -278.506067) (xy 291.812695 -278.496223) (xy 291.86187 -278.494242)
			(xy 291.910725 -278.500174) (xy 291.957996 -278.513866) (xy 292.002458 -278.534964) (xy 292.042961 -278.56292)
			(xy 292.078454 -278.597012) (xy 292.108019 -278.636356) (xy 292.13089 -278.679933) (xy 292.146474 -278.726614)
			(xy 292.154369 -278.775191) (xy 292.154864 -278.799798) (xy 293.443672 -278.799798) (xy 293.447632 -278.750744)
			(xy 293.459409 -278.70296) (xy 293.4787 -278.657684) (xy 293.505003 -278.616088) (xy 293.537638 -278.579251)
			(xy 293.575759 -278.548126) (xy 293.61838 -278.523519) (xy 293.664396 -278.506067) (xy 293.712615 -278.496223)
			(xy 293.76179 -278.494242) (xy 293.810645 -278.500174) (xy 293.857916 -278.513866) (xy 293.902378 -278.534964)
			(xy 293.942881 -278.56292) (xy 293.978374 -278.597012) (xy 294.007939 -278.636356) (xy 294.03081 -278.679933)
			(xy 294.046394 -278.726614) (xy 294.054289 -278.775191) (xy 294.054784 -278.799798) (xy 295.343846 -278.799798)
			(xy 295.347806 -278.750744) (xy 295.359583 -278.70296) (xy 295.378874 -278.657684) (xy 295.405177 -278.616088)
			(xy 295.437812 -278.579251) (xy 295.475933 -278.548126) (xy 295.518554 -278.523519) (xy 295.56457 -278.506067)
			(xy 295.612789 -278.496223) (xy 295.661964 -278.494242) (xy 295.710819 -278.500174) (xy 295.75809 -278.513866)
			(xy 295.802552 -278.534964) (xy 295.843055 -278.56292) (xy 295.878548 -278.597012) (xy 295.908113 -278.636356)
			(xy 295.930984 -278.679933) (xy 295.946568 -278.726614) (xy 295.954463 -278.775191) (xy 295.954958 -278.799798)
			(xy 297.243766 -278.799798) (xy 297.247726 -278.750744) (xy 297.259503 -278.70296) (xy 297.278794 -278.657684)
			(xy 297.305097 -278.616088) (xy 297.337732 -278.579251) (xy 297.375853 -278.548126) (xy 297.418474 -278.523519)
			(xy 297.46449 -278.506067) (xy 297.512709 -278.496223) (xy 297.561884 -278.494242) (xy 297.610739 -278.500174)
			(xy 297.65801 -278.513866) (xy 297.702472 -278.534964) (xy 297.742975 -278.56292) (xy 297.778468 -278.597012)
			(xy 297.808033 -278.636356) (xy 297.830904 -278.679933) (xy 297.846488 -278.726614) (xy 297.854383 -278.775191)
			(xy 297.854878 -278.799798) (xy 299.143686 -278.799798) (xy 299.147646 -278.750744) (xy 299.159423 -278.70296)
			(xy 299.178714 -278.657684) (xy 299.205017 -278.616088) (xy 299.237652 -278.579251) (xy 299.275773 -278.548126)
			(xy 299.318394 -278.523519) (xy 299.36441 -278.506067) (xy 299.412629 -278.496223) (xy 299.461804 -278.494242)
			(xy 299.510659 -278.500174) (xy 299.55793 -278.513866) (xy 299.602392 -278.534964) (xy 299.642895 -278.56292)
			(xy 299.678388 -278.597012) (xy 299.707953 -278.636356) (xy 299.730824 -278.679933) (xy 299.746408 -278.726614)
			(xy 299.754303 -278.775191) (xy 299.754798 -278.799798) (xy 301.04386 -278.799798) (xy 301.04782 -278.750744)
			(xy 301.059597 -278.70296) (xy 301.078888 -278.657684) (xy 301.105191 -278.616088) (xy 301.137826 -278.579251)
			(xy 301.175947 -278.548126) (xy 301.218568 -278.523519) (xy 301.264584 -278.506067) (xy 301.312803 -278.496223)
			(xy 301.361978 -278.494242) (xy 301.410833 -278.500174) (xy 301.458104 -278.513866) (xy 301.502566 -278.534964)
			(xy 301.543069 -278.56292) (xy 301.578562 -278.597012) (xy 301.608127 -278.636356) (xy 301.630998 -278.679933)
			(xy 301.646582 -278.726614) (xy 301.654477 -278.775191) (xy 301.654972 -278.799798) (xy 302.94378 -278.799798)
			(xy 302.94774 -278.750744) (xy 302.959517 -278.70296) (xy 302.978808 -278.657684) (xy 303.005111 -278.616088)
			(xy 303.037746 -278.579251) (xy 303.075867 -278.548126) (xy 303.118488 -278.523519) (xy 303.164504 -278.506067)
			(xy 303.212723 -278.496223) (xy 303.261898 -278.494242) (xy 303.310753 -278.500174) (xy 303.358024 -278.513866)
			(xy 303.402486 -278.534964) (xy 303.442989 -278.56292) (xy 303.478482 -278.597012) (xy 303.508047 -278.636356)
			(xy 303.530918 -278.679933) (xy 303.546502 -278.726614) (xy 303.554397 -278.775191) (xy 303.554892 -278.799798)
			(xy 304.8437 -278.799798) (xy 304.84766 -278.750744) (xy 304.859437 -278.70296) (xy 304.878728 -278.657684)
			(xy 304.905031 -278.616088) (xy 304.937666 -278.579251) (xy 304.975787 -278.548126) (xy 305.018408 -278.523519)
			(xy 305.064424 -278.506067) (xy 305.112643 -278.496223) (xy 305.161818 -278.494242) (xy 305.210673 -278.500174)
			(xy 305.257944 -278.513866) (xy 305.302406 -278.534964) (xy 305.342909 -278.56292) (xy 305.378402 -278.597012)
			(xy 305.407967 -278.636356) (xy 305.430838 -278.679933) (xy 305.446422 -278.726614) (xy 305.454317 -278.775191)
			(xy 305.454812 -278.799798) (xy 306.743874 -278.799798) (xy 306.747834 -278.750744) (xy 306.759611 -278.70296)
			(xy 306.778902 -278.657684) (xy 306.805205 -278.616088) (xy 306.83784 -278.579251) (xy 306.875961 -278.548126)
			(xy 306.918582 -278.523519) (xy 306.964598 -278.506067) (xy 307.012817 -278.496223) (xy 307.061992 -278.494242)
			(xy 307.110847 -278.500174) (xy 307.158118 -278.513866) (xy 307.20258 -278.534964) (xy 307.243083 -278.56292)
			(xy 307.278576 -278.597012) (xy 307.308141 -278.636356) (xy 307.331012 -278.679933) (xy 307.346596 -278.726614)
			(xy 307.354491 -278.775191) (xy 307.354986 -278.799798) (xy 308.643794 -278.799798) (xy 308.647754 -278.750744)
			(xy 308.659531 -278.70296) (xy 308.678822 -278.657684) (xy 308.705125 -278.616088) (xy 308.73776 -278.579251)
			(xy 308.775881 -278.548126) (xy 308.818502 -278.523519) (xy 308.864518 -278.506067) (xy 308.912737 -278.496223)
			(xy 308.961912 -278.494242) (xy 309.010767 -278.500174) (xy 309.058038 -278.513866) (xy 309.1025 -278.534964)
			(xy 309.143003 -278.56292) (xy 309.178496 -278.597012) (xy 309.208061 -278.636356) (xy 309.230932 -278.679933)
			(xy 309.246516 -278.726614) (xy 309.254411 -278.775191) (xy 309.254906 -278.799798) (xy 310.543714 -278.799798)
			(xy 310.547674 -278.750744) (xy 310.559451 -278.70296) (xy 310.578742 -278.657684) (xy 310.605045 -278.616088)
			(xy 310.63768 -278.579251) (xy 310.675801 -278.548126) (xy 310.718422 -278.523519) (xy 310.764438 -278.506067)
			(xy 310.812657 -278.496223) (xy 310.861832 -278.494242) (xy 310.910687 -278.500174) (xy 310.957958 -278.513866)
			(xy 311.00242 -278.534964) (xy 311.042923 -278.56292) (xy 311.078416 -278.597012) (xy 311.107981 -278.636356)
			(xy 311.130852 -278.679933) (xy 311.146436 -278.726614) (xy 311.154331 -278.775191) (xy 311.154826 -278.799798)
			(xy 312.443888 -278.799798) (xy 312.447848 -278.750744) (xy 312.459625 -278.70296) (xy 312.478916 -278.657684)
			(xy 312.505219 -278.616088) (xy 312.537854 -278.579251) (xy 312.575975 -278.548126) (xy 312.618596 -278.523519)
			(xy 312.664612 -278.506067) (xy 312.712831 -278.496223) (xy 312.762006 -278.494242) (xy 312.810861 -278.500174)
			(xy 312.858132 -278.513866) (xy 312.902594 -278.534964) (xy 312.943097 -278.56292) (xy 312.97859 -278.597012)
			(xy 313.008155 -278.636356) (xy 313.031026 -278.679933) (xy 313.04661 -278.726614) (xy 313.054505 -278.775191)
			(xy 313.055 -278.799798) (xy 392.443982 -278.799798) (xy 392.447942 -278.750744) (xy 392.459719 -278.70296)
			(xy 392.47901 -278.657684) (xy 392.505313 -278.616088) (xy 392.537948 -278.579251) (xy 392.576069 -278.548126)
			(xy 392.61869 -278.523519) (xy 392.664706 -278.506067) (xy 392.712925 -278.496223) (xy 392.7621 -278.494242)
			(xy 392.810955 -278.500174) (xy 392.858226 -278.513866) (xy 392.902688 -278.534964) (xy 392.943191 -278.56292)
			(xy 392.978684 -278.597012) (xy 393.008249 -278.636356) (xy 393.03112 -278.679933) (xy 393.046704 -278.726614)
			(xy 393.054599 -278.775191) (xy 393.055094 -278.799798) (xy 394.344156 -278.799798) (xy 394.348116 -278.750744)
			(xy 394.359893 -278.70296) (xy 394.379184 -278.657684) (xy 394.405487 -278.616088) (xy 394.438122 -278.579251)
			(xy 394.476243 -278.548126) (xy 394.518864 -278.523519) (xy 394.56488 -278.506067) (xy 394.613099 -278.496223)
			(xy 394.662274 -278.494242) (xy 394.711129 -278.500174) (xy 394.7584 -278.513866) (xy 394.802862 -278.534964)
			(xy 394.843365 -278.56292) (xy 394.878858 -278.597012) (xy 394.908423 -278.636356) (xy 394.931294 -278.679933)
			(xy 394.946878 -278.726614) (xy 394.954773 -278.775191) (xy 394.955268 -278.799798) (xy 396.244076 -278.799798)
			(xy 396.248036 -278.750744) (xy 396.259813 -278.70296) (xy 396.279104 -278.657684) (xy 396.305407 -278.616088)
			(xy 396.338042 -278.579251) (xy 396.376163 -278.548126) (xy 396.418784 -278.523519) (xy 396.4648 -278.506067)
			(xy 396.513019 -278.496223) (xy 396.562194 -278.494242) (xy 396.611049 -278.500174) (xy 396.65832 -278.513866)
			(xy 396.702782 -278.534964) (xy 396.743285 -278.56292) (xy 396.778778 -278.597012) (xy 396.808343 -278.636356)
			(xy 396.831214 -278.679933) (xy 396.846798 -278.726614) (xy 396.854693 -278.775191) (xy 396.855188 -278.799798)
			(xy 398.143996 -278.799798) (xy 398.147956 -278.750744) (xy 398.159733 -278.70296) (xy 398.179024 -278.657684)
			(xy 398.205327 -278.616088) (xy 398.237962 -278.579251) (xy 398.276083 -278.548126) (xy 398.318704 -278.523519)
			(xy 398.36472 -278.506067) (xy 398.412939 -278.496223) (xy 398.462114 -278.494242) (xy 398.510969 -278.500174)
			(xy 398.55824 -278.513866) (xy 398.602702 -278.534964) (xy 398.643205 -278.56292) (xy 398.678698 -278.597012)
			(xy 398.708263 -278.636356) (xy 398.731134 -278.679933) (xy 398.746718 -278.726614) (xy 398.754613 -278.775191)
			(xy 398.755108 -278.799798) (xy 400.04417 -278.799798) (xy 400.04813 -278.750744) (xy 400.059907 -278.70296)
			(xy 400.079198 -278.657684) (xy 400.105501 -278.616088) (xy 400.138136 -278.579251) (xy 400.176257 -278.548126)
			(xy 400.218878 -278.523519) (xy 400.264894 -278.506067) (xy 400.313113 -278.496223) (xy 400.362288 -278.494242)
			(xy 400.411143 -278.500174) (xy 400.458414 -278.513866) (xy 400.502876 -278.534964) (xy 400.543379 -278.56292)
			(xy 400.578872 -278.597012) (xy 400.608437 -278.636356) (xy 400.631308 -278.679933) (xy 400.646892 -278.726614)
			(xy 400.654787 -278.775191) (xy 400.655282 -278.799798) (xy 401.94409 -278.799798) (xy 401.94805 -278.750744)
			(xy 401.959827 -278.70296) (xy 401.979118 -278.657684) (xy 402.005421 -278.616088) (xy 402.038056 -278.579251)
			(xy 402.076177 -278.548126) (xy 402.118798 -278.523519) (xy 402.164814 -278.506067) (xy 402.213033 -278.496223)
			(xy 402.262208 -278.494242) (xy 402.311063 -278.500174) (xy 402.358334 -278.513866) (xy 402.402796 -278.534964)
			(xy 402.443299 -278.56292) (xy 402.478792 -278.597012) (xy 402.508357 -278.636356) (xy 402.531228 -278.679933)
			(xy 402.546812 -278.726614) (xy 402.554707 -278.775191) (xy 402.555202 -278.799798) (xy 403.84401 -278.799798)
			(xy 403.84797 -278.750744) (xy 403.859747 -278.70296) (xy 403.879038 -278.657684) (xy 403.905341 -278.616088)
			(xy 403.937976 -278.579251) (xy 403.976097 -278.548126) (xy 404.018718 -278.523519) (xy 404.064734 -278.506067)
			(xy 404.112953 -278.496223) (xy 404.162128 -278.494242) (xy 404.210983 -278.500174) (xy 404.258254 -278.513866)
			(xy 404.302716 -278.534964) (xy 404.343219 -278.56292) (xy 404.378712 -278.597012) (xy 404.408277 -278.636356)
			(xy 404.431148 -278.679933) (xy 404.446732 -278.726614) (xy 404.454627 -278.775191) (xy 404.455122 -278.799798)
			(xy 405.744184 -278.799798) (xy 405.748144 -278.750744) (xy 405.759921 -278.70296) (xy 405.779212 -278.657684)
			(xy 405.805515 -278.616088) (xy 405.83815 -278.579251) (xy 405.876271 -278.548126) (xy 405.918892 -278.523519)
			(xy 405.964908 -278.506067) (xy 406.013127 -278.496223) (xy 406.062302 -278.494242) (xy 406.111157 -278.500174)
			(xy 406.158428 -278.513866) (xy 406.20289 -278.534964) (xy 406.243393 -278.56292) (xy 406.278886 -278.597012)
			(xy 406.308451 -278.636356) (xy 406.331322 -278.679933) (xy 406.346906 -278.726614) (xy 406.354801 -278.775191)
			(xy 406.355296 -278.799798) (xy 407.64385 -278.799798) (xy 407.64781 -278.750744) (xy 407.659587 -278.70296)
			(xy 407.678878 -278.657684) (xy 407.705181 -278.616088) (xy 407.737816 -278.579251) (xy 407.775937 -278.548126)
			(xy 407.818558 -278.523519) (xy 407.864574 -278.506067) (xy 407.912793 -278.496223) (xy 407.961968 -278.494242)
			(xy 408.010823 -278.500174) (xy 408.058094 -278.513866) (xy 408.102556 -278.534964) (xy 408.143059 -278.56292)
			(xy 408.178552 -278.597012) (xy 408.208117 -278.636356) (xy 408.230988 -278.679933) (xy 408.246572 -278.726614)
			(xy 408.254467 -278.775191) (xy 408.254962 -278.799798) (xy 409.54377 -278.799798) (xy 409.54773 -278.750744)
			(xy 409.559507 -278.70296) (xy 409.578798 -278.657684) (xy 409.605101 -278.616088) (xy 409.637736 -278.579251)
			(xy 409.675857 -278.548126) (xy 409.718478 -278.523519) (xy 409.764494 -278.506067) (xy 409.812713 -278.496223)
			(xy 409.861888 -278.494242) (xy 409.910743 -278.500174) (xy 409.958014 -278.513866) (xy 410.002476 -278.534964)
			(xy 410.042979 -278.56292) (xy 410.078472 -278.597012) (xy 410.108037 -278.636356) (xy 410.130908 -278.679933)
			(xy 410.146492 -278.726614) (xy 410.154387 -278.775191) (xy 410.154882 -278.799798) (xy 411.443944 -278.799798)
			(xy 411.447904 -278.750744) (xy 411.459681 -278.70296) (xy 411.478972 -278.657684) (xy 411.505275 -278.616088)
			(xy 411.53791 -278.579251) (xy 411.576031 -278.548126) (xy 411.618652 -278.523519) (xy 411.664668 -278.506067)
			(xy 411.712887 -278.496223) (xy 411.762062 -278.494242) (xy 411.810917 -278.500174) (xy 411.858188 -278.513866)
			(xy 411.90265 -278.534964) (xy 411.943153 -278.56292) (xy 411.978646 -278.597012) (xy 412.008211 -278.636356)
			(xy 412.031082 -278.679933) (xy 412.046666 -278.726614) (xy 412.054561 -278.775191) (xy 412.055056 -278.799798)
			(xy 413.343864 -278.799798) (xy 413.347824 -278.750744) (xy 413.359601 -278.70296) (xy 413.378892 -278.657684)
			(xy 413.405195 -278.616088) (xy 413.43783 -278.579251) (xy 413.475951 -278.548126) (xy 413.518572 -278.523519)
			(xy 413.564588 -278.506067) (xy 413.612807 -278.496223) (xy 413.661982 -278.494242) (xy 413.710837 -278.500174)
			(xy 413.758108 -278.513866) (xy 413.80257 -278.534964) (xy 413.843073 -278.56292) (xy 413.878566 -278.597012)
			(xy 413.908131 -278.636356) (xy 413.931002 -278.679933) (xy 413.946586 -278.726614) (xy 413.954481 -278.775191)
			(xy 413.954976 -278.799798) (xy 415.243784 -278.799798) (xy 415.247744 -278.750744) (xy 415.259521 -278.70296)
			(xy 415.278812 -278.657684) (xy 415.305115 -278.616088) (xy 415.33775 -278.579251) (xy 415.375871 -278.548126)
			(xy 415.418492 -278.523519) (xy 415.464508 -278.506067) (xy 415.512727 -278.496223) (xy 415.561902 -278.494242)
			(xy 415.610757 -278.500174) (xy 415.658028 -278.513866) (xy 415.70249 -278.534964) (xy 415.742993 -278.56292)
			(xy 415.778486 -278.597012) (xy 415.808051 -278.636356) (xy 415.830922 -278.679933) (xy 415.846506 -278.726614)
			(xy 415.854401 -278.775191) (xy 415.854896 -278.799798) (xy 417.143958 -278.799798) (xy 417.147918 -278.750744)
			(xy 417.159695 -278.70296) (xy 417.178986 -278.657684) (xy 417.205289 -278.616088) (xy 417.237924 -278.579251)
			(xy 417.276045 -278.548126) (xy 417.318666 -278.523519) (xy 417.364682 -278.506067) (xy 417.412901 -278.496223)
			(xy 417.462076 -278.494242) (xy 417.510931 -278.500174) (xy 417.558202 -278.513866) (xy 417.602664 -278.534964)
			(xy 417.643167 -278.56292) (xy 417.67866 -278.597012) (xy 417.708225 -278.636356) (xy 417.731096 -278.679933)
			(xy 417.74668 -278.726614) (xy 417.754575 -278.775191) (xy 417.75507 -278.799798) (xy 419.043878 -278.799798)
			(xy 419.047838 -278.750744) (xy 419.059615 -278.70296) (xy 419.078906 -278.657684) (xy 419.105209 -278.616088)
			(xy 419.137844 -278.579251) (xy 419.175965 -278.548126) (xy 419.218586 -278.523519) (xy 419.264602 -278.506067)
			(xy 419.312821 -278.496223) (xy 419.361996 -278.494242) (xy 419.410851 -278.500174) (xy 419.458122 -278.513866)
			(xy 419.502584 -278.534964) (xy 419.543087 -278.56292) (xy 419.57858 -278.597012) (xy 419.608145 -278.636356)
			(xy 419.631016 -278.679933) (xy 419.6466 -278.726614) (xy 419.654495 -278.775191) (xy 419.65499 -278.799798)
			(xy 420.943798 -278.799798) (xy 420.947758 -278.750744) (xy 420.959535 -278.70296) (xy 420.978826 -278.657684)
			(xy 421.005129 -278.616088) (xy 421.037764 -278.579251) (xy 421.075885 -278.548126) (xy 421.118506 -278.523519)
			(xy 421.164522 -278.506067) (xy 421.212741 -278.496223) (xy 421.261916 -278.494242) (xy 421.310771 -278.500174)
			(xy 421.358042 -278.513866) (xy 421.402504 -278.534964) (xy 421.443007 -278.56292) (xy 421.4785 -278.597012)
			(xy 421.508065 -278.636356) (xy 421.530936 -278.679933) (xy 421.54652 -278.726614) (xy 421.554415 -278.775191)
			(xy 421.55491 -278.799798) (xy 422.843972 -278.799798) (xy 422.847932 -278.750744) (xy 422.859709 -278.70296)
			(xy 422.879 -278.657684) (xy 422.905303 -278.616088) (xy 422.937938 -278.579251) (xy 422.976059 -278.548126)
			(xy 423.01868 -278.523519) (xy 423.064696 -278.506067) (xy 423.112915 -278.496223) (xy 423.16209 -278.494242)
			(xy 423.210945 -278.500174) (xy 423.258216 -278.513866) (xy 423.302678 -278.534964) (xy 423.343181 -278.56292)
			(xy 423.378674 -278.597012) (xy 423.408239 -278.636356) (xy 423.43111 -278.679933) (xy 423.446694 -278.726614)
			(xy 423.454589 -278.775191) (xy 423.455084 -278.799798) (xy 424.743892 -278.799798) (xy 424.747852 -278.750744)
			(xy 424.759629 -278.70296) (xy 424.77892 -278.657684) (xy 424.805223 -278.616088) (xy 424.837858 -278.579251)
			(xy 424.875979 -278.548126) (xy 424.9186 -278.523519) (xy 424.964616 -278.506067) (xy 425.012835 -278.496223)
			(xy 425.06201 -278.494242) (xy 425.110865 -278.500174) (xy 425.158136 -278.513866) (xy 425.202598 -278.534964)
			(xy 425.243101 -278.56292) (xy 425.278594 -278.597012) (xy 425.308159 -278.636356) (xy 425.33103 -278.679933)
			(xy 425.346614 -278.726614) (xy 425.354509 -278.775191) (xy 425.355004 -278.799798) (xy 426.643812 -278.799798)
			(xy 426.647772 -278.750744) (xy 426.659549 -278.70296) (xy 426.67884 -278.657684) (xy 426.705143 -278.616088)
			(xy 426.737778 -278.579251) (xy 426.775899 -278.548126) (xy 426.81852 -278.523519) (xy 426.864536 -278.506067)
			(xy 426.912755 -278.496223) (xy 426.96193 -278.494242) (xy 427.010785 -278.500174) (xy 427.058056 -278.513866)
			(xy 427.102518 -278.534964) (xy 427.143021 -278.56292) (xy 427.178514 -278.597012) (xy 427.208079 -278.636356)
			(xy 427.23095 -278.679933) (xy 427.246534 -278.726614) (xy 427.254429 -278.775191) (xy 427.254924 -278.799798)
			(xy 428.543986 -278.799798) (xy 428.547946 -278.750744) (xy 428.559723 -278.70296) (xy 428.579014 -278.657684)
			(xy 428.605317 -278.616088) (xy 428.637952 -278.579251) (xy 428.676073 -278.548126) (xy 428.718694 -278.523519)
			(xy 428.76471 -278.506067) (xy 428.812929 -278.496223) (xy 428.862104 -278.494242) (xy 428.910959 -278.500174)
			(xy 428.95823 -278.513866) (xy 429.002692 -278.534964) (xy 429.043195 -278.56292) (xy 429.078688 -278.597012)
			(xy 429.108253 -278.636356) (xy 429.131124 -278.679933) (xy 429.146708 -278.726614) (xy 429.154603 -278.775191)
			(xy 429.155098 -278.799798) (xy 429.154603 -278.824405) (xy 429.146708 -278.872982) (xy 429.131124 -278.919663)
			(xy 429.108253 -278.96324) (xy 429.078688 -279.002584) (xy 429.043195 -279.036676) (xy 429.002692 -279.064632)
			(xy 428.95823 -279.08573) (xy 428.910959 -279.099422) (xy 428.862104 -279.105354) (xy 428.812929 -279.103373)
			(xy 428.76471 -279.093529) (xy 428.718694 -279.076077) (xy 428.676073 -279.05147) (xy 428.637952 -279.020345)
			(xy 428.605317 -278.983508) (xy 428.579014 -278.941912) (xy 428.559723 -278.896636) (xy 428.547946 -278.848852)
			(xy 428.543986 -278.799798) (xy 427.254924 -278.799798) (xy 427.254429 -278.824405) (xy 427.246534 -278.872982)
			(xy 427.23095 -278.919663) (xy 427.208079 -278.96324) (xy 427.178514 -279.002584) (xy 427.143021 -279.036676)
			(xy 427.102518 -279.064632) (xy 427.058056 -279.08573) (xy 427.010785 -279.099422) (xy 426.96193 -279.105354)
			(xy 426.912755 -279.103373) (xy 426.864536 -279.093529) (xy 426.81852 -279.076077) (xy 426.775899 -279.05147)
			(xy 426.737778 -279.020345) (xy 426.705143 -278.983508) (xy 426.67884 -278.941912) (xy 426.659549 -278.896636)
			(xy 426.647772 -278.848852) (xy 426.643812 -278.799798) (xy 425.355004 -278.799798) (xy 425.354509 -278.824405)
			(xy 425.346614 -278.872982) (xy 425.33103 -278.919663) (xy 425.308159 -278.96324) (xy 425.278594 -279.002584)
			(xy 425.243101 -279.036676) (xy 425.202598 -279.064632) (xy 425.158136 -279.08573) (xy 425.110865 -279.099422)
			(xy 425.06201 -279.105354) (xy 425.012835 -279.103373) (xy 424.964616 -279.093529) (xy 424.9186 -279.076077)
			(xy 424.875979 -279.05147) (xy 424.837858 -279.020345) (xy 424.805223 -278.983508) (xy 424.77892 -278.941912)
			(xy 424.759629 -278.896636) (xy 424.747852 -278.848852) (xy 424.743892 -278.799798) (xy 423.455084 -278.799798)
			(xy 423.454589 -278.824405) (xy 423.446694 -278.872982) (xy 423.43111 -278.919663) (xy 423.408239 -278.96324)
			(xy 423.378674 -279.002584) (xy 423.343181 -279.036676) (xy 423.302678 -279.064632) (xy 423.258216 -279.08573)
			(xy 423.210945 -279.099422) (xy 423.16209 -279.105354) (xy 423.112915 -279.103373) (xy 423.064696 -279.093529)
			(xy 423.01868 -279.076077) (xy 422.976059 -279.05147) (xy 422.937938 -279.020345) (xy 422.905303 -278.983508)
			(xy 422.879 -278.941912) (xy 422.859709 -278.896636) (xy 422.847932 -278.848852) (xy 422.843972 -278.799798)
			(xy 421.55491 -278.799798) (xy 421.554415 -278.824405) (xy 421.54652 -278.872982) (xy 421.530936 -278.919663)
			(xy 421.508065 -278.96324) (xy 421.4785 -279.002584) (xy 421.443007 -279.036676) (xy 421.402504 -279.064632)
			(xy 421.358042 -279.08573) (xy 421.310771 -279.099422) (xy 421.261916 -279.105354) (xy 421.212741 -279.103373)
			(xy 421.164522 -279.093529) (xy 421.118506 -279.076077) (xy 421.075885 -279.05147) (xy 421.037764 -279.020345)
			(xy 421.005129 -278.983508) (xy 420.978826 -278.941912) (xy 420.959535 -278.896636) (xy 420.947758 -278.848852)
			(xy 420.943798 -278.799798) (xy 419.65499 -278.799798) (xy 419.654495 -278.824405) (xy 419.6466 -278.872982)
			(xy 419.631016 -278.919663) (xy 419.608145 -278.96324) (xy 419.57858 -279.002584) (xy 419.543087 -279.036676)
			(xy 419.502584 -279.064632) (xy 419.458122 -279.08573) (xy 419.410851 -279.099422) (xy 419.361996 -279.105354)
			(xy 419.312821 -279.103373) (xy 419.264602 -279.093529) (xy 419.218586 -279.076077) (xy 419.175965 -279.05147)
			(xy 419.137844 -279.020345) (xy 419.105209 -278.983508) (xy 419.078906 -278.941912) (xy 419.059615 -278.896636)
			(xy 419.047838 -278.848852) (xy 419.043878 -278.799798) (xy 417.75507 -278.799798) (xy 417.754575 -278.824405)
			(xy 417.74668 -278.872982) (xy 417.731096 -278.919663) (xy 417.708225 -278.96324) (xy 417.67866 -279.002584)
			(xy 417.643167 -279.036676) (xy 417.602664 -279.064632) (xy 417.558202 -279.08573) (xy 417.510931 -279.099422)
			(xy 417.462076 -279.105354) (xy 417.412901 -279.103373) (xy 417.364682 -279.093529) (xy 417.318666 -279.076077)
			(xy 417.276045 -279.05147) (xy 417.237924 -279.020345) (xy 417.205289 -278.983508) (xy 417.178986 -278.941912)
			(xy 417.159695 -278.896636) (xy 417.147918 -278.848852) (xy 417.143958 -278.799798) (xy 415.854896 -278.799798)
			(xy 415.854401 -278.824405) (xy 415.846506 -278.872982) (xy 415.830922 -278.919663) (xy 415.808051 -278.96324)
			(xy 415.778486 -279.002584) (xy 415.742993 -279.036676) (xy 415.70249 -279.064632) (xy 415.658028 -279.08573)
			(xy 415.610757 -279.099422) (xy 415.561902 -279.105354) (xy 415.512727 -279.103373) (xy 415.464508 -279.093529)
			(xy 415.418492 -279.076077) (xy 415.375871 -279.05147) (xy 415.33775 -279.020345) (xy 415.305115 -278.983508)
			(xy 415.278812 -278.941912) (xy 415.259521 -278.896636) (xy 415.247744 -278.848852) (xy 415.243784 -278.799798)
			(xy 413.954976 -278.799798) (xy 413.954481 -278.824405) (xy 413.946586 -278.872982) (xy 413.931002 -278.919663)
			(xy 413.908131 -278.96324) (xy 413.878566 -279.002584) (xy 413.843073 -279.036676) (xy 413.80257 -279.064632)
			(xy 413.758108 -279.08573) (xy 413.710837 -279.099422) (xy 413.661982 -279.105354) (xy 413.612807 -279.103373)
			(xy 413.564588 -279.093529) (xy 413.518572 -279.076077) (xy 413.475951 -279.05147) (xy 413.43783 -279.020345)
			(xy 413.405195 -278.983508) (xy 413.378892 -278.941912) (xy 413.359601 -278.896636) (xy 413.347824 -278.848852)
			(xy 413.343864 -278.799798) (xy 412.055056 -278.799798) (xy 412.054561 -278.824405) (xy 412.046666 -278.872982)
			(xy 412.031082 -278.919663) (xy 412.008211 -278.96324) (xy 411.978646 -279.002584) (xy 411.943153 -279.036676)
			(xy 411.90265 -279.064632) (xy 411.858188 -279.08573) (xy 411.810917 -279.099422) (xy 411.762062 -279.105354)
			(xy 411.712887 -279.103373) (xy 411.664668 -279.093529) (xy 411.618652 -279.076077) (xy 411.576031 -279.05147)
			(xy 411.53791 -279.020345) (xy 411.505275 -278.983508) (xy 411.478972 -278.941912) (xy 411.459681 -278.896636)
			(xy 411.447904 -278.848852) (xy 411.443944 -278.799798) (xy 410.154882 -278.799798) (xy 410.154387 -278.824405)
			(xy 410.146492 -278.872982) (xy 410.130908 -278.919663) (xy 410.108037 -278.96324) (xy 410.078472 -279.002584)
			(xy 410.042979 -279.036676) (xy 410.002476 -279.064632) (xy 409.958014 -279.08573) (xy 409.910743 -279.099422)
			(xy 409.861888 -279.105354) (xy 409.812713 -279.103373) (xy 409.764494 -279.093529) (xy 409.718478 -279.076077)
			(xy 409.675857 -279.05147) (xy 409.637736 -279.020345) (xy 409.605101 -278.983508) (xy 409.578798 -278.941912)
			(xy 409.559507 -278.896636) (xy 409.54773 -278.848852) (xy 409.54377 -278.799798) (xy 408.254962 -278.799798)
			(xy 408.254467 -278.824405) (xy 408.246572 -278.872982) (xy 408.230988 -278.919663) (xy 408.208117 -278.96324)
			(xy 408.178552 -279.002584) (xy 408.143059 -279.036676) (xy 408.102556 -279.064632) (xy 408.058094 -279.08573)
			(xy 408.010823 -279.099422) (xy 407.961968 -279.105354) (xy 407.912793 -279.103373) (xy 407.864574 -279.093529)
			(xy 407.818558 -279.076077) (xy 407.775937 -279.05147) (xy 407.737816 -279.020345) (xy 407.705181 -278.983508)
			(xy 407.678878 -278.941912) (xy 407.659587 -278.896636) (xy 407.64781 -278.848852) (xy 407.64385 -278.799798)
			(xy 406.355296 -278.799798) (xy 406.354801 -278.824405) (xy 406.346906 -278.872982) (xy 406.331322 -278.919663)
			(xy 406.308451 -278.96324) (xy 406.278886 -279.002584) (xy 406.243393 -279.036676) (xy 406.20289 -279.064632)
			(xy 406.158428 -279.08573) (xy 406.111157 -279.099422) (xy 406.062302 -279.105354) (xy 406.013127 -279.103373)
			(xy 405.964908 -279.093529) (xy 405.918892 -279.076077) (xy 405.876271 -279.05147) (xy 405.83815 -279.020345)
			(xy 405.805515 -278.983508) (xy 405.779212 -278.941912) (xy 405.759921 -278.896636) (xy 405.748144 -278.848852)
			(xy 405.744184 -278.799798) (xy 404.455122 -278.799798) (xy 404.454627 -278.824405) (xy 404.446732 -278.872982)
			(xy 404.431148 -278.919663) (xy 404.408277 -278.96324) (xy 404.378712 -279.002584) (xy 404.343219 -279.036676)
			(xy 404.302716 -279.064632) (xy 404.258254 -279.08573) (xy 404.210983 -279.099422) (xy 404.162128 -279.105354)
			(xy 404.112953 -279.103373) (xy 404.064734 -279.093529) (xy 404.018718 -279.076077) (xy 403.976097 -279.05147)
			(xy 403.937976 -279.020345) (xy 403.905341 -278.983508) (xy 403.879038 -278.941912) (xy 403.859747 -278.896636)
			(xy 403.84797 -278.848852) (xy 403.84401 -278.799798) (xy 402.555202 -278.799798) (xy 402.554707 -278.824405)
			(xy 402.546812 -278.872982) (xy 402.531228 -278.919663) (xy 402.508357 -278.96324) (xy 402.478792 -279.002584)
			(xy 402.443299 -279.036676) (xy 402.402796 -279.064632) (xy 402.358334 -279.08573) (xy 402.311063 -279.099422)
			(xy 402.262208 -279.105354) (xy 402.213033 -279.103373) (xy 402.164814 -279.093529) (xy 402.118798 -279.076077)
			(xy 402.076177 -279.05147) (xy 402.038056 -279.020345) (xy 402.005421 -278.983508) (xy 401.979118 -278.941912)
			(xy 401.959827 -278.896636) (xy 401.94805 -278.848852) (xy 401.94409 -278.799798) (xy 400.655282 -278.799798)
			(xy 400.654787 -278.824405) (xy 400.646892 -278.872982) (xy 400.631308 -278.919663) (xy 400.608437 -278.96324)
			(xy 400.578872 -279.002584) (xy 400.543379 -279.036676) (xy 400.502876 -279.064632) (xy 400.458414 -279.08573)
			(xy 400.411143 -279.099422) (xy 400.362288 -279.105354) (xy 400.313113 -279.103373) (xy 400.264894 -279.093529)
			(xy 400.218878 -279.076077) (xy 400.176257 -279.05147) (xy 400.138136 -279.020345) (xy 400.105501 -278.983508)
			(xy 400.079198 -278.941912) (xy 400.059907 -278.896636) (xy 400.04813 -278.848852) (xy 400.04417 -278.799798)
			(xy 398.755108 -278.799798) (xy 398.754613 -278.824405) (xy 398.746718 -278.872982) (xy 398.731134 -278.919663)
			(xy 398.708263 -278.96324) (xy 398.678698 -279.002584) (xy 398.643205 -279.036676) (xy 398.602702 -279.064632)
			(xy 398.55824 -279.08573) (xy 398.510969 -279.099422) (xy 398.462114 -279.105354) (xy 398.412939 -279.103373)
			(xy 398.36472 -279.093529) (xy 398.318704 -279.076077) (xy 398.276083 -279.05147) (xy 398.237962 -279.020345)
			(xy 398.205327 -278.983508) (xy 398.179024 -278.941912) (xy 398.159733 -278.896636) (xy 398.147956 -278.848852)
			(xy 398.143996 -278.799798) (xy 396.855188 -278.799798) (xy 396.854693 -278.824405) (xy 396.846798 -278.872982)
			(xy 396.831214 -278.919663) (xy 396.808343 -278.96324) (xy 396.778778 -279.002584) (xy 396.743285 -279.036676)
			(xy 396.702782 -279.064632) (xy 396.65832 -279.08573) (xy 396.611049 -279.099422) (xy 396.562194 -279.105354)
			(xy 396.513019 -279.103373) (xy 396.4648 -279.093529) (xy 396.418784 -279.076077) (xy 396.376163 -279.05147)
			(xy 396.338042 -279.020345) (xy 396.305407 -278.983508) (xy 396.279104 -278.941912) (xy 396.259813 -278.896636)
			(xy 396.248036 -278.848852) (xy 396.244076 -278.799798) (xy 394.955268 -278.799798) (xy 394.954773 -278.824405)
			(xy 394.946878 -278.872982) (xy 394.931294 -278.919663) (xy 394.908423 -278.96324) (xy 394.878858 -279.002584)
			(xy 394.843365 -279.036676) (xy 394.802862 -279.064632) (xy 394.7584 -279.08573) (xy 394.711129 -279.099422)
			(xy 394.662274 -279.105354) (xy 394.613099 -279.103373) (xy 394.56488 -279.093529) (xy 394.518864 -279.076077)
			(xy 394.476243 -279.05147) (xy 394.438122 -279.020345) (xy 394.405487 -278.983508) (xy 394.379184 -278.941912)
			(xy 394.359893 -278.896636) (xy 394.348116 -278.848852) (xy 394.344156 -278.799798) (xy 393.055094 -278.799798)
			(xy 393.054599 -278.824405) (xy 393.046704 -278.872982) (xy 393.03112 -278.919663) (xy 393.008249 -278.96324)
			(xy 392.978684 -279.002584) (xy 392.943191 -279.036676) (xy 392.902688 -279.064632) (xy 392.858226 -279.08573)
			(xy 392.810955 -279.099422) (xy 392.7621 -279.105354) (xy 392.712925 -279.103373) (xy 392.664706 -279.093529)
			(xy 392.61869 -279.076077) (xy 392.576069 -279.05147) (xy 392.537948 -279.020345) (xy 392.505313 -278.983508)
			(xy 392.47901 -278.941912) (xy 392.459719 -278.896636) (xy 392.447942 -278.848852) (xy 392.443982 -278.799798)
			(xy 313.055 -278.799798) (xy 313.054505 -278.824405) (xy 313.04661 -278.872982) (xy 313.031026 -278.919663)
			(xy 313.008155 -278.96324) (xy 312.97859 -279.002584) (xy 312.943097 -279.036676) (xy 312.902594 -279.064632)
			(xy 312.858132 -279.08573) (xy 312.810861 -279.099422) (xy 312.762006 -279.105354) (xy 312.712831 -279.103373)
			(xy 312.664612 -279.093529) (xy 312.618596 -279.076077) (xy 312.575975 -279.05147) (xy 312.537854 -279.020345)
			(xy 312.505219 -278.983508) (xy 312.478916 -278.941912) (xy 312.459625 -278.896636) (xy 312.447848 -278.848852)
			(xy 312.443888 -278.799798) (xy 311.154826 -278.799798) (xy 311.154331 -278.824405) (xy 311.146436 -278.872982)
			(xy 311.130852 -278.919663) (xy 311.107981 -278.96324) (xy 311.078416 -279.002584) (xy 311.042923 -279.036676)
			(xy 311.00242 -279.064632) (xy 310.957958 -279.08573) (xy 310.910687 -279.099422) (xy 310.861832 -279.105354)
			(xy 310.812657 -279.103373) (xy 310.764438 -279.093529) (xy 310.718422 -279.076077) (xy 310.675801 -279.05147)
			(xy 310.63768 -279.020345) (xy 310.605045 -278.983508) (xy 310.578742 -278.941912) (xy 310.559451 -278.896636)
			(xy 310.547674 -278.848852) (xy 310.543714 -278.799798) (xy 309.254906 -278.799798) (xy 309.254411 -278.824405)
			(xy 309.246516 -278.872982) (xy 309.230932 -278.919663) (xy 309.208061 -278.96324) (xy 309.178496 -279.002584)
			(xy 309.143003 -279.036676) (xy 309.1025 -279.064632) (xy 309.058038 -279.08573) (xy 309.010767 -279.099422)
			(xy 308.961912 -279.105354) (xy 308.912737 -279.103373) (xy 308.864518 -279.093529) (xy 308.818502 -279.076077)
			(xy 308.775881 -279.05147) (xy 308.73776 -279.020345) (xy 308.705125 -278.983508) (xy 308.678822 -278.941912)
			(xy 308.659531 -278.896636) (xy 308.647754 -278.848852) (xy 308.643794 -278.799798) (xy 307.354986 -278.799798)
			(xy 307.354491 -278.824405) (xy 307.346596 -278.872982) (xy 307.331012 -278.919663) (xy 307.308141 -278.96324)
			(xy 307.278576 -279.002584) (xy 307.243083 -279.036676) (xy 307.20258 -279.064632) (xy 307.158118 -279.08573)
			(xy 307.110847 -279.099422) (xy 307.061992 -279.105354) (xy 307.012817 -279.103373) (xy 306.964598 -279.093529)
			(xy 306.918582 -279.076077) (xy 306.875961 -279.05147) (xy 306.83784 -279.020345) (xy 306.805205 -278.983508)
			(xy 306.778902 -278.941912) (xy 306.759611 -278.896636) (xy 306.747834 -278.848852) (xy 306.743874 -278.799798)
			(xy 305.454812 -278.799798) (xy 305.454317 -278.824405) (xy 305.446422 -278.872982) (xy 305.430838 -278.919663)
			(xy 305.407967 -278.96324) (xy 305.378402 -279.002584) (xy 305.342909 -279.036676) (xy 305.302406 -279.064632)
			(xy 305.257944 -279.08573) (xy 305.210673 -279.099422) (xy 305.161818 -279.105354) (xy 305.112643 -279.103373)
			(xy 305.064424 -279.093529) (xy 305.018408 -279.076077) (xy 304.975787 -279.05147) (xy 304.937666 -279.020345)
			(xy 304.905031 -278.983508) (xy 304.878728 -278.941912) (xy 304.859437 -278.896636) (xy 304.84766 -278.848852)
			(xy 304.8437 -278.799798) (xy 303.554892 -278.799798) (xy 303.554397 -278.824405) (xy 303.546502 -278.872982)
			(xy 303.530918 -278.919663) (xy 303.508047 -278.96324) (xy 303.478482 -279.002584) (xy 303.442989 -279.036676)
			(xy 303.402486 -279.064632) (xy 303.358024 -279.08573) (xy 303.310753 -279.099422) (xy 303.261898 -279.105354)
			(xy 303.212723 -279.103373) (xy 303.164504 -279.093529) (xy 303.118488 -279.076077) (xy 303.075867 -279.05147)
			(xy 303.037746 -279.020345) (xy 303.005111 -278.983508) (xy 302.978808 -278.941912) (xy 302.959517 -278.896636)
			(xy 302.94774 -278.848852) (xy 302.94378 -278.799798) (xy 301.654972 -278.799798) (xy 301.654477 -278.824405)
			(xy 301.646582 -278.872982) (xy 301.630998 -278.919663) (xy 301.608127 -278.96324) (xy 301.578562 -279.002584)
			(xy 301.543069 -279.036676) (xy 301.502566 -279.064632) (xy 301.458104 -279.08573) (xy 301.410833 -279.099422)
			(xy 301.361978 -279.105354) (xy 301.312803 -279.103373) (xy 301.264584 -279.093529) (xy 301.218568 -279.076077)
			(xy 301.175947 -279.05147) (xy 301.137826 -279.020345) (xy 301.105191 -278.983508) (xy 301.078888 -278.941912)
			(xy 301.059597 -278.896636) (xy 301.04782 -278.848852) (xy 301.04386 -278.799798) (xy 299.754798 -278.799798)
			(xy 299.754303 -278.824405) (xy 299.746408 -278.872982) (xy 299.730824 -278.919663) (xy 299.707953 -278.96324)
			(xy 299.678388 -279.002584) (xy 299.642895 -279.036676) (xy 299.602392 -279.064632) (xy 299.55793 -279.08573)
			(xy 299.510659 -279.099422) (xy 299.461804 -279.105354) (xy 299.412629 -279.103373) (xy 299.36441 -279.093529)
			(xy 299.318394 -279.076077) (xy 299.275773 -279.05147) (xy 299.237652 -279.020345) (xy 299.205017 -278.983508)
			(xy 299.178714 -278.941912) (xy 299.159423 -278.896636) (xy 299.147646 -278.848852) (xy 299.143686 -278.799798)
			(xy 297.854878 -278.799798) (xy 297.854383 -278.824405) (xy 297.846488 -278.872982) (xy 297.830904 -278.919663)
			(xy 297.808033 -278.96324) (xy 297.778468 -279.002584) (xy 297.742975 -279.036676) (xy 297.702472 -279.064632)
			(xy 297.65801 -279.08573) (xy 297.610739 -279.099422) (xy 297.561884 -279.105354) (xy 297.512709 -279.103373)
			(xy 297.46449 -279.093529) (xy 297.418474 -279.076077) (xy 297.375853 -279.05147) (xy 297.337732 -279.020345)
			(xy 297.305097 -278.983508) (xy 297.278794 -278.941912) (xy 297.259503 -278.896636) (xy 297.247726 -278.848852)
			(xy 297.243766 -278.799798) (xy 295.954958 -278.799798) (xy 295.954463 -278.824405) (xy 295.946568 -278.872982)
			(xy 295.930984 -278.919663) (xy 295.908113 -278.96324) (xy 295.878548 -279.002584) (xy 295.843055 -279.036676)
			(xy 295.802552 -279.064632) (xy 295.75809 -279.08573) (xy 295.710819 -279.099422) (xy 295.661964 -279.105354)
			(xy 295.612789 -279.103373) (xy 295.56457 -279.093529) (xy 295.518554 -279.076077) (xy 295.475933 -279.05147)
			(xy 295.437812 -279.020345) (xy 295.405177 -278.983508) (xy 295.378874 -278.941912) (xy 295.359583 -278.896636)
			(xy 295.347806 -278.848852) (xy 295.343846 -278.799798) (xy 294.054784 -278.799798) (xy 294.054289 -278.824405)
			(xy 294.046394 -278.872982) (xy 294.03081 -278.919663) (xy 294.007939 -278.96324) (xy 293.978374 -279.002584)
			(xy 293.942881 -279.036676) (xy 293.902378 -279.064632) (xy 293.857916 -279.08573) (xy 293.810645 -279.099422)
			(xy 293.76179 -279.105354) (xy 293.712615 -279.103373) (xy 293.664396 -279.093529) (xy 293.61838 -279.076077)
			(xy 293.575759 -279.05147) (xy 293.537638 -279.020345) (xy 293.505003 -278.983508) (xy 293.4787 -278.941912)
			(xy 293.459409 -278.896636) (xy 293.447632 -278.848852) (xy 293.443672 -278.799798) (xy 292.154864 -278.799798)
			(xy 292.154369 -278.824405) (xy 292.146474 -278.872982) (xy 292.13089 -278.919663) (xy 292.108019 -278.96324)
			(xy 292.078454 -279.002584) (xy 292.042961 -279.036676) (xy 292.002458 -279.064632) (xy 291.957996 -279.08573)
			(xy 291.910725 -279.099422) (xy 291.86187 -279.105354) (xy 291.812695 -279.103373) (xy 291.764476 -279.093529)
			(xy 291.71846 -279.076077) (xy 291.675839 -279.05147) (xy 291.637718 -279.020345) (xy 291.605083 -278.983508)
			(xy 291.57878 -278.941912) (xy 291.559489 -278.896636) (xy 291.547712 -278.848852) (xy 291.543752 -278.799798)
			(xy 290.255198 -278.799798) (xy 290.254703 -278.824405) (xy 290.246808 -278.872982) (xy 290.231224 -278.919663)
			(xy 290.208353 -278.96324) (xy 290.178788 -279.002584) (xy 290.143295 -279.036676) (xy 290.102792 -279.064632)
			(xy 290.05833 -279.08573) (xy 290.011059 -279.099422) (xy 289.962204 -279.105354) (xy 289.913029 -279.103373)
			(xy 289.86481 -279.093529) (xy 289.818794 -279.076077) (xy 289.776173 -279.05147) (xy 289.738052 -279.020345)
			(xy 289.705417 -278.983508) (xy 289.679114 -278.941912) (xy 289.659823 -278.896636) (xy 289.648046 -278.848852)
			(xy 289.644086 -278.799798) (xy 288.355024 -278.799798) (xy 288.354529 -278.824405) (xy 288.346634 -278.872982)
			(xy 288.33105 -278.919663) (xy 288.308179 -278.96324) (xy 288.278614 -279.002584) (xy 288.243121 -279.036676)
			(xy 288.202618 -279.064632) (xy 288.158156 -279.08573) (xy 288.110885 -279.099422) (xy 288.06203 -279.105354)
			(xy 288.012855 -279.103373) (xy 287.964636 -279.093529) (xy 287.91862 -279.076077) (xy 287.875999 -279.05147)
			(xy 287.837878 -279.020345) (xy 287.805243 -278.983508) (xy 287.77894 -278.941912) (xy 287.759649 -278.896636)
			(xy 287.747872 -278.848852) (xy 287.743912 -278.799798) (xy 286.455104 -278.799798) (xy 286.454609 -278.824405)
			(xy 286.446714 -278.872982) (xy 286.43113 -278.919663) (xy 286.408259 -278.96324) (xy 286.378694 -279.002584)
			(xy 286.343201 -279.036676) (xy 286.302698 -279.064632) (xy 286.258236 -279.08573) (xy 286.210965 -279.099422)
			(xy 286.16211 -279.105354) (xy 286.112935 -279.103373) (xy 286.064716 -279.093529) (xy 286.0187 -279.076077)
			(xy 285.976079 -279.05147) (xy 285.937958 -279.020345) (xy 285.905323 -278.983508) (xy 285.87902 -278.941912)
			(xy 285.859729 -278.896636) (xy 285.847952 -278.848852) (xy 285.843992 -278.799798) (xy 284.555184 -278.799798)
			(xy 284.554689 -278.824405) (xy 284.546794 -278.872982) (xy 284.53121 -278.919663) (xy 284.508339 -278.96324)
			(xy 284.478774 -279.002584) (xy 284.443281 -279.036676) (xy 284.402778 -279.064632) (xy 284.358316 -279.08573)
			(xy 284.311045 -279.099422) (xy 284.26219 -279.105354) (xy 284.213015 -279.103373) (xy 284.164796 -279.093529)
			(xy 284.11878 -279.076077) (xy 284.076159 -279.05147) (xy 284.038038 -279.020345) (xy 284.005403 -278.983508)
			(xy 283.9791 -278.941912) (xy 283.959809 -278.896636) (xy 283.948032 -278.848852) (xy 283.944072 -278.799798)
			(xy 282.65501 -278.799798) (xy 282.654515 -278.824405) (xy 282.64662 -278.872982) (xy 282.631036 -278.919663)
			(xy 282.608165 -278.96324) (xy 282.5786 -279.002584) (xy 282.543107 -279.036676) (xy 282.502604 -279.064632)
			(xy 282.458142 -279.08573) (xy 282.410871 -279.099422) (xy 282.362016 -279.105354) (xy 282.312841 -279.103373)
			(xy 282.264622 -279.093529) (xy 282.218606 -279.076077) (xy 282.175985 -279.05147) (xy 282.137864 -279.020345)
			(xy 282.105229 -278.983508) (xy 282.078926 -278.941912) (xy 282.059635 -278.896636) (xy 282.047858 -278.848852)
			(xy 282.043898 -278.799798) (xy 280.75509 -278.799798) (xy 280.754595 -278.824405) (xy 280.7467 -278.872982)
			(xy 280.731116 -278.919663) (xy 280.708245 -278.96324) (xy 280.67868 -279.002584) (xy 280.643187 -279.036676)
			(xy 280.602684 -279.064632) (xy 280.558222 -279.08573) (xy 280.510951 -279.099422) (xy 280.462096 -279.105354)
			(xy 280.412921 -279.103373) (xy 280.364702 -279.093529) (xy 280.318686 -279.076077) (xy 280.276065 -279.05147)
			(xy 280.237944 -279.020345) (xy 280.205309 -278.983508) (xy 280.179006 -278.941912) (xy 280.159715 -278.896636)
			(xy 280.147938 -278.848852) (xy 280.143978 -278.799798) (xy 278.85517 -278.799798) (xy 278.854675 -278.824405)
			(xy 278.84678 -278.872982) (xy 278.831196 -278.919663) (xy 278.808325 -278.96324) (xy 278.77876 -279.002584)
			(xy 278.743267 -279.036676) (xy 278.702764 -279.064632) (xy 278.658302 -279.08573) (xy 278.611031 -279.099422)
			(xy 278.562176 -279.105354) (xy 278.513001 -279.103373) (xy 278.464782 -279.093529) (xy 278.418766 -279.076077)
			(xy 278.376145 -279.05147) (xy 278.338024 -279.020345) (xy 278.305389 -278.983508) (xy 278.279086 -278.941912)
			(xy 278.259795 -278.896636) (xy 278.248018 -278.848852) (xy 278.244058 -278.799798) (xy 276.954996 -278.799798)
			(xy 276.954501 -278.824405) (xy 276.946606 -278.872982) (xy 276.931022 -278.919663) (xy 276.908151 -278.96324)
			(xy 276.878586 -279.002584) (xy 276.843093 -279.036676) (xy 276.80259 -279.064632) (xy 276.758128 -279.08573)
			(xy 276.710857 -279.099422) (xy 276.662002 -279.105354) (xy 276.612827 -279.103373) (xy 276.564608 -279.093529)
			(xy 276.518592 -279.076077) (xy 276.475971 -279.05147) (xy 276.43785 -279.020345) (xy 276.405215 -278.983508)
			(xy 276.378912 -278.941912) (xy 276.359621 -278.896636) (xy 276.347844 -278.848852) (xy 276.343884 -278.799798)
			(xy 196.955156 -278.799798) (xy 196.954661 -278.824405) (xy 196.946766 -278.872982) (xy 196.931182 -278.919663)
			(xy 196.908311 -278.96324) (xy 196.878746 -279.002584) (xy 196.843253 -279.036676) (xy 196.80275 -279.064632)
			(xy 196.758288 -279.08573) (xy 196.711017 -279.099422) (xy 196.662162 -279.105354) (xy 196.612987 -279.103373)
			(xy 196.564768 -279.093529) (xy 196.518752 -279.076077) (xy 196.476131 -279.05147) (xy 196.43801 -279.020345)
			(xy 196.405375 -278.983508) (xy 196.379072 -278.941912) (xy 196.359781 -278.896636) (xy 196.348004 -278.848852)
			(xy 196.344044 -278.799798) (xy 195.054982 -278.799798) (xy 195.054487 -278.824405) (xy 195.046592 -278.872982)
			(xy 195.031008 -278.919663) (xy 195.008137 -278.96324) (xy 194.978572 -279.002584) (xy 194.943079 -279.036676)
			(xy 194.902576 -279.064632) (xy 194.858114 -279.08573) (xy 194.810843 -279.099422) (xy 194.761988 -279.105354)
			(xy 194.712813 -279.103373) (xy 194.664594 -279.093529) (xy 194.618578 -279.076077) (xy 194.575957 -279.05147)
			(xy 194.537836 -279.020345) (xy 194.505201 -278.983508) (xy 194.478898 -278.941912) (xy 194.459607 -278.896636)
			(xy 194.44783 -278.848852) (xy 194.44387 -278.799798) (xy 193.155062 -278.799798) (xy 193.154567 -278.824405)
			(xy 193.146672 -278.872982) (xy 193.131088 -278.919663) (xy 193.108217 -278.96324) (xy 193.078652 -279.002584)
			(xy 193.043159 -279.036676) (xy 193.002656 -279.064632) (xy 192.958194 -279.08573) (xy 192.910923 -279.099422)
			(xy 192.862068 -279.105354) (xy 192.812893 -279.103373) (xy 192.764674 -279.093529) (xy 192.718658 -279.076077)
			(xy 192.676037 -279.05147) (xy 192.637916 -279.020345) (xy 192.605281 -278.983508) (xy 192.578978 -278.941912)
			(xy 192.559687 -278.896636) (xy 192.54791 -278.848852) (xy 192.54395 -278.799798) (xy 191.255142 -278.799798)
			(xy 191.254647 -278.824405) (xy 191.246752 -278.872982) (xy 191.231168 -278.919663) (xy 191.208297 -278.96324)
			(xy 191.178732 -279.002584) (xy 191.143239 -279.036676) (xy 191.102736 -279.064632) (xy 191.058274 -279.08573)
			(xy 191.011003 -279.099422) (xy 190.962148 -279.105354) (xy 190.912973 -279.103373) (xy 190.864754 -279.093529)
			(xy 190.818738 -279.076077) (xy 190.776117 -279.05147) (xy 190.737996 -279.020345) (xy 190.705361 -278.983508)
			(xy 190.679058 -278.941912) (xy 190.659767 -278.896636) (xy 190.64799 -278.848852) (xy 190.64403 -278.799798)
			(xy 189.354968 -278.799798) (xy 189.354473 -278.824405) (xy 189.346578 -278.872982) (xy 189.330994 -278.919663)
			(xy 189.308123 -278.96324) (xy 189.278558 -279.002584) (xy 189.243065 -279.036676) (xy 189.202562 -279.064632)
			(xy 189.1581 -279.08573) (xy 189.110829 -279.099422) (xy 189.061974 -279.105354) (xy 189.012799 -279.103373)
			(xy 188.96458 -279.093529) (xy 188.918564 -279.076077) (xy 188.875943 -279.05147) (xy 188.837822 -279.020345)
			(xy 188.805187 -278.983508) (xy 188.778884 -278.941912) (xy 188.759593 -278.896636) (xy 188.747816 -278.848852)
			(xy 188.743856 -278.799798) (xy 187.455048 -278.799798) (xy 187.454553 -278.824405) (xy 187.446658 -278.872982)
			(xy 187.431074 -278.919663) (xy 187.408203 -278.96324) (xy 187.378638 -279.002584) (xy 187.343145 -279.036676)
			(xy 187.302642 -279.064632) (xy 187.25818 -279.08573) (xy 187.210909 -279.099422) (xy 187.162054 -279.105354)
			(xy 187.112879 -279.103373) (xy 187.06466 -279.093529) (xy 187.018644 -279.076077) (xy 186.976023 -279.05147)
			(xy 186.937902 -279.020345) (xy 186.905267 -278.983508) (xy 186.878964 -278.941912) (xy 186.859673 -278.896636)
			(xy 186.847896 -278.848852) (xy 186.843936 -278.799798) (xy 185.555128 -278.799798) (xy 185.554633 -278.824405)
			(xy 185.546738 -278.872982) (xy 185.531154 -278.919663) (xy 185.508283 -278.96324) (xy 185.478718 -279.002584)
			(xy 185.443225 -279.036676) (xy 185.402722 -279.064632) (xy 185.35826 -279.08573) (xy 185.310989 -279.099422)
			(xy 185.262134 -279.105354) (xy 185.212959 -279.103373) (xy 185.16474 -279.093529) (xy 185.118724 -279.076077)
			(xy 185.076103 -279.05147) (xy 185.037982 -279.020345) (xy 185.005347 -278.983508) (xy 184.979044 -278.941912)
			(xy 184.959753 -278.896636) (xy 184.947976 -278.848852) (xy 184.944016 -278.799798) (xy 183.654954 -278.799798)
			(xy 183.654459 -278.824405) (xy 183.646564 -278.872982) (xy 183.63098 -278.919663) (xy 183.608109 -278.96324)
			(xy 183.578544 -279.002584) (xy 183.543051 -279.036676) (xy 183.502548 -279.064632) (xy 183.458086 -279.08573)
			(xy 183.410815 -279.099422) (xy 183.36196 -279.105354) (xy 183.312785 -279.103373) (xy 183.264566 -279.093529)
			(xy 183.21855 -279.076077) (xy 183.175929 -279.05147) (xy 183.137808 -279.020345) (xy 183.105173 -278.983508)
			(xy 183.07887 -278.941912) (xy 183.059579 -278.896636) (xy 183.047802 -278.848852) (xy 183.043842 -278.799798)
			(xy 181.755034 -278.799798) (xy 181.754539 -278.824405) (xy 181.746644 -278.872982) (xy 181.73106 -278.919663)
			(xy 181.708189 -278.96324) (xy 181.678624 -279.002584) (xy 181.643131 -279.036676) (xy 181.602628 -279.064632)
			(xy 181.558166 -279.08573) (xy 181.510895 -279.099422) (xy 181.46204 -279.105354) (xy 181.412865 -279.103373)
			(xy 181.364646 -279.093529) (xy 181.31863 -279.076077) (xy 181.276009 -279.05147) (xy 181.237888 -279.020345)
			(xy 181.205253 -278.983508) (xy 181.17895 -278.941912) (xy 181.159659 -278.896636) (xy 181.147882 -278.848852)
			(xy 181.143922 -278.799798) (xy 179.855114 -278.799798) (xy 179.854619 -278.824405) (xy 179.846724 -278.872982)
			(xy 179.83114 -278.919663) (xy 179.808269 -278.96324) (xy 179.778704 -279.002584) (xy 179.743211 -279.036676)
			(xy 179.702708 -279.064632) (xy 179.658246 -279.08573) (xy 179.610975 -279.099422) (xy 179.56212 -279.105354)
			(xy 179.512945 -279.103373) (xy 179.464726 -279.093529) (xy 179.41871 -279.076077) (xy 179.376089 -279.05147)
			(xy 179.337968 -279.020345) (xy 179.305333 -278.983508) (xy 179.27903 -278.941912) (xy 179.259739 -278.896636)
			(xy 179.247962 -278.848852) (xy 179.244002 -278.799798) (xy 177.95494 -278.799798) (xy 177.954445 -278.824405)
			(xy 177.94655 -278.872982) (xy 177.930966 -278.919663) (xy 177.908095 -278.96324) (xy 177.87853 -279.002584)
			(xy 177.843037 -279.036676) (xy 177.802534 -279.064632) (xy 177.758072 -279.08573) (xy 177.710801 -279.099422)
			(xy 177.661946 -279.105354) (xy 177.612771 -279.103373) (xy 177.564552 -279.093529) (xy 177.518536 -279.076077)
			(xy 177.475915 -279.05147) (xy 177.437794 -279.020345) (xy 177.405159 -278.983508) (xy 177.378856 -278.941912)
			(xy 177.359565 -278.896636) (xy 177.347788 -278.848852) (xy 177.343828 -278.799798) (xy 176.05502 -278.799798)
			(xy 176.054525 -278.824405) (xy 176.04663 -278.872982) (xy 176.031046 -278.919663) (xy 176.008175 -278.96324)
			(xy 175.97861 -279.002584) (xy 175.943117 -279.036676) (xy 175.902614 -279.064632) (xy 175.858152 -279.08573)
			(xy 175.810881 -279.099422) (xy 175.762026 -279.105354) (xy 175.712851 -279.103373) (xy 175.664632 -279.093529)
			(xy 175.618616 -279.076077) (xy 175.575995 -279.05147) (xy 175.537874 -279.020345) (xy 175.505239 -278.983508)
			(xy 175.478936 -278.941912) (xy 175.459645 -278.896636) (xy 175.447868 -278.848852) (xy 175.443908 -278.799798)
			(xy 174.155354 -278.799798) (xy 174.154859 -278.824405) (xy 174.146964 -278.872982) (xy 174.13138 -278.919663)
			(xy 174.108509 -278.96324) (xy 174.078944 -279.002584) (xy 174.043451 -279.036676) (xy 174.002948 -279.064632)
			(xy 173.958486 -279.08573) (xy 173.911215 -279.099422) (xy 173.86236 -279.105354) (xy 173.813185 -279.103373)
			(xy 173.764966 -279.093529) (xy 173.71895 -279.076077) (xy 173.676329 -279.05147) (xy 173.638208 -279.020345)
			(xy 173.605573 -278.983508) (xy 173.57927 -278.941912) (xy 173.559979 -278.896636) (xy 173.548202 -278.848852)
			(xy 173.544242 -278.799798) (xy 172.25518 -278.799798) (xy 172.254685 -278.824405) (xy 172.24679 -278.872982)
			(xy 172.231206 -278.919663) (xy 172.208335 -278.96324) (xy 172.17877 -279.002584) (xy 172.143277 -279.036676)
			(xy 172.102774 -279.064632) (xy 172.058312 -279.08573) (xy 172.011041 -279.099422) (xy 171.962186 -279.105354)
			(xy 171.913011 -279.103373) (xy 171.864792 -279.093529) (xy 171.818776 -279.076077) (xy 171.776155 -279.05147)
			(xy 171.738034 -279.020345) (xy 171.705399 -278.983508) (xy 171.679096 -278.941912) (xy 171.659805 -278.896636)
			(xy 171.648028 -278.848852) (xy 171.644068 -278.799798) (xy 170.35526 -278.799798) (xy 170.354765 -278.824405)
			(xy 170.34687 -278.872982) (xy 170.331286 -278.919663) (xy 170.308415 -278.96324) (xy 170.27885 -279.002584)
			(xy 170.243357 -279.036676) (xy 170.202854 -279.064632) (xy 170.158392 -279.08573) (xy 170.111121 -279.099422)
			(xy 170.062266 -279.105354) (xy 170.013091 -279.103373) (xy 169.964872 -279.093529) (xy 169.918856 -279.076077)
			(xy 169.876235 -279.05147) (xy 169.838114 -279.020345) (xy 169.805479 -278.983508) (xy 169.779176 -278.941912)
			(xy 169.759885 -278.896636) (xy 169.748108 -278.848852) (xy 169.744148 -278.799798) (xy 168.45534 -278.799798)
			(xy 168.454845 -278.824405) (xy 168.44695 -278.872982) (xy 168.431366 -278.919663) (xy 168.408495 -278.96324)
			(xy 168.37893 -279.002584) (xy 168.343437 -279.036676) (xy 168.302934 -279.064632) (xy 168.258472 -279.08573)
			(xy 168.211201 -279.099422) (xy 168.162346 -279.105354) (xy 168.113171 -279.103373) (xy 168.064952 -279.093529)
			(xy 168.018936 -279.076077) (xy 167.976315 -279.05147) (xy 167.938194 -279.020345) (xy 167.905559 -278.983508)
			(xy 167.879256 -278.941912) (xy 167.859965 -278.896636) (xy 167.848188 -278.848852) (xy 167.844228 -278.799798)
			(xy 166.555166 -278.799798) (xy 166.554671 -278.824405) (xy 166.546776 -278.872982) (xy 166.531192 -278.919663)
			(xy 166.508321 -278.96324) (xy 166.478756 -279.002584) (xy 166.443263 -279.036676) (xy 166.40276 -279.064632)
			(xy 166.358298 -279.08573) (xy 166.311027 -279.099422) (xy 166.262172 -279.105354) (xy 166.212997 -279.103373)
			(xy 166.164778 -279.093529) (xy 166.118762 -279.076077) (xy 166.076141 -279.05147) (xy 166.03802 -279.020345)
			(xy 166.005385 -278.983508) (xy 165.979082 -278.941912) (xy 165.959791 -278.896636) (xy 165.948014 -278.848852)
			(xy 165.944054 -278.799798) (xy 164.655246 -278.799798) (xy 164.654751 -278.824405) (xy 164.646856 -278.872982)
			(xy 164.631272 -278.919663) (xy 164.608401 -278.96324) (xy 164.578836 -279.002584) (xy 164.543343 -279.036676)
			(xy 164.50284 -279.064632) (xy 164.458378 -279.08573) (xy 164.411107 -279.099422) (xy 164.362252 -279.105354)
			(xy 164.313077 -279.103373) (xy 164.264858 -279.093529) (xy 164.218842 -279.076077) (xy 164.176221 -279.05147)
			(xy 164.1381 -279.020345) (xy 164.105465 -278.983508) (xy 164.079162 -278.941912) (xy 164.059871 -278.896636)
			(xy 164.048094 -278.848852) (xy 164.044134 -278.799798) (xy 162.755326 -278.799798) (xy 162.754831 -278.824405)
			(xy 162.746936 -278.872982) (xy 162.731352 -278.919663) (xy 162.708481 -278.96324) (xy 162.678916 -279.002584)
			(xy 162.643423 -279.036676) (xy 162.60292 -279.064632) (xy 162.558458 -279.08573) (xy 162.511187 -279.099422)
			(xy 162.462332 -279.105354) (xy 162.413157 -279.103373) (xy 162.364938 -279.093529) (xy 162.318922 -279.076077)
			(xy 162.276301 -279.05147) (xy 162.23818 -279.020345) (xy 162.205545 -278.983508) (xy 162.179242 -278.941912)
			(xy 162.159951 -278.896636) (xy 162.148174 -278.848852) (xy 162.144214 -278.799798) (xy 160.855152 -278.799798)
			(xy 160.854657 -278.824405) (xy 160.846762 -278.872982) (xy 160.831178 -278.919663) (xy 160.808307 -278.96324)
			(xy 160.778742 -279.002584) (xy 160.743249 -279.036676) (xy 160.702746 -279.064632) (xy 160.658284 -279.08573)
			(xy 160.611013 -279.099422) (xy 160.562158 -279.105354) (xy 160.512983 -279.103373) (xy 160.464764 -279.093529)
			(xy 160.418748 -279.076077) (xy 160.376127 -279.05147) (xy 160.338006 -279.020345) (xy 160.305371 -278.983508)
			(xy 160.279068 -278.941912) (xy 160.259777 -278.896636) (xy 160.248 -278.848852) (xy 160.24404 -278.799798)
			(xy 80.855058 -278.799798) (xy 80.854563 -278.824405) (xy 80.846668 -278.872982) (xy 80.831084 -278.919663)
			(xy 80.808213 -278.96324) (xy 80.778648 -279.002584) (xy 80.743155 -279.036676) (xy 80.702652 -279.064632)
			(xy 80.65819 -279.08573) (xy 80.610919 -279.099422) (xy 80.562064 -279.105354) (xy 80.512889 -279.103373)
			(xy 80.46467 -279.093529) (xy 80.418654 -279.076077) (xy 80.376033 -279.05147) (xy 80.337912 -279.020345)
			(xy 80.305277 -278.983508) (xy 80.278974 -278.941912) (xy 80.259683 -278.896636) (xy 80.247906 -278.848852)
			(xy 80.243946 -278.799798) (xy 78.954884 -278.799798) (xy 78.954389 -278.824405) (xy 78.946494 -278.872982)
			(xy 78.93091 -278.919663) (xy 78.908039 -278.96324) (xy 78.878474 -279.002584) (xy 78.842981 -279.036676)
			(xy 78.802478 -279.064632) (xy 78.758016 -279.08573) (xy 78.710745 -279.099422) (xy 78.66189 -279.105354)
			(xy 78.612715 -279.103373) (xy 78.564496 -279.093529) (xy 78.51848 -279.076077) (xy 78.475859 -279.05147)
			(xy 78.437738 -279.020345) (xy 78.405103 -278.983508) (xy 78.3788 -278.941912) (xy 78.359509 -278.896636)
			(xy 78.347732 -278.848852) (xy 78.343772 -278.799798) (xy 77.054964 -278.799798) (xy 77.054469 -278.824405)
			(xy 77.046574 -278.872982) (xy 77.03099 -278.919663) (xy 77.008119 -278.96324) (xy 76.978554 -279.002584)
			(xy 76.943061 -279.036676) (xy 76.902558 -279.064632) (xy 76.858096 -279.08573) (xy 76.810825 -279.099422)
			(xy 76.76197 -279.105354) (xy 76.712795 -279.103373) (xy 76.664576 -279.093529) (xy 76.61856 -279.076077)
			(xy 76.575939 -279.05147) (xy 76.537818 -279.020345) (xy 76.505183 -278.983508) (xy 76.47888 -278.941912)
			(xy 76.459589 -278.896636) (xy 76.447812 -278.848852) (xy 76.443852 -278.799798) (xy 75.155044 -278.799798)
			(xy 75.154549 -278.824405) (xy 75.146654 -278.872982) (xy 75.13107 -278.919663) (xy 75.108199 -278.96324)
			(xy 75.078634 -279.002584) (xy 75.043141 -279.036676) (xy 75.002638 -279.064632) (xy 74.958176 -279.08573)
			(xy 74.910905 -279.099422) (xy 74.86205 -279.105354) (xy 74.812875 -279.103373) (xy 74.764656 -279.093529)
			(xy 74.71864 -279.076077) (xy 74.676019 -279.05147) (xy 74.637898 -279.020345) (xy 74.605263 -278.983508)
			(xy 74.57896 -278.941912) (xy 74.559669 -278.896636) (xy 74.547892 -278.848852) (xy 74.543932 -278.799798)
			(xy 73.25487 -278.799798) (xy 73.254375 -278.824405) (xy 73.24648 -278.872982) (xy 73.230896 -278.919663)
			(xy 73.208025 -278.96324) (xy 73.17846 -279.002584) (xy 73.142967 -279.036676) (xy 73.102464 -279.064632)
			(xy 73.058002 -279.08573) (xy 73.010731 -279.099422) (xy 72.961876 -279.105354) (xy 72.912701 -279.103373)
			(xy 72.864482 -279.093529) (xy 72.818466 -279.076077) (xy 72.775845 -279.05147) (xy 72.737724 -279.020345)
			(xy 72.705089 -278.983508) (xy 72.678786 -278.941912) (xy 72.659495 -278.896636) (xy 72.647718 -278.848852)
			(xy 72.643758 -278.799798) (xy 71.35495 -278.799798) (xy 71.354455 -278.824405) (xy 71.34656 -278.872982)
			(xy 71.330976 -278.919663) (xy 71.308105 -278.96324) (xy 71.27854 -279.002584) (xy 71.243047 -279.036676)
			(xy 71.202544 -279.064632) (xy 71.158082 -279.08573) (xy 71.110811 -279.099422) (xy 71.061956 -279.105354)
			(xy 71.012781 -279.103373) (xy 70.964562 -279.093529) (xy 70.918546 -279.076077) (xy 70.875925 -279.05147)
			(xy 70.837804 -279.020345) (xy 70.805169 -278.983508) (xy 70.778866 -278.941912) (xy 70.759575 -278.896636)
			(xy 70.747798 -278.848852) (xy 70.743838 -278.799798) (xy 69.45503 -278.799798) (xy 69.454535 -278.824405)
			(xy 69.44664 -278.872982) (xy 69.431056 -278.919663) (xy 69.408185 -278.96324) (xy 69.37862 -279.002584)
			(xy 69.343127 -279.036676) (xy 69.302624 -279.064632) (xy 69.258162 -279.08573) (xy 69.210891 -279.099422)
			(xy 69.162036 -279.105354) (xy 69.112861 -279.103373) (xy 69.064642 -279.093529) (xy 69.018626 -279.076077)
			(xy 68.976005 -279.05147) (xy 68.937884 -279.020345) (xy 68.905249 -278.983508) (xy 68.878946 -278.941912)
			(xy 68.859655 -278.896636) (xy 68.847878 -278.848852) (xy 68.843918 -278.799798) (xy 67.554856 -278.799798)
			(xy 67.554361 -278.824405) (xy 67.546466 -278.872982) (xy 67.530882 -278.919663) (xy 67.508011 -278.96324)
			(xy 67.478446 -279.002584) (xy 67.442953 -279.036676) (xy 67.40245 -279.064632) (xy 67.357988 -279.08573)
			(xy 67.310717 -279.099422) (xy 67.261862 -279.105354) (xy 67.212687 -279.103373) (xy 67.164468 -279.093529)
			(xy 67.118452 -279.076077) (xy 67.075831 -279.05147) (xy 67.03771 -279.020345) (xy 67.005075 -278.983508)
			(xy 66.978772 -278.941912) (xy 66.959481 -278.896636) (xy 66.947704 -278.848852) (xy 66.943744 -278.799798)
			(xy 65.654936 -278.799798) (xy 65.654441 -278.824405) (xy 65.646546 -278.872982) (xy 65.630962 -278.919663)
			(xy 65.608091 -278.96324) (xy 65.578526 -279.002584) (xy 65.543033 -279.036676) (xy 65.50253 -279.064632)
			(xy 65.458068 -279.08573) (xy 65.410797 -279.099422) (xy 65.361942 -279.105354) (xy 65.312767 -279.103373)
			(xy 65.264548 -279.093529) (xy 65.218532 -279.076077) (xy 65.175911 -279.05147) (xy 65.13779 -279.020345)
			(xy 65.105155 -278.983508) (xy 65.078852 -278.941912) (xy 65.059561 -278.896636) (xy 65.047784 -278.848852)
			(xy 65.043824 -278.799798) (xy 63.755016 -278.799798) (xy 63.754521 -278.824405) (xy 63.746626 -278.872982)
			(xy 63.731042 -278.919663) (xy 63.708171 -278.96324) (xy 63.678606 -279.002584) (xy 63.643113 -279.036676)
			(xy 63.60261 -279.064632) (xy 63.558148 -279.08573) (xy 63.510877 -279.099422) (xy 63.462022 -279.105354)
			(xy 63.412847 -279.103373) (xy 63.364628 -279.093529) (xy 63.318612 -279.076077) (xy 63.275991 -279.05147)
			(xy 63.23787 -279.020345) (xy 63.205235 -278.983508) (xy 63.178932 -278.941912) (xy 63.159641 -278.896636)
			(xy 63.147864 -278.848852) (xy 63.143904 -278.799798) (xy 61.854842 -278.799798) (xy 61.854347 -278.824405)
			(xy 61.846452 -278.872982) (xy 61.830868 -278.919663) (xy 61.807997 -278.96324) (xy 61.778432 -279.002584)
			(xy 61.742939 -279.036676) (xy 61.702436 -279.064632) (xy 61.657974 -279.08573) (xy 61.610703 -279.099422)
			(xy 61.561848 -279.105354) (xy 61.512673 -279.103373) (xy 61.464454 -279.093529) (xy 61.418438 -279.076077)
			(xy 61.375817 -279.05147) (xy 61.337696 -279.020345) (xy 61.305061 -278.983508) (xy 61.278758 -278.941912)
			(xy 61.259467 -278.896636) (xy 61.24769 -278.848852) (xy 61.24373 -278.799798) (xy 59.954922 -278.799798)
			(xy 59.954427 -278.824405) (xy 59.946532 -278.872982) (xy 59.930948 -278.919663) (xy 59.908077 -278.96324)
			(xy 59.878512 -279.002584) (xy 59.843019 -279.036676) (xy 59.802516 -279.064632) (xy 59.758054 -279.08573)
			(xy 59.710783 -279.099422) (xy 59.661928 -279.105354) (xy 59.612753 -279.103373) (xy 59.564534 -279.093529)
			(xy 59.518518 -279.076077) (xy 59.475897 -279.05147) (xy 59.437776 -279.020345) (xy 59.405141 -278.983508)
			(xy 59.378838 -278.941912) (xy 59.359547 -278.896636) (xy 59.34777 -278.848852) (xy 59.34381 -278.799798)
			(xy 58.055256 -278.799798) (xy 58.054761 -278.824405) (xy 58.046866 -278.872982) (xy 58.031282 -278.919663)
			(xy 58.008411 -278.96324) (xy 57.978846 -279.002584) (xy 57.943353 -279.036676) (xy 57.90285 -279.064632)
			(xy 57.858388 -279.08573) (xy 57.811117 -279.099422) (xy 57.762262 -279.105354) (xy 57.713087 -279.103373)
			(xy 57.664868 -279.093529) (xy 57.618852 -279.076077) (xy 57.576231 -279.05147) (xy 57.53811 -279.020345)
			(xy 57.505475 -278.983508) (xy 57.479172 -278.941912) (xy 57.459881 -278.896636) (xy 57.448104 -278.848852)
			(xy 57.444144 -278.799798) (xy 56.155082 -278.799798) (xy 56.154587 -278.824405) (xy 56.146692 -278.872982)
			(xy 56.131108 -278.919663) (xy 56.108237 -278.96324) (xy 56.078672 -279.002584) (xy 56.043179 -279.036676)
			(xy 56.002676 -279.064632) (xy 55.958214 -279.08573) (xy 55.910943 -279.099422) (xy 55.862088 -279.105354)
			(xy 55.812913 -279.103373) (xy 55.764694 -279.093529) (xy 55.718678 -279.076077) (xy 55.676057 -279.05147)
			(xy 55.637936 -279.020345) (xy 55.605301 -278.983508) (xy 55.578998 -278.941912) (xy 55.559707 -278.896636)
			(xy 55.54793 -278.848852) (xy 55.54397 -278.799798) (xy 54.255162 -278.799798) (xy 54.254667 -278.824405)
			(xy 54.246772 -278.872982) (xy 54.231188 -278.919663) (xy 54.208317 -278.96324) (xy 54.178752 -279.002584)
			(xy 54.143259 -279.036676) (xy 54.102756 -279.064632) (xy 54.058294 -279.08573) (xy 54.011023 -279.099422)
			(xy 53.962168 -279.105354) (xy 53.912993 -279.103373) (xy 53.864774 -279.093529) (xy 53.818758 -279.076077)
			(xy 53.776137 -279.05147) (xy 53.738016 -279.020345) (xy 53.705381 -278.983508) (xy 53.679078 -278.941912)
			(xy 53.659787 -278.896636) (xy 53.64801 -278.848852) (xy 53.64405 -278.799798) (xy 52.355242 -278.799798)
			(xy 52.354747 -278.824405) (xy 52.346852 -278.872982) (xy 52.331268 -278.919663) (xy 52.308397 -278.96324)
			(xy 52.278832 -279.002584) (xy 52.243339 -279.036676) (xy 52.202836 -279.064632) (xy 52.158374 -279.08573)
			(xy 52.111103 -279.099422) (xy 52.062248 -279.105354) (xy 52.013073 -279.103373) (xy 51.964854 -279.093529)
			(xy 51.918838 -279.076077) (xy 51.876217 -279.05147) (xy 51.838096 -279.020345) (xy 51.805461 -278.983508)
			(xy 51.779158 -278.941912) (xy 51.759867 -278.896636) (xy 51.74809 -278.848852) (xy 51.74413 -278.799798)
			(xy 50.455068 -278.799798) (xy 50.454573 -278.824405) (xy 50.446678 -278.872982) (xy 50.431094 -278.919663)
			(xy 50.408223 -278.96324) (xy 50.378658 -279.002584) (xy 50.343165 -279.036676) (xy 50.302662 -279.064632)
			(xy 50.2582 -279.08573) (xy 50.210929 -279.099422) (xy 50.162074 -279.105354) (xy 50.112899 -279.103373)
			(xy 50.06468 -279.093529) (xy 50.018664 -279.076077) (xy 49.976043 -279.05147) (xy 49.937922 -279.020345)
			(xy 49.905287 -278.983508) (xy 49.878984 -278.941912) (xy 49.859693 -278.896636) (xy 49.847916 -278.848852)
			(xy 49.843956 -278.799798) (xy 48.555148 -278.799798) (xy 48.554653 -278.824405) (xy 48.546758 -278.872982)
			(xy 48.531174 -278.919663) (xy 48.508303 -278.96324) (xy 48.478738 -279.002584) (xy 48.443245 -279.036676)
			(xy 48.402742 -279.064632) (xy 48.35828 -279.08573) (xy 48.311009 -279.099422) (xy 48.262154 -279.105354)
			(xy 48.212979 -279.103373) (xy 48.16476 -279.093529) (xy 48.118744 -279.076077) (xy 48.076123 -279.05147)
			(xy 48.038002 -279.020345) (xy 48.005367 -278.983508) (xy 47.979064 -278.941912) (xy 47.959773 -278.896636)
			(xy 47.947996 -278.848852) (xy 47.944036 -278.799798) (xy 46.655228 -278.799798) (xy 46.654733 -278.824405)
			(xy 46.646838 -278.872982) (xy 46.631254 -278.919663) (xy 46.608383 -278.96324) (xy 46.578818 -279.002584)
			(xy 46.543325 -279.036676) (xy 46.502822 -279.064632) (xy 46.45836 -279.08573) (xy 46.411089 -279.099422)
			(xy 46.362234 -279.105354) (xy 46.313059 -279.103373) (xy 46.26484 -279.093529) (xy 46.218824 -279.076077)
			(xy 46.176203 -279.05147) (xy 46.138082 -279.020345) (xy 46.105447 -278.983508) (xy 46.079144 -278.941912)
			(xy 46.059853 -278.896636) (xy 46.048076 -278.848852) (xy 46.044116 -278.799798) (xy 44.755054 -278.799798)
			(xy 44.754559 -278.824405) (xy 44.746664 -278.872982) (xy 44.73108 -278.919663) (xy 44.708209 -278.96324)
			(xy 44.678644 -279.002584) (xy 44.643151 -279.036676) (xy 44.602648 -279.064632) (xy 44.558186 -279.08573)
			(xy 44.510915 -279.099422) (xy 44.46206 -279.105354) (xy 44.412885 -279.103373) (xy 44.364666 -279.093529)
			(xy 44.31865 -279.076077) (xy 44.276029 -279.05147) (xy 44.237908 -279.020345) (xy 44.205273 -278.983508)
			(xy 44.17897 -278.941912) (xy 44.159679 -278.896636) (xy 44.147902 -278.848852) (xy 44.143942 -278.799798)
			(xy 0.508 -278.799798) (xy 0.508 -279.749504) (xy 45.094156 -279.749504) (xy 45.098116 -279.70045)
			(xy 45.109893 -279.652666) (xy 45.129184 -279.60739) (xy 45.155487 -279.565794) (xy 45.188122 -279.528957)
			(xy 45.226243 -279.497832) (xy 45.268864 -279.473225) (xy 45.31488 -279.455773) (xy 45.363099 -279.445929)
			(xy 45.412274 -279.443948) (xy 45.461129 -279.44988) (xy 45.5084 -279.463572) (xy 45.552862 -279.48467)
			(xy 45.593365 -279.512626) (xy 45.628858 -279.546718) (xy 45.658423 -279.586062) (xy 45.681294 -279.629639)
			(xy 45.696878 -279.67632) (xy 45.704773 -279.724897) (xy 45.705268 -279.749504) (xy 46.994076 -279.749504)
			(xy 46.998036 -279.70045) (xy 47.009813 -279.652666) (xy 47.029104 -279.60739) (xy 47.055407 -279.565794)
			(xy 47.088042 -279.528957) (xy 47.126163 -279.497832) (xy 47.168784 -279.473225) (xy 47.2148 -279.455773)
			(xy 47.263019 -279.445929) (xy 47.312194 -279.443948) (xy 47.361049 -279.44988) (xy 47.40832 -279.463572)
			(xy 47.452782 -279.48467) (xy 47.493285 -279.512626) (xy 47.528778 -279.546718) (xy 47.558343 -279.586062)
			(xy 47.581214 -279.629639) (xy 47.596798 -279.67632) (xy 47.604693 -279.724897) (xy 47.605188 -279.749504)
			(xy 48.893996 -279.749504) (xy 48.897956 -279.70045) (xy 48.909733 -279.652666) (xy 48.929024 -279.60739)
			(xy 48.955327 -279.565794) (xy 48.987962 -279.528957) (xy 49.026083 -279.497832) (xy 49.068704 -279.473225)
			(xy 49.11472 -279.455773) (xy 49.162939 -279.445929) (xy 49.212114 -279.443948) (xy 49.260969 -279.44988)
			(xy 49.30824 -279.463572) (xy 49.352702 -279.48467) (xy 49.393205 -279.512626) (xy 49.428698 -279.546718)
			(xy 49.458263 -279.586062) (xy 49.481134 -279.629639) (xy 49.496718 -279.67632) (xy 49.504613 -279.724897)
			(xy 49.505108 -279.749504) (xy 50.79417 -279.749504) (xy 50.79813 -279.70045) (xy 50.809907 -279.652666)
			(xy 50.829198 -279.60739) (xy 50.855501 -279.565794) (xy 50.888136 -279.528957) (xy 50.926257 -279.497832)
			(xy 50.968878 -279.473225) (xy 51.014894 -279.455773) (xy 51.063113 -279.445929) (xy 51.112288 -279.443948)
			(xy 51.161143 -279.44988) (xy 51.208414 -279.463572) (xy 51.252876 -279.48467) (xy 51.293379 -279.512626)
			(xy 51.328872 -279.546718) (xy 51.358437 -279.586062) (xy 51.381308 -279.629639) (xy 51.396892 -279.67632)
			(xy 51.404787 -279.724897) (xy 51.405282 -279.749504) (xy 52.69409 -279.749504) (xy 52.69805 -279.70045)
			(xy 52.709827 -279.652666) (xy 52.729118 -279.60739) (xy 52.755421 -279.565794) (xy 52.788056 -279.528957)
			(xy 52.826177 -279.497832) (xy 52.868798 -279.473225) (xy 52.914814 -279.455773) (xy 52.963033 -279.445929)
			(xy 53.012208 -279.443948) (xy 53.061063 -279.44988) (xy 53.108334 -279.463572) (xy 53.152796 -279.48467)
			(xy 53.193299 -279.512626) (xy 53.228792 -279.546718) (xy 53.258357 -279.586062) (xy 53.281228 -279.629639)
			(xy 53.296812 -279.67632) (xy 53.304707 -279.724897) (xy 53.305202 -279.749504) (xy 54.59401 -279.749504)
			(xy 54.59797 -279.70045) (xy 54.609747 -279.652666) (xy 54.629038 -279.60739) (xy 54.655341 -279.565794)
			(xy 54.687976 -279.528957) (xy 54.726097 -279.497832) (xy 54.768718 -279.473225) (xy 54.814734 -279.455773)
			(xy 54.862953 -279.445929) (xy 54.912128 -279.443948) (xy 54.960983 -279.44988) (xy 55.008254 -279.463572)
			(xy 55.052716 -279.48467) (xy 55.093219 -279.512626) (xy 55.128712 -279.546718) (xy 55.158277 -279.586062)
			(xy 55.181148 -279.629639) (xy 55.196732 -279.67632) (xy 55.204627 -279.724897) (xy 55.205122 -279.749504)
			(xy 56.49393 -279.749504) (xy 56.49789 -279.70045) (xy 56.509667 -279.652666) (xy 56.528958 -279.60739)
			(xy 56.555261 -279.565794) (xy 56.587896 -279.528957) (xy 56.626017 -279.497832) (xy 56.668638 -279.473225)
			(xy 56.714654 -279.455773) (xy 56.762873 -279.445929) (xy 56.812048 -279.443948) (xy 56.860903 -279.44988)
			(xy 56.908174 -279.463572) (xy 56.952636 -279.48467) (xy 56.993139 -279.512626) (xy 57.028632 -279.546718)
			(xy 57.058197 -279.586062) (xy 57.081068 -279.629639) (xy 57.096652 -279.67632) (xy 57.104547 -279.724897)
			(xy 57.105042 -279.749504) (xy 58.394104 -279.749504) (xy 58.398064 -279.70045) (xy 58.409841 -279.652666)
			(xy 58.429132 -279.60739) (xy 58.455435 -279.565794) (xy 58.48807 -279.528957) (xy 58.526191 -279.497832)
			(xy 58.568812 -279.473225) (xy 58.614828 -279.455773) (xy 58.663047 -279.445929) (xy 58.712222 -279.443948)
			(xy 58.761077 -279.44988) (xy 58.808348 -279.463572) (xy 58.85281 -279.48467) (xy 58.893313 -279.512626)
			(xy 58.928806 -279.546718) (xy 58.958371 -279.586062) (xy 58.981242 -279.629639) (xy 58.996826 -279.67632)
			(xy 59.004721 -279.724897) (xy 59.005216 -279.749504) (xy 60.294024 -279.749504) (xy 60.297984 -279.70045)
			(xy 60.309761 -279.652666) (xy 60.329052 -279.60739) (xy 60.355355 -279.565794) (xy 60.38799 -279.528957)
			(xy 60.426111 -279.497832) (xy 60.468732 -279.473225) (xy 60.514748 -279.455773) (xy 60.562967 -279.445929)
			(xy 60.612142 -279.443948) (xy 60.660997 -279.44988) (xy 60.708268 -279.463572) (xy 60.75273 -279.48467)
			(xy 60.793233 -279.512626) (xy 60.828726 -279.546718) (xy 60.858291 -279.586062) (xy 60.881162 -279.629639)
			(xy 60.896746 -279.67632) (xy 60.904641 -279.724897) (xy 60.905136 -279.749504) (xy 62.193944 -279.749504)
			(xy 62.197904 -279.70045) (xy 62.209681 -279.652666) (xy 62.228972 -279.60739) (xy 62.255275 -279.565794)
			(xy 62.28791 -279.528957) (xy 62.326031 -279.497832) (xy 62.368652 -279.473225) (xy 62.414668 -279.455773)
			(xy 62.462887 -279.445929) (xy 62.512062 -279.443948) (xy 62.560917 -279.44988) (xy 62.608188 -279.463572)
			(xy 62.65265 -279.48467) (xy 62.693153 -279.512626) (xy 62.728646 -279.546718) (xy 62.758211 -279.586062)
			(xy 62.781082 -279.629639) (xy 62.796666 -279.67632) (xy 62.804561 -279.724897) (xy 62.805056 -279.749504)
			(xy 64.094118 -279.749504) (xy 64.098078 -279.70045) (xy 64.109855 -279.652666) (xy 64.129146 -279.60739)
			(xy 64.155449 -279.565794) (xy 64.188084 -279.528957) (xy 64.226205 -279.497832) (xy 64.268826 -279.473225)
			(xy 64.314842 -279.455773) (xy 64.363061 -279.445929) (xy 64.412236 -279.443948) (xy 64.461091 -279.44988)
			(xy 64.508362 -279.463572) (xy 64.552824 -279.48467) (xy 64.593327 -279.512626) (xy 64.62882 -279.546718)
			(xy 64.658385 -279.586062) (xy 64.681256 -279.629639) (xy 64.69684 -279.67632) (xy 64.704735 -279.724897)
			(xy 64.70523 -279.749504) (xy 65.994038 -279.749504) (xy 65.997998 -279.70045) (xy 66.009775 -279.652666)
			(xy 66.029066 -279.60739) (xy 66.055369 -279.565794) (xy 66.088004 -279.528957) (xy 66.126125 -279.497832)
			(xy 66.168746 -279.473225) (xy 66.214762 -279.455773) (xy 66.262981 -279.445929) (xy 66.312156 -279.443948)
			(xy 66.361011 -279.44988) (xy 66.408282 -279.463572) (xy 66.452744 -279.48467) (xy 66.493247 -279.512626)
			(xy 66.52874 -279.546718) (xy 66.558305 -279.586062) (xy 66.581176 -279.629639) (xy 66.59676 -279.67632)
			(xy 66.604655 -279.724897) (xy 66.60515 -279.749504) (xy 67.893958 -279.749504) (xy 67.897918 -279.70045)
			(xy 67.909695 -279.652666) (xy 67.928986 -279.60739) (xy 67.955289 -279.565794) (xy 67.987924 -279.528957)
			(xy 68.026045 -279.497832) (xy 68.068666 -279.473225) (xy 68.114682 -279.455773) (xy 68.162901 -279.445929)
			(xy 68.212076 -279.443948) (xy 68.260931 -279.44988) (xy 68.308202 -279.463572) (xy 68.352664 -279.48467)
			(xy 68.393167 -279.512626) (xy 68.42866 -279.546718) (xy 68.458225 -279.586062) (xy 68.481096 -279.629639)
			(xy 68.49668 -279.67632) (xy 68.504575 -279.724897) (xy 68.50507 -279.749504) (xy 69.794132 -279.749504)
			(xy 69.798092 -279.70045) (xy 69.809869 -279.652666) (xy 69.82916 -279.60739) (xy 69.855463 -279.565794)
			(xy 69.888098 -279.528957) (xy 69.926219 -279.497832) (xy 69.96884 -279.473225) (xy 70.014856 -279.455773)
			(xy 70.063075 -279.445929) (xy 70.11225 -279.443948) (xy 70.161105 -279.44988) (xy 70.208376 -279.463572)
			(xy 70.252838 -279.48467) (xy 70.293341 -279.512626) (xy 70.328834 -279.546718) (xy 70.358399 -279.586062)
			(xy 70.38127 -279.629639) (xy 70.396854 -279.67632) (xy 70.404749 -279.724897) (xy 70.405244 -279.749504)
			(xy 71.694052 -279.749504) (xy 71.698012 -279.70045) (xy 71.709789 -279.652666) (xy 71.72908 -279.60739)
			(xy 71.755383 -279.565794) (xy 71.788018 -279.528957) (xy 71.826139 -279.497832) (xy 71.86876 -279.473225)
			(xy 71.914776 -279.455773) (xy 71.962995 -279.445929) (xy 72.01217 -279.443948) (xy 72.061025 -279.44988)
			(xy 72.108296 -279.463572) (xy 72.152758 -279.48467) (xy 72.193261 -279.512626) (xy 72.228754 -279.546718)
			(xy 72.258319 -279.586062) (xy 72.28119 -279.629639) (xy 72.296774 -279.67632) (xy 72.304669 -279.724897)
			(xy 72.305164 -279.749504) (xy 73.593972 -279.749504) (xy 73.597932 -279.70045) (xy 73.609709 -279.652666)
			(xy 73.629 -279.60739) (xy 73.655303 -279.565794) (xy 73.687938 -279.528957) (xy 73.726059 -279.497832)
			(xy 73.76868 -279.473225) (xy 73.814696 -279.455773) (xy 73.862915 -279.445929) (xy 73.91209 -279.443948)
			(xy 73.960945 -279.44988) (xy 74.008216 -279.463572) (xy 74.052678 -279.48467) (xy 74.093181 -279.512626)
			(xy 74.128674 -279.546718) (xy 74.158239 -279.586062) (xy 74.18111 -279.629639) (xy 74.196694 -279.67632)
			(xy 74.204589 -279.724897) (xy 74.205084 -279.749504) (xy 75.494146 -279.749504) (xy 75.498106 -279.70045)
			(xy 75.509883 -279.652666) (xy 75.529174 -279.60739) (xy 75.555477 -279.565794) (xy 75.588112 -279.528957)
			(xy 75.626233 -279.497832) (xy 75.668854 -279.473225) (xy 75.71487 -279.455773) (xy 75.763089 -279.445929)
			(xy 75.812264 -279.443948) (xy 75.861119 -279.44988) (xy 75.90839 -279.463572) (xy 75.952852 -279.48467)
			(xy 75.993355 -279.512626) (xy 76.028848 -279.546718) (xy 76.058413 -279.586062) (xy 76.081284 -279.629639)
			(xy 76.096868 -279.67632) (xy 76.104763 -279.724897) (xy 76.105258 -279.749504) (xy 77.394066 -279.749504)
			(xy 77.398026 -279.70045) (xy 77.409803 -279.652666) (xy 77.429094 -279.60739) (xy 77.455397 -279.565794)
			(xy 77.488032 -279.528957) (xy 77.526153 -279.497832) (xy 77.568774 -279.473225) (xy 77.61479 -279.455773)
			(xy 77.663009 -279.445929) (xy 77.712184 -279.443948) (xy 77.761039 -279.44988) (xy 77.80831 -279.463572)
			(xy 77.852772 -279.48467) (xy 77.893275 -279.512626) (xy 77.928768 -279.546718) (xy 77.958333 -279.586062)
			(xy 77.981204 -279.629639) (xy 77.996788 -279.67632) (xy 78.004683 -279.724897) (xy 78.005178 -279.749504)
			(xy 78.005173 -279.749758) (xy 79.293986 -279.749758) (xy 79.297946 -279.700704) (xy 79.309723 -279.65292)
			(xy 79.329014 -279.607644) (xy 79.355317 -279.566048) (xy 79.387952 -279.529211) (xy 79.426073 -279.498086)
			(xy 79.468694 -279.473479) (xy 79.51471 -279.456027) (xy 79.562929 -279.446183) (xy 79.612104 -279.444202)
			(xy 79.660959 -279.450134) (xy 79.70823 -279.463826) (xy 79.752692 -279.484924) (xy 79.793195 -279.51288)
			(xy 79.828688 -279.546972) (xy 79.858253 -279.586316) (xy 79.881124 -279.629893) (xy 79.896708 -279.676574)
			(xy 79.904603 -279.725151) (xy 79.905098 -279.749758) (xy 81.19416 -279.749758) (xy 81.19812 -279.700704)
			(xy 81.209897 -279.65292) (xy 81.229188 -279.607644) (xy 81.255491 -279.566048) (xy 81.288126 -279.529211)
			(xy 81.326247 -279.498086) (xy 81.368868 -279.473479) (xy 81.414884 -279.456027) (xy 81.463103 -279.446183)
			(xy 81.512278 -279.444202) (xy 81.561133 -279.450134) (xy 81.608404 -279.463826) (xy 81.652866 -279.484924)
			(xy 81.693369 -279.51288) (xy 81.728862 -279.546972) (xy 81.758427 -279.586316) (xy 81.781298 -279.629893)
			(xy 81.796882 -279.676574) (xy 81.804777 -279.725151) (xy 81.805272 -279.749758) (xy 82.14412 -279.749758)
			(xy 82.14808 -279.700704) (xy 82.159857 -279.65292) (xy 82.179148 -279.607644) (xy 82.205451 -279.566048)
			(xy 82.238086 -279.529211) (xy 82.276207 -279.498086) (xy 82.318828 -279.473479) (xy 82.364844 -279.456027)
			(xy 82.413063 -279.446183) (xy 82.462238 -279.444202) (xy 82.511093 -279.450134) (xy 82.558364 -279.463826)
			(xy 82.602826 -279.484924) (xy 82.643329 -279.51288) (xy 82.678822 -279.546972) (xy 82.708387 -279.586316)
			(xy 82.731258 -279.629893) (xy 82.746842 -279.676574) (xy 82.754737 -279.725151) (xy 82.755227 -279.749504)
			(xy 161.194254 -279.749504) (xy 161.198214 -279.70045) (xy 161.209991 -279.652666) (xy 161.229282 -279.60739)
			(xy 161.255585 -279.565794) (xy 161.28822 -279.528957) (xy 161.326341 -279.497832) (xy 161.368962 -279.473225)
			(xy 161.414978 -279.455773) (xy 161.463197 -279.445929) (xy 161.512372 -279.443948) (xy 161.561227 -279.44988)
			(xy 161.608498 -279.463572) (xy 161.65296 -279.48467) (xy 161.693463 -279.512626) (xy 161.728956 -279.546718)
			(xy 161.758521 -279.586062) (xy 161.781392 -279.629639) (xy 161.796976 -279.67632) (xy 161.804871 -279.724897)
			(xy 161.805366 -279.749504) (xy 163.094174 -279.749504) (xy 163.098134 -279.70045) (xy 163.109911 -279.652666)
			(xy 163.129202 -279.60739) (xy 163.155505 -279.565794) (xy 163.18814 -279.528957) (xy 163.226261 -279.497832)
			(xy 163.268882 -279.473225) (xy 163.314898 -279.455773) (xy 163.363117 -279.445929) (xy 163.412292 -279.443948)
			(xy 163.461147 -279.44988) (xy 163.508418 -279.463572) (xy 163.55288 -279.48467) (xy 163.593383 -279.512626)
			(xy 163.628876 -279.546718) (xy 163.658441 -279.586062) (xy 163.681312 -279.629639) (xy 163.696896 -279.67632)
			(xy 163.704791 -279.724897) (xy 163.705286 -279.749504) (xy 164.994094 -279.749504) (xy 164.998054 -279.70045)
			(xy 165.009831 -279.652666) (xy 165.029122 -279.60739) (xy 165.055425 -279.565794) (xy 165.08806 -279.528957)
			(xy 165.126181 -279.497832) (xy 165.168802 -279.473225) (xy 165.214818 -279.455773) (xy 165.263037 -279.445929)
			(xy 165.312212 -279.443948) (xy 165.361067 -279.44988) (xy 165.408338 -279.463572) (xy 165.4528 -279.48467)
			(xy 165.493303 -279.512626) (xy 165.528796 -279.546718) (xy 165.558361 -279.586062) (xy 165.581232 -279.629639)
			(xy 165.596816 -279.67632) (xy 165.604711 -279.724897) (xy 165.605206 -279.749504) (xy 166.894268 -279.749504)
			(xy 166.898228 -279.70045) (xy 166.910005 -279.652666) (xy 166.929296 -279.60739) (xy 166.955599 -279.565794)
			(xy 166.988234 -279.528957) (xy 167.026355 -279.497832) (xy 167.068976 -279.473225) (xy 167.114992 -279.455773)
			(xy 167.163211 -279.445929) (xy 167.212386 -279.443948) (xy 167.261241 -279.44988) (xy 167.308512 -279.463572)
			(xy 167.352974 -279.48467) (xy 167.393477 -279.512626) (xy 167.42897 -279.546718) (xy 167.458535 -279.586062)
			(xy 167.481406 -279.629639) (xy 167.49699 -279.67632) (xy 167.504885 -279.724897) (xy 167.50538 -279.749504)
			(xy 168.794188 -279.749504) (xy 168.798148 -279.70045) (xy 168.809925 -279.652666) (xy 168.829216 -279.60739)
			(xy 168.855519 -279.565794) (xy 168.888154 -279.528957) (xy 168.926275 -279.497832) (xy 168.968896 -279.473225)
			(xy 169.014912 -279.455773) (xy 169.063131 -279.445929) (xy 169.112306 -279.443948) (xy 169.161161 -279.44988)
			(xy 169.208432 -279.463572) (xy 169.252894 -279.48467) (xy 169.293397 -279.512626) (xy 169.32889 -279.546718)
			(xy 169.358455 -279.586062) (xy 169.381326 -279.629639) (xy 169.39691 -279.67632) (xy 169.404805 -279.724897)
			(xy 169.4053 -279.749504) (xy 170.694108 -279.749504) (xy 170.698068 -279.70045) (xy 170.709845 -279.652666)
			(xy 170.729136 -279.60739) (xy 170.755439 -279.565794) (xy 170.788074 -279.528957) (xy 170.826195 -279.497832)
			(xy 170.868816 -279.473225) (xy 170.914832 -279.455773) (xy 170.963051 -279.445929) (xy 171.012226 -279.443948)
			(xy 171.061081 -279.44988) (xy 171.108352 -279.463572) (xy 171.152814 -279.48467) (xy 171.193317 -279.512626)
			(xy 171.22881 -279.546718) (xy 171.258375 -279.586062) (xy 171.281246 -279.629639) (xy 171.29683 -279.67632)
			(xy 171.304725 -279.724897) (xy 171.30522 -279.749504) (xy 172.594028 -279.749504) (xy 172.597988 -279.70045)
			(xy 172.609765 -279.652666) (xy 172.629056 -279.60739) (xy 172.655359 -279.565794) (xy 172.687994 -279.528957)
			(xy 172.726115 -279.497832) (xy 172.768736 -279.473225) (xy 172.814752 -279.455773) (xy 172.862971 -279.445929)
			(xy 172.912146 -279.443948) (xy 172.961001 -279.44988) (xy 173.008272 -279.463572) (xy 173.052734 -279.48467)
			(xy 173.093237 -279.512626) (xy 173.12873 -279.546718) (xy 173.158295 -279.586062) (xy 173.181166 -279.629639)
			(xy 173.19675 -279.67632) (xy 173.204645 -279.724897) (xy 173.20514 -279.749504) (xy 174.494202 -279.749504)
			(xy 174.498162 -279.70045) (xy 174.509939 -279.652666) (xy 174.52923 -279.60739) (xy 174.555533 -279.565794)
			(xy 174.588168 -279.528957) (xy 174.626289 -279.497832) (xy 174.66891 -279.473225) (xy 174.714926 -279.455773)
			(xy 174.763145 -279.445929) (xy 174.81232 -279.443948) (xy 174.861175 -279.44988) (xy 174.908446 -279.463572)
			(xy 174.952908 -279.48467) (xy 174.993411 -279.512626) (xy 175.028904 -279.546718) (xy 175.058469 -279.586062)
			(xy 175.08134 -279.629639) (xy 175.096924 -279.67632) (xy 175.104819 -279.724897) (xy 175.105314 -279.749504)
			(xy 176.394122 -279.749504) (xy 176.398082 -279.70045) (xy 176.409859 -279.652666) (xy 176.42915 -279.60739)
			(xy 176.455453 -279.565794) (xy 176.488088 -279.528957) (xy 176.526209 -279.497832) (xy 176.56883 -279.473225)
			(xy 176.614846 -279.455773) (xy 176.663065 -279.445929) (xy 176.71224 -279.443948) (xy 176.761095 -279.44988)
			(xy 176.808366 -279.463572) (xy 176.852828 -279.48467) (xy 176.893331 -279.512626) (xy 176.928824 -279.546718)
			(xy 176.958389 -279.586062) (xy 176.98126 -279.629639) (xy 176.996844 -279.67632) (xy 177.004739 -279.724897)
			(xy 177.005234 -279.749504) (xy 178.294042 -279.749504) (xy 178.298002 -279.70045) (xy 178.309779 -279.652666)
			(xy 178.32907 -279.60739) (xy 178.355373 -279.565794) (xy 178.388008 -279.528957) (xy 178.426129 -279.497832)
			(xy 178.46875 -279.473225) (xy 178.514766 -279.455773) (xy 178.562985 -279.445929) (xy 178.61216 -279.443948)
			(xy 178.661015 -279.44988) (xy 178.708286 -279.463572) (xy 178.752748 -279.48467) (xy 178.793251 -279.512626)
			(xy 178.828744 -279.546718) (xy 178.858309 -279.586062) (xy 178.88118 -279.629639) (xy 178.896764 -279.67632)
			(xy 178.904659 -279.724897) (xy 178.905154 -279.749504) (xy 180.194216 -279.749504) (xy 180.198176 -279.70045)
			(xy 180.209953 -279.652666) (xy 180.229244 -279.60739) (xy 180.255547 -279.565794) (xy 180.288182 -279.528957)
			(xy 180.326303 -279.497832) (xy 180.368924 -279.473225) (xy 180.41494 -279.455773) (xy 180.463159 -279.445929)
			(xy 180.512334 -279.443948) (xy 180.561189 -279.44988) (xy 180.60846 -279.463572) (xy 180.652922 -279.48467)
			(xy 180.693425 -279.512626) (xy 180.728918 -279.546718) (xy 180.758483 -279.586062) (xy 180.781354 -279.629639)
			(xy 180.796938 -279.67632) (xy 180.804833 -279.724897) (xy 180.805328 -279.749504) (xy 182.094136 -279.749504)
			(xy 182.098096 -279.70045) (xy 182.109873 -279.652666) (xy 182.129164 -279.60739) (xy 182.155467 -279.565794)
			(xy 182.188102 -279.528957) (xy 182.226223 -279.497832) (xy 182.268844 -279.473225) (xy 182.31486 -279.455773)
			(xy 182.363079 -279.445929) (xy 182.412254 -279.443948) (xy 182.461109 -279.44988) (xy 182.50838 -279.463572)
			(xy 182.552842 -279.48467) (xy 182.593345 -279.512626) (xy 182.628838 -279.546718) (xy 182.658403 -279.586062)
			(xy 182.681274 -279.629639) (xy 182.696858 -279.67632) (xy 182.704753 -279.724897) (xy 182.705248 -279.749504)
			(xy 183.994056 -279.749504) (xy 183.998016 -279.70045) (xy 184.009793 -279.652666) (xy 184.029084 -279.60739)
			(xy 184.055387 -279.565794) (xy 184.088022 -279.528957) (xy 184.126143 -279.497832) (xy 184.168764 -279.473225)
			(xy 184.21478 -279.455773) (xy 184.262999 -279.445929) (xy 184.312174 -279.443948) (xy 184.361029 -279.44988)
			(xy 184.4083 -279.463572) (xy 184.452762 -279.48467) (xy 184.493265 -279.512626) (xy 184.528758 -279.546718)
			(xy 184.558323 -279.586062) (xy 184.581194 -279.629639) (xy 184.596778 -279.67632) (xy 184.604673 -279.724897)
			(xy 184.605168 -279.749504) (xy 185.89423 -279.749504) (xy 185.89819 -279.70045) (xy 185.909967 -279.652666)
			(xy 185.929258 -279.60739) (xy 185.955561 -279.565794) (xy 185.988196 -279.528957) (xy 186.026317 -279.497832)
			(xy 186.068938 -279.473225) (xy 186.114954 -279.455773) (xy 186.163173 -279.445929) (xy 186.212348 -279.443948)
			(xy 186.261203 -279.44988) (xy 186.308474 -279.463572) (xy 186.352936 -279.48467) (xy 186.393439 -279.512626)
			(xy 186.428932 -279.546718) (xy 186.458497 -279.586062) (xy 186.481368 -279.629639) (xy 186.496952 -279.67632)
			(xy 186.504847 -279.724897) (xy 186.505342 -279.749504) (xy 187.79415 -279.749504) (xy 187.79811 -279.70045)
			(xy 187.809887 -279.652666) (xy 187.829178 -279.60739) (xy 187.855481 -279.565794) (xy 187.888116 -279.528957)
			(xy 187.926237 -279.497832) (xy 187.968858 -279.473225) (xy 188.014874 -279.455773) (xy 188.063093 -279.445929)
			(xy 188.112268 -279.443948) (xy 188.161123 -279.44988) (xy 188.208394 -279.463572) (xy 188.252856 -279.48467)
			(xy 188.293359 -279.512626) (xy 188.328852 -279.546718) (xy 188.358417 -279.586062) (xy 188.381288 -279.629639)
			(xy 188.396872 -279.67632) (xy 188.404767 -279.724897) (xy 188.405262 -279.749504) (xy 189.69407 -279.749504)
			(xy 189.69803 -279.70045) (xy 189.709807 -279.652666) (xy 189.729098 -279.60739) (xy 189.755401 -279.565794)
			(xy 189.788036 -279.528957) (xy 189.826157 -279.497832) (xy 189.868778 -279.473225) (xy 189.914794 -279.455773)
			(xy 189.963013 -279.445929) (xy 190.012188 -279.443948) (xy 190.061043 -279.44988) (xy 190.108314 -279.463572)
			(xy 190.152776 -279.48467) (xy 190.193279 -279.512626) (xy 190.228772 -279.546718) (xy 190.258337 -279.586062)
			(xy 190.281208 -279.629639) (xy 190.296792 -279.67632) (xy 190.304687 -279.724897) (xy 190.305182 -279.749504)
			(xy 191.594244 -279.749504) (xy 191.598204 -279.70045) (xy 191.609981 -279.652666) (xy 191.629272 -279.60739)
			(xy 191.655575 -279.565794) (xy 191.68821 -279.528957) (xy 191.726331 -279.497832) (xy 191.768952 -279.473225)
			(xy 191.814968 -279.455773) (xy 191.863187 -279.445929) (xy 191.912362 -279.443948) (xy 191.961217 -279.44988)
			(xy 192.008488 -279.463572) (xy 192.05295 -279.48467) (xy 192.093453 -279.512626) (xy 192.128946 -279.546718)
			(xy 192.158511 -279.586062) (xy 192.181382 -279.629639) (xy 192.196966 -279.67632) (xy 192.204861 -279.724897)
			(xy 192.205356 -279.749504) (xy 193.494164 -279.749504) (xy 193.498124 -279.70045) (xy 193.509901 -279.652666)
			(xy 193.529192 -279.60739) (xy 193.555495 -279.565794) (xy 193.58813 -279.528957) (xy 193.626251 -279.497832)
			(xy 193.668872 -279.473225) (xy 193.714888 -279.455773) (xy 193.763107 -279.445929) (xy 193.812282 -279.443948)
			(xy 193.861137 -279.44988) (xy 193.908408 -279.463572) (xy 193.95287 -279.48467) (xy 193.993373 -279.512626)
			(xy 194.028866 -279.546718) (xy 194.058431 -279.586062) (xy 194.081302 -279.629639) (xy 194.096886 -279.67632)
			(xy 194.104781 -279.724897) (xy 194.105276 -279.749504) (xy 194.105271 -279.749758) (xy 195.394084 -279.749758)
			(xy 195.398044 -279.700704) (xy 195.409821 -279.65292) (xy 195.429112 -279.607644) (xy 195.455415 -279.566048)
			(xy 195.48805 -279.529211) (xy 195.526171 -279.498086) (xy 195.568792 -279.473479) (xy 195.614808 -279.456027)
			(xy 195.663027 -279.446183) (xy 195.712202 -279.444202) (xy 195.761057 -279.450134) (xy 195.808328 -279.463826)
			(xy 195.85279 -279.484924) (xy 195.893293 -279.51288) (xy 195.928786 -279.546972) (xy 195.958351 -279.586316)
			(xy 195.981222 -279.629893) (xy 195.996806 -279.676574) (xy 196.004701 -279.725151) (xy 196.005196 -279.749758)
			(xy 197.294258 -279.749758) (xy 197.298218 -279.700704) (xy 197.309995 -279.65292) (xy 197.329286 -279.607644)
			(xy 197.355589 -279.566048) (xy 197.388224 -279.529211) (xy 197.426345 -279.498086) (xy 197.468966 -279.473479)
			(xy 197.514982 -279.456027) (xy 197.563201 -279.446183) (xy 197.612376 -279.444202) (xy 197.661231 -279.450134)
			(xy 197.708502 -279.463826) (xy 197.752964 -279.484924) (xy 197.793467 -279.51288) (xy 197.82896 -279.546972)
			(xy 197.858525 -279.586316) (xy 197.881396 -279.629893) (xy 197.89698 -279.676574) (xy 197.904875 -279.725151)
			(xy 197.90537 -279.749758) (xy 198.244218 -279.749758) (xy 198.248178 -279.700704) (xy 198.259955 -279.65292)
			(xy 198.279246 -279.607644) (xy 198.305549 -279.566048) (xy 198.338184 -279.529211) (xy 198.376305 -279.498086)
			(xy 198.418926 -279.473479) (xy 198.464942 -279.456027) (xy 198.513161 -279.446183) (xy 198.562336 -279.444202)
			(xy 198.611191 -279.450134) (xy 198.658462 -279.463826) (xy 198.702924 -279.484924) (xy 198.743427 -279.51288)
			(xy 198.77892 -279.546972) (xy 198.808485 -279.586316) (xy 198.831356 -279.629893) (xy 198.84694 -279.676574)
			(xy 198.854835 -279.725151) (xy 198.855325 -279.749504) (xy 277.294098 -279.749504) (xy 277.298058 -279.70045)
			(xy 277.309835 -279.652666) (xy 277.329126 -279.60739) (xy 277.355429 -279.565794) (xy 277.388064 -279.528957)
			(xy 277.426185 -279.497832) (xy 277.468806 -279.473225) (xy 277.514822 -279.455773) (xy 277.563041 -279.445929)
			(xy 277.612216 -279.443948) (xy 277.661071 -279.44988) (xy 277.708342 -279.463572) (xy 277.752804 -279.48467)
			(xy 277.793307 -279.512626) (xy 277.8288 -279.546718) (xy 277.858365 -279.586062) (xy 277.881236 -279.629639)
			(xy 277.89682 -279.67632) (xy 277.904715 -279.724897) (xy 277.90521 -279.749504) (xy 279.194018 -279.749504)
			(xy 279.197978 -279.70045) (xy 279.209755 -279.652666) (xy 279.229046 -279.60739) (xy 279.255349 -279.565794)
			(xy 279.287984 -279.528957) (xy 279.326105 -279.497832) (xy 279.368726 -279.473225) (xy 279.414742 -279.455773)
			(xy 279.462961 -279.445929) (xy 279.512136 -279.443948) (xy 279.560991 -279.44988) (xy 279.608262 -279.463572)
			(xy 279.652724 -279.48467) (xy 279.693227 -279.512626) (xy 279.72872 -279.546718) (xy 279.758285 -279.586062)
			(xy 279.781156 -279.629639) (xy 279.79674 -279.67632) (xy 279.804635 -279.724897) (xy 279.80513 -279.749504)
			(xy 281.093938 -279.749504) (xy 281.097898 -279.70045) (xy 281.109675 -279.652666) (xy 281.128966 -279.60739)
			(xy 281.155269 -279.565794) (xy 281.187904 -279.528957) (xy 281.226025 -279.497832) (xy 281.268646 -279.473225)
			(xy 281.314662 -279.455773) (xy 281.362881 -279.445929) (xy 281.412056 -279.443948) (xy 281.460911 -279.44988)
			(xy 281.508182 -279.463572) (xy 281.552644 -279.48467) (xy 281.593147 -279.512626) (xy 281.62864 -279.546718)
			(xy 281.658205 -279.586062) (xy 281.681076 -279.629639) (xy 281.69666 -279.67632) (xy 281.704555 -279.724897)
			(xy 281.70505 -279.749504) (xy 282.994112 -279.749504) (xy 282.998072 -279.70045) (xy 283.009849 -279.652666)
			(xy 283.02914 -279.60739) (xy 283.055443 -279.565794) (xy 283.088078 -279.528957) (xy 283.126199 -279.497832)
			(xy 283.16882 -279.473225) (xy 283.214836 -279.455773) (xy 283.263055 -279.445929) (xy 283.31223 -279.443948)
			(xy 283.361085 -279.44988) (xy 283.408356 -279.463572) (xy 283.452818 -279.48467) (xy 283.493321 -279.512626)
			(xy 283.528814 -279.546718) (xy 283.558379 -279.586062) (xy 283.58125 -279.629639) (xy 283.596834 -279.67632)
			(xy 283.604729 -279.724897) (xy 283.605224 -279.749504) (xy 284.894032 -279.749504) (xy 284.897992 -279.70045)
			(xy 284.909769 -279.652666) (xy 284.92906 -279.60739) (xy 284.955363 -279.565794) (xy 284.987998 -279.528957)
			(xy 285.026119 -279.497832) (xy 285.06874 -279.473225) (xy 285.114756 -279.455773) (xy 285.162975 -279.445929)
			(xy 285.21215 -279.443948) (xy 285.261005 -279.44988) (xy 285.308276 -279.463572) (xy 285.352738 -279.48467)
			(xy 285.393241 -279.512626) (xy 285.428734 -279.546718) (xy 285.458299 -279.586062) (xy 285.48117 -279.629639)
			(xy 285.496754 -279.67632) (xy 285.504649 -279.724897) (xy 285.505144 -279.749504) (xy 286.793952 -279.749504)
			(xy 286.797912 -279.70045) (xy 286.809689 -279.652666) (xy 286.82898 -279.60739) (xy 286.855283 -279.565794)
			(xy 286.887918 -279.528957) (xy 286.926039 -279.497832) (xy 286.96866 -279.473225) (xy 287.014676 -279.455773)
			(xy 287.062895 -279.445929) (xy 287.11207 -279.443948) (xy 287.160925 -279.44988) (xy 287.208196 -279.463572)
			(xy 287.252658 -279.48467) (xy 287.293161 -279.512626) (xy 287.328654 -279.546718) (xy 287.358219 -279.586062)
			(xy 287.38109 -279.629639) (xy 287.396674 -279.67632) (xy 287.404569 -279.724897) (xy 287.405064 -279.749504)
			(xy 288.693872 -279.749504) (xy 288.697832 -279.70045) (xy 288.709609 -279.652666) (xy 288.7289 -279.60739)
			(xy 288.755203 -279.565794) (xy 288.787838 -279.528957) (xy 288.825959 -279.497832) (xy 288.86858 -279.473225)
			(xy 288.914596 -279.455773) (xy 288.962815 -279.445929) (xy 289.01199 -279.443948) (xy 289.060845 -279.44988)
			(xy 289.108116 -279.463572) (xy 289.152578 -279.48467) (xy 289.193081 -279.512626) (xy 289.228574 -279.546718)
			(xy 289.258139 -279.586062) (xy 289.28101 -279.629639) (xy 289.296594 -279.67632) (xy 289.304489 -279.724897)
			(xy 289.304984 -279.749504) (xy 290.594046 -279.749504) (xy 290.598006 -279.70045) (xy 290.609783 -279.652666)
			(xy 290.629074 -279.60739) (xy 290.655377 -279.565794) (xy 290.688012 -279.528957) (xy 290.726133 -279.497832)
			(xy 290.768754 -279.473225) (xy 290.81477 -279.455773) (xy 290.862989 -279.445929) (xy 290.912164 -279.443948)
			(xy 290.961019 -279.44988) (xy 291.00829 -279.463572) (xy 291.052752 -279.48467) (xy 291.093255 -279.512626)
			(xy 291.128748 -279.546718) (xy 291.158313 -279.586062) (xy 291.181184 -279.629639) (xy 291.196768 -279.67632)
			(xy 291.204663 -279.724897) (xy 291.205158 -279.749504) (xy 292.493966 -279.749504) (xy 292.497926 -279.70045)
			(xy 292.509703 -279.652666) (xy 292.528994 -279.60739) (xy 292.555297 -279.565794) (xy 292.587932 -279.528957)
			(xy 292.626053 -279.497832) (xy 292.668674 -279.473225) (xy 292.71469 -279.455773) (xy 292.762909 -279.445929)
			(xy 292.812084 -279.443948) (xy 292.860939 -279.44988) (xy 292.90821 -279.463572) (xy 292.952672 -279.48467)
			(xy 292.993175 -279.512626) (xy 293.028668 -279.546718) (xy 293.058233 -279.586062) (xy 293.081104 -279.629639)
			(xy 293.096688 -279.67632) (xy 293.104583 -279.724897) (xy 293.105078 -279.749504) (xy 294.393886 -279.749504)
			(xy 294.397846 -279.70045) (xy 294.409623 -279.652666) (xy 294.428914 -279.60739) (xy 294.455217 -279.565794)
			(xy 294.487852 -279.528957) (xy 294.525973 -279.497832) (xy 294.568594 -279.473225) (xy 294.61461 -279.455773)
			(xy 294.662829 -279.445929) (xy 294.712004 -279.443948) (xy 294.760859 -279.44988) (xy 294.80813 -279.463572)
			(xy 294.852592 -279.48467) (xy 294.893095 -279.512626) (xy 294.928588 -279.546718) (xy 294.958153 -279.586062)
			(xy 294.981024 -279.629639) (xy 294.996608 -279.67632) (xy 295.004503 -279.724897) (xy 295.004998 -279.749504)
			(xy 296.29406 -279.749504) (xy 296.29802 -279.70045) (xy 296.309797 -279.652666) (xy 296.329088 -279.60739)
			(xy 296.355391 -279.565794) (xy 296.388026 -279.528957) (xy 296.426147 -279.497832) (xy 296.468768 -279.473225)
			(xy 296.514784 -279.455773) (xy 296.563003 -279.445929) (xy 296.612178 -279.443948) (xy 296.661033 -279.44988)
			(xy 296.708304 -279.463572) (xy 296.752766 -279.48467) (xy 296.793269 -279.512626) (xy 296.828762 -279.546718)
			(xy 296.858327 -279.586062) (xy 296.881198 -279.629639) (xy 296.896782 -279.67632) (xy 296.904677 -279.724897)
			(xy 296.905172 -279.749504) (xy 298.19398 -279.749504) (xy 298.19794 -279.70045) (xy 298.209717 -279.652666)
			(xy 298.229008 -279.60739) (xy 298.255311 -279.565794) (xy 298.287946 -279.528957) (xy 298.326067 -279.497832)
			(xy 298.368688 -279.473225) (xy 298.414704 -279.455773) (xy 298.462923 -279.445929) (xy 298.512098 -279.443948)
			(xy 298.560953 -279.44988) (xy 298.608224 -279.463572) (xy 298.652686 -279.48467) (xy 298.693189 -279.512626)
			(xy 298.728682 -279.546718) (xy 298.758247 -279.586062) (xy 298.781118 -279.629639) (xy 298.796702 -279.67632)
			(xy 298.804597 -279.724897) (xy 298.805092 -279.749504) (xy 300.0939 -279.749504) (xy 300.09786 -279.70045)
			(xy 300.109637 -279.652666) (xy 300.128928 -279.60739) (xy 300.155231 -279.565794) (xy 300.187866 -279.528957)
			(xy 300.225987 -279.497832) (xy 300.268608 -279.473225) (xy 300.314624 -279.455773) (xy 300.362843 -279.445929)
			(xy 300.412018 -279.443948) (xy 300.460873 -279.44988) (xy 300.508144 -279.463572) (xy 300.552606 -279.48467)
			(xy 300.593109 -279.512626) (xy 300.628602 -279.546718) (xy 300.658167 -279.586062) (xy 300.681038 -279.629639)
			(xy 300.696622 -279.67632) (xy 300.704517 -279.724897) (xy 300.705012 -279.749504) (xy 301.994074 -279.749504)
			(xy 301.998034 -279.70045) (xy 302.009811 -279.652666) (xy 302.029102 -279.60739) (xy 302.055405 -279.565794)
			(xy 302.08804 -279.528957) (xy 302.126161 -279.497832) (xy 302.168782 -279.473225) (xy 302.214798 -279.455773)
			(xy 302.263017 -279.445929) (xy 302.312192 -279.443948) (xy 302.361047 -279.44988) (xy 302.408318 -279.463572)
			(xy 302.45278 -279.48467) (xy 302.493283 -279.512626) (xy 302.528776 -279.546718) (xy 302.558341 -279.586062)
			(xy 302.581212 -279.629639) (xy 302.596796 -279.67632) (xy 302.604691 -279.724897) (xy 302.605186 -279.749504)
			(xy 303.893994 -279.749504) (xy 303.897954 -279.70045) (xy 303.909731 -279.652666) (xy 303.929022 -279.60739)
			(xy 303.955325 -279.565794) (xy 303.98796 -279.528957) (xy 304.026081 -279.497832) (xy 304.068702 -279.473225)
			(xy 304.114718 -279.455773) (xy 304.162937 -279.445929) (xy 304.212112 -279.443948) (xy 304.260967 -279.44988)
			(xy 304.308238 -279.463572) (xy 304.3527 -279.48467) (xy 304.393203 -279.512626) (xy 304.428696 -279.546718)
			(xy 304.458261 -279.586062) (xy 304.481132 -279.629639) (xy 304.496716 -279.67632) (xy 304.504611 -279.724897)
			(xy 304.505106 -279.749504) (xy 305.793914 -279.749504) (xy 305.797874 -279.70045) (xy 305.809651 -279.652666)
			(xy 305.828942 -279.60739) (xy 305.855245 -279.565794) (xy 305.88788 -279.528957) (xy 305.926001 -279.497832)
			(xy 305.968622 -279.473225) (xy 306.014638 -279.455773) (xy 306.062857 -279.445929) (xy 306.112032 -279.443948)
			(xy 306.160887 -279.44988) (xy 306.208158 -279.463572) (xy 306.25262 -279.48467) (xy 306.293123 -279.512626)
			(xy 306.328616 -279.546718) (xy 306.358181 -279.586062) (xy 306.381052 -279.629639) (xy 306.396636 -279.67632)
			(xy 306.404531 -279.724897) (xy 306.405026 -279.749504) (xy 307.694088 -279.749504) (xy 307.698048 -279.70045)
			(xy 307.709825 -279.652666) (xy 307.729116 -279.60739) (xy 307.755419 -279.565794) (xy 307.788054 -279.528957)
			(xy 307.826175 -279.497832) (xy 307.868796 -279.473225) (xy 307.914812 -279.455773) (xy 307.963031 -279.445929)
			(xy 308.012206 -279.443948) (xy 308.061061 -279.44988) (xy 308.108332 -279.463572) (xy 308.152794 -279.48467)
			(xy 308.193297 -279.512626) (xy 308.22879 -279.546718) (xy 308.258355 -279.586062) (xy 308.281226 -279.629639)
			(xy 308.29681 -279.67632) (xy 308.304705 -279.724897) (xy 308.3052 -279.749504) (xy 309.594008 -279.749504)
			(xy 309.597968 -279.70045) (xy 309.609745 -279.652666) (xy 309.629036 -279.60739) (xy 309.655339 -279.565794)
			(xy 309.687974 -279.528957) (xy 309.726095 -279.497832) (xy 309.768716 -279.473225) (xy 309.814732 -279.455773)
			(xy 309.862951 -279.445929) (xy 309.912126 -279.443948) (xy 309.960981 -279.44988) (xy 310.008252 -279.463572)
			(xy 310.052714 -279.48467) (xy 310.093217 -279.512626) (xy 310.12871 -279.546718) (xy 310.158275 -279.586062)
			(xy 310.181146 -279.629639) (xy 310.19673 -279.67632) (xy 310.204625 -279.724897) (xy 310.20512 -279.749504)
			(xy 310.205115 -279.749758) (xy 311.493928 -279.749758) (xy 311.497888 -279.700704) (xy 311.509665 -279.65292)
			(xy 311.528956 -279.607644) (xy 311.555259 -279.566048) (xy 311.587894 -279.529211) (xy 311.626015 -279.498086)
			(xy 311.668636 -279.473479) (xy 311.714652 -279.456027) (xy 311.762871 -279.446183) (xy 311.812046 -279.444202)
			(xy 311.860901 -279.450134) (xy 311.908172 -279.463826) (xy 311.952634 -279.484924) (xy 311.993137 -279.51288)
			(xy 312.02863 -279.546972) (xy 312.058195 -279.586316) (xy 312.081066 -279.629893) (xy 312.09665 -279.676574)
			(xy 312.104545 -279.725151) (xy 312.10504 -279.749758) (xy 313.394102 -279.749758) (xy 313.398062 -279.700704)
			(xy 313.409839 -279.65292) (xy 313.42913 -279.607644) (xy 313.455433 -279.566048) (xy 313.488068 -279.529211)
			(xy 313.526189 -279.498086) (xy 313.56881 -279.473479) (xy 313.614826 -279.456027) (xy 313.663045 -279.446183)
			(xy 313.71222 -279.444202) (xy 313.761075 -279.450134) (xy 313.808346 -279.463826) (xy 313.852808 -279.484924)
			(xy 313.893311 -279.51288) (xy 313.928804 -279.546972) (xy 313.958369 -279.586316) (xy 313.98124 -279.629893)
			(xy 313.996824 -279.676574) (xy 314.004719 -279.725151) (xy 314.005214 -279.749758) (xy 314.344062 -279.749758)
			(xy 314.348022 -279.700704) (xy 314.359799 -279.65292) (xy 314.37909 -279.607644) (xy 314.405393 -279.566048)
			(xy 314.438028 -279.529211) (xy 314.476149 -279.498086) (xy 314.51877 -279.473479) (xy 314.564786 -279.456027)
			(xy 314.613005 -279.446183) (xy 314.66218 -279.444202) (xy 314.711035 -279.450134) (xy 314.758306 -279.463826)
			(xy 314.802768 -279.484924) (xy 314.843271 -279.51288) (xy 314.878764 -279.546972) (xy 314.908329 -279.586316)
			(xy 314.9312 -279.629893) (xy 314.946784 -279.676574) (xy 314.954679 -279.725151) (xy 314.955169 -279.749504)
			(xy 393.394196 -279.749504) (xy 393.398156 -279.70045) (xy 393.409933 -279.652666) (xy 393.429224 -279.60739)
			(xy 393.455527 -279.565794) (xy 393.488162 -279.528957) (xy 393.526283 -279.497832) (xy 393.568904 -279.473225)
			(xy 393.61492 -279.455773) (xy 393.663139 -279.445929) (xy 393.712314 -279.443948) (xy 393.761169 -279.44988)
			(xy 393.80844 -279.463572) (xy 393.852902 -279.48467) (xy 393.893405 -279.512626) (xy 393.928898 -279.546718)
			(xy 393.958463 -279.586062) (xy 393.981334 -279.629639) (xy 393.996918 -279.67632) (xy 394.004813 -279.724897)
			(xy 394.005308 -279.749504) (xy 395.294116 -279.749504) (xy 395.298076 -279.70045) (xy 395.309853 -279.652666)
			(xy 395.329144 -279.60739) (xy 395.355447 -279.565794) (xy 395.388082 -279.528957) (xy 395.426203 -279.497832)
			(xy 395.468824 -279.473225) (xy 395.51484 -279.455773) (xy 395.563059 -279.445929) (xy 395.612234 -279.443948)
			(xy 395.661089 -279.44988) (xy 395.70836 -279.463572) (xy 395.752822 -279.48467) (xy 395.793325 -279.512626)
			(xy 395.828818 -279.546718) (xy 395.858383 -279.586062) (xy 395.881254 -279.629639) (xy 395.896838 -279.67632)
			(xy 395.904733 -279.724897) (xy 395.905228 -279.749504) (xy 397.194036 -279.749504) (xy 397.197996 -279.70045)
			(xy 397.209773 -279.652666) (xy 397.229064 -279.60739) (xy 397.255367 -279.565794) (xy 397.288002 -279.528957)
			(xy 397.326123 -279.497832) (xy 397.368744 -279.473225) (xy 397.41476 -279.455773) (xy 397.462979 -279.445929)
			(xy 397.512154 -279.443948) (xy 397.561009 -279.44988) (xy 397.60828 -279.463572) (xy 397.652742 -279.48467)
			(xy 397.693245 -279.512626) (xy 397.728738 -279.546718) (xy 397.758303 -279.586062) (xy 397.781174 -279.629639)
			(xy 397.796758 -279.67632) (xy 397.804653 -279.724897) (xy 397.805148 -279.749504) (xy 399.09421 -279.749504)
			(xy 399.09817 -279.70045) (xy 399.109947 -279.652666) (xy 399.129238 -279.60739) (xy 399.155541 -279.565794)
			(xy 399.188176 -279.528957) (xy 399.226297 -279.497832) (xy 399.268918 -279.473225) (xy 399.314934 -279.455773)
			(xy 399.363153 -279.445929) (xy 399.412328 -279.443948) (xy 399.461183 -279.44988) (xy 399.508454 -279.463572)
			(xy 399.552916 -279.48467) (xy 399.593419 -279.512626) (xy 399.628912 -279.546718) (xy 399.658477 -279.586062)
			(xy 399.681348 -279.629639) (xy 399.696932 -279.67632) (xy 399.704827 -279.724897) (xy 399.705322 -279.749504)
			(xy 400.99413 -279.749504) (xy 400.99809 -279.70045) (xy 401.009867 -279.652666) (xy 401.029158 -279.60739)
			(xy 401.055461 -279.565794) (xy 401.088096 -279.528957) (xy 401.126217 -279.497832) (xy 401.168838 -279.473225)
			(xy 401.214854 -279.455773) (xy 401.263073 -279.445929) (xy 401.312248 -279.443948) (xy 401.361103 -279.44988)
			(xy 401.408374 -279.463572) (xy 401.452836 -279.48467) (xy 401.493339 -279.512626) (xy 401.528832 -279.546718)
			(xy 401.558397 -279.586062) (xy 401.581268 -279.629639) (xy 401.596852 -279.67632) (xy 401.604747 -279.724897)
			(xy 401.605242 -279.749504) (xy 402.89405 -279.749504) (xy 402.89801 -279.70045) (xy 402.909787 -279.652666)
			(xy 402.929078 -279.60739) (xy 402.955381 -279.565794) (xy 402.988016 -279.528957) (xy 403.026137 -279.497832)
			(xy 403.068758 -279.473225) (xy 403.114774 -279.455773) (xy 403.162993 -279.445929) (xy 403.212168 -279.443948)
			(xy 403.261023 -279.44988) (xy 403.308294 -279.463572) (xy 403.352756 -279.48467) (xy 403.393259 -279.512626)
			(xy 403.428752 -279.546718) (xy 403.458317 -279.586062) (xy 403.481188 -279.629639) (xy 403.496772 -279.67632)
			(xy 403.504667 -279.724897) (xy 403.505162 -279.749504) (xy 404.79397 -279.749504) (xy 404.79793 -279.70045)
			(xy 404.809707 -279.652666) (xy 404.828998 -279.60739) (xy 404.855301 -279.565794) (xy 404.887936 -279.528957)
			(xy 404.926057 -279.497832) (xy 404.968678 -279.473225) (xy 405.014694 -279.455773) (xy 405.062913 -279.445929)
			(xy 405.112088 -279.443948) (xy 405.160943 -279.44988) (xy 405.208214 -279.463572) (xy 405.252676 -279.48467)
			(xy 405.293179 -279.512626) (xy 405.328672 -279.546718) (xy 405.358237 -279.586062) (xy 405.381108 -279.629639)
			(xy 405.396692 -279.67632) (xy 405.404587 -279.724897) (xy 405.405082 -279.749504) (xy 406.694144 -279.749504)
			(xy 406.698104 -279.70045) (xy 406.709881 -279.652666) (xy 406.729172 -279.60739) (xy 406.755475 -279.565794)
			(xy 406.78811 -279.528957) (xy 406.826231 -279.497832) (xy 406.868852 -279.473225) (xy 406.914868 -279.455773)
			(xy 406.963087 -279.445929) (xy 407.012262 -279.443948) (xy 407.061117 -279.44988) (xy 407.108388 -279.463572)
			(xy 407.15285 -279.48467) (xy 407.193353 -279.512626) (xy 407.228846 -279.546718) (xy 407.258411 -279.586062)
			(xy 407.281282 -279.629639) (xy 407.296866 -279.67632) (xy 407.304761 -279.724897) (xy 407.305256 -279.749504)
			(xy 408.594064 -279.749504) (xy 408.598024 -279.70045) (xy 408.609801 -279.652666) (xy 408.629092 -279.60739)
			(xy 408.655395 -279.565794) (xy 408.68803 -279.528957) (xy 408.726151 -279.497832) (xy 408.768772 -279.473225)
			(xy 408.814788 -279.455773) (xy 408.863007 -279.445929) (xy 408.912182 -279.443948) (xy 408.961037 -279.44988)
			(xy 409.008308 -279.463572) (xy 409.05277 -279.48467) (xy 409.093273 -279.512626) (xy 409.128766 -279.546718)
			(xy 409.158331 -279.586062) (xy 409.181202 -279.629639) (xy 409.196786 -279.67632) (xy 409.204681 -279.724897)
			(xy 409.205176 -279.749504) (xy 410.493984 -279.749504) (xy 410.497944 -279.70045) (xy 410.509721 -279.652666)
			(xy 410.529012 -279.60739) (xy 410.555315 -279.565794) (xy 410.58795 -279.528957) (xy 410.626071 -279.497832)
			(xy 410.668692 -279.473225) (xy 410.714708 -279.455773) (xy 410.762927 -279.445929) (xy 410.812102 -279.443948)
			(xy 410.860957 -279.44988) (xy 410.908228 -279.463572) (xy 410.95269 -279.48467) (xy 410.993193 -279.512626)
			(xy 411.028686 -279.546718) (xy 411.058251 -279.586062) (xy 411.081122 -279.629639) (xy 411.096706 -279.67632)
			(xy 411.104601 -279.724897) (xy 411.105096 -279.749504) (xy 412.394158 -279.749504) (xy 412.398118 -279.70045)
			(xy 412.409895 -279.652666) (xy 412.429186 -279.60739) (xy 412.455489 -279.565794) (xy 412.488124 -279.528957)
			(xy 412.526245 -279.497832) (xy 412.568866 -279.473225) (xy 412.614882 -279.455773) (xy 412.663101 -279.445929)
			(xy 412.712276 -279.443948) (xy 412.761131 -279.44988) (xy 412.808402 -279.463572) (xy 412.852864 -279.48467)
			(xy 412.893367 -279.512626) (xy 412.92886 -279.546718) (xy 412.958425 -279.586062) (xy 412.981296 -279.629639)
			(xy 412.99688 -279.67632) (xy 413.004775 -279.724897) (xy 413.00527 -279.749504) (xy 414.294078 -279.749504)
			(xy 414.298038 -279.70045) (xy 414.309815 -279.652666) (xy 414.329106 -279.60739) (xy 414.355409 -279.565794)
			(xy 414.388044 -279.528957) (xy 414.426165 -279.497832) (xy 414.468786 -279.473225) (xy 414.514802 -279.455773)
			(xy 414.563021 -279.445929) (xy 414.612196 -279.443948) (xy 414.661051 -279.44988) (xy 414.708322 -279.463572)
			(xy 414.752784 -279.48467) (xy 414.793287 -279.512626) (xy 414.82878 -279.546718) (xy 414.858345 -279.586062)
			(xy 414.881216 -279.629639) (xy 414.8968 -279.67632) (xy 414.904695 -279.724897) (xy 414.90519 -279.749504)
			(xy 416.193998 -279.749504) (xy 416.197958 -279.70045) (xy 416.209735 -279.652666) (xy 416.229026 -279.60739)
			(xy 416.255329 -279.565794) (xy 416.287964 -279.528957) (xy 416.326085 -279.497832) (xy 416.368706 -279.473225)
			(xy 416.414722 -279.455773) (xy 416.462941 -279.445929) (xy 416.512116 -279.443948) (xy 416.560971 -279.44988)
			(xy 416.608242 -279.463572) (xy 416.652704 -279.48467) (xy 416.693207 -279.512626) (xy 416.7287 -279.546718)
			(xy 416.758265 -279.586062) (xy 416.781136 -279.629639) (xy 416.79672 -279.67632) (xy 416.804615 -279.724897)
			(xy 416.80511 -279.749504) (xy 418.094172 -279.749504) (xy 418.098132 -279.70045) (xy 418.109909 -279.652666)
			(xy 418.1292 -279.60739) (xy 418.155503 -279.565794) (xy 418.188138 -279.528957) (xy 418.226259 -279.497832)
			(xy 418.26888 -279.473225) (xy 418.314896 -279.455773) (xy 418.363115 -279.445929) (xy 418.41229 -279.443948)
			(xy 418.461145 -279.44988) (xy 418.508416 -279.463572) (xy 418.552878 -279.48467) (xy 418.593381 -279.512626)
			(xy 418.628874 -279.546718) (xy 418.658439 -279.586062) (xy 418.68131 -279.629639) (xy 418.696894 -279.67632)
			(xy 418.704789 -279.724897) (xy 418.705284 -279.749504) (xy 419.994092 -279.749504) (xy 419.998052 -279.70045)
			(xy 420.009829 -279.652666) (xy 420.02912 -279.60739) (xy 420.055423 -279.565794) (xy 420.088058 -279.528957)
			(xy 420.126179 -279.497832) (xy 420.1688 -279.473225) (xy 420.214816 -279.455773) (xy 420.263035 -279.445929)
			(xy 420.31221 -279.443948) (xy 420.361065 -279.44988) (xy 420.408336 -279.463572) (xy 420.452798 -279.48467)
			(xy 420.493301 -279.512626) (xy 420.528794 -279.546718) (xy 420.558359 -279.586062) (xy 420.58123 -279.629639)
			(xy 420.596814 -279.67632) (xy 420.604709 -279.724897) (xy 420.605204 -279.749504) (xy 421.894012 -279.749504)
			(xy 421.897972 -279.70045) (xy 421.909749 -279.652666) (xy 421.92904 -279.60739) (xy 421.955343 -279.565794)
			(xy 421.987978 -279.528957) (xy 422.026099 -279.497832) (xy 422.06872 -279.473225) (xy 422.114736 -279.455773)
			(xy 422.162955 -279.445929) (xy 422.21213 -279.443948) (xy 422.260985 -279.44988) (xy 422.308256 -279.463572)
			(xy 422.352718 -279.48467) (xy 422.393221 -279.512626) (xy 422.428714 -279.546718) (xy 422.458279 -279.586062)
			(xy 422.48115 -279.629639) (xy 422.496734 -279.67632) (xy 422.504629 -279.724897) (xy 422.505124 -279.749504)
			(xy 423.794186 -279.749504) (xy 423.798146 -279.70045) (xy 423.809923 -279.652666) (xy 423.829214 -279.60739)
			(xy 423.855517 -279.565794) (xy 423.888152 -279.528957) (xy 423.926273 -279.497832) (xy 423.968894 -279.473225)
			(xy 424.01491 -279.455773) (xy 424.063129 -279.445929) (xy 424.112304 -279.443948) (xy 424.161159 -279.44988)
			(xy 424.20843 -279.463572) (xy 424.252892 -279.48467) (xy 424.293395 -279.512626) (xy 424.328888 -279.546718)
			(xy 424.358453 -279.586062) (xy 424.381324 -279.629639) (xy 424.396908 -279.67632) (xy 424.404803 -279.724897)
			(xy 424.405298 -279.749504) (xy 425.694106 -279.749504) (xy 425.698066 -279.70045) (xy 425.709843 -279.652666)
			(xy 425.729134 -279.60739) (xy 425.755437 -279.565794) (xy 425.788072 -279.528957) (xy 425.826193 -279.497832)
			(xy 425.868814 -279.473225) (xy 425.91483 -279.455773) (xy 425.963049 -279.445929) (xy 426.012224 -279.443948)
			(xy 426.061079 -279.44988) (xy 426.10835 -279.463572) (xy 426.152812 -279.48467) (xy 426.193315 -279.512626)
			(xy 426.228808 -279.546718) (xy 426.258373 -279.586062) (xy 426.281244 -279.629639) (xy 426.296828 -279.67632)
			(xy 426.304723 -279.724897) (xy 426.305218 -279.749504) (xy 426.305213 -279.749758) (xy 427.594026 -279.749758)
			(xy 427.597986 -279.700704) (xy 427.609763 -279.65292) (xy 427.629054 -279.607644) (xy 427.655357 -279.566048)
			(xy 427.687992 -279.529211) (xy 427.726113 -279.498086) (xy 427.768734 -279.473479) (xy 427.81475 -279.456027)
			(xy 427.862969 -279.446183) (xy 427.912144 -279.444202) (xy 427.960999 -279.450134) (xy 428.00827 -279.463826)
			(xy 428.052732 -279.484924) (xy 428.093235 -279.51288) (xy 428.128728 -279.546972) (xy 428.158293 -279.586316)
			(xy 428.181164 -279.629893) (xy 428.196748 -279.676574) (xy 428.204643 -279.725151) (xy 428.205138 -279.749758)
			(xy 429.4942 -279.749758) (xy 429.49816 -279.700704) (xy 429.509937 -279.65292) (xy 429.529228 -279.607644)
			(xy 429.555531 -279.566048) (xy 429.588166 -279.529211) (xy 429.626287 -279.498086) (xy 429.668908 -279.473479)
			(xy 429.714924 -279.456027) (xy 429.763143 -279.446183) (xy 429.812318 -279.444202) (xy 429.861173 -279.450134)
			(xy 429.908444 -279.463826) (xy 429.952906 -279.484924) (xy 429.993409 -279.51288) (xy 430.028902 -279.546972)
			(xy 430.058467 -279.586316) (xy 430.081338 -279.629893) (xy 430.096922 -279.676574) (xy 430.104817 -279.725151)
			(xy 430.105312 -279.749758) (xy 430.44416 -279.749758) (xy 430.44812 -279.700704) (xy 430.459897 -279.65292)
			(xy 430.479188 -279.607644) (xy 430.505491 -279.566048) (xy 430.538126 -279.529211) (xy 430.576247 -279.498086)
			(xy 430.618868 -279.473479) (xy 430.664884 -279.456027) (xy 430.713103 -279.446183) (xy 430.762278 -279.444202)
			(xy 430.811133 -279.450134) (xy 430.858404 -279.463826) (xy 430.902866 -279.484924) (xy 430.943369 -279.51288)
			(xy 430.978862 -279.546972) (xy 431.008427 -279.586316) (xy 431.031298 -279.629893) (xy 431.046882 -279.676574)
			(xy 431.054777 -279.725151) (xy 431.055272 -279.749758) (xy 431.054777 -279.774365) (xy 431.046882 -279.822942)
			(xy 431.031298 -279.869623) (xy 431.008427 -279.9132) (xy 430.978862 -279.952544) (xy 430.943369 -279.986636)
			(xy 430.902866 -280.014592) (xy 430.858404 -280.03569) (xy 430.811133 -280.049382) (xy 430.762278 -280.055314)
			(xy 430.713103 -280.053333) (xy 430.664884 -280.043489) (xy 430.618868 -280.026037) (xy 430.576247 -280.00143)
			(xy 430.538126 -279.970305) (xy 430.505491 -279.933468) (xy 430.479188 -279.891872) (xy 430.459897 -279.846596)
			(xy 430.44812 -279.798812) (xy 430.44416 -279.749758) (xy 430.105312 -279.749758) (xy 430.104817 -279.774365)
			(xy 430.096922 -279.822942) (xy 430.081338 -279.869623) (xy 430.058467 -279.9132) (xy 430.028902 -279.952544)
			(xy 429.993409 -279.986636) (xy 429.952906 -280.014592) (xy 429.908444 -280.03569) (xy 429.861173 -280.049382)
			(xy 429.812318 -280.055314) (xy 429.763143 -280.053333) (xy 429.714924 -280.043489) (xy 429.668908 -280.026037)
			(xy 429.626287 -280.00143) (xy 429.588166 -279.970305) (xy 429.555531 -279.933468) (xy 429.529228 -279.891872)
			(xy 429.509937 -279.846596) (xy 429.49816 -279.798812) (xy 429.4942 -279.749758) (xy 428.205138 -279.749758)
			(xy 428.204643 -279.774365) (xy 428.196748 -279.822942) (xy 428.181164 -279.869623) (xy 428.158293 -279.9132)
			(xy 428.128728 -279.952544) (xy 428.093235 -279.986636) (xy 428.052732 -280.014592) (xy 428.00827 -280.03569)
			(xy 427.960999 -280.049382) (xy 427.912144 -280.055314) (xy 427.862969 -280.053333) (xy 427.81475 -280.043489)
			(xy 427.768734 -280.026037) (xy 427.726113 -280.00143) (xy 427.687992 -279.970305) (xy 427.655357 -279.933468)
			(xy 427.629054 -279.891872) (xy 427.609763 -279.846596) (xy 427.597986 -279.798812) (xy 427.594026 -279.749758)
			(xy 426.305213 -279.749758) (xy 426.304723 -279.774111) (xy 426.296828 -279.822688) (xy 426.281244 -279.869369)
			(xy 426.258373 -279.912946) (xy 426.228808 -279.95229) (xy 426.193315 -279.986382) (xy 426.152812 -280.014338)
			(xy 426.10835 -280.035436) (xy 426.061079 -280.049128) (xy 426.012224 -280.05506) (xy 425.963049 -280.053079)
			(xy 425.91483 -280.043235) (xy 425.868814 -280.025783) (xy 425.826193 -280.001176) (xy 425.788072 -279.970051)
			(xy 425.755437 -279.933214) (xy 425.729134 -279.891618) (xy 425.709843 -279.846342) (xy 425.698066 -279.798558)
			(xy 425.694106 -279.749504) (xy 424.405298 -279.749504) (xy 424.404803 -279.774111) (xy 424.396908 -279.822688)
			(xy 424.381324 -279.869369) (xy 424.358453 -279.912946) (xy 424.328888 -279.95229) (xy 424.293395 -279.986382)
			(xy 424.252892 -280.014338) (xy 424.20843 -280.035436) (xy 424.161159 -280.049128) (xy 424.112304 -280.05506)
			(xy 424.063129 -280.053079) (xy 424.01491 -280.043235) (xy 423.968894 -280.025783) (xy 423.926273 -280.001176)
			(xy 423.888152 -279.970051) (xy 423.855517 -279.933214) (xy 423.829214 -279.891618) (xy 423.809923 -279.846342)
			(xy 423.798146 -279.798558) (xy 423.794186 -279.749504) (xy 422.505124 -279.749504) (xy 422.504629 -279.774111)
			(xy 422.496734 -279.822688) (xy 422.48115 -279.869369) (xy 422.458279 -279.912946) (xy 422.428714 -279.95229)
			(xy 422.393221 -279.986382) (xy 422.352718 -280.014338) (xy 422.308256 -280.035436) (xy 422.260985 -280.049128)
			(xy 422.21213 -280.05506) (xy 422.162955 -280.053079) (xy 422.114736 -280.043235) (xy 422.06872 -280.025783)
			(xy 422.026099 -280.001176) (xy 421.987978 -279.970051) (xy 421.955343 -279.933214) (xy 421.92904 -279.891618)
			(xy 421.909749 -279.846342) (xy 421.897972 -279.798558) (xy 421.894012 -279.749504) (xy 420.605204 -279.749504)
			(xy 420.604709 -279.774111) (xy 420.596814 -279.822688) (xy 420.58123 -279.869369) (xy 420.558359 -279.912946)
			(xy 420.528794 -279.95229) (xy 420.493301 -279.986382) (xy 420.452798 -280.014338) (xy 420.408336 -280.035436)
			(xy 420.361065 -280.049128) (xy 420.31221 -280.05506) (xy 420.263035 -280.053079) (xy 420.214816 -280.043235)
			(xy 420.1688 -280.025783) (xy 420.126179 -280.001176) (xy 420.088058 -279.970051) (xy 420.055423 -279.933214)
			(xy 420.02912 -279.891618) (xy 420.009829 -279.846342) (xy 419.998052 -279.798558) (xy 419.994092 -279.749504)
			(xy 418.705284 -279.749504) (xy 418.704789 -279.774111) (xy 418.696894 -279.822688) (xy 418.68131 -279.869369)
			(xy 418.658439 -279.912946) (xy 418.628874 -279.95229) (xy 418.593381 -279.986382) (xy 418.552878 -280.014338)
			(xy 418.508416 -280.035436) (xy 418.461145 -280.049128) (xy 418.41229 -280.05506) (xy 418.363115 -280.053079)
			(xy 418.314896 -280.043235) (xy 418.26888 -280.025783) (xy 418.226259 -280.001176) (xy 418.188138 -279.970051)
			(xy 418.155503 -279.933214) (xy 418.1292 -279.891618) (xy 418.109909 -279.846342) (xy 418.098132 -279.798558)
			(xy 418.094172 -279.749504) (xy 416.80511 -279.749504) (xy 416.804615 -279.774111) (xy 416.79672 -279.822688)
			(xy 416.781136 -279.869369) (xy 416.758265 -279.912946) (xy 416.7287 -279.95229) (xy 416.693207 -279.986382)
			(xy 416.652704 -280.014338) (xy 416.608242 -280.035436) (xy 416.560971 -280.049128) (xy 416.512116 -280.05506)
			(xy 416.462941 -280.053079) (xy 416.414722 -280.043235) (xy 416.368706 -280.025783) (xy 416.326085 -280.001176)
			(xy 416.287964 -279.970051) (xy 416.255329 -279.933214) (xy 416.229026 -279.891618) (xy 416.209735 -279.846342)
			(xy 416.197958 -279.798558) (xy 416.193998 -279.749504) (xy 414.90519 -279.749504) (xy 414.904695 -279.774111)
			(xy 414.8968 -279.822688) (xy 414.881216 -279.869369) (xy 414.858345 -279.912946) (xy 414.82878 -279.95229)
			(xy 414.793287 -279.986382) (xy 414.752784 -280.014338) (xy 414.708322 -280.035436) (xy 414.661051 -280.049128)
			(xy 414.612196 -280.05506) (xy 414.563021 -280.053079) (xy 414.514802 -280.043235) (xy 414.468786 -280.025783)
			(xy 414.426165 -280.001176) (xy 414.388044 -279.970051) (xy 414.355409 -279.933214) (xy 414.329106 -279.891618)
			(xy 414.309815 -279.846342) (xy 414.298038 -279.798558) (xy 414.294078 -279.749504) (xy 413.00527 -279.749504)
			(xy 413.004775 -279.774111) (xy 412.99688 -279.822688) (xy 412.981296 -279.869369) (xy 412.958425 -279.912946)
			(xy 412.92886 -279.95229) (xy 412.893367 -279.986382) (xy 412.852864 -280.014338) (xy 412.808402 -280.035436)
			(xy 412.761131 -280.049128) (xy 412.712276 -280.05506) (xy 412.663101 -280.053079) (xy 412.614882 -280.043235)
			(xy 412.568866 -280.025783) (xy 412.526245 -280.001176) (xy 412.488124 -279.970051) (xy 412.455489 -279.933214)
			(xy 412.429186 -279.891618) (xy 412.409895 -279.846342) (xy 412.398118 -279.798558) (xy 412.394158 -279.749504)
			(xy 411.105096 -279.749504) (xy 411.104601 -279.774111) (xy 411.096706 -279.822688) (xy 411.081122 -279.869369)
			(xy 411.058251 -279.912946) (xy 411.028686 -279.95229) (xy 410.993193 -279.986382) (xy 410.95269 -280.014338)
			(xy 410.908228 -280.035436) (xy 410.860957 -280.049128) (xy 410.812102 -280.05506) (xy 410.762927 -280.053079)
			(xy 410.714708 -280.043235) (xy 410.668692 -280.025783) (xy 410.626071 -280.001176) (xy 410.58795 -279.970051)
			(xy 410.555315 -279.933214) (xy 410.529012 -279.891618) (xy 410.509721 -279.846342) (xy 410.497944 -279.798558)
			(xy 410.493984 -279.749504) (xy 409.205176 -279.749504) (xy 409.204681 -279.774111) (xy 409.196786 -279.822688)
			(xy 409.181202 -279.869369) (xy 409.158331 -279.912946) (xy 409.128766 -279.95229) (xy 409.093273 -279.986382)
			(xy 409.05277 -280.014338) (xy 409.008308 -280.035436) (xy 408.961037 -280.049128) (xy 408.912182 -280.05506)
			(xy 408.863007 -280.053079) (xy 408.814788 -280.043235) (xy 408.768772 -280.025783) (xy 408.726151 -280.001176)
			(xy 408.68803 -279.970051) (xy 408.655395 -279.933214) (xy 408.629092 -279.891618) (xy 408.609801 -279.846342)
			(xy 408.598024 -279.798558) (xy 408.594064 -279.749504) (xy 407.305256 -279.749504) (xy 407.304761 -279.774111)
			(xy 407.296866 -279.822688) (xy 407.281282 -279.869369) (xy 407.258411 -279.912946) (xy 407.228846 -279.95229)
			(xy 407.193353 -279.986382) (xy 407.15285 -280.014338) (xy 407.108388 -280.035436) (xy 407.061117 -280.049128)
			(xy 407.012262 -280.05506) (xy 406.963087 -280.053079) (xy 406.914868 -280.043235) (xy 406.868852 -280.025783)
			(xy 406.826231 -280.001176) (xy 406.78811 -279.970051) (xy 406.755475 -279.933214) (xy 406.729172 -279.891618)
			(xy 406.709881 -279.846342) (xy 406.698104 -279.798558) (xy 406.694144 -279.749504) (xy 405.405082 -279.749504)
			(xy 405.404587 -279.774111) (xy 405.396692 -279.822688) (xy 405.381108 -279.869369) (xy 405.358237 -279.912946)
			(xy 405.328672 -279.95229) (xy 405.293179 -279.986382) (xy 405.252676 -280.014338) (xy 405.208214 -280.035436)
			(xy 405.160943 -280.049128) (xy 405.112088 -280.05506) (xy 405.062913 -280.053079) (xy 405.014694 -280.043235)
			(xy 404.968678 -280.025783) (xy 404.926057 -280.001176) (xy 404.887936 -279.970051) (xy 404.855301 -279.933214)
			(xy 404.828998 -279.891618) (xy 404.809707 -279.846342) (xy 404.79793 -279.798558) (xy 404.79397 -279.749504)
			(xy 403.505162 -279.749504) (xy 403.504667 -279.774111) (xy 403.496772 -279.822688) (xy 403.481188 -279.869369)
			(xy 403.458317 -279.912946) (xy 403.428752 -279.95229) (xy 403.393259 -279.986382) (xy 403.352756 -280.014338)
			(xy 403.308294 -280.035436) (xy 403.261023 -280.049128) (xy 403.212168 -280.05506) (xy 403.162993 -280.053079)
			(xy 403.114774 -280.043235) (xy 403.068758 -280.025783) (xy 403.026137 -280.001176) (xy 402.988016 -279.970051)
			(xy 402.955381 -279.933214) (xy 402.929078 -279.891618) (xy 402.909787 -279.846342) (xy 402.89801 -279.798558)
			(xy 402.89405 -279.749504) (xy 401.605242 -279.749504) (xy 401.604747 -279.774111) (xy 401.596852 -279.822688)
			(xy 401.581268 -279.869369) (xy 401.558397 -279.912946) (xy 401.528832 -279.95229) (xy 401.493339 -279.986382)
			(xy 401.452836 -280.014338) (xy 401.408374 -280.035436) (xy 401.361103 -280.049128) (xy 401.312248 -280.05506)
			(xy 401.263073 -280.053079) (xy 401.214854 -280.043235) (xy 401.168838 -280.025783) (xy 401.126217 -280.001176)
			(xy 401.088096 -279.970051) (xy 401.055461 -279.933214) (xy 401.029158 -279.891618) (xy 401.009867 -279.846342)
			(xy 400.99809 -279.798558) (xy 400.99413 -279.749504) (xy 399.705322 -279.749504) (xy 399.704827 -279.774111)
			(xy 399.696932 -279.822688) (xy 399.681348 -279.869369) (xy 399.658477 -279.912946) (xy 399.628912 -279.95229)
			(xy 399.593419 -279.986382) (xy 399.552916 -280.014338) (xy 399.508454 -280.035436) (xy 399.461183 -280.049128)
			(xy 399.412328 -280.05506) (xy 399.363153 -280.053079) (xy 399.314934 -280.043235) (xy 399.268918 -280.025783)
			(xy 399.226297 -280.001176) (xy 399.188176 -279.970051) (xy 399.155541 -279.933214) (xy 399.129238 -279.891618)
			(xy 399.109947 -279.846342) (xy 399.09817 -279.798558) (xy 399.09421 -279.749504) (xy 397.805148 -279.749504)
			(xy 397.804653 -279.774111) (xy 397.796758 -279.822688) (xy 397.781174 -279.869369) (xy 397.758303 -279.912946)
			(xy 397.728738 -279.95229) (xy 397.693245 -279.986382) (xy 397.652742 -280.014338) (xy 397.60828 -280.035436)
			(xy 397.561009 -280.049128) (xy 397.512154 -280.05506) (xy 397.462979 -280.053079) (xy 397.41476 -280.043235)
			(xy 397.368744 -280.025783) (xy 397.326123 -280.001176) (xy 397.288002 -279.970051) (xy 397.255367 -279.933214)
			(xy 397.229064 -279.891618) (xy 397.209773 -279.846342) (xy 397.197996 -279.798558) (xy 397.194036 -279.749504)
			(xy 395.905228 -279.749504) (xy 395.904733 -279.774111) (xy 395.896838 -279.822688) (xy 395.881254 -279.869369)
			(xy 395.858383 -279.912946) (xy 395.828818 -279.95229) (xy 395.793325 -279.986382) (xy 395.752822 -280.014338)
			(xy 395.70836 -280.035436) (xy 395.661089 -280.049128) (xy 395.612234 -280.05506) (xy 395.563059 -280.053079)
			(xy 395.51484 -280.043235) (xy 395.468824 -280.025783) (xy 395.426203 -280.001176) (xy 395.388082 -279.970051)
			(xy 395.355447 -279.933214) (xy 395.329144 -279.891618) (xy 395.309853 -279.846342) (xy 395.298076 -279.798558)
			(xy 395.294116 -279.749504) (xy 394.005308 -279.749504) (xy 394.004813 -279.774111) (xy 393.996918 -279.822688)
			(xy 393.981334 -279.869369) (xy 393.958463 -279.912946) (xy 393.928898 -279.95229) (xy 393.893405 -279.986382)
			(xy 393.852902 -280.014338) (xy 393.80844 -280.035436) (xy 393.761169 -280.049128) (xy 393.712314 -280.05506)
			(xy 393.663139 -280.053079) (xy 393.61492 -280.043235) (xy 393.568904 -280.025783) (xy 393.526283 -280.001176)
			(xy 393.488162 -279.970051) (xy 393.455527 -279.933214) (xy 393.429224 -279.891618) (xy 393.409933 -279.846342)
			(xy 393.398156 -279.798558) (xy 393.394196 -279.749504) (xy 314.955169 -279.749504) (xy 314.955174 -279.749758)
			(xy 314.954679 -279.774365) (xy 314.946784 -279.822942) (xy 314.9312 -279.869623) (xy 314.908329 -279.9132)
			(xy 314.878764 -279.952544) (xy 314.843271 -279.986636) (xy 314.802768 -280.014592) (xy 314.758306 -280.03569)
			(xy 314.711035 -280.049382) (xy 314.66218 -280.055314) (xy 314.613005 -280.053333) (xy 314.564786 -280.043489)
			(xy 314.51877 -280.026037) (xy 314.476149 -280.00143) (xy 314.438028 -279.970305) (xy 314.405393 -279.933468)
			(xy 314.37909 -279.891872) (xy 314.359799 -279.846596) (xy 314.348022 -279.798812) (xy 314.344062 -279.749758)
			(xy 314.005214 -279.749758) (xy 314.004719 -279.774365) (xy 313.996824 -279.822942) (xy 313.98124 -279.869623)
			(xy 313.958369 -279.9132) (xy 313.928804 -279.952544) (xy 313.893311 -279.986636) (xy 313.852808 -280.014592)
			(xy 313.808346 -280.03569) (xy 313.761075 -280.049382) (xy 313.71222 -280.055314) (xy 313.663045 -280.053333)
			(xy 313.614826 -280.043489) (xy 313.56881 -280.026037) (xy 313.526189 -280.00143) (xy 313.488068 -279.970305)
			(xy 313.455433 -279.933468) (xy 313.42913 -279.891872) (xy 313.409839 -279.846596) (xy 313.398062 -279.798812)
			(xy 313.394102 -279.749758) (xy 312.10504 -279.749758) (xy 312.104545 -279.774365) (xy 312.09665 -279.822942)
			(xy 312.081066 -279.869623) (xy 312.058195 -279.9132) (xy 312.02863 -279.952544) (xy 311.993137 -279.986636)
			(xy 311.952634 -280.014592) (xy 311.908172 -280.03569) (xy 311.860901 -280.049382) (xy 311.812046 -280.055314)
			(xy 311.762871 -280.053333) (xy 311.714652 -280.043489) (xy 311.668636 -280.026037) (xy 311.626015 -280.00143)
			(xy 311.587894 -279.970305) (xy 311.555259 -279.933468) (xy 311.528956 -279.891872) (xy 311.509665 -279.846596)
			(xy 311.497888 -279.798812) (xy 311.493928 -279.749758) (xy 310.205115 -279.749758) (xy 310.204625 -279.774111)
			(xy 310.19673 -279.822688) (xy 310.181146 -279.869369) (xy 310.158275 -279.912946) (xy 310.12871 -279.95229)
			(xy 310.093217 -279.986382) (xy 310.052714 -280.014338) (xy 310.008252 -280.035436) (xy 309.960981 -280.049128)
			(xy 309.912126 -280.05506) (xy 309.862951 -280.053079) (xy 309.814732 -280.043235) (xy 309.768716 -280.025783)
			(xy 309.726095 -280.001176) (xy 309.687974 -279.970051) (xy 309.655339 -279.933214) (xy 309.629036 -279.891618)
			(xy 309.609745 -279.846342) (xy 309.597968 -279.798558) (xy 309.594008 -279.749504) (xy 308.3052 -279.749504)
			(xy 308.304705 -279.774111) (xy 308.29681 -279.822688) (xy 308.281226 -279.869369) (xy 308.258355 -279.912946)
			(xy 308.22879 -279.95229) (xy 308.193297 -279.986382) (xy 308.152794 -280.014338) (xy 308.108332 -280.035436)
			(xy 308.061061 -280.049128) (xy 308.012206 -280.05506) (xy 307.963031 -280.053079) (xy 307.914812 -280.043235)
			(xy 307.868796 -280.025783) (xy 307.826175 -280.001176) (xy 307.788054 -279.970051) (xy 307.755419 -279.933214)
			(xy 307.729116 -279.891618) (xy 307.709825 -279.846342) (xy 307.698048 -279.798558) (xy 307.694088 -279.749504)
			(xy 306.405026 -279.749504) (xy 306.404531 -279.774111) (xy 306.396636 -279.822688) (xy 306.381052 -279.869369)
			(xy 306.358181 -279.912946) (xy 306.328616 -279.95229) (xy 306.293123 -279.986382) (xy 306.25262 -280.014338)
			(xy 306.208158 -280.035436) (xy 306.160887 -280.049128) (xy 306.112032 -280.05506) (xy 306.062857 -280.053079)
			(xy 306.014638 -280.043235) (xy 305.968622 -280.025783) (xy 305.926001 -280.001176) (xy 305.88788 -279.970051)
			(xy 305.855245 -279.933214) (xy 305.828942 -279.891618) (xy 305.809651 -279.846342) (xy 305.797874 -279.798558)
			(xy 305.793914 -279.749504) (xy 304.505106 -279.749504) (xy 304.504611 -279.774111) (xy 304.496716 -279.822688)
			(xy 304.481132 -279.869369) (xy 304.458261 -279.912946) (xy 304.428696 -279.95229) (xy 304.393203 -279.986382)
			(xy 304.3527 -280.014338) (xy 304.308238 -280.035436) (xy 304.260967 -280.049128) (xy 304.212112 -280.05506)
			(xy 304.162937 -280.053079) (xy 304.114718 -280.043235) (xy 304.068702 -280.025783) (xy 304.026081 -280.001176)
			(xy 303.98796 -279.970051) (xy 303.955325 -279.933214) (xy 303.929022 -279.891618) (xy 303.909731 -279.846342)
			(xy 303.897954 -279.798558) (xy 303.893994 -279.749504) (xy 302.605186 -279.749504) (xy 302.604691 -279.774111)
			(xy 302.596796 -279.822688) (xy 302.581212 -279.869369) (xy 302.558341 -279.912946) (xy 302.528776 -279.95229)
			(xy 302.493283 -279.986382) (xy 302.45278 -280.014338) (xy 302.408318 -280.035436) (xy 302.361047 -280.049128)
			(xy 302.312192 -280.05506) (xy 302.263017 -280.053079) (xy 302.214798 -280.043235) (xy 302.168782 -280.025783)
			(xy 302.126161 -280.001176) (xy 302.08804 -279.970051) (xy 302.055405 -279.933214) (xy 302.029102 -279.891618)
			(xy 302.009811 -279.846342) (xy 301.998034 -279.798558) (xy 301.994074 -279.749504) (xy 300.705012 -279.749504)
			(xy 300.704517 -279.774111) (xy 300.696622 -279.822688) (xy 300.681038 -279.869369) (xy 300.658167 -279.912946)
			(xy 300.628602 -279.95229) (xy 300.593109 -279.986382) (xy 300.552606 -280.014338) (xy 300.508144 -280.035436)
			(xy 300.460873 -280.049128) (xy 300.412018 -280.05506) (xy 300.362843 -280.053079) (xy 300.314624 -280.043235)
			(xy 300.268608 -280.025783) (xy 300.225987 -280.001176) (xy 300.187866 -279.970051) (xy 300.155231 -279.933214)
			(xy 300.128928 -279.891618) (xy 300.109637 -279.846342) (xy 300.09786 -279.798558) (xy 300.0939 -279.749504)
			(xy 298.805092 -279.749504) (xy 298.804597 -279.774111) (xy 298.796702 -279.822688) (xy 298.781118 -279.869369)
			(xy 298.758247 -279.912946) (xy 298.728682 -279.95229) (xy 298.693189 -279.986382) (xy 298.652686 -280.014338)
			(xy 298.608224 -280.035436) (xy 298.560953 -280.049128) (xy 298.512098 -280.05506) (xy 298.462923 -280.053079)
			(xy 298.414704 -280.043235) (xy 298.368688 -280.025783) (xy 298.326067 -280.001176) (xy 298.287946 -279.970051)
			(xy 298.255311 -279.933214) (xy 298.229008 -279.891618) (xy 298.209717 -279.846342) (xy 298.19794 -279.798558)
			(xy 298.19398 -279.749504) (xy 296.905172 -279.749504) (xy 296.904677 -279.774111) (xy 296.896782 -279.822688)
			(xy 296.881198 -279.869369) (xy 296.858327 -279.912946) (xy 296.828762 -279.95229) (xy 296.793269 -279.986382)
			(xy 296.752766 -280.014338) (xy 296.708304 -280.035436) (xy 296.661033 -280.049128) (xy 296.612178 -280.05506)
			(xy 296.563003 -280.053079) (xy 296.514784 -280.043235) (xy 296.468768 -280.025783) (xy 296.426147 -280.001176)
			(xy 296.388026 -279.970051) (xy 296.355391 -279.933214) (xy 296.329088 -279.891618) (xy 296.309797 -279.846342)
			(xy 296.29802 -279.798558) (xy 296.29406 -279.749504) (xy 295.004998 -279.749504) (xy 295.004503 -279.774111)
			(xy 294.996608 -279.822688) (xy 294.981024 -279.869369) (xy 294.958153 -279.912946) (xy 294.928588 -279.95229)
			(xy 294.893095 -279.986382) (xy 294.852592 -280.014338) (xy 294.80813 -280.035436) (xy 294.760859 -280.049128)
			(xy 294.712004 -280.05506) (xy 294.662829 -280.053079) (xy 294.61461 -280.043235) (xy 294.568594 -280.025783)
			(xy 294.525973 -280.001176) (xy 294.487852 -279.970051) (xy 294.455217 -279.933214) (xy 294.428914 -279.891618)
			(xy 294.409623 -279.846342) (xy 294.397846 -279.798558) (xy 294.393886 -279.749504) (xy 293.105078 -279.749504)
			(xy 293.104583 -279.774111) (xy 293.096688 -279.822688) (xy 293.081104 -279.869369) (xy 293.058233 -279.912946)
			(xy 293.028668 -279.95229) (xy 292.993175 -279.986382) (xy 292.952672 -280.014338) (xy 292.90821 -280.035436)
			(xy 292.860939 -280.049128) (xy 292.812084 -280.05506) (xy 292.762909 -280.053079) (xy 292.71469 -280.043235)
			(xy 292.668674 -280.025783) (xy 292.626053 -280.001176) (xy 292.587932 -279.970051) (xy 292.555297 -279.933214)
			(xy 292.528994 -279.891618) (xy 292.509703 -279.846342) (xy 292.497926 -279.798558) (xy 292.493966 -279.749504)
			(xy 291.205158 -279.749504) (xy 291.204663 -279.774111) (xy 291.196768 -279.822688) (xy 291.181184 -279.869369)
			(xy 291.158313 -279.912946) (xy 291.128748 -279.95229) (xy 291.093255 -279.986382) (xy 291.052752 -280.014338)
			(xy 291.00829 -280.035436) (xy 290.961019 -280.049128) (xy 290.912164 -280.05506) (xy 290.862989 -280.053079)
			(xy 290.81477 -280.043235) (xy 290.768754 -280.025783) (xy 290.726133 -280.001176) (xy 290.688012 -279.970051)
			(xy 290.655377 -279.933214) (xy 290.629074 -279.891618) (xy 290.609783 -279.846342) (xy 290.598006 -279.798558)
			(xy 290.594046 -279.749504) (xy 289.304984 -279.749504) (xy 289.304489 -279.774111) (xy 289.296594 -279.822688)
			(xy 289.28101 -279.869369) (xy 289.258139 -279.912946) (xy 289.228574 -279.95229) (xy 289.193081 -279.986382)
			(xy 289.152578 -280.014338) (xy 289.108116 -280.035436) (xy 289.060845 -280.049128) (xy 289.01199 -280.05506)
			(xy 288.962815 -280.053079) (xy 288.914596 -280.043235) (xy 288.86858 -280.025783) (xy 288.825959 -280.001176)
			(xy 288.787838 -279.970051) (xy 288.755203 -279.933214) (xy 288.7289 -279.891618) (xy 288.709609 -279.846342)
			(xy 288.697832 -279.798558) (xy 288.693872 -279.749504) (xy 287.405064 -279.749504) (xy 287.404569 -279.774111)
			(xy 287.396674 -279.822688) (xy 287.38109 -279.869369) (xy 287.358219 -279.912946) (xy 287.328654 -279.95229)
			(xy 287.293161 -279.986382) (xy 287.252658 -280.014338) (xy 287.208196 -280.035436) (xy 287.160925 -280.049128)
			(xy 287.11207 -280.05506) (xy 287.062895 -280.053079) (xy 287.014676 -280.043235) (xy 286.96866 -280.025783)
			(xy 286.926039 -280.001176) (xy 286.887918 -279.970051) (xy 286.855283 -279.933214) (xy 286.82898 -279.891618)
			(xy 286.809689 -279.846342) (xy 286.797912 -279.798558) (xy 286.793952 -279.749504) (xy 285.505144 -279.749504)
			(xy 285.504649 -279.774111) (xy 285.496754 -279.822688) (xy 285.48117 -279.869369) (xy 285.458299 -279.912946)
			(xy 285.428734 -279.95229) (xy 285.393241 -279.986382) (xy 285.352738 -280.014338) (xy 285.308276 -280.035436)
			(xy 285.261005 -280.049128) (xy 285.21215 -280.05506) (xy 285.162975 -280.053079) (xy 285.114756 -280.043235)
			(xy 285.06874 -280.025783) (xy 285.026119 -280.001176) (xy 284.987998 -279.970051) (xy 284.955363 -279.933214)
			(xy 284.92906 -279.891618) (xy 284.909769 -279.846342) (xy 284.897992 -279.798558) (xy 284.894032 -279.749504)
			(xy 283.605224 -279.749504) (xy 283.604729 -279.774111) (xy 283.596834 -279.822688) (xy 283.58125 -279.869369)
			(xy 283.558379 -279.912946) (xy 283.528814 -279.95229) (xy 283.493321 -279.986382) (xy 283.452818 -280.014338)
			(xy 283.408356 -280.035436) (xy 283.361085 -280.049128) (xy 283.31223 -280.05506) (xy 283.263055 -280.053079)
			(xy 283.214836 -280.043235) (xy 283.16882 -280.025783) (xy 283.126199 -280.001176) (xy 283.088078 -279.970051)
			(xy 283.055443 -279.933214) (xy 283.02914 -279.891618) (xy 283.009849 -279.846342) (xy 282.998072 -279.798558)
			(xy 282.994112 -279.749504) (xy 281.70505 -279.749504) (xy 281.704555 -279.774111) (xy 281.69666 -279.822688)
			(xy 281.681076 -279.869369) (xy 281.658205 -279.912946) (xy 281.62864 -279.95229) (xy 281.593147 -279.986382)
			(xy 281.552644 -280.014338) (xy 281.508182 -280.035436) (xy 281.460911 -280.049128) (xy 281.412056 -280.05506)
			(xy 281.362881 -280.053079) (xy 281.314662 -280.043235) (xy 281.268646 -280.025783) (xy 281.226025 -280.001176)
			(xy 281.187904 -279.970051) (xy 281.155269 -279.933214) (xy 281.128966 -279.891618) (xy 281.109675 -279.846342)
			(xy 281.097898 -279.798558) (xy 281.093938 -279.749504) (xy 279.80513 -279.749504) (xy 279.804635 -279.774111)
			(xy 279.79674 -279.822688) (xy 279.781156 -279.869369) (xy 279.758285 -279.912946) (xy 279.72872 -279.95229)
			(xy 279.693227 -279.986382) (xy 279.652724 -280.014338) (xy 279.608262 -280.035436) (xy 279.560991 -280.049128)
			(xy 279.512136 -280.05506) (xy 279.462961 -280.053079) (xy 279.414742 -280.043235) (xy 279.368726 -280.025783)
			(xy 279.326105 -280.001176) (xy 279.287984 -279.970051) (xy 279.255349 -279.933214) (xy 279.229046 -279.891618)
			(xy 279.209755 -279.846342) (xy 279.197978 -279.798558) (xy 279.194018 -279.749504) (xy 277.90521 -279.749504)
			(xy 277.904715 -279.774111) (xy 277.89682 -279.822688) (xy 277.881236 -279.869369) (xy 277.858365 -279.912946)
			(xy 277.8288 -279.95229) (xy 277.793307 -279.986382) (xy 277.752804 -280.014338) (xy 277.708342 -280.035436)
			(xy 277.661071 -280.049128) (xy 277.612216 -280.05506) (xy 277.563041 -280.053079) (xy 277.514822 -280.043235)
			(xy 277.468806 -280.025783) (xy 277.426185 -280.001176) (xy 277.388064 -279.970051) (xy 277.355429 -279.933214)
			(xy 277.329126 -279.891618) (xy 277.309835 -279.846342) (xy 277.298058 -279.798558) (xy 277.294098 -279.749504)
			(xy 198.855325 -279.749504) (xy 198.85533 -279.749758) (xy 198.854835 -279.774365) (xy 198.84694 -279.822942)
			(xy 198.831356 -279.869623) (xy 198.808485 -279.9132) (xy 198.77892 -279.952544) (xy 198.743427 -279.986636)
			(xy 198.702924 -280.014592) (xy 198.658462 -280.03569) (xy 198.611191 -280.049382) (xy 198.562336 -280.055314)
			(xy 198.513161 -280.053333) (xy 198.464942 -280.043489) (xy 198.418926 -280.026037) (xy 198.376305 -280.00143)
			(xy 198.338184 -279.970305) (xy 198.305549 -279.933468) (xy 198.279246 -279.891872) (xy 198.259955 -279.846596)
			(xy 198.248178 -279.798812) (xy 198.244218 -279.749758) (xy 197.90537 -279.749758) (xy 197.904875 -279.774365)
			(xy 197.89698 -279.822942) (xy 197.881396 -279.869623) (xy 197.858525 -279.9132) (xy 197.82896 -279.952544)
			(xy 197.793467 -279.986636) (xy 197.752964 -280.014592) (xy 197.708502 -280.03569) (xy 197.661231 -280.049382)
			(xy 197.612376 -280.055314) (xy 197.563201 -280.053333) (xy 197.514982 -280.043489) (xy 197.468966 -280.026037)
			(xy 197.426345 -280.00143) (xy 197.388224 -279.970305) (xy 197.355589 -279.933468) (xy 197.329286 -279.891872)
			(xy 197.309995 -279.846596) (xy 197.298218 -279.798812) (xy 197.294258 -279.749758) (xy 196.005196 -279.749758)
			(xy 196.004701 -279.774365) (xy 195.996806 -279.822942) (xy 195.981222 -279.869623) (xy 195.958351 -279.9132)
			(xy 195.928786 -279.952544) (xy 195.893293 -279.986636) (xy 195.85279 -280.014592) (xy 195.808328 -280.03569)
			(xy 195.761057 -280.049382) (xy 195.712202 -280.055314) (xy 195.663027 -280.053333) (xy 195.614808 -280.043489)
			(xy 195.568792 -280.026037) (xy 195.526171 -280.00143) (xy 195.48805 -279.970305) (xy 195.455415 -279.933468)
			(xy 195.429112 -279.891872) (xy 195.409821 -279.846596) (xy 195.398044 -279.798812) (xy 195.394084 -279.749758)
			(xy 194.105271 -279.749758) (xy 194.104781 -279.774111) (xy 194.096886 -279.822688) (xy 194.081302 -279.869369)
			(xy 194.058431 -279.912946) (xy 194.028866 -279.95229) (xy 193.993373 -279.986382) (xy 193.95287 -280.014338)
			(xy 193.908408 -280.035436) (xy 193.861137 -280.049128) (xy 193.812282 -280.05506) (xy 193.763107 -280.053079)
			(xy 193.714888 -280.043235) (xy 193.668872 -280.025783) (xy 193.626251 -280.001176) (xy 193.58813 -279.970051)
			(xy 193.555495 -279.933214) (xy 193.529192 -279.891618) (xy 193.509901 -279.846342) (xy 193.498124 -279.798558)
			(xy 193.494164 -279.749504) (xy 192.205356 -279.749504) (xy 192.204861 -279.774111) (xy 192.196966 -279.822688)
			(xy 192.181382 -279.869369) (xy 192.158511 -279.912946) (xy 192.128946 -279.95229) (xy 192.093453 -279.986382)
			(xy 192.05295 -280.014338) (xy 192.008488 -280.035436) (xy 191.961217 -280.049128) (xy 191.912362 -280.05506)
			(xy 191.863187 -280.053079) (xy 191.814968 -280.043235) (xy 191.768952 -280.025783) (xy 191.726331 -280.001176)
			(xy 191.68821 -279.970051) (xy 191.655575 -279.933214) (xy 191.629272 -279.891618) (xy 191.609981 -279.846342)
			(xy 191.598204 -279.798558) (xy 191.594244 -279.749504) (xy 190.305182 -279.749504) (xy 190.304687 -279.774111)
			(xy 190.296792 -279.822688) (xy 190.281208 -279.869369) (xy 190.258337 -279.912946) (xy 190.228772 -279.95229)
			(xy 190.193279 -279.986382) (xy 190.152776 -280.014338) (xy 190.108314 -280.035436) (xy 190.061043 -280.049128)
			(xy 190.012188 -280.05506) (xy 189.963013 -280.053079) (xy 189.914794 -280.043235) (xy 189.868778 -280.025783)
			(xy 189.826157 -280.001176) (xy 189.788036 -279.970051) (xy 189.755401 -279.933214) (xy 189.729098 -279.891618)
			(xy 189.709807 -279.846342) (xy 189.69803 -279.798558) (xy 189.69407 -279.749504) (xy 188.405262 -279.749504)
			(xy 188.404767 -279.774111) (xy 188.396872 -279.822688) (xy 188.381288 -279.869369) (xy 188.358417 -279.912946)
			(xy 188.328852 -279.95229) (xy 188.293359 -279.986382) (xy 188.252856 -280.014338) (xy 188.208394 -280.035436)
			(xy 188.161123 -280.049128) (xy 188.112268 -280.05506) (xy 188.063093 -280.053079) (xy 188.014874 -280.043235)
			(xy 187.968858 -280.025783) (xy 187.926237 -280.001176) (xy 187.888116 -279.970051) (xy 187.855481 -279.933214)
			(xy 187.829178 -279.891618) (xy 187.809887 -279.846342) (xy 187.79811 -279.798558) (xy 187.79415 -279.749504)
			(xy 186.505342 -279.749504) (xy 186.504847 -279.774111) (xy 186.496952 -279.822688) (xy 186.481368 -279.869369)
			(xy 186.458497 -279.912946) (xy 186.428932 -279.95229) (xy 186.393439 -279.986382) (xy 186.352936 -280.014338)
			(xy 186.308474 -280.035436) (xy 186.261203 -280.049128) (xy 186.212348 -280.05506) (xy 186.163173 -280.053079)
			(xy 186.114954 -280.043235) (xy 186.068938 -280.025783) (xy 186.026317 -280.001176) (xy 185.988196 -279.970051)
			(xy 185.955561 -279.933214) (xy 185.929258 -279.891618) (xy 185.909967 -279.846342) (xy 185.89819 -279.798558)
			(xy 185.89423 -279.749504) (xy 184.605168 -279.749504) (xy 184.604673 -279.774111) (xy 184.596778 -279.822688)
			(xy 184.581194 -279.869369) (xy 184.558323 -279.912946) (xy 184.528758 -279.95229) (xy 184.493265 -279.986382)
			(xy 184.452762 -280.014338) (xy 184.4083 -280.035436) (xy 184.361029 -280.049128) (xy 184.312174 -280.05506)
			(xy 184.262999 -280.053079) (xy 184.21478 -280.043235) (xy 184.168764 -280.025783) (xy 184.126143 -280.001176)
			(xy 184.088022 -279.970051) (xy 184.055387 -279.933214) (xy 184.029084 -279.891618) (xy 184.009793 -279.846342)
			(xy 183.998016 -279.798558) (xy 183.994056 -279.749504) (xy 182.705248 -279.749504) (xy 182.704753 -279.774111)
			(xy 182.696858 -279.822688) (xy 182.681274 -279.869369) (xy 182.658403 -279.912946) (xy 182.628838 -279.95229)
			(xy 182.593345 -279.986382) (xy 182.552842 -280.014338) (xy 182.50838 -280.035436) (xy 182.461109 -280.049128)
			(xy 182.412254 -280.05506) (xy 182.363079 -280.053079) (xy 182.31486 -280.043235) (xy 182.268844 -280.025783)
			(xy 182.226223 -280.001176) (xy 182.188102 -279.970051) (xy 182.155467 -279.933214) (xy 182.129164 -279.891618)
			(xy 182.109873 -279.846342) (xy 182.098096 -279.798558) (xy 182.094136 -279.749504) (xy 180.805328 -279.749504)
			(xy 180.804833 -279.774111) (xy 180.796938 -279.822688) (xy 180.781354 -279.869369) (xy 180.758483 -279.912946)
			(xy 180.728918 -279.95229) (xy 180.693425 -279.986382) (xy 180.652922 -280.014338) (xy 180.60846 -280.035436)
			(xy 180.561189 -280.049128) (xy 180.512334 -280.05506) (xy 180.463159 -280.053079) (xy 180.41494 -280.043235)
			(xy 180.368924 -280.025783) (xy 180.326303 -280.001176) (xy 180.288182 -279.970051) (xy 180.255547 -279.933214)
			(xy 180.229244 -279.891618) (xy 180.209953 -279.846342) (xy 180.198176 -279.798558) (xy 180.194216 -279.749504)
			(xy 178.905154 -279.749504) (xy 178.904659 -279.774111) (xy 178.896764 -279.822688) (xy 178.88118 -279.869369)
			(xy 178.858309 -279.912946) (xy 178.828744 -279.95229) (xy 178.793251 -279.986382) (xy 178.752748 -280.014338)
			(xy 178.708286 -280.035436) (xy 178.661015 -280.049128) (xy 178.61216 -280.05506) (xy 178.562985 -280.053079)
			(xy 178.514766 -280.043235) (xy 178.46875 -280.025783) (xy 178.426129 -280.001176) (xy 178.388008 -279.970051)
			(xy 178.355373 -279.933214) (xy 178.32907 -279.891618) (xy 178.309779 -279.846342) (xy 178.298002 -279.798558)
			(xy 178.294042 -279.749504) (xy 177.005234 -279.749504) (xy 177.004739 -279.774111) (xy 176.996844 -279.822688)
			(xy 176.98126 -279.869369) (xy 176.958389 -279.912946) (xy 176.928824 -279.95229) (xy 176.893331 -279.986382)
			(xy 176.852828 -280.014338) (xy 176.808366 -280.035436) (xy 176.761095 -280.049128) (xy 176.71224 -280.05506)
			(xy 176.663065 -280.053079) (xy 176.614846 -280.043235) (xy 176.56883 -280.025783) (xy 176.526209 -280.001176)
			(xy 176.488088 -279.970051) (xy 176.455453 -279.933214) (xy 176.42915 -279.891618) (xy 176.409859 -279.846342)
			(xy 176.398082 -279.798558) (xy 176.394122 -279.749504) (xy 175.105314 -279.749504) (xy 175.104819 -279.774111)
			(xy 175.096924 -279.822688) (xy 175.08134 -279.869369) (xy 175.058469 -279.912946) (xy 175.028904 -279.95229)
			(xy 174.993411 -279.986382) (xy 174.952908 -280.014338) (xy 174.908446 -280.035436) (xy 174.861175 -280.049128)
			(xy 174.81232 -280.05506) (xy 174.763145 -280.053079) (xy 174.714926 -280.043235) (xy 174.66891 -280.025783)
			(xy 174.626289 -280.001176) (xy 174.588168 -279.970051) (xy 174.555533 -279.933214) (xy 174.52923 -279.891618)
			(xy 174.509939 -279.846342) (xy 174.498162 -279.798558) (xy 174.494202 -279.749504) (xy 173.20514 -279.749504)
			(xy 173.204645 -279.774111) (xy 173.19675 -279.822688) (xy 173.181166 -279.869369) (xy 173.158295 -279.912946)
			(xy 173.12873 -279.95229) (xy 173.093237 -279.986382) (xy 173.052734 -280.014338) (xy 173.008272 -280.035436)
			(xy 172.961001 -280.049128) (xy 172.912146 -280.05506) (xy 172.862971 -280.053079) (xy 172.814752 -280.043235)
			(xy 172.768736 -280.025783) (xy 172.726115 -280.001176) (xy 172.687994 -279.970051) (xy 172.655359 -279.933214)
			(xy 172.629056 -279.891618) (xy 172.609765 -279.846342) (xy 172.597988 -279.798558) (xy 172.594028 -279.749504)
			(xy 171.30522 -279.749504) (xy 171.304725 -279.774111) (xy 171.29683 -279.822688) (xy 171.281246 -279.869369)
			(xy 171.258375 -279.912946) (xy 171.22881 -279.95229) (xy 171.193317 -279.986382) (xy 171.152814 -280.014338)
			(xy 171.108352 -280.035436) (xy 171.061081 -280.049128) (xy 171.012226 -280.05506) (xy 170.963051 -280.053079)
			(xy 170.914832 -280.043235) (xy 170.868816 -280.025783) (xy 170.826195 -280.001176) (xy 170.788074 -279.970051)
			(xy 170.755439 -279.933214) (xy 170.729136 -279.891618) (xy 170.709845 -279.846342) (xy 170.698068 -279.798558)
			(xy 170.694108 -279.749504) (xy 169.4053 -279.749504) (xy 169.404805 -279.774111) (xy 169.39691 -279.822688)
			(xy 169.381326 -279.869369) (xy 169.358455 -279.912946) (xy 169.32889 -279.95229) (xy 169.293397 -279.986382)
			(xy 169.252894 -280.014338) (xy 169.208432 -280.035436) (xy 169.161161 -280.049128) (xy 169.112306 -280.05506)
			(xy 169.063131 -280.053079) (xy 169.014912 -280.043235) (xy 168.968896 -280.025783) (xy 168.926275 -280.001176)
			(xy 168.888154 -279.970051) (xy 168.855519 -279.933214) (xy 168.829216 -279.891618) (xy 168.809925 -279.846342)
			(xy 168.798148 -279.798558) (xy 168.794188 -279.749504) (xy 167.50538 -279.749504) (xy 167.504885 -279.774111)
			(xy 167.49699 -279.822688) (xy 167.481406 -279.869369) (xy 167.458535 -279.912946) (xy 167.42897 -279.95229)
			(xy 167.393477 -279.986382) (xy 167.352974 -280.014338) (xy 167.308512 -280.035436) (xy 167.261241 -280.049128)
			(xy 167.212386 -280.05506) (xy 167.163211 -280.053079) (xy 167.114992 -280.043235) (xy 167.068976 -280.025783)
			(xy 167.026355 -280.001176) (xy 166.988234 -279.970051) (xy 166.955599 -279.933214) (xy 166.929296 -279.891618)
			(xy 166.910005 -279.846342) (xy 166.898228 -279.798558) (xy 166.894268 -279.749504) (xy 165.605206 -279.749504)
			(xy 165.604711 -279.774111) (xy 165.596816 -279.822688) (xy 165.581232 -279.869369) (xy 165.558361 -279.912946)
			(xy 165.528796 -279.95229) (xy 165.493303 -279.986382) (xy 165.4528 -280.014338) (xy 165.408338 -280.035436)
			(xy 165.361067 -280.049128) (xy 165.312212 -280.05506) (xy 165.263037 -280.053079) (xy 165.214818 -280.043235)
			(xy 165.168802 -280.025783) (xy 165.126181 -280.001176) (xy 165.08806 -279.970051) (xy 165.055425 -279.933214)
			(xy 165.029122 -279.891618) (xy 165.009831 -279.846342) (xy 164.998054 -279.798558) (xy 164.994094 -279.749504)
			(xy 163.705286 -279.749504) (xy 163.704791 -279.774111) (xy 163.696896 -279.822688) (xy 163.681312 -279.869369)
			(xy 163.658441 -279.912946) (xy 163.628876 -279.95229) (xy 163.593383 -279.986382) (xy 163.55288 -280.014338)
			(xy 163.508418 -280.035436) (xy 163.461147 -280.049128) (xy 163.412292 -280.05506) (xy 163.363117 -280.053079)
			(xy 163.314898 -280.043235) (xy 163.268882 -280.025783) (xy 163.226261 -280.001176) (xy 163.18814 -279.970051)
			(xy 163.155505 -279.933214) (xy 163.129202 -279.891618) (xy 163.109911 -279.846342) (xy 163.098134 -279.798558)
			(xy 163.094174 -279.749504) (xy 161.805366 -279.749504) (xy 161.804871 -279.774111) (xy 161.796976 -279.822688)
			(xy 161.781392 -279.869369) (xy 161.758521 -279.912946) (xy 161.728956 -279.95229) (xy 161.693463 -279.986382)
			(xy 161.65296 -280.014338) (xy 161.608498 -280.035436) (xy 161.561227 -280.049128) (xy 161.512372 -280.05506)
			(xy 161.463197 -280.053079) (xy 161.414978 -280.043235) (xy 161.368962 -280.025783) (xy 161.326341 -280.001176)
			(xy 161.28822 -279.970051) (xy 161.255585 -279.933214) (xy 161.229282 -279.891618) (xy 161.209991 -279.846342)
			(xy 161.198214 -279.798558) (xy 161.194254 -279.749504) (xy 82.755227 -279.749504) (xy 82.755232 -279.749758)
			(xy 82.754737 -279.774365) (xy 82.746842 -279.822942) (xy 82.731258 -279.869623) (xy 82.708387 -279.9132)
			(xy 82.678822 -279.952544) (xy 82.643329 -279.986636) (xy 82.602826 -280.014592) (xy 82.558364 -280.03569)
			(xy 82.511093 -280.049382) (xy 82.462238 -280.055314) (xy 82.413063 -280.053333) (xy 82.364844 -280.043489)
			(xy 82.318828 -280.026037) (xy 82.276207 -280.00143) (xy 82.238086 -279.970305) (xy 82.205451 -279.933468)
			(xy 82.179148 -279.891872) (xy 82.159857 -279.846596) (xy 82.14808 -279.798812) (xy 82.14412 -279.749758)
			(xy 81.805272 -279.749758) (xy 81.804777 -279.774365) (xy 81.796882 -279.822942) (xy 81.781298 -279.869623)
			(xy 81.758427 -279.9132) (xy 81.728862 -279.952544) (xy 81.693369 -279.986636) (xy 81.652866 -280.014592)
			(xy 81.608404 -280.03569) (xy 81.561133 -280.049382) (xy 81.512278 -280.055314) (xy 81.463103 -280.053333)
			(xy 81.414884 -280.043489) (xy 81.368868 -280.026037) (xy 81.326247 -280.00143) (xy 81.288126 -279.970305)
			(xy 81.255491 -279.933468) (xy 81.229188 -279.891872) (xy 81.209897 -279.846596) (xy 81.19812 -279.798812)
			(xy 81.19416 -279.749758) (xy 79.905098 -279.749758) (xy 79.904603 -279.774365) (xy 79.896708 -279.822942)
			(xy 79.881124 -279.869623) (xy 79.858253 -279.9132) (xy 79.828688 -279.952544) (xy 79.793195 -279.986636)
			(xy 79.752692 -280.014592) (xy 79.70823 -280.03569) (xy 79.660959 -280.049382) (xy 79.612104 -280.055314)
			(xy 79.562929 -280.053333) (xy 79.51471 -280.043489) (xy 79.468694 -280.026037) (xy 79.426073 -280.00143)
			(xy 79.387952 -279.970305) (xy 79.355317 -279.933468) (xy 79.329014 -279.891872) (xy 79.309723 -279.846596)
			(xy 79.297946 -279.798812) (xy 79.293986 -279.749758) (xy 78.005173 -279.749758) (xy 78.004683 -279.774111)
			(xy 77.996788 -279.822688) (xy 77.981204 -279.869369) (xy 77.958333 -279.912946) (xy 77.928768 -279.95229)
			(xy 77.893275 -279.986382) (xy 77.852772 -280.014338) (xy 77.80831 -280.035436) (xy 77.761039 -280.049128)
			(xy 77.712184 -280.05506) (xy 77.663009 -280.053079) (xy 77.61479 -280.043235) (xy 77.568774 -280.025783)
			(xy 77.526153 -280.001176) (xy 77.488032 -279.970051) (xy 77.455397 -279.933214) (xy 77.429094 -279.891618)
			(xy 77.409803 -279.846342) (xy 77.398026 -279.798558) (xy 77.394066 -279.749504) (xy 76.105258 -279.749504)
			(xy 76.104763 -279.774111) (xy 76.096868 -279.822688) (xy 76.081284 -279.869369) (xy 76.058413 -279.912946)
			(xy 76.028848 -279.95229) (xy 75.993355 -279.986382) (xy 75.952852 -280.014338) (xy 75.90839 -280.035436)
			(xy 75.861119 -280.049128) (xy 75.812264 -280.05506) (xy 75.763089 -280.053079) (xy 75.71487 -280.043235)
			(xy 75.668854 -280.025783) (xy 75.626233 -280.001176) (xy 75.588112 -279.970051) (xy 75.555477 -279.933214)
			(xy 75.529174 -279.891618) (xy 75.509883 -279.846342) (xy 75.498106 -279.798558) (xy 75.494146 -279.749504)
			(xy 74.205084 -279.749504) (xy 74.204589 -279.774111) (xy 74.196694 -279.822688) (xy 74.18111 -279.869369)
			(xy 74.158239 -279.912946) (xy 74.128674 -279.95229) (xy 74.093181 -279.986382) (xy 74.052678 -280.014338)
			(xy 74.008216 -280.035436) (xy 73.960945 -280.049128) (xy 73.91209 -280.05506) (xy 73.862915 -280.053079)
			(xy 73.814696 -280.043235) (xy 73.76868 -280.025783) (xy 73.726059 -280.001176) (xy 73.687938 -279.970051)
			(xy 73.655303 -279.933214) (xy 73.629 -279.891618) (xy 73.609709 -279.846342) (xy 73.597932 -279.798558)
			(xy 73.593972 -279.749504) (xy 72.305164 -279.749504) (xy 72.304669 -279.774111) (xy 72.296774 -279.822688)
			(xy 72.28119 -279.869369) (xy 72.258319 -279.912946) (xy 72.228754 -279.95229) (xy 72.193261 -279.986382)
			(xy 72.152758 -280.014338) (xy 72.108296 -280.035436) (xy 72.061025 -280.049128) (xy 72.01217 -280.05506)
			(xy 71.962995 -280.053079) (xy 71.914776 -280.043235) (xy 71.86876 -280.025783) (xy 71.826139 -280.001176)
			(xy 71.788018 -279.970051) (xy 71.755383 -279.933214) (xy 71.72908 -279.891618) (xy 71.709789 -279.846342)
			(xy 71.698012 -279.798558) (xy 71.694052 -279.749504) (xy 70.405244 -279.749504) (xy 70.404749 -279.774111)
			(xy 70.396854 -279.822688) (xy 70.38127 -279.869369) (xy 70.358399 -279.912946) (xy 70.328834 -279.95229)
			(xy 70.293341 -279.986382) (xy 70.252838 -280.014338) (xy 70.208376 -280.035436) (xy 70.161105 -280.049128)
			(xy 70.11225 -280.05506) (xy 70.063075 -280.053079) (xy 70.014856 -280.043235) (xy 69.96884 -280.025783)
			(xy 69.926219 -280.001176) (xy 69.888098 -279.970051) (xy 69.855463 -279.933214) (xy 69.82916 -279.891618)
			(xy 69.809869 -279.846342) (xy 69.798092 -279.798558) (xy 69.794132 -279.749504) (xy 68.50507 -279.749504)
			(xy 68.504575 -279.774111) (xy 68.49668 -279.822688) (xy 68.481096 -279.869369) (xy 68.458225 -279.912946)
			(xy 68.42866 -279.95229) (xy 68.393167 -279.986382) (xy 68.352664 -280.014338) (xy 68.308202 -280.035436)
			(xy 68.260931 -280.049128) (xy 68.212076 -280.05506) (xy 68.162901 -280.053079) (xy 68.114682 -280.043235)
			(xy 68.068666 -280.025783) (xy 68.026045 -280.001176) (xy 67.987924 -279.970051) (xy 67.955289 -279.933214)
			(xy 67.928986 -279.891618) (xy 67.909695 -279.846342) (xy 67.897918 -279.798558) (xy 67.893958 -279.749504)
			(xy 66.60515 -279.749504) (xy 66.604655 -279.774111) (xy 66.59676 -279.822688) (xy 66.581176 -279.869369)
			(xy 66.558305 -279.912946) (xy 66.52874 -279.95229) (xy 66.493247 -279.986382) (xy 66.452744 -280.014338)
			(xy 66.408282 -280.035436) (xy 66.361011 -280.049128) (xy 66.312156 -280.05506) (xy 66.262981 -280.053079)
			(xy 66.214762 -280.043235) (xy 66.168746 -280.025783) (xy 66.126125 -280.001176) (xy 66.088004 -279.970051)
			(xy 66.055369 -279.933214) (xy 66.029066 -279.891618) (xy 66.009775 -279.846342) (xy 65.997998 -279.798558)
			(xy 65.994038 -279.749504) (xy 64.70523 -279.749504) (xy 64.704735 -279.774111) (xy 64.69684 -279.822688)
			(xy 64.681256 -279.869369) (xy 64.658385 -279.912946) (xy 64.62882 -279.95229) (xy 64.593327 -279.986382)
			(xy 64.552824 -280.014338) (xy 64.508362 -280.035436) (xy 64.461091 -280.049128) (xy 64.412236 -280.05506)
			(xy 64.363061 -280.053079) (xy 64.314842 -280.043235) (xy 64.268826 -280.025783) (xy 64.226205 -280.001176)
			(xy 64.188084 -279.970051) (xy 64.155449 -279.933214) (xy 64.129146 -279.891618) (xy 64.109855 -279.846342)
			(xy 64.098078 -279.798558) (xy 64.094118 -279.749504) (xy 62.805056 -279.749504) (xy 62.804561 -279.774111)
			(xy 62.796666 -279.822688) (xy 62.781082 -279.869369) (xy 62.758211 -279.912946) (xy 62.728646 -279.95229)
			(xy 62.693153 -279.986382) (xy 62.65265 -280.014338) (xy 62.608188 -280.035436) (xy 62.560917 -280.049128)
			(xy 62.512062 -280.05506) (xy 62.462887 -280.053079) (xy 62.414668 -280.043235) (xy 62.368652 -280.025783)
			(xy 62.326031 -280.001176) (xy 62.28791 -279.970051) (xy 62.255275 -279.933214) (xy 62.228972 -279.891618)
			(xy 62.209681 -279.846342) (xy 62.197904 -279.798558) (xy 62.193944 -279.749504) (xy 60.905136 -279.749504)
			(xy 60.904641 -279.774111) (xy 60.896746 -279.822688) (xy 60.881162 -279.869369) (xy 60.858291 -279.912946)
			(xy 60.828726 -279.95229) (xy 60.793233 -279.986382) (xy 60.75273 -280.014338) (xy 60.708268 -280.035436)
			(xy 60.660997 -280.049128) (xy 60.612142 -280.05506) (xy 60.562967 -280.053079) (xy 60.514748 -280.043235)
			(xy 60.468732 -280.025783) (xy 60.426111 -280.001176) (xy 60.38799 -279.970051) (xy 60.355355 -279.933214)
			(xy 60.329052 -279.891618) (xy 60.309761 -279.846342) (xy 60.297984 -279.798558) (xy 60.294024 -279.749504)
			(xy 59.005216 -279.749504) (xy 59.004721 -279.774111) (xy 58.996826 -279.822688) (xy 58.981242 -279.869369)
			(xy 58.958371 -279.912946) (xy 58.928806 -279.95229) (xy 58.893313 -279.986382) (xy 58.85281 -280.014338)
			(xy 58.808348 -280.035436) (xy 58.761077 -280.049128) (xy 58.712222 -280.05506) (xy 58.663047 -280.053079)
			(xy 58.614828 -280.043235) (xy 58.568812 -280.025783) (xy 58.526191 -280.001176) (xy 58.48807 -279.970051)
			(xy 58.455435 -279.933214) (xy 58.429132 -279.891618) (xy 58.409841 -279.846342) (xy 58.398064 -279.798558)
			(xy 58.394104 -279.749504) (xy 57.105042 -279.749504) (xy 57.104547 -279.774111) (xy 57.096652 -279.822688)
			(xy 57.081068 -279.869369) (xy 57.058197 -279.912946) (xy 57.028632 -279.95229) (xy 56.993139 -279.986382)
			(xy 56.952636 -280.014338) (xy 56.908174 -280.035436) (xy 56.860903 -280.049128) (xy 56.812048 -280.05506)
			(xy 56.762873 -280.053079) (xy 56.714654 -280.043235) (xy 56.668638 -280.025783) (xy 56.626017 -280.001176)
			(xy 56.587896 -279.970051) (xy 56.555261 -279.933214) (xy 56.528958 -279.891618) (xy 56.509667 -279.846342)
			(xy 56.49789 -279.798558) (xy 56.49393 -279.749504) (xy 55.205122 -279.749504) (xy 55.204627 -279.774111)
			(xy 55.196732 -279.822688) (xy 55.181148 -279.869369) (xy 55.158277 -279.912946) (xy 55.128712 -279.95229)
			(xy 55.093219 -279.986382) (xy 55.052716 -280.014338) (xy 55.008254 -280.035436) (xy 54.960983 -280.049128)
			(xy 54.912128 -280.05506) (xy 54.862953 -280.053079) (xy 54.814734 -280.043235) (xy 54.768718 -280.025783)
			(xy 54.726097 -280.001176) (xy 54.687976 -279.970051) (xy 54.655341 -279.933214) (xy 54.629038 -279.891618)
			(xy 54.609747 -279.846342) (xy 54.59797 -279.798558) (xy 54.59401 -279.749504) (xy 53.305202 -279.749504)
			(xy 53.304707 -279.774111) (xy 53.296812 -279.822688) (xy 53.281228 -279.869369) (xy 53.258357 -279.912946)
			(xy 53.228792 -279.95229) (xy 53.193299 -279.986382) (xy 53.152796 -280.014338) (xy 53.108334 -280.035436)
			(xy 53.061063 -280.049128) (xy 53.012208 -280.05506) (xy 52.963033 -280.053079) (xy 52.914814 -280.043235)
			(xy 52.868798 -280.025783) (xy 52.826177 -280.001176) (xy 52.788056 -279.970051) (xy 52.755421 -279.933214)
			(xy 52.729118 -279.891618) (xy 52.709827 -279.846342) (xy 52.69805 -279.798558) (xy 52.69409 -279.749504)
			(xy 51.405282 -279.749504) (xy 51.404787 -279.774111) (xy 51.396892 -279.822688) (xy 51.381308 -279.869369)
			(xy 51.358437 -279.912946) (xy 51.328872 -279.95229) (xy 51.293379 -279.986382) (xy 51.252876 -280.014338)
			(xy 51.208414 -280.035436) (xy 51.161143 -280.049128) (xy 51.112288 -280.05506) (xy 51.063113 -280.053079)
			(xy 51.014894 -280.043235) (xy 50.968878 -280.025783) (xy 50.926257 -280.001176) (xy 50.888136 -279.970051)
			(xy 50.855501 -279.933214) (xy 50.829198 -279.891618) (xy 50.809907 -279.846342) (xy 50.79813 -279.798558)
			(xy 50.79417 -279.749504) (xy 49.505108 -279.749504) (xy 49.504613 -279.774111) (xy 49.496718 -279.822688)
			(xy 49.481134 -279.869369) (xy 49.458263 -279.912946) (xy 49.428698 -279.95229) (xy 49.393205 -279.986382)
			(xy 49.352702 -280.014338) (xy 49.30824 -280.035436) (xy 49.260969 -280.049128) (xy 49.212114 -280.05506)
			(xy 49.162939 -280.053079) (xy 49.11472 -280.043235) (xy 49.068704 -280.025783) (xy 49.026083 -280.001176)
			(xy 48.987962 -279.970051) (xy 48.955327 -279.933214) (xy 48.929024 -279.891618) (xy 48.909733 -279.846342)
			(xy 48.897956 -279.798558) (xy 48.893996 -279.749504) (xy 47.605188 -279.749504) (xy 47.604693 -279.774111)
			(xy 47.596798 -279.822688) (xy 47.581214 -279.869369) (xy 47.558343 -279.912946) (xy 47.528778 -279.95229)
			(xy 47.493285 -279.986382) (xy 47.452782 -280.014338) (xy 47.40832 -280.035436) (xy 47.361049 -280.049128)
			(xy 47.312194 -280.05506) (xy 47.263019 -280.053079) (xy 47.2148 -280.043235) (xy 47.168784 -280.025783)
			(xy 47.126163 -280.001176) (xy 47.088042 -279.970051) (xy 47.055407 -279.933214) (xy 47.029104 -279.891618)
			(xy 47.009813 -279.846342) (xy 46.998036 -279.798558) (xy 46.994076 -279.749504) (xy 45.705268 -279.749504)
			(xy 45.704773 -279.774111) (xy 45.696878 -279.822688) (xy 45.681294 -279.869369) (xy 45.658423 -279.912946)
			(xy 45.628858 -279.95229) (xy 45.593365 -279.986382) (xy 45.552862 -280.014338) (xy 45.5084 -280.035436)
			(xy 45.461129 -280.049128) (xy 45.412274 -280.05506) (xy 45.363099 -280.053079) (xy 45.31488 -280.043235)
			(xy 45.268864 -280.025783) (xy 45.226243 -280.001176) (xy 45.188122 -279.970051) (xy 45.155487 -279.933214)
			(xy 45.129184 -279.891618) (xy 45.109893 -279.846342) (xy 45.098116 -279.798558) (xy 45.094156 -279.749504)
			(xy 0.508 -279.749504) (xy 0.508 -280.699718) (xy 45.094156 -280.699718) (xy 45.098116 -280.650664)
			(xy 45.109893 -280.60288) (xy 45.129184 -280.557604) (xy 45.155487 -280.516008) (xy 45.188122 -280.479171)
			(xy 45.226243 -280.448046) (xy 45.268864 -280.423439) (xy 45.31488 -280.405987) (xy 45.363099 -280.396143)
			(xy 45.412274 -280.394162) (xy 45.461129 -280.400094) (xy 45.5084 -280.413786) (xy 45.552862 -280.434884)
			(xy 45.593365 -280.46284) (xy 45.628858 -280.496932) (xy 45.658423 -280.536276) (xy 45.681294 -280.579853)
			(xy 45.696878 -280.626534) (xy 45.704773 -280.675111) (xy 45.705268 -280.699718) (xy 46.994076 -280.699718)
			(xy 46.998036 -280.650664) (xy 47.009813 -280.60288) (xy 47.029104 -280.557604) (xy 47.055407 -280.516008)
			(xy 47.088042 -280.479171) (xy 47.126163 -280.448046) (xy 47.168784 -280.423439) (xy 47.2148 -280.405987)
			(xy 47.263019 -280.396143) (xy 47.312194 -280.394162) (xy 47.361049 -280.400094) (xy 47.40832 -280.413786)
			(xy 47.452782 -280.434884) (xy 47.493285 -280.46284) (xy 47.528778 -280.496932) (xy 47.558343 -280.536276)
			(xy 47.581214 -280.579853) (xy 47.596798 -280.626534) (xy 47.604693 -280.675111) (xy 47.605188 -280.699718)
			(xy 48.893996 -280.699718) (xy 48.897956 -280.650664) (xy 48.909733 -280.60288) (xy 48.929024 -280.557604)
			(xy 48.955327 -280.516008) (xy 48.987962 -280.479171) (xy 49.026083 -280.448046) (xy 49.068704 -280.423439)
			(xy 49.11472 -280.405987) (xy 49.162939 -280.396143) (xy 49.212114 -280.394162) (xy 49.260969 -280.400094)
			(xy 49.30824 -280.413786) (xy 49.352702 -280.434884) (xy 49.393205 -280.46284) (xy 49.428698 -280.496932)
			(xy 49.458263 -280.536276) (xy 49.481134 -280.579853) (xy 49.496718 -280.626534) (xy 49.504613 -280.675111)
			(xy 49.505108 -280.699718) (xy 50.79417 -280.699718) (xy 50.79813 -280.650664) (xy 50.809907 -280.60288)
			(xy 50.829198 -280.557604) (xy 50.855501 -280.516008) (xy 50.888136 -280.479171) (xy 50.926257 -280.448046)
			(xy 50.968878 -280.423439) (xy 51.014894 -280.405987) (xy 51.063113 -280.396143) (xy 51.112288 -280.394162)
			(xy 51.161143 -280.400094) (xy 51.208414 -280.413786) (xy 51.252876 -280.434884) (xy 51.293379 -280.46284)
			(xy 51.328872 -280.496932) (xy 51.358437 -280.536276) (xy 51.381308 -280.579853) (xy 51.396892 -280.626534)
			(xy 51.404787 -280.675111) (xy 51.405282 -280.699718) (xy 52.69409 -280.699718) (xy 52.69805 -280.650664)
			(xy 52.709827 -280.60288) (xy 52.729118 -280.557604) (xy 52.755421 -280.516008) (xy 52.788056 -280.479171)
			(xy 52.826177 -280.448046) (xy 52.868798 -280.423439) (xy 52.914814 -280.405987) (xy 52.963033 -280.396143)
			(xy 53.012208 -280.394162) (xy 53.061063 -280.400094) (xy 53.108334 -280.413786) (xy 53.152796 -280.434884)
			(xy 53.193299 -280.46284) (xy 53.228792 -280.496932) (xy 53.258357 -280.536276) (xy 53.281228 -280.579853)
			(xy 53.296812 -280.626534) (xy 53.304707 -280.675111) (xy 53.305202 -280.699718) (xy 54.59401 -280.699718)
			(xy 54.59797 -280.650664) (xy 54.609747 -280.60288) (xy 54.629038 -280.557604) (xy 54.655341 -280.516008)
			(xy 54.687976 -280.479171) (xy 54.726097 -280.448046) (xy 54.768718 -280.423439) (xy 54.814734 -280.405987)
			(xy 54.862953 -280.396143) (xy 54.912128 -280.394162) (xy 54.960983 -280.400094) (xy 55.008254 -280.413786)
			(xy 55.052716 -280.434884) (xy 55.093219 -280.46284) (xy 55.128712 -280.496932) (xy 55.158277 -280.536276)
			(xy 55.181148 -280.579853) (xy 55.196732 -280.626534) (xy 55.204627 -280.675111) (xy 55.205122 -280.699718)
			(xy 56.49393 -280.699718) (xy 56.49789 -280.650664) (xy 56.509667 -280.60288) (xy 56.528958 -280.557604)
			(xy 56.555261 -280.516008) (xy 56.587896 -280.479171) (xy 56.626017 -280.448046) (xy 56.668638 -280.423439)
			(xy 56.714654 -280.405987) (xy 56.762873 -280.396143) (xy 56.812048 -280.394162) (xy 56.860903 -280.400094)
			(xy 56.908174 -280.413786) (xy 56.952636 -280.434884) (xy 56.993139 -280.46284) (xy 57.028632 -280.496932)
			(xy 57.058197 -280.536276) (xy 57.081068 -280.579853) (xy 57.096652 -280.626534) (xy 57.104547 -280.675111)
			(xy 57.105042 -280.699718) (xy 58.394104 -280.699718) (xy 58.398064 -280.650664) (xy 58.409841 -280.60288)
			(xy 58.429132 -280.557604) (xy 58.455435 -280.516008) (xy 58.48807 -280.479171) (xy 58.526191 -280.448046)
			(xy 58.568812 -280.423439) (xy 58.614828 -280.405987) (xy 58.663047 -280.396143) (xy 58.712222 -280.394162)
			(xy 58.761077 -280.400094) (xy 58.808348 -280.413786) (xy 58.85281 -280.434884) (xy 58.893313 -280.46284)
			(xy 58.928806 -280.496932) (xy 58.958371 -280.536276) (xy 58.981242 -280.579853) (xy 58.996826 -280.626534)
			(xy 59.004721 -280.675111) (xy 59.005216 -280.699718) (xy 60.294024 -280.699718) (xy 60.297984 -280.650664)
			(xy 60.309761 -280.60288) (xy 60.329052 -280.557604) (xy 60.355355 -280.516008) (xy 60.38799 -280.479171)
			(xy 60.426111 -280.448046) (xy 60.468732 -280.423439) (xy 60.514748 -280.405987) (xy 60.562967 -280.396143)
			(xy 60.612142 -280.394162) (xy 60.660997 -280.400094) (xy 60.708268 -280.413786) (xy 60.75273 -280.434884)
			(xy 60.793233 -280.46284) (xy 60.828726 -280.496932) (xy 60.858291 -280.536276) (xy 60.881162 -280.579853)
			(xy 60.896746 -280.626534) (xy 60.904641 -280.675111) (xy 60.905136 -280.699718) (xy 62.193944 -280.699718)
			(xy 62.197904 -280.650664) (xy 62.209681 -280.60288) (xy 62.228972 -280.557604) (xy 62.255275 -280.516008)
			(xy 62.28791 -280.479171) (xy 62.326031 -280.448046) (xy 62.368652 -280.423439) (xy 62.414668 -280.405987)
			(xy 62.462887 -280.396143) (xy 62.512062 -280.394162) (xy 62.560917 -280.400094) (xy 62.608188 -280.413786)
			(xy 62.65265 -280.434884) (xy 62.693153 -280.46284) (xy 62.728646 -280.496932) (xy 62.758211 -280.536276)
			(xy 62.781082 -280.579853) (xy 62.796666 -280.626534) (xy 62.804561 -280.675111) (xy 62.805056 -280.699718)
			(xy 64.094118 -280.699718) (xy 64.098078 -280.650664) (xy 64.109855 -280.60288) (xy 64.129146 -280.557604)
			(xy 64.155449 -280.516008) (xy 64.188084 -280.479171) (xy 64.226205 -280.448046) (xy 64.268826 -280.423439)
			(xy 64.314842 -280.405987) (xy 64.363061 -280.396143) (xy 64.412236 -280.394162) (xy 64.461091 -280.400094)
			(xy 64.508362 -280.413786) (xy 64.552824 -280.434884) (xy 64.593327 -280.46284) (xy 64.62882 -280.496932)
			(xy 64.658385 -280.536276) (xy 64.681256 -280.579853) (xy 64.69684 -280.626534) (xy 64.704735 -280.675111)
			(xy 64.70523 -280.699718) (xy 65.994038 -280.699718) (xy 65.997998 -280.650664) (xy 66.009775 -280.60288)
			(xy 66.029066 -280.557604) (xy 66.055369 -280.516008) (xy 66.088004 -280.479171) (xy 66.126125 -280.448046)
			(xy 66.168746 -280.423439) (xy 66.214762 -280.405987) (xy 66.262981 -280.396143) (xy 66.312156 -280.394162)
			(xy 66.361011 -280.400094) (xy 66.408282 -280.413786) (xy 66.452744 -280.434884) (xy 66.493247 -280.46284)
			(xy 66.52874 -280.496932) (xy 66.558305 -280.536276) (xy 66.581176 -280.579853) (xy 66.59676 -280.626534)
			(xy 66.604655 -280.675111) (xy 66.60515 -280.699718) (xy 67.893958 -280.699718) (xy 67.897918 -280.650664)
			(xy 67.909695 -280.60288) (xy 67.928986 -280.557604) (xy 67.955289 -280.516008) (xy 67.987924 -280.479171)
			(xy 68.026045 -280.448046) (xy 68.068666 -280.423439) (xy 68.114682 -280.405987) (xy 68.162901 -280.396143)
			(xy 68.212076 -280.394162) (xy 68.260931 -280.400094) (xy 68.308202 -280.413786) (xy 68.352664 -280.434884)
			(xy 68.393167 -280.46284) (xy 68.42866 -280.496932) (xy 68.458225 -280.536276) (xy 68.481096 -280.579853)
			(xy 68.49668 -280.626534) (xy 68.504575 -280.675111) (xy 68.50507 -280.699718) (xy 69.794132 -280.699718)
			(xy 69.798092 -280.650664) (xy 69.809869 -280.60288) (xy 69.82916 -280.557604) (xy 69.855463 -280.516008)
			(xy 69.888098 -280.479171) (xy 69.926219 -280.448046) (xy 69.96884 -280.423439) (xy 70.014856 -280.405987)
			(xy 70.063075 -280.396143) (xy 70.11225 -280.394162) (xy 70.161105 -280.400094) (xy 70.208376 -280.413786)
			(xy 70.252838 -280.434884) (xy 70.293341 -280.46284) (xy 70.328834 -280.496932) (xy 70.358399 -280.536276)
			(xy 70.38127 -280.579853) (xy 70.396854 -280.626534) (xy 70.404749 -280.675111) (xy 70.405244 -280.699718)
			(xy 71.694052 -280.699718) (xy 71.698012 -280.650664) (xy 71.709789 -280.60288) (xy 71.72908 -280.557604)
			(xy 71.755383 -280.516008) (xy 71.788018 -280.479171) (xy 71.826139 -280.448046) (xy 71.86876 -280.423439)
			(xy 71.914776 -280.405987) (xy 71.962995 -280.396143) (xy 72.01217 -280.394162) (xy 72.061025 -280.400094)
			(xy 72.108296 -280.413786) (xy 72.152758 -280.434884) (xy 72.193261 -280.46284) (xy 72.228754 -280.496932)
			(xy 72.258319 -280.536276) (xy 72.28119 -280.579853) (xy 72.296774 -280.626534) (xy 72.304669 -280.675111)
			(xy 72.305164 -280.699718) (xy 73.593972 -280.699718) (xy 73.597932 -280.650664) (xy 73.609709 -280.60288)
			(xy 73.629 -280.557604) (xy 73.655303 -280.516008) (xy 73.687938 -280.479171) (xy 73.726059 -280.448046)
			(xy 73.76868 -280.423439) (xy 73.814696 -280.405987) (xy 73.862915 -280.396143) (xy 73.91209 -280.394162)
			(xy 73.960945 -280.400094) (xy 74.008216 -280.413786) (xy 74.052678 -280.434884) (xy 74.093181 -280.46284)
			(xy 74.128674 -280.496932) (xy 74.158239 -280.536276) (xy 74.18111 -280.579853) (xy 74.196694 -280.626534)
			(xy 74.204589 -280.675111) (xy 74.205084 -280.699718) (xy 75.494146 -280.699718) (xy 75.498106 -280.650664)
			(xy 75.509883 -280.60288) (xy 75.529174 -280.557604) (xy 75.555477 -280.516008) (xy 75.588112 -280.479171)
			(xy 75.626233 -280.448046) (xy 75.668854 -280.423439) (xy 75.71487 -280.405987) (xy 75.763089 -280.396143)
			(xy 75.812264 -280.394162) (xy 75.861119 -280.400094) (xy 75.90839 -280.413786) (xy 75.952852 -280.434884)
			(xy 75.993355 -280.46284) (xy 76.028848 -280.496932) (xy 76.058413 -280.536276) (xy 76.081284 -280.579853)
			(xy 76.096868 -280.626534) (xy 76.104763 -280.675111) (xy 76.105258 -280.699718) (xy 77.394066 -280.699718)
			(xy 77.398026 -280.650664) (xy 77.409803 -280.60288) (xy 77.429094 -280.557604) (xy 77.455397 -280.516008)
			(xy 77.488032 -280.479171) (xy 77.526153 -280.448046) (xy 77.568774 -280.423439) (xy 77.61479 -280.405987)
			(xy 77.663009 -280.396143) (xy 77.712184 -280.394162) (xy 77.761039 -280.400094) (xy 77.80831 -280.413786)
			(xy 77.852772 -280.434884) (xy 77.893275 -280.46284) (xy 77.928768 -280.496932) (xy 77.958333 -280.536276)
			(xy 77.981204 -280.579853) (xy 77.996788 -280.626534) (xy 78.004683 -280.675111) (xy 78.005178 -280.699718)
			(xy 79.293986 -280.699718) (xy 79.297946 -280.650664) (xy 79.309723 -280.60288) (xy 79.329014 -280.557604)
			(xy 79.355317 -280.516008) (xy 79.387952 -280.479171) (xy 79.426073 -280.448046) (xy 79.468694 -280.423439)
			(xy 79.51471 -280.405987) (xy 79.562929 -280.396143) (xy 79.612104 -280.394162) (xy 79.660959 -280.400094)
			(xy 79.70823 -280.413786) (xy 79.752692 -280.434884) (xy 79.793195 -280.46284) (xy 79.828688 -280.496932)
			(xy 79.858253 -280.536276) (xy 79.881124 -280.579853) (xy 79.896708 -280.626534) (xy 79.904603 -280.675111)
			(xy 79.905098 -280.699718) (xy 161.194254 -280.699718) (xy 161.198214 -280.650664) (xy 161.209991 -280.60288)
			(xy 161.229282 -280.557604) (xy 161.255585 -280.516008) (xy 161.28822 -280.479171) (xy 161.326341 -280.448046)
			(xy 161.368962 -280.423439) (xy 161.414978 -280.405987) (xy 161.463197 -280.396143) (xy 161.512372 -280.394162)
			(xy 161.561227 -280.400094) (xy 161.608498 -280.413786) (xy 161.65296 -280.434884) (xy 161.693463 -280.46284)
			(xy 161.728956 -280.496932) (xy 161.758521 -280.536276) (xy 161.781392 -280.579853) (xy 161.796976 -280.626534)
			(xy 161.804871 -280.675111) (xy 161.805366 -280.699718) (xy 163.094174 -280.699718) (xy 163.098134 -280.650664)
			(xy 163.109911 -280.60288) (xy 163.129202 -280.557604) (xy 163.155505 -280.516008) (xy 163.18814 -280.479171)
			(xy 163.226261 -280.448046) (xy 163.268882 -280.423439) (xy 163.314898 -280.405987) (xy 163.363117 -280.396143)
			(xy 163.412292 -280.394162) (xy 163.461147 -280.400094) (xy 163.508418 -280.413786) (xy 163.55288 -280.434884)
			(xy 163.593383 -280.46284) (xy 163.628876 -280.496932) (xy 163.658441 -280.536276) (xy 163.681312 -280.579853)
			(xy 163.696896 -280.626534) (xy 163.704791 -280.675111) (xy 163.705286 -280.699718) (xy 164.994094 -280.699718)
			(xy 164.998054 -280.650664) (xy 165.009831 -280.60288) (xy 165.029122 -280.557604) (xy 165.055425 -280.516008)
			(xy 165.08806 -280.479171) (xy 165.126181 -280.448046) (xy 165.168802 -280.423439) (xy 165.214818 -280.405987)
			(xy 165.263037 -280.396143) (xy 165.312212 -280.394162) (xy 165.361067 -280.400094) (xy 165.408338 -280.413786)
			(xy 165.4528 -280.434884) (xy 165.493303 -280.46284) (xy 165.528796 -280.496932) (xy 165.558361 -280.536276)
			(xy 165.581232 -280.579853) (xy 165.596816 -280.626534) (xy 165.604711 -280.675111) (xy 165.605206 -280.699718)
			(xy 166.894268 -280.699718) (xy 166.898228 -280.650664) (xy 166.910005 -280.60288) (xy 166.929296 -280.557604)
			(xy 166.955599 -280.516008) (xy 166.988234 -280.479171) (xy 167.026355 -280.448046) (xy 167.068976 -280.423439)
			(xy 167.114992 -280.405987) (xy 167.163211 -280.396143) (xy 167.212386 -280.394162) (xy 167.261241 -280.400094)
			(xy 167.308512 -280.413786) (xy 167.352974 -280.434884) (xy 167.393477 -280.46284) (xy 167.42897 -280.496932)
			(xy 167.458535 -280.536276) (xy 167.481406 -280.579853) (xy 167.49699 -280.626534) (xy 167.504885 -280.675111)
			(xy 167.50538 -280.699718) (xy 168.794188 -280.699718) (xy 168.798148 -280.650664) (xy 168.809925 -280.60288)
			(xy 168.829216 -280.557604) (xy 168.855519 -280.516008) (xy 168.888154 -280.479171) (xy 168.926275 -280.448046)
			(xy 168.968896 -280.423439) (xy 169.014912 -280.405987) (xy 169.063131 -280.396143) (xy 169.112306 -280.394162)
			(xy 169.161161 -280.400094) (xy 169.208432 -280.413786) (xy 169.252894 -280.434884) (xy 169.293397 -280.46284)
			(xy 169.32889 -280.496932) (xy 169.358455 -280.536276) (xy 169.381326 -280.579853) (xy 169.39691 -280.626534)
			(xy 169.404805 -280.675111) (xy 169.4053 -280.699718) (xy 170.694108 -280.699718) (xy 170.698068 -280.650664)
			(xy 170.709845 -280.60288) (xy 170.729136 -280.557604) (xy 170.755439 -280.516008) (xy 170.788074 -280.479171)
			(xy 170.826195 -280.448046) (xy 170.868816 -280.423439) (xy 170.914832 -280.405987) (xy 170.963051 -280.396143)
			(xy 171.012226 -280.394162) (xy 171.061081 -280.400094) (xy 171.108352 -280.413786) (xy 171.152814 -280.434884)
			(xy 171.193317 -280.46284) (xy 171.22881 -280.496932) (xy 171.258375 -280.536276) (xy 171.281246 -280.579853)
			(xy 171.29683 -280.626534) (xy 171.304725 -280.675111) (xy 171.30522 -280.699718) (xy 172.594028 -280.699718)
			(xy 172.597988 -280.650664) (xy 172.609765 -280.60288) (xy 172.629056 -280.557604) (xy 172.655359 -280.516008)
			(xy 172.687994 -280.479171) (xy 172.726115 -280.448046) (xy 172.768736 -280.423439) (xy 172.814752 -280.405987)
			(xy 172.862971 -280.396143) (xy 172.912146 -280.394162) (xy 172.961001 -280.400094) (xy 173.008272 -280.413786)
			(xy 173.052734 -280.434884) (xy 173.093237 -280.46284) (xy 173.12873 -280.496932) (xy 173.158295 -280.536276)
			(xy 173.181166 -280.579853) (xy 173.19675 -280.626534) (xy 173.204645 -280.675111) (xy 173.20514 -280.699718)
			(xy 174.494202 -280.699718) (xy 174.498162 -280.650664) (xy 174.509939 -280.60288) (xy 174.52923 -280.557604)
			(xy 174.555533 -280.516008) (xy 174.588168 -280.479171) (xy 174.626289 -280.448046) (xy 174.66891 -280.423439)
			(xy 174.714926 -280.405987) (xy 174.763145 -280.396143) (xy 174.81232 -280.394162) (xy 174.861175 -280.400094)
			(xy 174.908446 -280.413786) (xy 174.952908 -280.434884) (xy 174.993411 -280.46284) (xy 175.028904 -280.496932)
			(xy 175.058469 -280.536276) (xy 175.08134 -280.579853) (xy 175.096924 -280.626534) (xy 175.104819 -280.675111)
			(xy 175.105314 -280.699718) (xy 176.394122 -280.699718) (xy 176.398082 -280.650664) (xy 176.409859 -280.60288)
			(xy 176.42915 -280.557604) (xy 176.455453 -280.516008) (xy 176.488088 -280.479171) (xy 176.526209 -280.448046)
			(xy 176.56883 -280.423439) (xy 176.614846 -280.405987) (xy 176.663065 -280.396143) (xy 176.71224 -280.394162)
			(xy 176.761095 -280.400094) (xy 176.808366 -280.413786) (xy 176.852828 -280.434884) (xy 176.893331 -280.46284)
			(xy 176.928824 -280.496932) (xy 176.958389 -280.536276) (xy 176.98126 -280.579853) (xy 176.996844 -280.626534)
			(xy 177.004739 -280.675111) (xy 177.005234 -280.699718) (xy 178.294042 -280.699718) (xy 178.298002 -280.650664)
			(xy 178.309779 -280.60288) (xy 178.32907 -280.557604) (xy 178.355373 -280.516008) (xy 178.388008 -280.479171)
			(xy 178.426129 -280.448046) (xy 178.46875 -280.423439) (xy 178.514766 -280.405987) (xy 178.562985 -280.396143)
			(xy 178.61216 -280.394162) (xy 178.661015 -280.400094) (xy 178.708286 -280.413786) (xy 178.752748 -280.434884)
			(xy 178.793251 -280.46284) (xy 178.828744 -280.496932) (xy 178.858309 -280.536276) (xy 178.88118 -280.579853)
			(xy 178.896764 -280.626534) (xy 178.904659 -280.675111) (xy 178.905154 -280.699718) (xy 180.194216 -280.699718)
			(xy 180.198176 -280.650664) (xy 180.209953 -280.60288) (xy 180.229244 -280.557604) (xy 180.255547 -280.516008)
			(xy 180.288182 -280.479171) (xy 180.326303 -280.448046) (xy 180.368924 -280.423439) (xy 180.41494 -280.405987)
			(xy 180.463159 -280.396143) (xy 180.512334 -280.394162) (xy 180.561189 -280.400094) (xy 180.60846 -280.413786)
			(xy 180.652922 -280.434884) (xy 180.693425 -280.46284) (xy 180.728918 -280.496932) (xy 180.758483 -280.536276)
			(xy 180.781354 -280.579853) (xy 180.796938 -280.626534) (xy 180.804833 -280.675111) (xy 180.805328 -280.699718)
			(xy 182.094136 -280.699718) (xy 182.098096 -280.650664) (xy 182.109873 -280.60288) (xy 182.129164 -280.557604)
			(xy 182.155467 -280.516008) (xy 182.188102 -280.479171) (xy 182.226223 -280.448046) (xy 182.268844 -280.423439)
			(xy 182.31486 -280.405987) (xy 182.363079 -280.396143) (xy 182.412254 -280.394162) (xy 182.461109 -280.400094)
			(xy 182.50838 -280.413786) (xy 182.552842 -280.434884) (xy 182.593345 -280.46284) (xy 182.628838 -280.496932)
			(xy 182.658403 -280.536276) (xy 182.681274 -280.579853) (xy 182.696858 -280.626534) (xy 182.704753 -280.675111)
			(xy 182.705248 -280.699718) (xy 183.994056 -280.699718) (xy 183.998016 -280.650664) (xy 184.009793 -280.60288)
			(xy 184.029084 -280.557604) (xy 184.055387 -280.516008) (xy 184.088022 -280.479171) (xy 184.126143 -280.448046)
			(xy 184.168764 -280.423439) (xy 184.21478 -280.405987) (xy 184.262999 -280.396143) (xy 184.312174 -280.394162)
			(xy 184.361029 -280.400094) (xy 184.4083 -280.413786) (xy 184.452762 -280.434884) (xy 184.493265 -280.46284)
			(xy 184.528758 -280.496932) (xy 184.558323 -280.536276) (xy 184.581194 -280.579853) (xy 184.596778 -280.626534)
			(xy 184.604673 -280.675111) (xy 184.605168 -280.699718) (xy 185.89423 -280.699718) (xy 185.89819 -280.650664)
			(xy 185.909967 -280.60288) (xy 185.929258 -280.557604) (xy 185.955561 -280.516008) (xy 185.988196 -280.479171)
			(xy 186.026317 -280.448046) (xy 186.068938 -280.423439) (xy 186.114954 -280.405987) (xy 186.163173 -280.396143)
			(xy 186.212348 -280.394162) (xy 186.261203 -280.400094) (xy 186.308474 -280.413786) (xy 186.352936 -280.434884)
			(xy 186.393439 -280.46284) (xy 186.428932 -280.496932) (xy 186.458497 -280.536276) (xy 186.481368 -280.579853)
			(xy 186.496952 -280.626534) (xy 186.504847 -280.675111) (xy 186.505342 -280.699718) (xy 187.79415 -280.699718)
			(xy 187.79811 -280.650664) (xy 187.809887 -280.60288) (xy 187.829178 -280.557604) (xy 187.855481 -280.516008)
			(xy 187.888116 -280.479171) (xy 187.926237 -280.448046) (xy 187.968858 -280.423439) (xy 188.014874 -280.405987)
			(xy 188.063093 -280.396143) (xy 188.112268 -280.394162) (xy 188.161123 -280.400094) (xy 188.208394 -280.413786)
			(xy 188.252856 -280.434884) (xy 188.293359 -280.46284) (xy 188.328852 -280.496932) (xy 188.358417 -280.536276)
			(xy 188.381288 -280.579853) (xy 188.396872 -280.626534) (xy 188.404767 -280.675111) (xy 188.405262 -280.699718)
			(xy 189.69407 -280.699718) (xy 189.69803 -280.650664) (xy 189.709807 -280.60288) (xy 189.729098 -280.557604)
			(xy 189.755401 -280.516008) (xy 189.788036 -280.479171) (xy 189.826157 -280.448046) (xy 189.868778 -280.423439)
			(xy 189.914794 -280.405987) (xy 189.963013 -280.396143) (xy 190.012188 -280.394162) (xy 190.061043 -280.400094)
			(xy 190.108314 -280.413786) (xy 190.152776 -280.434884) (xy 190.193279 -280.46284) (xy 190.228772 -280.496932)
			(xy 190.258337 -280.536276) (xy 190.281208 -280.579853) (xy 190.296792 -280.626534) (xy 190.304687 -280.675111)
			(xy 190.305182 -280.699718) (xy 191.594244 -280.699718) (xy 191.598204 -280.650664) (xy 191.609981 -280.60288)
			(xy 191.629272 -280.557604) (xy 191.655575 -280.516008) (xy 191.68821 -280.479171) (xy 191.726331 -280.448046)
			(xy 191.768952 -280.423439) (xy 191.814968 -280.405987) (xy 191.863187 -280.396143) (xy 191.912362 -280.394162)
			(xy 191.961217 -280.400094) (xy 192.008488 -280.413786) (xy 192.05295 -280.434884) (xy 192.093453 -280.46284)
			(xy 192.128946 -280.496932) (xy 192.158511 -280.536276) (xy 192.181382 -280.579853) (xy 192.196966 -280.626534)
			(xy 192.204861 -280.675111) (xy 192.205356 -280.699718) (xy 193.494164 -280.699718) (xy 193.498124 -280.650664)
			(xy 193.509901 -280.60288) (xy 193.529192 -280.557604) (xy 193.555495 -280.516008) (xy 193.58813 -280.479171)
			(xy 193.626251 -280.448046) (xy 193.668872 -280.423439) (xy 193.714888 -280.405987) (xy 193.763107 -280.396143)
			(xy 193.812282 -280.394162) (xy 193.861137 -280.400094) (xy 193.908408 -280.413786) (xy 193.95287 -280.434884)
			(xy 193.993373 -280.46284) (xy 194.028866 -280.496932) (xy 194.058431 -280.536276) (xy 194.081302 -280.579853)
			(xy 194.096886 -280.626534) (xy 194.104781 -280.675111) (xy 194.105276 -280.699718) (xy 195.394084 -280.699718)
			(xy 195.398044 -280.650664) (xy 195.409821 -280.60288) (xy 195.429112 -280.557604) (xy 195.455415 -280.516008)
			(xy 195.48805 -280.479171) (xy 195.526171 -280.448046) (xy 195.568792 -280.423439) (xy 195.614808 -280.405987)
			(xy 195.663027 -280.396143) (xy 195.712202 -280.394162) (xy 195.761057 -280.400094) (xy 195.808328 -280.413786)
			(xy 195.85279 -280.434884) (xy 195.893293 -280.46284) (xy 195.928786 -280.496932) (xy 195.958351 -280.536276)
			(xy 195.981222 -280.579853) (xy 195.996806 -280.626534) (xy 196.004701 -280.675111) (xy 196.005191 -280.699464)
			(xy 277.294098 -280.699464) (xy 277.298058 -280.65041) (xy 277.309835 -280.602626) (xy 277.329126 -280.55735)
			(xy 277.355429 -280.515754) (xy 277.388064 -280.478917) (xy 277.426185 -280.447792) (xy 277.468806 -280.423185)
			(xy 277.514822 -280.405733) (xy 277.563041 -280.395889) (xy 277.612216 -280.393908) (xy 277.661071 -280.39984)
			(xy 277.708342 -280.413532) (xy 277.752804 -280.43463) (xy 277.793307 -280.462586) (xy 277.8288 -280.496678)
			(xy 277.858365 -280.536022) (xy 277.881236 -280.579599) (xy 277.89682 -280.62628) (xy 277.904715 -280.674857)
			(xy 277.90521 -280.699464) (xy 279.194018 -280.699464) (xy 279.197978 -280.65041) (xy 279.209755 -280.602626)
			(xy 279.229046 -280.55735) (xy 279.255349 -280.515754) (xy 279.287984 -280.478917) (xy 279.326105 -280.447792)
			(xy 279.368726 -280.423185) (xy 279.414742 -280.405733) (xy 279.462961 -280.395889) (xy 279.512136 -280.393908)
			(xy 279.560991 -280.39984) (xy 279.608262 -280.413532) (xy 279.652724 -280.43463) (xy 279.693227 -280.462586)
			(xy 279.72872 -280.496678) (xy 279.758285 -280.536022) (xy 279.781156 -280.579599) (xy 279.79674 -280.62628)
			(xy 279.804635 -280.674857) (xy 279.80513 -280.699464) (xy 281.093938 -280.699464) (xy 281.097898 -280.65041)
			(xy 281.109675 -280.602626) (xy 281.128966 -280.55735) (xy 281.155269 -280.515754) (xy 281.187904 -280.478917)
			(xy 281.226025 -280.447792) (xy 281.268646 -280.423185) (xy 281.314662 -280.405733) (xy 281.362881 -280.395889)
			(xy 281.412056 -280.393908) (xy 281.460911 -280.39984) (xy 281.508182 -280.413532) (xy 281.552644 -280.43463)
			(xy 281.593147 -280.462586) (xy 281.62864 -280.496678) (xy 281.658205 -280.536022) (xy 281.681076 -280.579599)
			(xy 281.69666 -280.62628) (xy 281.704555 -280.674857) (xy 281.70505 -280.699464) (xy 282.994112 -280.699464)
			(xy 282.998072 -280.65041) (xy 283.009849 -280.602626) (xy 283.02914 -280.55735) (xy 283.055443 -280.515754)
			(xy 283.088078 -280.478917) (xy 283.126199 -280.447792) (xy 283.16882 -280.423185) (xy 283.214836 -280.405733)
			(xy 283.263055 -280.395889) (xy 283.31223 -280.393908) (xy 283.361085 -280.39984) (xy 283.408356 -280.413532)
			(xy 283.452818 -280.43463) (xy 283.493321 -280.462586) (xy 283.528814 -280.496678) (xy 283.558379 -280.536022)
			(xy 283.58125 -280.579599) (xy 283.596834 -280.62628) (xy 283.604729 -280.674857) (xy 283.605224 -280.699464)
			(xy 284.894032 -280.699464) (xy 284.897992 -280.65041) (xy 284.909769 -280.602626) (xy 284.92906 -280.55735)
			(xy 284.955363 -280.515754) (xy 284.987998 -280.478917) (xy 285.026119 -280.447792) (xy 285.06874 -280.423185)
			(xy 285.114756 -280.405733) (xy 285.162975 -280.395889) (xy 285.21215 -280.393908) (xy 285.261005 -280.39984)
			(xy 285.308276 -280.413532) (xy 285.352738 -280.43463) (xy 285.393241 -280.462586) (xy 285.428734 -280.496678)
			(xy 285.458299 -280.536022) (xy 285.48117 -280.579599) (xy 285.496754 -280.62628) (xy 285.504649 -280.674857)
			(xy 285.505144 -280.699464) (xy 286.793952 -280.699464) (xy 286.797912 -280.65041) (xy 286.809689 -280.602626)
			(xy 286.82898 -280.55735) (xy 286.855283 -280.515754) (xy 286.887918 -280.478917) (xy 286.926039 -280.447792)
			(xy 286.96866 -280.423185) (xy 287.014676 -280.405733) (xy 287.062895 -280.395889) (xy 287.11207 -280.393908)
			(xy 287.160925 -280.39984) (xy 287.208196 -280.413532) (xy 287.252658 -280.43463) (xy 287.293161 -280.462586)
			(xy 287.328654 -280.496678) (xy 287.358219 -280.536022) (xy 287.38109 -280.579599) (xy 287.396674 -280.62628)
			(xy 287.404569 -280.674857) (xy 287.405064 -280.699464) (xy 288.693872 -280.699464) (xy 288.697832 -280.65041)
			(xy 288.709609 -280.602626) (xy 288.7289 -280.55735) (xy 288.755203 -280.515754) (xy 288.787838 -280.478917)
			(xy 288.825959 -280.447792) (xy 288.86858 -280.423185) (xy 288.914596 -280.405733) (xy 288.962815 -280.395889)
			(xy 289.01199 -280.393908) (xy 289.060845 -280.39984) (xy 289.108116 -280.413532) (xy 289.152578 -280.43463)
			(xy 289.193081 -280.462586) (xy 289.228574 -280.496678) (xy 289.258139 -280.536022) (xy 289.28101 -280.579599)
			(xy 289.296594 -280.62628) (xy 289.304489 -280.674857) (xy 289.304984 -280.699464) (xy 290.594046 -280.699464)
			(xy 290.598006 -280.65041) (xy 290.609783 -280.602626) (xy 290.629074 -280.55735) (xy 290.655377 -280.515754)
			(xy 290.688012 -280.478917) (xy 290.726133 -280.447792) (xy 290.768754 -280.423185) (xy 290.81477 -280.405733)
			(xy 290.862989 -280.395889) (xy 290.912164 -280.393908) (xy 290.961019 -280.39984) (xy 291.00829 -280.413532)
			(xy 291.052752 -280.43463) (xy 291.093255 -280.462586) (xy 291.128748 -280.496678) (xy 291.158313 -280.536022)
			(xy 291.181184 -280.579599) (xy 291.196768 -280.62628) (xy 291.204663 -280.674857) (xy 291.205158 -280.699464)
			(xy 292.493966 -280.699464) (xy 292.497926 -280.65041) (xy 292.509703 -280.602626) (xy 292.528994 -280.55735)
			(xy 292.555297 -280.515754) (xy 292.587932 -280.478917) (xy 292.626053 -280.447792) (xy 292.668674 -280.423185)
			(xy 292.71469 -280.405733) (xy 292.762909 -280.395889) (xy 292.812084 -280.393908) (xy 292.860939 -280.39984)
			(xy 292.90821 -280.413532) (xy 292.952672 -280.43463) (xy 292.993175 -280.462586) (xy 293.028668 -280.496678)
			(xy 293.058233 -280.536022) (xy 293.081104 -280.579599) (xy 293.096688 -280.62628) (xy 293.104583 -280.674857)
			(xy 293.105078 -280.699464) (xy 294.393886 -280.699464) (xy 294.397846 -280.65041) (xy 294.409623 -280.602626)
			(xy 294.428914 -280.55735) (xy 294.455217 -280.515754) (xy 294.487852 -280.478917) (xy 294.525973 -280.447792)
			(xy 294.568594 -280.423185) (xy 294.61461 -280.405733) (xy 294.662829 -280.395889) (xy 294.712004 -280.393908)
			(xy 294.760859 -280.39984) (xy 294.80813 -280.413532) (xy 294.852592 -280.43463) (xy 294.893095 -280.462586)
			(xy 294.928588 -280.496678) (xy 294.958153 -280.536022) (xy 294.981024 -280.579599) (xy 294.996608 -280.62628)
			(xy 295.004503 -280.674857) (xy 295.004998 -280.699464) (xy 296.29406 -280.699464) (xy 296.29802 -280.65041)
			(xy 296.309797 -280.602626) (xy 296.329088 -280.55735) (xy 296.355391 -280.515754) (xy 296.388026 -280.478917)
			(xy 296.426147 -280.447792) (xy 296.468768 -280.423185) (xy 296.514784 -280.405733) (xy 296.563003 -280.395889)
			(xy 296.612178 -280.393908) (xy 296.661033 -280.39984) (xy 296.708304 -280.413532) (xy 296.752766 -280.43463)
			(xy 296.793269 -280.462586) (xy 296.828762 -280.496678) (xy 296.858327 -280.536022) (xy 296.881198 -280.579599)
			(xy 296.896782 -280.62628) (xy 296.904677 -280.674857) (xy 296.905172 -280.699464) (xy 298.19398 -280.699464)
			(xy 298.19794 -280.65041) (xy 298.209717 -280.602626) (xy 298.229008 -280.55735) (xy 298.255311 -280.515754)
			(xy 298.287946 -280.478917) (xy 298.326067 -280.447792) (xy 298.368688 -280.423185) (xy 298.414704 -280.405733)
			(xy 298.462923 -280.395889) (xy 298.512098 -280.393908) (xy 298.560953 -280.39984) (xy 298.608224 -280.413532)
			(xy 298.652686 -280.43463) (xy 298.693189 -280.462586) (xy 298.728682 -280.496678) (xy 298.758247 -280.536022)
			(xy 298.781118 -280.579599) (xy 298.796702 -280.62628) (xy 298.804597 -280.674857) (xy 298.805092 -280.699464)
			(xy 300.0939 -280.699464) (xy 300.09786 -280.65041) (xy 300.109637 -280.602626) (xy 300.128928 -280.55735)
			(xy 300.155231 -280.515754) (xy 300.187866 -280.478917) (xy 300.225987 -280.447792) (xy 300.268608 -280.423185)
			(xy 300.314624 -280.405733) (xy 300.362843 -280.395889) (xy 300.412018 -280.393908) (xy 300.460873 -280.39984)
			(xy 300.508144 -280.413532) (xy 300.552606 -280.43463) (xy 300.593109 -280.462586) (xy 300.628602 -280.496678)
			(xy 300.658167 -280.536022) (xy 300.681038 -280.579599) (xy 300.696622 -280.62628) (xy 300.704517 -280.674857)
			(xy 300.705012 -280.699464) (xy 301.994074 -280.699464) (xy 301.998034 -280.65041) (xy 302.009811 -280.602626)
			(xy 302.029102 -280.55735) (xy 302.055405 -280.515754) (xy 302.08804 -280.478917) (xy 302.126161 -280.447792)
			(xy 302.168782 -280.423185) (xy 302.214798 -280.405733) (xy 302.263017 -280.395889) (xy 302.312192 -280.393908)
			(xy 302.361047 -280.39984) (xy 302.408318 -280.413532) (xy 302.45278 -280.43463) (xy 302.493283 -280.462586)
			(xy 302.528776 -280.496678) (xy 302.558341 -280.536022) (xy 302.581212 -280.579599) (xy 302.596796 -280.62628)
			(xy 302.604691 -280.674857) (xy 302.605186 -280.699464) (xy 303.893994 -280.699464) (xy 303.897954 -280.65041)
			(xy 303.909731 -280.602626) (xy 303.929022 -280.55735) (xy 303.955325 -280.515754) (xy 303.98796 -280.478917)
			(xy 304.026081 -280.447792) (xy 304.068702 -280.423185) (xy 304.114718 -280.405733) (xy 304.162937 -280.395889)
			(xy 304.212112 -280.393908) (xy 304.260967 -280.39984) (xy 304.308238 -280.413532) (xy 304.3527 -280.43463)
			(xy 304.393203 -280.462586) (xy 304.428696 -280.496678) (xy 304.458261 -280.536022) (xy 304.481132 -280.579599)
			(xy 304.496716 -280.62628) (xy 304.504611 -280.674857) (xy 304.505106 -280.699464) (xy 305.793914 -280.699464)
			(xy 305.797874 -280.65041) (xy 305.809651 -280.602626) (xy 305.828942 -280.55735) (xy 305.855245 -280.515754)
			(xy 305.88788 -280.478917) (xy 305.926001 -280.447792) (xy 305.968622 -280.423185) (xy 306.014638 -280.405733)
			(xy 306.062857 -280.395889) (xy 306.112032 -280.393908) (xy 306.160887 -280.39984) (xy 306.208158 -280.413532)
			(xy 306.25262 -280.43463) (xy 306.293123 -280.462586) (xy 306.328616 -280.496678) (xy 306.358181 -280.536022)
			(xy 306.381052 -280.579599) (xy 306.396636 -280.62628) (xy 306.404531 -280.674857) (xy 306.405026 -280.699464)
			(xy 307.694088 -280.699464) (xy 307.698048 -280.65041) (xy 307.709825 -280.602626) (xy 307.729116 -280.55735)
			(xy 307.755419 -280.515754) (xy 307.788054 -280.478917) (xy 307.826175 -280.447792) (xy 307.868796 -280.423185)
			(xy 307.914812 -280.405733) (xy 307.963031 -280.395889) (xy 308.012206 -280.393908) (xy 308.061061 -280.39984)
			(xy 308.108332 -280.413532) (xy 308.152794 -280.43463) (xy 308.193297 -280.462586) (xy 308.22879 -280.496678)
			(xy 308.258355 -280.536022) (xy 308.281226 -280.579599) (xy 308.29681 -280.62628) (xy 308.304705 -280.674857)
			(xy 308.3052 -280.699464) (xy 309.594008 -280.699464) (xy 309.597968 -280.65041) (xy 309.609745 -280.602626)
			(xy 309.629036 -280.55735) (xy 309.655339 -280.515754) (xy 309.687974 -280.478917) (xy 309.726095 -280.447792)
			(xy 309.768716 -280.423185) (xy 309.814732 -280.405733) (xy 309.862951 -280.395889) (xy 309.912126 -280.393908)
			(xy 309.960981 -280.39984) (xy 310.008252 -280.413532) (xy 310.052714 -280.43463) (xy 310.093217 -280.462586)
			(xy 310.12871 -280.496678) (xy 310.158275 -280.536022) (xy 310.181146 -280.579599) (xy 310.19673 -280.62628)
			(xy 310.204625 -280.674857) (xy 310.20512 -280.699464) (xy 310.205115 -280.699718) (xy 311.493928 -280.699718)
			(xy 311.497888 -280.650664) (xy 311.509665 -280.60288) (xy 311.528956 -280.557604) (xy 311.555259 -280.516008)
			(xy 311.587894 -280.479171) (xy 311.626015 -280.448046) (xy 311.668636 -280.423439) (xy 311.714652 -280.405987)
			(xy 311.762871 -280.396143) (xy 311.812046 -280.394162) (xy 311.860901 -280.400094) (xy 311.908172 -280.413786)
			(xy 311.952634 -280.434884) (xy 311.993137 -280.46284) (xy 312.02863 -280.496932) (xy 312.058195 -280.536276)
			(xy 312.081066 -280.579853) (xy 312.09665 -280.626534) (xy 312.104545 -280.675111) (xy 312.105035 -280.699464)
			(xy 393.394196 -280.699464) (xy 393.398156 -280.65041) (xy 393.409933 -280.602626) (xy 393.429224 -280.55735)
			(xy 393.455527 -280.515754) (xy 393.488162 -280.478917) (xy 393.526283 -280.447792) (xy 393.568904 -280.423185)
			(xy 393.61492 -280.405733) (xy 393.663139 -280.395889) (xy 393.712314 -280.393908) (xy 393.761169 -280.39984)
			(xy 393.80844 -280.413532) (xy 393.852902 -280.43463) (xy 393.893405 -280.462586) (xy 393.928898 -280.496678)
			(xy 393.958463 -280.536022) (xy 393.981334 -280.579599) (xy 393.996918 -280.62628) (xy 394.004813 -280.674857)
			(xy 394.005308 -280.699464) (xy 395.294116 -280.699464) (xy 395.298076 -280.65041) (xy 395.309853 -280.602626)
			(xy 395.329144 -280.55735) (xy 395.355447 -280.515754) (xy 395.388082 -280.478917) (xy 395.426203 -280.447792)
			(xy 395.468824 -280.423185) (xy 395.51484 -280.405733) (xy 395.563059 -280.395889) (xy 395.612234 -280.393908)
			(xy 395.661089 -280.39984) (xy 395.70836 -280.413532) (xy 395.752822 -280.43463) (xy 395.793325 -280.462586)
			(xy 395.828818 -280.496678) (xy 395.858383 -280.536022) (xy 395.881254 -280.579599) (xy 395.896838 -280.62628)
			(xy 395.904733 -280.674857) (xy 395.905228 -280.699464) (xy 397.194036 -280.699464) (xy 397.197996 -280.65041)
			(xy 397.209773 -280.602626) (xy 397.229064 -280.55735) (xy 397.255367 -280.515754) (xy 397.288002 -280.478917)
			(xy 397.326123 -280.447792) (xy 397.368744 -280.423185) (xy 397.41476 -280.405733) (xy 397.462979 -280.395889)
			(xy 397.512154 -280.393908) (xy 397.561009 -280.39984) (xy 397.60828 -280.413532) (xy 397.652742 -280.43463)
			(xy 397.693245 -280.462586) (xy 397.728738 -280.496678) (xy 397.758303 -280.536022) (xy 397.781174 -280.579599)
			(xy 397.796758 -280.62628) (xy 397.804653 -280.674857) (xy 397.805148 -280.699464) (xy 399.09421 -280.699464)
			(xy 399.09817 -280.65041) (xy 399.109947 -280.602626) (xy 399.129238 -280.55735) (xy 399.155541 -280.515754)
			(xy 399.188176 -280.478917) (xy 399.226297 -280.447792) (xy 399.268918 -280.423185) (xy 399.314934 -280.405733)
			(xy 399.363153 -280.395889) (xy 399.412328 -280.393908) (xy 399.461183 -280.39984) (xy 399.508454 -280.413532)
			(xy 399.552916 -280.43463) (xy 399.593419 -280.462586) (xy 399.628912 -280.496678) (xy 399.658477 -280.536022)
			(xy 399.681348 -280.579599) (xy 399.696932 -280.62628) (xy 399.704827 -280.674857) (xy 399.705322 -280.699464)
			(xy 400.99413 -280.699464) (xy 400.99809 -280.65041) (xy 401.009867 -280.602626) (xy 401.029158 -280.55735)
			(xy 401.055461 -280.515754) (xy 401.088096 -280.478917) (xy 401.126217 -280.447792) (xy 401.168838 -280.423185)
			(xy 401.214854 -280.405733) (xy 401.263073 -280.395889) (xy 401.312248 -280.393908) (xy 401.361103 -280.39984)
			(xy 401.408374 -280.413532) (xy 401.452836 -280.43463) (xy 401.493339 -280.462586) (xy 401.528832 -280.496678)
			(xy 401.558397 -280.536022) (xy 401.581268 -280.579599) (xy 401.596852 -280.62628) (xy 401.604747 -280.674857)
			(xy 401.605242 -280.699464) (xy 402.89405 -280.699464) (xy 402.89801 -280.65041) (xy 402.909787 -280.602626)
			(xy 402.929078 -280.55735) (xy 402.955381 -280.515754) (xy 402.988016 -280.478917) (xy 403.026137 -280.447792)
			(xy 403.068758 -280.423185) (xy 403.114774 -280.405733) (xy 403.162993 -280.395889) (xy 403.212168 -280.393908)
			(xy 403.261023 -280.39984) (xy 403.308294 -280.413532) (xy 403.352756 -280.43463) (xy 403.393259 -280.462586)
			(xy 403.428752 -280.496678) (xy 403.458317 -280.536022) (xy 403.481188 -280.579599) (xy 403.496772 -280.62628)
			(xy 403.504667 -280.674857) (xy 403.505162 -280.699464) (xy 404.79397 -280.699464) (xy 404.79793 -280.65041)
			(xy 404.809707 -280.602626) (xy 404.828998 -280.55735) (xy 404.855301 -280.515754) (xy 404.887936 -280.478917)
			(xy 404.926057 -280.447792) (xy 404.968678 -280.423185) (xy 405.014694 -280.405733) (xy 405.062913 -280.395889)
			(xy 405.112088 -280.393908) (xy 405.160943 -280.39984) (xy 405.208214 -280.413532) (xy 405.252676 -280.43463)
			(xy 405.293179 -280.462586) (xy 405.328672 -280.496678) (xy 405.358237 -280.536022) (xy 405.381108 -280.579599)
			(xy 405.396692 -280.62628) (xy 405.404587 -280.674857) (xy 405.405082 -280.699464) (xy 406.694144 -280.699464)
			(xy 406.698104 -280.65041) (xy 406.709881 -280.602626) (xy 406.729172 -280.55735) (xy 406.755475 -280.515754)
			(xy 406.78811 -280.478917) (xy 406.826231 -280.447792) (xy 406.868852 -280.423185) (xy 406.914868 -280.405733)
			(xy 406.963087 -280.395889) (xy 407.012262 -280.393908) (xy 407.061117 -280.39984) (xy 407.108388 -280.413532)
			(xy 407.15285 -280.43463) (xy 407.193353 -280.462586) (xy 407.228846 -280.496678) (xy 407.258411 -280.536022)
			(xy 407.281282 -280.579599) (xy 407.296866 -280.62628) (xy 407.304761 -280.674857) (xy 407.305256 -280.699464)
			(xy 408.594064 -280.699464) (xy 408.598024 -280.65041) (xy 408.609801 -280.602626) (xy 408.629092 -280.55735)
			(xy 408.655395 -280.515754) (xy 408.68803 -280.478917) (xy 408.726151 -280.447792) (xy 408.768772 -280.423185)
			(xy 408.814788 -280.405733) (xy 408.863007 -280.395889) (xy 408.912182 -280.393908) (xy 408.961037 -280.39984)
			(xy 409.008308 -280.413532) (xy 409.05277 -280.43463) (xy 409.093273 -280.462586) (xy 409.128766 -280.496678)
			(xy 409.158331 -280.536022) (xy 409.181202 -280.579599) (xy 409.196786 -280.62628) (xy 409.204681 -280.674857)
			(xy 409.205176 -280.699464) (xy 410.493984 -280.699464) (xy 410.497944 -280.65041) (xy 410.509721 -280.602626)
			(xy 410.529012 -280.55735) (xy 410.555315 -280.515754) (xy 410.58795 -280.478917) (xy 410.626071 -280.447792)
			(xy 410.668692 -280.423185) (xy 410.714708 -280.405733) (xy 410.762927 -280.395889) (xy 410.812102 -280.393908)
			(xy 410.860957 -280.39984) (xy 410.908228 -280.413532) (xy 410.95269 -280.43463) (xy 410.993193 -280.462586)
			(xy 411.028686 -280.496678) (xy 411.058251 -280.536022) (xy 411.081122 -280.579599) (xy 411.096706 -280.62628)
			(xy 411.104601 -280.674857) (xy 411.105096 -280.699464) (xy 412.394158 -280.699464) (xy 412.398118 -280.65041)
			(xy 412.409895 -280.602626) (xy 412.429186 -280.55735) (xy 412.455489 -280.515754) (xy 412.488124 -280.478917)
			(xy 412.526245 -280.447792) (xy 412.568866 -280.423185) (xy 412.614882 -280.405733) (xy 412.663101 -280.395889)
			(xy 412.712276 -280.393908) (xy 412.761131 -280.39984) (xy 412.808402 -280.413532) (xy 412.852864 -280.43463)
			(xy 412.893367 -280.462586) (xy 412.92886 -280.496678) (xy 412.958425 -280.536022) (xy 412.981296 -280.579599)
			(xy 412.99688 -280.62628) (xy 413.004775 -280.674857) (xy 413.00527 -280.699464) (xy 414.294078 -280.699464)
			(xy 414.298038 -280.65041) (xy 414.309815 -280.602626) (xy 414.329106 -280.55735) (xy 414.355409 -280.515754)
			(xy 414.388044 -280.478917) (xy 414.426165 -280.447792) (xy 414.468786 -280.423185) (xy 414.514802 -280.405733)
			(xy 414.563021 -280.395889) (xy 414.612196 -280.393908) (xy 414.661051 -280.39984) (xy 414.708322 -280.413532)
			(xy 414.752784 -280.43463) (xy 414.793287 -280.462586) (xy 414.82878 -280.496678) (xy 414.858345 -280.536022)
			(xy 414.881216 -280.579599) (xy 414.8968 -280.62628) (xy 414.904695 -280.674857) (xy 414.90519 -280.699464)
			(xy 416.193998 -280.699464) (xy 416.197958 -280.65041) (xy 416.209735 -280.602626) (xy 416.229026 -280.55735)
			(xy 416.255329 -280.515754) (xy 416.287964 -280.478917) (xy 416.326085 -280.447792) (xy 416.368706 -280.423185)
			(xy 416.414722 -280.405733) (xy 416.462941 -280.395889) (xy 416.512116 -280.393908) (xy 416.560971 -280.39984)
			(xy 416.608242 -280.413532) (xy 416.652704 -280.43463) (xy 416.693207 -280.462586) (xy 416.7287 -280.496678)
			(xy 416.758265 -280.536022) (xy 416.781136 -280.579599) (xy 416.79672 -280.62628) (xy 416.804615 -280.674857)
			(xy 416.80511 -280.699464) (xy 418.094172 -280.699464) (xy 418.098132 -280.65041) (xy 418.109909 -280.602626)
			(xy 418.1292 -280.55735) (xy 418.155503 -280.515754) (xy 418.188138 -280.478917) (xy 418.226259 -280.447792)
			(xy 418.26888 -280.423185) (xy 418.314896 -280.405733) (xy 418.363115 -280.395889) (xy 418.41229 -280.393908)
			(xy 418.461145 -280.39984) (xy 418.508416 -280.413532) (xy 418.552878 -280.43463) (xy 418.593381 -280.462586)
			(xy 418.628874 -280.496678) (xy 418.658439 -280.536022) (xy 418.68131 -280.579599) (xy 418.696894 -280.62628)
			(xy 418.704789 -280.674857) (xy 418.705284 -280.699464) (xy 419.994092 -280.699464) (xy 419.998052 -280.65041)
			(xy 420.009829 -280.602626) (xy 420.02912 -280.55735) (xy 420.055423 -280.515754) (xy 420.088058 -280.478917)
			(xy 420.126179 -280.447792) (xy 420.1688 -280.423185) (xy 420.214816 -280.405733) (xy 420.263035 -280.395889)
			(xy 420.31221 -280.393908) (xy 420.361065 -280.39984) (xy 420.408336 -280.413532) (xy 420.452798 -280.43463)
			(xy 420.493301 -280.462586) (xy 420.528794 -280.496678) (xy 420.558359 -280.536022) (xy 420.58123 -280.579599)
			(xy 420.596814 -280.62628) (xy 420.604709 -280.674857) (xy 420.605204 -280.699464) (xy 421.894012 -280.699464)
			(xy 421.897972 -280.65041) (xy 421.909749 -280.602626) (xy 421.92904 -280.55735) (xy 421.955343 -280.515754)
			(xy 421.987978 -280.478917) (xy 422.026099 -280.447792) (xy 422.06872 -280.423185) (xy 422.114736 -280.405733)
			(xy 422.162955 -280.395889) (xy 422.21213 -280.393908) (xy 422.260985 -280.39984) (xy 422.308256 -280.413532)
			(xy 422.352718 -280.43463) (xy 422.393221 -280.462586) (xy 422.428714 -280.496678) (xy 422.458279 -280.536022)
			(xy 422.48115 -280.579599) (xy 422.496734 -280.62628) (xy 422.504629 -280.674857) (xy 422.505124 -280.699464)
			(xy 423.794186 -280.699464) (xy 423.798146 -280.65041) (xy 423.809923 -280.602626) (xy 423.829214 -280.55735)
			(xy 423.855517 -280.515754) (xy 423.888152 -280.478917) (xy 423.926273 -280.447792) (xy 423.968894 -280.423185)
			(xy 424.01491 -280.405733) (xy 424.063129 -280.395889) (xy 424.112304 -280.393908) (xy 424.161159 -280.39984)
			(xy 424.20843 -280.413532) (xy 424.252892 -280.43463) (xy 424.293395 -280.462586) (xy 424.328888 -280.496678)
			(xy 424.358453 -280.536022) (xy 424.381324 -280.579599) (xy 424.396908 -280.62628) (xy 424.404803 -280.674857)
			(xy 424.405298 -280.699464) (xy 425.694106 -280.699464) (xy 425.698066 -280.65041) (xy 425.709843 -280.602626)
			(xy 425.729134 -280.55735) (xy 425.755437 -280.515754) (xy 425.788072 -280.478917) (xy 425.826193 -280.447792)
			(xy 425.868814 -280.423185) (xy 425.91483 -280.405733) (xy 425.963049 -280.395889) (xy 426.012224 -280.393908)
			(xy 426.061079 -280.39984) (xy 426.10835 -280.413532) (xy 426.152812 -280.43463) (xy 426.193315 -280.462586)
			(xy 426.228808 -280.496678) (xy 426.258373 -280.536022) (xy 426.281244 -280.579599) (xy 426.296828 -280.62628)
			(xy 426.304723 -280.674857) (xy 426.305218 -280.699464) (xy 426.305213 -280.699718) (xy 427.594026 -280.699718)
			(xy 427.597986 -280.650664) (xy 427.609763 -280.60288) (xy 427.629054 -280.557604) (xy 427.655357 -280.516008)
			(xy 427.687992 -280.479171) (xy 427.726113 -280.448046) (xy 427.768734 -280.423439) (xy 427.81475 -280.405987)
			(xy 427.862969 -280.396143) (xy 427.912144 -280.394162) (xy 427.960999 -280.400094) (xy 428.00827 -280.413786)
			(xy 428.052732 -280.434884) (xy 428.093235 -280.46284) (xy 428.128728 -280.496932) (xy 428.158293 -280.536276)
			(xy 428.181164 -280.579853) (xy 428.196748 -280.626534) (xy 428.204643 -280.675111) (xy 428.205138 -280.699718)
			(xy 428.204643 -280.724325) (xy 428.196748 -280.772902) (xy 428.181164 -280.819583) (xy 428.158293 -280.86316)
			(xy 428.128728 -280.902504) (xy 428.093235 -280.936596) (xy 428.052732 -280.964552) (xy 428.00827 -280.98565)
			(xy 427.960999 -280.999342) (xy 427.912144 -281.005274) (xy 427.862969 -281.003293) (xy 427.81475 -280.993449)
			(xy 427.768734 -280.975997) (xy 427.726113 -280.95139) (xy 427.687992 -280.920265) (xy 427.655357 -280.883428)
			(xy 427.629054 -280.841832) (xy 427.609763 -280.796556) (xy 427.597986 -280.748772) (xy 427.594026 -280.699718)
			(xy 426.305213 -280.699718) (xy 426.304723 -280.724071) (xy 426.296828 -280.772648) (xy 426.281244 -280.819329)
			(xy 426.258373 -280.862906) (xy 426.228808 -280.90225) (xy 426.193315 -280.936342) (xy 426.152812 -280.964298)
			(xy 426.10835 -280.985396) (xy 426.061079 -280.999088) (xy 426.012224 -281.00502) (xy 425.963049 -281.003039)
			(xy 425.91483 -280.993195) (xy 425.868814 -280.975743) (xy 425.826193 -280.951136) (xy 425.788072 -280.920011)
			(xy 425.755437 -280.883174) (xy 425.729134 -280.841578) (xy 425.709843 -280.796302) (xy 425.698066 -280.748518)
			(xy 425.694106 -280.699464) (xy 424.405298 -280.699464) (xy 424.404803 -280.724071) (xy 424.396908 -280.772648)
			(xy 424.381324 -280.819329) (xy 424.358453 -280.862906) (xy 424.328888 -280.90225) (xy 424.293395 -280.936342)
			(xy 424.252892 -280.964298) (xy 424.20843 -280.985396) (xy 424.161159 -280.999088) (xy 424.112304 -281.00502)
			(xy 424.063129 -281.003039) (xy 424.01491 -280.993195) (xy 423.968894 -280.975743) (xy 423.926273 -280.951136)
			(xy 423.888152 -280.920011) (xy 423.855517 -280.883174) (xy 423.829214 -280.841578) (xy 423.809923 -280.796302)
			(xy 423.798146 -280.748518) (xy 423.794186 -280.699464) (xy 422.505124 -280.699464) (xy 422.504629 -280.724071)
			(xy 422.496734 -280.772648) (xy 422.48115 -280.819329) (xy 422.458279 -280.862906) (xy 422.428714 -280.90225)
			(xy 422.393221 -280.936342) (xy 422.352718 -280.964298) (xy 422.308256 -280.985396) (xy 422.260985 -280.999088)
			(xy 422.21213 -281.00502) (xy 422.162955 -281.003039) (xy 422.114736 -280.993195) (xy 422.06872 -280.975743)
			(xy 422.026099 -280.951136) (xy 421.987978 -280.920011) (xy 421.955343 -280.883174) (xy 421.92904 -280.841578)
			(xy 421.909749 -280.796302) (xy 421.897972 -280.748518) (xy 421.894012 -280.699464) (xy 420.605204 -280.699464)
			(xy 420.604709 -280.724071) (xy 420.596814 -280.772648) (xy 420.58123 -280.819329) (xy 420.558359 -280.862906)
			(xy 420.528794 -280.90225) (xy 420.493301 -280.936342) (xy 420.452798 -280.964298) (xy 420.408336 -280.985396)
			(xy 420.361065 -280.999088) (xy 420.31221 -281.00502) (xy 420.263035 -281.003039) (xy 420.214816 -280.993195)
			(xy 420.1688 -280.975743) (xy 420.126179 -280.951136) (xy 420.088058 -280.920011) (xy 420.055423 -280.883174)
			(xy 420.02912 -280.841578) (xy 420.009829 -280.796302) (xy 419.998052 -280.748518) (xy 419.994092 -280.699464)
			(xy 418.705284 -280.699464) (xy 418.704789 -280.724071) (xy 418.696894 -280.772648) (xy 418.68131 -280.819329)
			(xy 418.658439 -280.862906) (xy 418.628874 -280.90225) (xy 418.593381 -280.936342) (xy 418.552878 -280.964298)
			(xy 418.508416 -280.985396) (xy 418.461145 -280.999088) (xy 418.41229 -281.00502) (xy 418.363115 -281.003039)
			(xy 418.314896 -280.993195) (xy 418.26888 -280.975743) (xy 418.226259 -280.951136) (xy 418.188138 -280.920011)
			(xy 418.155503 -280.883174) (xy 418.1292 -280.841578) (xy 418.109909 -280.796302) (xy 418.098132 -280.748518)
			(xy 418.094172 -280.699464) (xy 416.80511 -280.699464) (xy 416.804615 -280.724071) (xy 416.79672 -280.772648)
			(xy 416.781136 -280.819329) (xy 416.758265 -280.862906) (xy 416.7287 -280.90225) (xy 416.693207 -280.936342)
			(xy 416.652704 -280.964298) (xy 416.608242 -280.985396) (xy 416.560971 -280.999088) (xy 416.512116 -281.00502)
			(xy 416.462941 -281.003039) (xy 416.414722 -280.993195) (xy 416.368706 -280.975743) (xy 416.326085 -280.951136)
			(xy 416.287964 -280.920011) (xy 416.255329 -280.883174) (xy 416.229026 -280.841578) (xy 416.209735 -280.796302)
			(xy 416.197958 -280.748518) (xy 416.193998 -280.699464) (xy 414.90519 -280.699464) (xy 414.904695 -280.724071)
			(xy 414.8968 -280.772648) (xy 414.881216 -280.819329) (xy 414.858345 -280.862906) (xy 414.82878 -280.90225)
			(xy 414.793287 -280.936342) (xy 414.752784 -280.964298) (xy 414.708322 -280.985396) (xy 414.661051 -280.999088)
			(xy 414.612196 -281.00502) (xy 414.563021 -281.003039) (xy 414.514802 -280.993195) (xy 414.468786 -280.975743)
			(xy 414.426165 -280.951136) (xy 414.388044 -280.920011) (xy 414.355409 -280.883174) (xy 414.329106 -280.841578)
			(xy 414.309815 -280.796302) (xy 414.298038 -280.748518) (xy 414.294078 -280.699464) (xy 413.00527 -280.699464)
			(xy 413.004775 -280.724071) (xy 412.99688 -280.772648) (xy 412.981296 -280.819329) (xy 412.958425 -280.862906)
			(xy 412.92886 -280.90225) (xy 412.893367 -280.936342) (xy 412.852864 -280.964298) (xy 412.808402 -280.985396)
			(xy 412.761131 -280.999088) (xy 412.712276 -281.00502) (xy 412.663101 -281.003039) (xy 412.614882 -280.993195)
			(xy 412.568866 -280.975743) (xy 412.526245 -280.951136) (xy 412.488124 -280.920011) (xy 412.455489 -280.883174)
			(xy 412.429186 -280.841578) (xy 412.409895 -280.796302) (xy 412.398118 -280.748518) (xy 412.394158 -280.699464)
			(xy 411.105096 -280.699464) (xy 411.104601 -280.724071) (xy 411.096706 -280.772648) (xy 411.081122 -280.819329)
			(xy 411.058251 -280.862906) (xy 411.028686 -280.90225) (xy 410.993193 -280.936342) (xy 410.95269 -280.964298)
			(xy 410.908228 -280.985396) (xy 410.860957 -280.999088) (xy 410.812102 -281.00502) (xy 410.762927 -281.003039)
			(xy 410.714708 -280.993195) (xy 410.668692 -280.975743) (xy 410.626071 -280.951136) (xy 410.58795 -280.920011)
			(xy 410.555315 -280.883174) (xy 410.529012 -280.841578) (xy 410.509721 -280.796302) (xy 410.497944 -280.748518)
			(xy 410.493984 -280.699464) (xy 409.205176 -280.699464) (xy 409.204681 -280.724071) (xy 409.196786 -280.772648)
			(xy 409.181202 -280.819329) (xy 409.158331 -280.862906) (xy 409.128766 -280.90225) (xy 409.093273 -280.936342)
			(xy 409.05277 -280.964298) (xy 409.008308 -280.985396) (xy 408.961037 -280.999088) (xy 408.912182 -281.00502)
			(xy 408.863007 -281.003039) (xy 408.814788 -280.993195) (xy 408.768772 -280.975743) (xy 408.726151 -280.951136)
			(xy 408.68803 -280.920011) (xy 408.655395 -280.883174) (xy 408.629092 -280.841578) (xy 408.609801 -280.796302)
			(xy 408.598024 -280.748518) (xy 408.594064 -280.699464) (xy 407.305256 -280.699464) (xy 407.304761 -280.724071)
			(xy 407.296866 -280.772648) (xy 407.281282 -280.819329) (xy 407.258411 -280.862906) (xy 407.228846 -280.90225)
			(xy 407.193353 -280.936342) (xy 407.15285 -280.964298) (xy 407.108388 -280.985396) (xy 407.061117 -280.999088)
			(xy 407.012262 -281.00502) (xy 406.963087 -281.003039) (xy 406.914868 -280.993195) (xy 406.868852 -280.975743)
			(xy 406.826231 -280.951136) (xy 406.78811 -280.920011) (xy 406.755475 -280.883174) (xy 406.729172 -280.841578)
			(xy 406.709881 -280.796302) (xy 406.698104 -280.748518) (xy 406.694144 -280.699464) (xy 405.405082 -280.699464)
			(xy 405.404587 -280.724071) (xy 405.396692 -280.772648) (xy 405.381108 -280.819329) (xy 405.358237 -280.862906)
			(xy 405.328672 -280.90225) (xy 405.293179 -280.936342) (xy 405.252676 -280.964298) (xy 405.208214 -280.985396)
			(xy 405.160943 -280.999088) (xy 405.112088 -281.00502) (xy 405.062913 -281.003039) (xy 405.014694 -280.993195)
			(xy 404.968678 -280.975743) (xy 404.926057 -280.951136) (xy 404.887936 -280.920011) (xy 404.855301 -280.883174)
			(xy 404.828998 -280.841578) (xy 404.809707 -280.796302) (xy 404.79793 -280.748518) (xy 404.79397 -280.699464)
			(xy 403.505162 -280.699464) (xy 403.504667 -280.724071) (xy 403.496772 -280.772648) (xy 403.481188 -280.819329)
			(xy 403.458317 -280.862906) (xy 403.428752 -280.90225) (xy 403.393259 -280.936342) (xy 403.352756 -280.964298)
			(xy 403.308294 -280.985396) (xy 403.261023 -280.999088) (xy 403.212168 -281.00502) (xy 403.162993 -281.003039)
			(xy 403.114774 -280.993195) (xy 403.068758 -280.975743) (xy 403.026137 -280.951136) (xy 402.988016 -280.920011)
			(xy 402.955381 -280.883174) (xy 402.929078 -280.841578) (xy 402.909787 -280.796302) (xy 402.89801 -280.748518)
			(xy 402.89405 -280.699464) (xy 401.605242 -280.699464) (xy 401.604747 -280.724071) (xy 401.596852 -280.772648)
			(xy 401.581268 -280.819329) (xy 401.558397 -280.862906) (xy 401.528832 -280.90225) (xy 401.493339 -280.936342)
			(xy 401.452836 -280.964298) (xy 401.408374 -280.985396) (xy 401.361103 -280.999088) (xy 401.312248 -281.00502)
			(xy 401.263073 -281.003039) (xy 401.214854 -280.993195) (xy 401.168838 -280.975743) (xy 401.126217 -280.951136)
			(xy 401.088096 -280.920011) (xy 401.055461 -280.883174) (xy 401.029158 -280.841578) (xy 401.009867 -280.796302)
			(xy 400.99809 -280.748518) (xy 400.99413 -280.699464) (xy 399.705322 -280.699464) (xy 399.704827 -280.724071)
			(xy 399.696932 -280.772648) (xy 399.681348 -280.819329) (xy 399.658477 -280.862906) (xy 399.628912 -280.90225)
			(xy 399.593419 -280.936342) (xy 399.552916 -280.964298) (xy 399.508454 -280.985396) (xy 399.461183 -280.999088)
			(xy 399.412328 -281.00502) (xy 399.363153 -281.003039) (xy 399.314934 -280.993195) (xy 399.268918 -280.975743)
			(xy 399.226297 -280.951136) (xy 399.188176 -280.920011) (xy 399.155541 -280.883174) (xy 399.129238 -280.841578)
			(xy 399.109947 -280.796302) (xy 399.09817 -280.748518) (xy 399.09421 -280.699464) (xy 397.805148 -280.699464)
			(xy 397.804653 -280.724071) (xy 397.796758 -280.772648) (xy 397.781174 -280.819329) (xy 397.758303 -280.862906)
			(xy 397.728738 -280.90225) (xy 397.693245 -280.936342) (xy 397.652742 -280.964298) (xy 397.60828 -280.985396)
			(xy 397.561009 -280.999088) (xy 397.512154 -281.00502) (xy 397.462979 -281.003039) (xy 397.41476 -280.993195)
			(xy 397.368744 -280.975743) (xy 397.326123 -280.951136) (xy 397.288002 -280.920011) (xy 397.255367 -280.883174)
			(xy 397.229064 -280.841578) (xy 397.209773 -280.796302) (xy 397.197996 -280.748518) (xy 397.194036 -280.699464)
			(xy 395.905228 -280.699464) (xy 395.904733 -280.724071) (xy 395.896838 -280.772648) (xy 395.881254 -280.819329)
			(xy 395.858383 -280.862906) (xy 395.828818 -280.90225) (xy 395.793325 -280.936342) (xy 395.752822 -280.964298)
			(xy 395.70836 -280.985396) (xy 395.661089 -280.999088) (xy 395.612234 -281.00502) (xy 395.563059 -281.003039)
			(xy 395.51484 -280.993195) (xy 395.468824 -280.975743) (xy 395.426203 -280.951136) (xy 395.388082 -280.920011)
			(xy 395.355447 -280.883174) (xy 395.329144 -280.841578) (xy 395.309853 -280.796302) (xy 395.298076 -280.748518)
			(xy 395.294116 -280.699464) (xy 394.005308 -280.699464) (xy 394.004813 -280.724071) (xy 393.996918 -280.772648)
			(xy 393.981334 -280.819329) (xy 393.958463 -280.862906) (xy 393.928898 -280.90225) (xy 393.893405 -280.936342)
			(xy 393.852902 -280.964298) (xy 393.80844 -280.985396) (xy 393.761169 -280.999088) (xy 393.712314 -281.00502)
			(xy 393.663139 -281.003039) (xy 393.61492 -280.993195) (xy 393.568904 -280.975743) (xy 393.526283 -280.951136)
			(xy 393.488162 -280.920011) (xy 393.455527 -280.883174) (xy 393.429224 -280.841578) (xy 393.409933 -280.796302)
			(xy 393.398156 -280.748518) (xy 393.394196 -280.699464) (xy 312.105035 -280.699464) (xy 312.10504 -280.699718)
			(xy 312.104545 -280.724325) (xy 312.09665 -280.772902) (xy 312.081066 -280.819583) (xy 312.058195 -280.86316)
			(xy 312.02863 -280.902504) (xy 311.993137 -280.936596) (xy 311.952634 -280.964552) (xy 311.908172 -280.98565)
			(xy 311.860901 -280.999342) (xy 311.812046 -281.005274) (xy 311.762871 -281.003293) (xy 311.714652 -280.993449)
			(xy 311.668636 -280.975997) (xy 311.626015 -280.95139) (xy 311.587894 -280.920265) (xy 311.555259 -280.883428)
			(xy 311.528956 -280.841832) (xy 311.509665 -280.796556) (xy 311.497888 -280.748772) (xy 311.493928 -280.699718)
			(xy 310.205115 -280.699718) (xy 310.204625 -280.724071) (xy 310.19673 -280.772648) (xy 310.181146 -280.819329)
			(xy 310.158275 -280.862906) (xy 310.12871 -280.90225) (xy 310.093217 -280.936342) (xy 310.052714 -280.964298)
			(xy 310.008252 -280.985396) (xy 309.960981 -280.999088) (xy 309.912126 -281.00502) (xy 309.862951 -281.003039)
			(xy 309.814732 -280.993195) (xy 309.768716 -280.975743) (xy 309.726095 -280.951136) (xy 309.687974 -280.920011)
			(xy 309.655339 -280.883174) (xy 309.629036 -280.841578) (xy 309.609745 -280.796302) (xy 309.597968 -280.748518)
			(xy 309.594008 -280.699464) (xy 308.3052 -280.699464) (xy 308.304705 -280.724071) (xy 308.29681 -280.772648)
			(xy 308.281226 -280.819329) (xy 308.258355 -280.862906) (xy 308.22879 -280.90225) (xy 308.193297 -280.936342)
			(xy 308.152794 -280.964298) (xy 308.108332 -280.985396) (xy 308.061061 -280.999088) (xy 308.012206 -281.00502)
			(xy 307.963031 -281.003039) (xy 307.914812 -280.993195) (xy 307.868796 -280.975743) (xy 307.826175 -280.951136)
			(xy 307.788054 -280.920011) (xy 307.755419 -280.883174) (xy 307.729116 -280.841578) (xy 307.709825 -280.796302)
			(xy 307.698048 -280.748518) (xy 307.694088 -280.699464) (xy 306.405026 -280.699464) (xy 306.404531 -280.724071)
			(xy 306.396636 -280.772648) (xy 306.381052 -280.819329) (xy 306.358181 -280.862906) (xy 306.328616 -280.90225)
			(xy 306.293123 -280.936342) (xy 306.25262 -280.964298) (xy 306.208158 -280.985396) (xy 306.160887 -280.999088)
			(xy 306.112032 -281.00502) (xy 306.062857 -281.003039) (xy 306.014638 -280.993195) (xy 305.968622 -280.975743)
			(xy 305.926001 -280.951136) (xy 305.88788 -280.920011) (xy 305.855245 -280.883174) (xy 305.828942 -280.841578)
			(xy 305.809651 -280.796302) (xy 305.797874 -280.748518) (xy 305.793914 -280.699464) (xy 304.505106 -280.699464)
			(xy 304.504611 -280.724071) (xy 304.496716 -280.772648) (xy 304.481132 -280.819329) (xy 304.458261 -280.862906)
			(xy 304.428696 -280.90225) (xy 304.393203 -280.936342) (xy 304.3527 -280.964298) (xy 304.308238 -280.985396)
			(xy 304.260967 -280.999088) (xy 304.212112 -281.00502) (xy 304.162937 -281.003039) (xy 304.114718 -280.993195)
			(xy 304.068702 -280.975743) (xy 304.026081 -280.951136) (xy 303.98796 -280.920011) (xy 303.955325 -280.883174)
			(xy 303.929022 -280.841578) (xy 303.909731 -280.796302) (xy 303.897954 -280.748518) (xy 303.893994 -280.699464)
			(xy 302.605186 -280.699464) (xy 302.604691 -280.724071) (xy 302.596796 -280.772648) (xy 302.581212 -280.819329)
			(xy 302.558341 -280.862906) (xy 302.528776 -280.90225) (xy 302.493283 -280.936342) (xy 302.45278 -280.964298)
			(xy 302.408318 -280.985396) (xy 302.361047 -280.999088) (xy 302.312192 -281.00502) (xy 302.263017 -281.003039)
			(xy 302.214798 -280.993195) (xy 302.168782 -280.975743) (xy 302.126161 -280.951136) (xy 302.08804 -280.920011)
			(xy 302.055405 -280.883174) (xy 302.029102 -280.841578) (xy 302.009811 -280.796302) (xy 301.998034 -280.748518)
			(xy 301.994074 -280.699464) (xy 300.705012 -280.699464) (xy 300.704517 -280.724071) (xy 300.696622 -280.772648)
			(xy 300.681038 -280.819329) (xy 300.658167 -280.862906) (xy 300.628602 -280.90225) (xy 300.593109 -280.936342)
			(xy 300.552606 -280.964298) (xy 300.508144 -280.985396) (xy 300.460873 -280.999088) (xy 300.412018 -281.00502)
			(xy 300.362843 -281.003039) (xy 300.314624 -280.993195) (xy 300.268608 -280.975743) (xy 300.225987 -280.951136)
			(xy 300.187866 -280.920011) (xy 300.155231 -280.883174) (xy 300.128928 -280.841578) (xy 300.109637 -280.796302)
			(xy 300.09786 -280.748518) (xy 300.0939 -280.699464) (xy 298.805092 -280.699464) (xy 298.804597 -280.724071)
			(xy 298.796702 -280.772648) (xy 298.781118 -280.819329) (xy 298.758247 -280.862906) (xy 298.728682 -280.90225)
			(xy 298.693189 -280.936342) (xy 298.652686 -280.964298) (xy 298.608224 -280.985396) (xy 298.560953 -280.999088)
			(xy 298.512098 -281.00502) (xy 298.462923 -281.003039) (xy 298.414704 -280.993195) (xy 298.368688 -280.975743)
			(xy 298.326067 -280.951136) (xy 298.287946 -280.920011) (xy 298.255311 -280.883174) (xy 298.229008 -280.841578)
			(xy 298.209717 -280.796302) (xy 298.19794 -280.748518) (xy 298.19398 -280.699464) (xy 296.905172 -280.699464)
			(xy 296.904677 -280.724071) (xy 296.896782 -280.772648) (xy 296.881198 -280.819329) (xy 296.858327 -280.862906)
			(xy 296.828762 -280.90225) (xy 296.793269 -280.936342) (xy 296.752766 -280.964298) (xy 296.708304 -280.985396)
			(xy 296.661033 -280.999088) (xy 296.612178 -281.00502) (xy 296.563003 -281.003039) (xy 296.514784 -280.993195)
			(xy 296.468768 -280.975743) (xy 296.426147 -280.951136) (xy 296.388026 -280.920011) (xy 296.355391 -280.883174)
			(xy 296.329088 -280.841578) (xy 296.309797 -280.796302) (xy 296.29802 -280.748518) (xy 296.29406 -280.699464)
			(xy 295.004998 -280.699464) (xy 295.004503 -280.724071) (xy 294.996608 -280.772648) (xy 294.981024 -280.819329)
			(xy 294.958153 -280.862906) (xy 294.928588 -280.90225) (xy 294.893095 -280.936342) (xy 294.852592 -280.964298)
			(xy 294.80813 -280.985396) (xy 294.760859 -280.999088) (xy 294.712004 -281.00502) (xy 294.662829 -281.003039)
			(xy 294.61461 -280.993195) (xy 294.568594 -280.975743) (xy 294.525973 -280.951136) (xy 294.487852 -280.920011)
			(xy 294.455217 -280.883174) (xy 294.428914 -280.841578) (xy 294.409623 -280.796302) (xy 294.397846 -280.748518)
			(xy 294.393886 -280.699464) (xy 293.105078 -280.699464) (xy 293.104583 -280.724071) (xy 293.096688 -280.772648)
			(xy 293.081104 -280.819329) (xy 293.058233 -280.862906) (xy 293.028668 -280.90225) (xy 292.993175 -280.936342)
			(xy 292.952672 -280.964298) (xy 292.90821 -280.985396) (xy 292.860939 -280.999088) (xy 292.812084 -281.00502)
			(xy 292.762909 -281.003039) (xy 292.71469 -280.993195) (xy 292.668674 -280.975743) (xy 292.626053 -280.951136)
			(xy 292.587932 -280.920011) (xy 292.555297 -280.883174) (xy 292.528994 -280.841578) (xy 292.509703 -280.796302)
			(xy 292.497926 -280.748518) (xy 292.493966 -280.699464) (xy 291.205158 -280.699464) (xy 291.204663 -280.724071)
			(xy 291.196768 -280.772648) (xy 291.181184 -280.819329) (xy 291.158313 -280.862906) (xy 291.128748 -280.90225)
			(xy 291.093255 -280.936342) (xy 291.052752 -280.964298) (xy 291.00829 -280.985396) (xy 290.961019 -280.999088)
			(xy 290.912164 -281.00502) (xy 290.862989 -281.003039) (xy 290.81477 -280.993195) (xy 290.768754 -280.975743)
			(xy 290.726133 -280.951136) (xy 290.688012 -280.920011) (xy 290.655377 -280.883174) (xy 290.629074 -280.841578)
			(xy 290.609783 -280.796302) (xy 290.598006 -280.748518) (xy 290.594046 -280.699464) (xy 289.304984 -280.699464)
			(xy 289.304489 -280.724071) (xy 289.296594 -280.772648) (xy 289.28101 -280.819329) (xy 289.258139 -280.862906)
			(xy 289.228574 -280.90225) (xy 289.193081 -280.936342) (xy 289.152578 -280.964298) (xy 289.108116 -280.985396)
			(xy 289.060845 -280.999088) (xy 289.01199 -281.00502) (xy 288.962815 -281.003039) (xy 288.914596 -280.993195)
			(xy 288.86858 -280.975743) (xy 288.825959 -280.951136) (xy 288.787838 -280.920011) (xy 288.755203 -280.883174)
			(xy 288.7289 -280.841578) (xy 288.709609 -280.796302) (xy 288.697832 -280.748518) (xy 288.693872 -280.699464)
			(xy 287.405064 -280.699464) (xy 287.404569 -280.724071) (xy 287.396674 -280.772648) (xy 287.38109 -280.819329)
			(xy 287.358219 -280.862906) (xy 287.328654 -280.90225) (xy 287.293161 -280.936342) (xy 287.252658 -280.964298)
			(xy 287.208196 -280.985396) (xy 287.160925 -280.999088) (xy 287.11207 -281.00502) (xy 287.062895 -281.003039)
			(xy 287.014676 -280.993195) (xy 286.96866 -280.975743) (xy 286.926039 -280.951136) (xy 286.887918 -280.920011)
			(xy 286.855283 -280.883174) (xy 286.82898 -280.841578) (xy 286.809689 -280.796302) (xy 286.797912 -280.748518)
			(xy 286.793952 -280.699464) (xy 285.505144 -280.699464) (xy 285.504649 -280.724071) (xy 285.496754 -280.772648)
			(xy 285.48117 -280.819329) (xy 285.458299 -280.862906) (xy 285.428734 -280.90225) (xy 285.393241 -280.936342)
			(xy 285.352738 -280.964298) (xy 285.308276 -280.985396) (xy 285.261005 -280.999088) (xy 285.21215 -281.00502)
			(xy 285.162975 -281.003039) (xy 285.114756 -280.993195) (xy 285.06874 -280.975743) (xy 285.026119 -280.951136)
			(xy 284.987998 -280.920011) (xy 284.955363 -280.883174) (xy 284.92906 -280.841578) (xy 284.909769 -280.796302)
			(xy 284.897992 -280.748518) (xy 284.894032 -280.699464) (xy 283.605224 -280.699464) (xy 283.604729 -280.724071)
			(xy 283.596834 -280.772648) (xy 283.58125 -280.819329) (xy 283.558379 -280.862906) (xy 283.528814 -280.90225)
			(xy 283.493321 -280.936342) (xy 283.452818 -280.964298) (xy 283.408356 -280.985396) (xy 283.361085 -280.999088)
			(xy 283.31223 -281.00502) (xy 283.263055 -281.003039) (xy 283.214836 -280.993195) (xy 283.16882 -280.975743)
			(xy 283.126199 -280.951136) (xy 283.088078 -280.920011) (xy 283.055443 -280.883174) (xy 283.02914 -280.841578)
			(xy 283.009849 -280.796302) (xy 282.998072 -280.748518) (xy 282.994112 -280.699464) (xy 281.70505 -280.699464)
			(xy 281.704555 -280.724071) (xy 281.69666 -280.772648) (xy 281.681076 -280.819329) (xy 281.658205 -280.862906)
			(xy 281.62864 -280.90225) (xy 281.593147 -280.936342) (xy 281.552644 -280.964298) (xy 281.508182 -280.985396)
			(xy 281.460911 -280.999088) (xy 281.412056 -281.00502) (xy 281.362881 -281.003039) (xy 281.314662 -280.993195)
			(xy 281.268646 -280.975743) (xy 281.226025 -280.951136) (xy 281.187904 -280.920011) (xy 281.155269 -280.883174)
			(xy 281.128966 -280.841578) (xy 281.109675 -280.796302) (xy 281.097898 -280.748518) (xy 281.093938 -280.699464)
			(xy 279.80513 -280.699464) (xy 279.804635 -280.724071) (xy 279.79674 -280.772648) (xy 279.781156 -280.819329)
			(xy 279.758285 -280.862906) (xy 279.72872 -280.90225) (xy 279.693227 -280.936342) (xy 279.652724 -280.964298)
			(xy 279.608262 -280.985396) (xy 279.560991 -280.999088) (xy 279.512136 -281.00502) (xy 279.462961 -281.003039)
			(xy 279.414742 -280.993195) (xy 279.368726 -280.975743) (xy 279.326105 -280.951136) (xy 279.287984 -280.920011)
			(xy 279.255349 -280.883174) (xy 279.229046 -280.841578) (xy 279.209755 -280.796302) (xy 279.197978 -280.748518)
			(xy 279.194018 -280.699464) (xy 277.90521 -280.699464) (xy 277.904715 -280.724071) (xy 277.89682 -280.772648)
			(xy 277.881236 -280.819329) (xy 277.858365 -280.862906) (xy 277.8288 -280.90225) (xy 277.793307 -280.936342)
			(xy 277.752804 -280.964298) (xy 277.708342 -280.985396) (xy 277.661071 -280.999088) (xy 277.612216 -281.00502)
			(xy 277.563041 -281.003039) (xy 277.514822 -280.993195) (xy 277.468806 -280.975743) (xy 277.426185 -280.951136)
			(xy 277.388064 -280.920011) (xy 277.355429 -280.883174) (xy 277.329126 -280.841578) (xy 277.309835 -280.796302)
			(xy 277.298058 -280.748518) (xy 277.294098 -280.699464) (xy 196.005191 -280.699464) (xy 196.005196 -280.699718)
			(xy 196.004701 -280.724325) (xy 195.996806 -280.772902) (xy 195.981222 -280.819583) (xy 195.958351 -280.86316)
			(xy 195.928786 -280.902504) (xy 195.893293 -280.936596) (xy 195.85279 -280.964552) (xy 195.808328 -280.98565)
			(xy 195.761057 -280.999342) (xy 195.712202 -281.005274) (xy 195.663027 -281.003293) (xy 195.614808 -280.993449)
			(xy 195.568792 -280.975997) (xy 195.526171 -280.95139) (xy 195.48805 -280.920265) (xy 195.455415 -280.883428)
			(xy 195.429112 -280.841832) (xy 195.409821 -280.796556) (xy 195.398044 -280.748772) (xy 195.394084 -280.699718)
			(xy 194.105276 -280.699718) (xy 194.104781 -280.724325) (xy 194.096886 -280.772902) (xy 194.081302 -280.819583)
			(xy 194.058431 -280.86316) (xy 194.028866 -280.902504) (xy 193.993373 -280.936596) (xy 193.95287 -280.964552)
			(xy 193.908408 -280.98565) (xy 193.861137 -280.999342) (xy 193.812282 -281.005274) (xy 193.763107 -281.003293)
			(xy 193.714888 -280.993449) (xy 193.668872 -280.975997) (xy 193.626251 -280.95139) (xy 193.58813 -280.920265)
			(xy 193.555495 -280.883428) (xy 193.529192 -280.841832) (xy 193.509901 -280.796556) (xy 193.498124 -280.748772)
			(xy 193.494164 -280.699718) (xy 192.205356 -280.699718) (xy 192.204861 -280.724325) (xy 192.196966 -280.772902)
			(xy 192.181382 -280.819583) (xy 192.158511 -280.86316) (xy 192.128946 -280.902504) (xy 192.093453 -280.936596)
			(xy 192.05295 -280.964552) (xy 192.008488 -280.98565) (xy 191.961217 -280.999342) (xy 191.912362 -281.005274)
			(xy 191.863187 -281.003293) (xy 191.814968 -280.993449) (xy 191.768952 -280.975997) (xy 191.726331 -280.95139)
			(xy 191.68821 -280.920265) (xy 191.655575 -280.883428) (xy 191.629272 -280.841832) (xy 191.609981 -280.796556)
			(xy 191.598204 -280.748772) (xy 191.594244 -280.699718) (xy 190.305182 -280.699718) (xy 190.304687 -280.724325)
			(xy 190.296792 -280.772902) (xy 190.281208 -280.819583) (xy 190.258337 -280.86316) (xy 190.228772 -280.902504)
			(xy 190.193279 -280.936596) (xy 190.152776 -280.964552) (xy 190.108314 -280.98565) (xy 190.061043 -280.999342)
			(xy 190.012188 -281.005274) (xy 189.963013 -281.003293) (xy 189.914794 -280.993449) (xy 189.868778 -280.975997)
			(xy 189.826157 -280.95139) (xy 189.788036 -280.920265) (xy 189.755401 -280.883428) (xy 189.729098 -280.841832)
			(xy 189.709807 -280.796556) (xy 189.69803 -280.748772) (xy 189.69407 -280.699718) (xy 188.405262 -280.699718)
			(xy 188.404767 -280.724325) (xy 188.396872 -280.772902) (xy 188.381288 -280.819583) (xy 188.358417 -280.86316)
			(xy 188.328852 -280.902504) (xy 188.293359 -280.936596) (xy 188.252856 -280.964552) (xy 188.208394 -280.98565)
			(xy 188.161123 -280.999342) (xy 188.112268 -281.005274) (xy 188.063093 -281.003293) (xy 188.014874 -280.993449)
			(xy 187.968858 -280.975997) (xy 187.926237 -280.95139) (xy 187.888116 -280.920265) (xy 187.855481 -280.883428)
			(xy 187.829178 -280.841832) (xy 187.809887 -280.796556) (xy 187.79811 -280.748772) (xy 187.79415 -280.699718)
			(xy 186.505342 -280.699718) (xy 186.504847 -280.724325) (xy 186.496952 -280.772902) (xy 186.481368 -280.819583)
			(xy 186.458497 -280.86316) (xy 186.428932 -280.902504) (xy 186.393439 -280.936596) (xy 186.352936 -280.964552)
			(xy 186.308474 -280.98565) (xy 186.261203 -280.999342) (xy 186.212348 -281.005274) (xy 186.163173 -281.003293)
			(xy 186.114954 -280.993449) (xy 186.068938 -280.975997) (xy 186.026317 -280.95139) (xy 185.988196 -280.920265)
			(xy 185.955561 -280.883428) (xy 185.929258 -280.841832) (xy 185.909967 -280.796556) (xy 185.89819 -280.748772)
			(xy 185.89423 -280.699718) (xy 184.605168 -280.699718) (xy 184.604673 -280.724325) (xy 184.596778 -280.772902)
			(xy 184.581194 -280.819583) (xy 184.558323 -280.86316) (xy 184.528758 -280.902504) (xy 184.493265 -280.936596)
			(xy 184.452762 -280.964552) (xy 184.4083 -280.98565) (xy 184.361029 -280.999342) (xy 184.312174 -281.005274)
			(xy 184.262999 -281.003293) (xy 184.21478 -280.993449) (xy 184.168764 -280.975997) (xy 184.126143 -280.95139)
			(xy 184.088022 -280.920265) (xy 184.055387 -280.883428) (xy 184.029084 -280.841832) (xy 184.009793 -280.796556)
			(xy 183.998016 -280.748772) (xy 183.994056 -280.699718) (xy 182.705248 -280.699718) (xy 182.704753 -280.724325)
			(xy 182.696858 -280.772902) (xy 182.681274 -280.819583) (xy 182.658403 -280.86316) (xy 182.628838 -280.902504)
			(xy 182.593345 -280.936596) (xy 182.552842 -280.964552) (xy 182.50838 -280.98565) (xy 182.461109 -280.999342)
			(xy 182.412254 -281.005274) (xy 182.363079 -281.003293) (xy 182.31486 -280.993449) (xy 182.268844 -280.975997)
			(xy 182.226223 -280.95139) (xy 182.188102 -280.920265) (xy 182.155467 -280.883428) (xy 182.129164 -280.841832)
			(xy 182.109873 -280.796556) (xy 182.098096 -280.748772) (xy 182.094136 -280.699718) (xy 180.805328 -280.699718)
			(xy 180.804833 -280.724325) (xy 180.796938 -280.772902) (xy 180.781354 -280.819583) (xy 180.758483 -280.86316)
			(xy 180.728918 -280.902504) (xy 180.693425 -280.936596) (xy 180.652922 -280.964552) (xy 180.60846 -280.98565)
			(xy 180.561189 -280.999342) (xy 180.512334 -281.005274) (xy 180.463159 -281.003293) (xy 180.41494 -280.993449)
			(xy 180.368924 -280.975997) (xy 180.326303 -280.95139) (xy 180.288182 -280.920265) (xy 180.255547 -280.883428)
			(xy 180.229244 -280.841832) (xy 180.209953 -280.796556) (xy 180.198176 -280.748772) (xy 180.194216 -280.699718)
			(xy 178.905154 -280.699718) (xy 178.904659 -280.724325) (xy 178.896764 -280.772902) (xy 178.88118 -280.819583)
			(xy 178.858309 -280.86316) (xy 178.828744 -280.902504) (xy 178.793251 -280.936596) (xy 178.752748 -280.964552)
			(xy 178.708286 -280.98565) (xy 178.661015 -280.999342) (xy 178.61216 -281.005274) (xy 178.562985 -281.003293)
			(xy 178.514766 -280.993449) (xy 178.46875 -280.975997) (xy 178.426129 -280.95139) (xy 178.388008 -280.920265)
			(xy 178.355373 -280.883428) (xy 178.32907 -280.841832) (xy 178.309779 -280.796556) (xy 178.298002 -280.748772)
			(xy 178.294042 -280.699718) (xy 177.005234 -280.699718) (xy 177.004739 -280.724325) (xy 176.996844 -280.772902)
			(xy 176.98126 -280.819583) (xy 176.958389 -280.86316) (xy 176.928824 -280.902504) (xy 176.893331 -280.936596)
			(xy 176.852828 -280.964552) (xy 176.808366 -280.98565) (xy 176.761095 -280.999342) (xy 176.71224 -281.005274)
			(xy 176.663065 -281.003293) (xy 176.614846 -280.993449) (xy 176.56883 -280.975997) (xy 176.526209 -280.95139)
			(xy 176.488088 -280.920265) (xy 176.455453 -280.883428) (xy 176.42915 -280.841832) (xy 176.409859 -280.796556)
			(xy 176.398082 -280.748772) (xy 176.394122 -280.699718) (xy 175.105314 -280.699718) (xy 175.104819 -280.724325)
			(xy 175.096924 -280.772902) (xy 175.08134 -280.819583) (xy 175.058469 -280.86316) (xy 175.028904 -280.902504)
			(xy 174.993411 -280.936596) (xy 174.952908 -280.964552) (xy 174.908446 -280.98565) (xy 174.861175 -280.999342)
			(xy 174.81232 -281.005274) (xy 174.763145 -281.003293) (xy 174.714926 -280.993449) (xy 174.66891 -280.975997)
			(xy 174.626289 -280.95139) (xy 174.588168 -280.920265) (xy 174.555533 -280.883428) (xy 174.52923 -280.841832)
			(xy 174.509939 -280.796556) (xy 174.498162 -280.748772) (xy 174.494202 -280.699718) (xy 173.20514 -280.699718)
			(xy 173.204645 -280.724325) (xy 173.19675 -280.772902) (xy 173.181166 -280.819583) (xy 173.158295 -280.86316)
			(xy 173.12873 -280.902504) (xy 173.093237 -280.936596) (xy 173.052734 -280.964552) (xy 173.008272 -280.98565)
			(xy 172.961001 -280.999342) (xy 172.912146 -281.005274) (xy 172.862971 -281.003293) (xy 172.814752 -280.993449)
			(xy 172.768736 -280.975997) (xy 172.726115 -280.95139) (xy 172.687994 -280.920265) (xy 172.655359 -280.883428)
			(xy 172.629056 -280.841832) (xy 172.609765 -280.796556) (xy 172.597988 -280.748772) (xy 172.594028 -280.699718)
			(xy 171.30522 -280.699718) (xy 171.304725 -280.724325) (xy 171.29683 -280.772902) (xy 171.281246 -280.819583)
			(xy 171.258375 -280.86316) (xy 171.22881 -280.902504) (xy 171.193317 -280.936596) (xy 171.152814 -280.964552)
			(xy 171.108352 -280.98565) (xy 171.061081 -280.999342) (xy 171.012226 -281.005274) (xy 170.963051 -281.003293)
			(xy 170.914832 -280.993449) (xy 170.868816 -280.975997) (xy 170.826195 -280.95139) (xy 170.788074 -280.920265)
			(xy 170.755439 -280.883428) (xy 170.729136 -280.841832) (xy 170.709845 -280.796556) (xy 170.698068 -280.748772)
			(xy 170.694108 -280.699718) (xy 169.4053 -280.699718) (xy 169.404805 -280.724325) (xy 169.39691 -280.772902)
			(xy 169.381326 -280.819583) (xy 169.358455 -280.86316) (xy 169.32889 -280.902504) (xy 169.293397 -280.936596)
			(xy 169.252894 -280.964552) (xy 169.208432 -280.98565) (xy 169.161161 -280.999342) (xy 169.112306 -281.005274)
			(xy 169.063131 -281.003293) (xy 169.014912 -280.993449) (xy 168.968896 -280.975997) (xy 168.926275 -280.95139)
			(xy 168.888154 -280.920265) (xy 168.855519 -280.883428) (xy 168.829216 -280.841832) (xy 168.809925 -280.796556)
			(xy 168.798148 -280.748772) (xy 168.794188 -280.699718) (xy 167.50538 -280.699718) (xy 167.504885 -280.724325)
			(xy 167.49699 -280.772902) (xy 167.481406 -280.819583) (xy 167.458535 -280.86316) (xy 167.42897 -280.902504)
			(xy 167.393477 -280.936596) (xy 167.352974 -280.964552) (xy 167.308512 -280.98565) (xy 167.261241 -280.999342)
			(xy 167.212386 -281.005274) (xy 167.163211 -281.003293) (xy 167.114992 -280.993449) (xy 167.068976 -280.975997)
			(xy 167.026355 -280.95139) (xy 166.988234 -280.920265) (xy 166.955599 -280.883428) (xy 166.929296 -280.841832)
			(xy 166.910005 -280.796556) (xy 166.898228 -280.748772) (xy 166.894268 -280.699718) (xy 165.605206 -280.699718)
			(xy 165.604711 -280.724325) (xy 165.596816 -280.772902) (xy 165.581232 -280.819583) (xy 165.558361 -280.86316)
			(xy 165.528796 -280.902504) (xy 165.493303 -280.936596) (xy 165.4528 -280.964552) (xy 165.408338 -280.98565)
			(xy 165.361067 -280.999342) (xy 165.312212 -281.005274) (xy 165.263037 -281.003293) (xy 165.214818 -280.993449)
			(xy 165.168802 -280.975997) (xy 165.126181 -280.95139) (xy 165.08806 -280.920265) (xy 165.055425 -280.883428)
			(xy 165.029122 -280.841832) (xy 165.009831 -280.796556) (xy 164.998054 -280.748772) (xy 164.994094 -280.699718)
			(xy 163.705286 -280.699718) (xy 163.704791 -280.724325) (xy 163.696896 -280.772902) (xy 163.681312 -280.819583)
			(xy 163.658441 -280.86316) (xy 163.628876 -280.902504) (xy 163.593383 -280.936596) (xy 163.55288 -280.964552)
			(xy 163.508418 -280.98565) (xy 163.461147 -280.999342) (xy 163.412292 -281.005274) (xy 163.363117 -281.003293)
			(xy 163.314898 -280.993449) (xy 163.268882 -280.975997) (xy 163.226261 -280.95139) (xy 163.18814 -280.920265)
			(xy 163.155505 -280.883428) (xy 163.129202 -280.841832) (xy 163.109911 -280.796556) (xy 163.098134 -280.748772)
			(xy 163.094174 -280.699718) (xy 161.805366 -280.699718) (xy 161.804871 -280.724325) (xy 161.796976 -280.772902)
			(xy 161.781392 -280.819583) (xy 161.758521 -280.86316) (xy 161.728956 -280.902504) (xy 161.693463 -280.936596)
			(xy 161.65296 -280.964552) (xy 161.608498 -280.98565) (xy 161.561227 -280.999342) (xy 161.512372 -281.005274)
			(xy 161.463197 -281.003293) (xy 161.414978 -280.993449) (xy 161.368962 -280.975997) (xy 161.326341 -280.95139)
			(xy 161.28822 -280.920265) (xy 161.255585 -280.883428) (xy 161.229282 -280.841832) (xy 161.209991 -280.796556)
			(xy 161.198214 -280.748772) (xy 161.194254 -280.699718) (xy 79.905098 -280.699718) (xy 79.904603 -280.724325)
			(xy 79.896708 -280.772902) (xy 79.881124 -280.819583) (xy 79.858253 -280.86316) (xy 79.828688 -280.902504)
			(xy 79.793195 -280.936596) (xy 79.752692 -280.964552) (xy 79.70823 -280.98565) (xy 79.660959 -280.999342)
			(xy 79.612104 -281.005274) (xy 79.562929 -281.003293) (xy 79.51471 -280.993449) (xy 79.468694 -280.975997)
			(xy 79.426073 -280.95139) (xy 79.387952 -280.920265) (xy 79.355317 -280.883428) (xy 79.329014 -280.841832)
			(xy 79.309723 -280.796556) (xy 79.297946 -280.748772) (xy 79.293986 -280.699718) (xy 78.005178 -280.699718)
			(xy 78.004683 -280.724325) (xy 77.996788 -280.772902) (xy 77.981204 -280.819583) (xy 77.958333 -280.86316)
			(xy 77.928768 -280.902504) (xy 77.893275 -280.936596) (xy 77.852772 -280.964552) (xy 77.80831 -280.98565)
			(xy 77.761039 -280.999342) (xy 77.712184 -281.005274) (xy 77.663009 -281.003293) (xy 77.61479 -280.993449)
			(xy 77.568774 -280.975997) (xy 77.526153 -280.95139) (xy 77.488032 -280.920265) (xy 77.455397 -280.883428)
			(xy 77.429094 -280.841832) (xy 77.409803 -280.796556) (xy 77.398026 -280.748772) (xy 77.394066 -280.699718)
			(xy 76.105258 -280.699718) (xy 76.104763 -280.724325) (xy 76.096868 -280.772902) (xy 76.081284 -280.819583)
			(xy 76.058413 -280.86316) (xy 76.028848 -280.902504) (xy 75.993355 -280.936596) (xy 75.952852 -280.964552)
			(xy 75.90839 -280.98565) (xy 75.861119 -280.999342) (xy 75.812264 -281.005274) (xy 75.763089 -281.003293)
			(xy 75.71487 -280.993449) (xy 75.668854 -280.975997) (xy 75.626233 -280.95139) (xy 75.588112 -280.920265)
			(xy 75.555477 -280.883428) (xy 75.529174 -280.841832) (xy 75.509883 -280.796556) (xy 75.498106 -280.748772)
			(xy 75.494146 -280.699718) (xy 74.205084 -280.699718) (xy 74.204589 -280.724325) (xy 74.196694 -280.772902)
			(xy 74.18111 -280.819583) (xy 74.158239 -280.86316) (xy 74.128674 -280.902504) (xy 74.093181 -280.936596)
			(xy 74.052678 -280.964552) (xy 74.008216 -280.98565) (xy 73.960945 -280.999342) (xy 73.91209 -281.005274)
			(xy 73.862915 -281.003293) (xy 73.814696 -280.993449) (xy 73.76868 -280.975997) (xy 73.726059 -280.95139)
			(xy 73.687938 -280.920265) (xy 73.655303 -280.883428) (xy 73.629 -280.841832) (xy 73.609709 -280.796556)
			(xy 73.597932 -280.748772) (xy 73.593972 -280.699718) (xy 72.305164 -280.699718) (xy 72.304669 -280.724325)
			(xy 72.296774 -280.772902) (xy 72.28119 -280.819583) (xy 72.258319 -280.86316) (xy 72.228754 -280.902504)
			(xy 72.193261 -280.936596) (xy 72.152758 -280.964552) (xy 72.108296 -280.98565) (xy 72.061025 -280.999342)
			(xy 72.01217 -281.005274) (xy 71.962995 -281.003293) (xy 71.914776 -280.993449) (xy 71.86876 -280.975997)
			(xy 71.826139 -280.95139) (xy 71.788018 -280.920265) (xy 71.755383 -280.883428) (xy 71.72908 -280.841832)
			(xy 71.709789 -280.796556) (xy 71.698012 -280.748772) (xy 71.694052 -280.699718) (xy 70.405244 -280.699718)
			(xy 70.404749 -280.724325) (xy 70.396854 -280.772902) (xy 70.38127 -280.819583) (xy 70.358399 -280.86316)
			(xy 70.328834 -280.902504) (xy 70.293341 -280.936596) (xy 70.252838 -280.964552) (xy 70.208376 -280.98565)
			(xy 70.161105 -280.999342) (xy 70.11225 -281.005274) (xy 70.063075 -281.003293) (xy 70.014856 -280.993449)
			(xy 69.96884 -280.975997) (xy 69.926219 -280.95139) (xy 69.888098 -280.920265) (xy 69.855463 -280.883428)
			(xy 69.82916 -280.841832) (xy 69.809869 -280.796556) (xy 69.798092 -280.748772) (xy 69.794132 -280.699718)
			(xy 68.50507 -280.699718) (xy 68.504575 -280.724325) (xy 68.49668 -280.772902) (xy 68.481096 -280.819583)
			(xy 68.458225 -280.86316) (xy 68.42866 -280.902504) (xy 68.393167 -280.936596) (xy 68.352664 -280.964552)
			(xy 68.308202 -280.98565) (xy 68.260931 -280.999342) (xy 68.212076 -281.005274) (xy 68.162901 -281.003293)
			(xy 68.114682 -280.993449) (xy 68.068666 -280.975997) (xy 68.026045 -280.95139) (xy 67.987924 -280.920265)
			(xy 67.955289 -280.883428) (xy 67.928986 -280.841832) (xy 67.909695 -280.796556) (xy 67.897918 -280.748772)
			(xy 67.893958 -280.699718) (xy 66.60515 -280.699718) (xy 66.604655 -280.724325) (xy 66.59676 -280.772902)
			(xy 66.581176 -280.819583) (xy 66.558305 -280.86316) (xy 66.52874 -280.902504) (xy 66.493247 -280.936596)
			(xy 66.452744 -280.964552) (xy 66.408282 -280.98565) (xy 66.361011 -280.999342) (xy 66.312156 -281.005274)
			(xy 66.262981 -281.003293) (xy 66.214762 -280.993449) (xy 66.168746 -280.975997) (xy 66.126125 -280.95139)
			(xy 66.088004 -280.920265) (xy 66.055369 -280.883428) (xy 66.029066 -280.841832) (xy 66.009775 -280.796556)
			(xy 65.997998 -280.748772) (xy 65.994038 -280.699718) (xy 64.70523 -280.699718) (xy 64.704735 -280.724325)
			(xy 64.69684 -280.772902) (xy 64.681256 -280.819583) (xy 64.658385 -280.86316) (xy 64.62882 -280.902504)
			(xy 64.593327 -280.936596) (xy 64.552824 -280.964552) (xy 64.508362 -280.98565) (xy 64.461091 -280.999342)
			(xy 64.412236 -281.005274) (xy 64.363061 -281.003293) (xy 64.314842 -280.993449) (xy 64.268826 -280.975997)
			(xy 64.226205 -280.95139) (xy 64.188084 -280.920265) (xy 64.155449 -280.883428) (xy 64.129146 -280.841832)
			(xy 64.109855 -280.796556) (xy 64.098078 -280.748772) (xy 64.094118 -280.699718) (xy 62.805056 -280.699718)
			(xy 62.804561 -280.724325) (xy 62.796666 -280.772902) (xy 62.781082 -280.819583) (xy 62.758211 -280.86316)
			(xy 62.728646 -280.902504) (xy 62.693153 -280.936596) (xy 62.65265 -280.964552) (xy 62.608188 -280.98565)
			(xy 62.560917 -280.999342) (xy 62.512062 -281.005274) (xy 62.462887 -281.003293) (xy 62.414668 -280.993449)
			(xy 62.368652 -280.975997) (xy 62.326031 -280.95139) (xy 62.28791 -280.920265) (xy 62.255275 -280.883428)
			(xy 62.228972 -280.841832) (xy 62.209681 -280.796556) (xy 62.197904 -280.748772) (xy 62.193944 -280.699718)
			(xy 60.905136 -280.699718) (xy 60.904641 -280.724325) (xy 60.896746 -280.772902) (xy 60.881162 -280.819583)
			(xy 60.858291 -280.86316) (xy 60.828726 -280.902504) (xy 60.793233 -280.936596) (xy 60.75273 -280.964552)
			(xy 60.708268 -280.98565) (xy 60.660997 -280.999342) (xy 60.612142 -281.005274) (xy 60.562967 -281.003293)
			(xy 60.514748 -280.993449) (xy 60.468732 -280.975997) (xy 60.426111 -280.95139) (xy 60.38799 -280.920265)
			(xy 60.355355 -280.883428) (xy 60.329052 -280.841832) (xy 60.309761 -280.796556) (xy 60.297984 -280.748772)
			(xy 60.294024 -280.699718) (xy 59.005216 -280.699718) (xy 59.004721 -280.724325) (xy 58.996826 -280.772902)
			(xy 58.981242 -280.819583) (xy 58.958371 -280.86316) (xy 58.928806 -280.902504) (xy 58.893313 -280.936596)
			(xy 58.85281 -280.964552) (xy 58.808348 -280.98565) (xy 58.761077 -280.999342) (xy 58.712222 -281.005274)
			(xy 58.663047 -281.003293) (xy 58.614828 -280.993449) (xy 58.568812 -280.975997) (xy 58.526191 -280.95139)
			(xy 58.48807 -280.920265) (xy 58.455435 -280.883428) (xy 58.429132 -280.841832) (xy 58.409841 -280.796556)
			(xy 58.398064 -280.748772) (xy 58.394104 -280.699718) (xy 57.105042 -280.699718) (xy 57.104547 -280.724325)
			(xy 57.096652 -280.772902) (xy 57.081068 -280.819583) (xy 57.058197 -280.86316) (xy 57.028632 -280.902504)
			(xy 56.993139 -280.936596) (xy 56.952636 -280.964552) (xy 56.908174 -280.98565) (xy 56.860903 -280.999342)
			(xy 56.812048 -281.005274) (xy 56.762873 -281.003293) (xy 56.714654 -280.993449) (xy 56.668638 -280.975997)
			(xy 56.626017 -280.95139) (xy 56.587896 -280.920265) (xy 56.555261 -280.883428) (xy 56.528958 -280.841832)
			(xy 56.509667 -280.796556) (xy 56.49789 -280.748772) (xy 56.49393 -280.699718) (xy 55.205122 -280.699718)
			(xy 55.204627 -280.724325) (xy 55.196732 -280.772902) (xy 55.181148 -280.819583) (xy 55.158277 -280.86316)
			(xy 55.128712 -280.902504) (xy 55.093219 -280.936596) (xy 55.052716 -280.964552) (xy 55.008254 -280.98565)
			(xy 54.960983 -280.999342) (xy 54.912128 -281.005274) (xy 54.862953 -281.003293) (xy 54.814734 -280.993449)
			(xy 54.768718 -280.975997) (xy 54.726097 -280.95139) (xy 54.687976 -280.920265) (xy 54.655341 -280.883428)
			(xy 54.629038 -280.841832) (xy 54.609747 -280.796556) (xy 54.59797 -280.748772) (xy 54.59401 -280.699718)
			(xy 53.305202 -280.699718) (xy 53.304707 -280.724325) (xy 53.296812 -280.772902) (xy 53.281228 -280.819583)
			(xy 53.258357 -280.86316) (xy 53.228792 -280.902504) (xy 53.193299 -280.936596) (xy 53.152796 -280.964552)
			(xy 53.108334 -280.98565) (xy 53.061063 -280.999342) (xy 53.012208 -281.005274) (xy 52.963033 -281.003293)
			(xy 52.914814 -280.993449) (xy 52.868798 -280.975997) (xy 52.826177 -280.95139) (xy 52.788056 -280.920265)
			(xy 52.755421 -280.883428) (xy 52.729118 -280.841832) (xy 52.709827 -280.796556) (xy 52.69805 -280.748772)
			(xy 52.69409 -280.699718) (xy 51.405282 -280.699718) (xy 51.404787 -280.724325) (xy 51.396892 -280.772902)
			(xy 51.381308 -280.819583) (xy 51.358437 -280.86316) (xy 51.328872 -280.902504) (xy 51.293379 -280.936596)
			(xy 51.252876 -280.964552) (xy 51.208414 -280.98565) (xy 51.161143 -280.999342) (xy 51.112288 -281.005274)
			(xy 51.063113 -281.003293) (xy 51.014894 -280.993449) (xy 50.968878 -280.975997) (xy 50.926257 -280.95139)
			(xy 50.888136 -280.920265) (xy 50.855501 -280.883428) (xy 50.829198 -280.841832) (xy 50.809907 -280.796556)
			(xy 50.79813 -280.748772) (xy 50.79417 -280.699718) (xy 49.505108 -280.699718) (xy 49.504613 -280.724325)
			(xy 49.496718 -280.772902) (xy 49.481134 -280.819583) (xy 49.458263 -280.86316) (xy 49.428698 -280.902504)
			(xy 49.393205 -280.936596) (xy 49.352702 -280.964552) (xy 49.30824 -280.98565) (xy 49.260969 -280.999342)
			(xy 49.212114 -281.005274) (xy 49.162939 -281.003293) (xy 49.11472 -280.993449) (xy 49.068704 -280.975997)
			(xy 49.026083 -280.95139) (xy 48.987962 -280.920265) (xy 48.955327 -280.883428) (xy 48.929024 -280.841832)
			(xy 48.909733 -280.796556) (xy 48.897956 -280.748772) (xy 48.893996 -280.699718) (xy 47.605188 -280.699718)
			(xy 47.604693 -280.724325) (xy 47.596798 -280.772902) (xy 47.581214 -280.819583) (xy 47.558343 -280.86316)
			(xy 47.528778 -280.902504) (xy 47.493285 -280.936596) (xy 47.452782 -280.964552) (xy 47.40832 -280.98565)
			(xy 47.361049 -280.999342) (xy 47.312194 -281.005274) (xy 47.263019 -281.003293) (xy 47.2148 -280.993449)
			(xy 47.168784 -280.975997) (xy 47.126163 -280.95139) (xy 47.088042 -280.920265) (xy 47.055407 -280.883428)
			(xy 47.029104 -280.841832) (xy 47.009813 -280.796556) (xy 46.998036 -280.748772) (xy 46.994076 -280.699718)
			(xy 45.705268 -280.699718) (xy 45.704773 -280.724325) (xy 45.696878 -280.772902) (xy 45.681294 -280.819583)
			(xy 45.658423 -280.86316) (xy 45.628858 -280.902504) (xy 45.593365 -280.936596) (xy 45.552862 -280.964552)
			(xy 45.5084 -280.98565) (xy 45.461129 -280.999342) (xy 45.412274 -281.005274) (xy 45.363099 -281.003293)
			(xy 45.31488 -280.993449) (xy 45.268864 -280.975997) (xy 45.226243 -280.95139) (xy 45.188122 -280.920265)
			(xy 45.155487 -280.883428) (xy 45.129184 -280.841832) (xy 45.109893 -280.796556) (xy 45.098116 -280.748772)
			(xy 45.094156 -280.699718) (xy 0.508 -280.699718) (xy 0.508 -282.599892) (xy 76.444106 -282.599892)
			(xy 76.448066 -282.550838) (xy 76.459843 -282.503054) (xy 76.479134 -282.457778) (xy 76.505437 -282.416182)
			(xy 76.538072 -282.379345) (xy 76.576193 -282.34822) (xy 76.618814 -282.323613) (xy 76.66483 -282.306161)
			(xy 76.713049 -282.296317) (xy 76.762224 -282.294336) (xy 76.811079 -282.300268) (xy 76.85835 -282.31396)
			(xy 76.902812 -282.335058) (xy 76.943315 -282.363014) (xy 76.978808 -282.397106) (xy 77.008373 -282.43645)
			(xy 77.031244 -282.480027) (xy 77.046828 -282.526708) (xy 77.054723 -282.575285) (xy 77.055218 -282.599892)
			(xy 77.394066 -282.599892) (xy 77.398026 -282.550838) (xy 77.409803 -282.503054) (xy 77.429094 -282.457778)
			(xy 77.455397 -282.416182) (xy 77.488032 -282.379345) (xy 77.526153 -282.34822) (xy 77.568774 -282.323613)
			(xy 77.61479 -282.306161) (xy 77.663009 -282.296317) (xy 77.712184 -282.294336) (xy 77.761039 -282.300268)
			(xy 77.80831 -282.31396) (xy 77.852772 -282.335058) (xy 77.893275 -282.363014) (xy 77.928768 -282.397106)
			(xy 77.958333 -282.43645) (xy 77.981204 -282.480027) (xy 77.996788 -282.526708) (xy 78.004683 -282.575285)
			(xy 78.005178 -282.599892) (xy 192.544204 -282.599892) (xy 192.548164 -282.550838) (xy 192.559941 -282.503054)
			(xy 192.579232 -282.457778) (xy 192.605535 -282.416182) (xy 192.63817 -282.379345) (xy 192.676291 -282.34822)
			(xy 192.718912 -282.323613) (xy 192.764928 -282.306161) (xy 192.813147 -282.296317) (xy 192.862322 -282.294336)
			(xy 192.911177 -282.300268) (xy 192.958448 -282.31396) (xy 193.00291 -282.335058) (xy 193.043413 -282.363014)
			(xy 193.078906 -282.397106) (xy 193.108471 -282.43645) (xy 193.131342 -282.480027) (xy 193.146926 -282.526708)
			(xy 193.154821 -282.575285) (xy 193.155316 -282.599892) (xy 193.494164 -282.599892) (xy 193.498124 -282.550838)
			(xy 193.509901 -282.503054) (xy 193.529192 -282.457778) (xy 193.555495 -282.416182) (xy 193.58813 -282.379345)
			(xy 193.626251 -282.34822) (xy 193.668872 -282.323613) (xy 193.714888 -282.306161) (xy 193.763107 -282.296317)
			(xy 193.812282 -282.294336) (xy 193.861137 -282.300268) (xy 193.908408 -282.31396) (xy 193.95287 -282.335058)
			(xy 193.993373 -282.363014) (xy 194.028866 -282.397106) (xy 194.058431 -282.43645) (xy 194.081302 -282.480027)
			(xy 194.096886 -282.526708) (xy 194.104781 -282.575285) (xy 194.105276 -282.599892) (xy 308.644048 -282.599892)
			(xy 308.648008 -282.550838) (xy 308.659785 -282.503054) (xy 308.679076 -282.457778) (xy 308.705379 -282.416182)
			(xy 308.738014 -282.379345) (xy 308.776135 -282.34822) (xy 308.818756 -282.323613) (xy 308.864772 -282.306161)
			(xy 308.912991 -282.296317) (xy 308.962166 -282.294336) (xy 309.011021 -282.300268) (xy 309.058292 -282.31396)
			(xy 309.102754 -282.335058) (xy 309.143257 -282.363014) (xy 309.17875 -282.397106) (xy 309.208315 -282.43645)
			(xy 309.231186 -282.480027) (xy 309.24677 -282.526708) (xy 309.254665 -282.575285) (xy 309.25516 -282.599892)
			(xy 309.594008 -282.599892) (xy 309.597968 -282.550838) (xy 309.609745 -282.503054) (xy 309.629036 -282.457778)
			(xy 309.655339 -282.416182) (xy 309.687974 -282.379345) (xy 309.726095 -282.34822) (xy 309.768716 -282.323613)
			(xy 309.814732 -282.306161) (xy 309.862951 -282.296317) (xy 309.912126 -282.294336) (xy 309.960981 -282.300268)
			(xy 310.008252 -282.31396) (xy 310.052714 -282.335058) (xy 310.093217 -282.363014) (xy 310.12871 -282.397106)
			(xy 310.158275 -282.43645) (xy 310.181146 -282.480027) (xy 310.19673 -282.526708) (xy 310.204625 -282.575285)
			(xy 310.20512 -282.599892) (xy 424.744146 -282.599892) (xy 424.748106 -282.550838) (xy 424.759883 -282.503054)
			(xy 424.779174 -282.457778) (xy 424.805477 -282.416182) (xy 424.838112 -282.379345) (xy 424.876233 -282.34822)
			(xy 424.918854 -282.323613) (xy 424.96487 -282.306161) (xy 425.013089 -282.296317) (xy 425.062264 -282.294336)
			(xy 425.111119 -282.300268) (xy 425.15839 -282.31396) (xy 425.202852 -282.335058) (xy 425.243355 -282.363014)
			(xy 425.278848 -282.397106) (xy 425.308413 -282.43645) (xy 425.331284 -282.480027) (xy 425.346868 -282.526708)
			(xy 425.354763 -282.575285) (xy 425.355258 -282.599892) (xy 425.694106 -282.599892) (xy 425.698066 -282.550838)
			(xy 425.709843 -282.503054) (xy 425.729134 -282.457778) (xy 425.755437 -282.416182) (xy 425.788072 -282.379345)
			(xy 425.826193 -282.34822) (xy 425.868814 -282.323613) (xy 425.91483 -282.306161) (xy 425.963049 -282.296317)
			(xy 426.012224 -282.294336) (xy 426.061079 -282.300268) (xy 426.10835 -282.31396) (xy 426.152812 -282.335058)
			(xy 426.193315 -282.363014) (xy 426.228808 -282.397106) (xy 426.258373 -282.43645) (xy 426.281244 -282.480027)
			(xy 426.296828 -282.526708) (xy 426.304723 -282.575285) (xy 426.305218 -282.599892) (xy 426.304723 -282.624499)
			(xy 426.296828 -282.673076) (xy 426.281244 -282.719757) (xy 426.258373 -282.763334) (xy 426.228808 -282.802678)
			(xy 426.193315 -282.83677) (xy 426.152812 -282.864726) (xy 426.10835 -282.885824) (xy 426.061079 -282.899516)
			(xy 426.012224 -282.905448) (xy 425.963049 -282.903467) (xy 425.91483 -282.893623) (xy 425.868814 -282.876171)
			(xy 425.826193 -282.851564) (xy 425.788072 -282.820439) (xy 425.755437 -282.783602) (xy 425.729134 -282.742006)
			(xy 425.709843 -282.69673) (xy 425.698066 -282.648946) (xy 425.694106 -282.599892) (xy 425.355258 -282.599892)
			(xy 425.354763 -282.624499) (xy 425.346868 -282.673076) (xy 425.331284 -282.719757) (xy 425.308413 -282.763334)
			(xy 425.278848 -282.802678) (xy 425.243355 -282.83677) (xy 425.202852 -282.864726) (xy 425.15839 -282.885824)
			(xy 425.111119 -282.899516) (xy 425.062264 -282.905448) (xy 425.013089 -282.903467) (xy 424.96487 -282.893623)
			(xy 424.918854 -282.876171) (xy 424.876233 -282.851564) (xy 424.838112 -282.820439) (xy 424.805477 -282.783602)
			(xy 424.779174 -282.742006) (xy 424.759883 -282.69673) (xy 424.748106 -282.648946) (xy 424.744146 -282.599892)
			(xy 310.20512 -282.599892) (xy 310.204625 -282.624499) (xy 310.19673 -282.673076) (xy 310.181146 -282.719757)
			(xy 310.158275 -282.763334) (xy 310.12871 -282.802678) (xy 310.093217 -282.83677) (xy 310.052714 -282.864726)
			(xy 310.008252 -282.885824) (xy 309.960981 -282.899516) (xy 309.912126 -282.905448) (xy 309.862951 -282.903467)
			(xy 309.814732 -282.893623) (xy 309.768716 -282.876171) (xy 309.726095 -282.851564) (xy 309.687974 -282.820439)
			(xy 309.655339 -282.783602) (xy 309.629036 -282.742006) (xy 309.609745 -282.69673) (xy 309.597968 -282.648946)
			(xy 309.594008 -282.599892) (xy 309.25516 -282.599892) (xy 309.254665 -282.624499) (xy 309.24677 -282.673076)
			(xy 309.231186 -282.719757) (xy 309.208315 -282.763334) (xy 309.17875 -282.802678) (xy 309.143257 -282.83677)
			(xy 309.102754 -282.864726) (xy 309.058292 -282.885824) (xy 309.011021 -282.899516) (xy 308.962166 -282.905448)
			(xy 308.912991 -282.903467) (xy 308.864772 -282.893623) (xy 308.818756 -282.876171) (xy 308.776135 -282.851564)
			(xy 308.738014 -282.820439) (xy 308.705379 -282.783602) (xy 308.679076 -282.742006) (xy 308.659785 -282.69673)
			(xy 308.648008 -282.648946) (xy 308.644048 -282.599892) (xy 194.105276 -282.599892) (xy 194.104781 -282.624499)
			(xy 194.096886 -282.673076) (xy 194.081302 -282.719757) (xy 194.058431 -282.763334) (xy 194.028866 -282.802678)
			(xy 193.993373 -282.83677) (xy 193.95287 -282.864726) (xy 193.908408 -282.885824) (xy 193.861137 -282.899516)
			(xy 193.812282 -282.905448) (xy 193.763107 -282.903467) (xy 193.714888 -282.893623) (xy 193.668872 -282.876171)
			(xy 193.626251 -282.851564) (xy 193.58813 -282.820439) (xy 193.555495 -282.783602) (xy 193.529192 -282.742006)
			(xy 193.509901 -282.69673) (xy 193.498124 -282.648946) (xy 193.494164 -282.599892) (xy 193.155316 -282.599892)
			(xy 193.154821 -282.624499) (xy 193.146926 -282.673076) (xy 193.131342 -282.719757) (xy 193.108471 -282.763334)
			(xy 193.078906 -282.802678) (xy 193.043413 -282.83677) (xy 193.00291 -282.864726) (xy 192.958448 -282.885824)
			(xy 192.911177 -282.899516) (xy 192.862322 -282.905448) (xy 192.813147 -282.903467) (xy 192.764928 -282.893623)
			(xy 192.718912 -282.876171) (xy 192.676291 -282.851564) (xy 192.63817 -282.820439) (xy 192.605535 -282.783602)
			(xy 192.579232 -282.742006) (xy 192.559941 -282.69673) (xy 192.548164 -282.648946) (xy 192.544204 -282.599892)
			(xy 78.005178 -282.599892) (xy 78.004683 -282.624499) (xy 77.996788 -282.673076) (xy 77.981204 -282.719757)
			(xy 77.958333 -282.763334) (xy 77.928768 -282.802678) (xy 77.893275 -282.83677) (xy 77.852772 -282.864726)
			(xy 77.80831 -282.885824) (xy 77.761039 -282.899516) (xy 77.712184 -282.905448) (xy 77.663009 -282.903467)
			(xy 77.61479 -282.893623) (xy 77.568774 -282.876171) (xy 77.526153 -282.851564) (xy 77.488032 -282.820439)
			(xy 77.455397 -282.783602) (xy 77.429094 -282.742006) (xy 77.409803 -282.69673) (xy 77.398026 -282.648946)
			(xy 77.394066 -282.599892) (xy 77.055218 -282.599892) (xy 77.054723 -282.624499) (xy 77.046828 -282.673076)
			(xy 77.031244 -282.719757) (xy 77.008373 -282.763334) (xy 76.978808 -282.802678) (xy 76.943315 -282.83677)
			(xy 76.902812 -282.864726) (xy 76.85835 -282.885824) (xy 76.811079 -282.899516) (xy 76.762224 -282.905448)
			(xy 76.713049 -282.903467) (xy 76.66483 -282.893623) (xy 76.618814 -282.876171) (xy 76.576193 -282.851564)
			(xy 76.538072 -282.820439) (xy 76.505437 -282.783602) (xy 76.479134 -282.742006) (xy 76.459843 -282.69673)
			(xy 76.448066 -282.648946) (xy 76.444106 -282.599892) (xy 0.508 -282.599892) (xy 0.508 -283.549852)
			(xy 74.543932 -283.549852) (xy 74.547892 -283.500798) (xy 74.559669 -283.453014) (xy 74.57896 -283.407738)
			(xy 74.605263 -283.366142) (xy 74.637898 -283.329305) (xy 74.676019 -283.29818) (xy 74.71864 -283.273573)
			(xy 74.764656 -283.256121) (xy 74.812875 -283.246277) (xy 74.86205 -283.244296) (xy 74.910905 -283.250228)
			(xy 74.958176 -283.26392) (xy 75.002638 -283.285018) (xy 75.043141 -283.312974) (xy 75.078634 -283.347066)
			(xy 75.108199 -283.38641) (xy 75.13107 -283.429987) (xy 75.146654 -283.476668) (xy 75.154549 -283.525245)
			(xy 75.155044 -283.549852) (xy 75.494146 -283.549852) (xy 75.498106 -283.500798) (xy 75.509883 -283.453014)
			(xy 75.529174 -283.407738) (xy 75.555477 -283.366142) (xy 75.588112 -283.329305) (xy 75.626233 -283.29818)
			(xy 75.668854 -283.273573) (xy 75.71487 -283.256121) (xy 75.763089 -283.246277) (xy 75.812264 -283.244296)
			(xy 75.861119 -283.250228) (xy 75.90839 -283.26392) (xy 75.952852 -283.285018) (xy 75.993355 -283.312974)
			(xy 76.028848 -283.347066) (xy 76.058413 -283.38641) (xy 76.081284 -283.429987) (xy 76.096868 -283.476668)
			(xy 76.104763 -283.525245) (xy 76.105258 -283.549852) (xy 190.64403 -283.549852) (xy 190.64799 -283.500798)
			(xy 190.659767 -283.453014) (xy 190.679058 -283.407738) (xy 190.705361 -283.366142) (xy 190.737996 -283.329305)
			(xy 190.776117 -283.29818) (xy 190.818738 -283.273573) (xy 190.864754 -283.256121) (xy 190.912973 -283.246277)
			(xy 190.962148 -283.244296) (xy 191.011003 -283.250228) (xy 191.058274 -283.26392) (xy 191.102736 -283.285018)
			(xy 191.143239 -283.312974) (xy 191.178732 -283.347066) (xy 191.208297 -283.38641) (xy 191.231168 -283.429987)
			(xy 191.246752 -283.476668) (xy 191.254647 -283.525245) (xy 191.255142 -283.549852) (xy 191.594244 -283.549852)
			(xy 191.598204 -283.500798) (xy 191.609981 -283.453014) (xy 191.629272 -283.407738) (xy 191.655575 -283.366142)
			(xy 191.68821 -283.329305) (xy 191.726331 -283.29818) (xy 191.768952 -283.273573) (xy 191.814968 -283.256121)
			(xy 191.863187 -283.246277) (xy 191.912362 -283.244296) (xy 191.961217 -283.250228) (xy 192.008488 -283.26392)
			(xy 192.05295 -283.285018) (xy 192.093453 -283.312974) (xy 192.128946 -283.347066) (xy 192.158511 -283.38641)
			(xy 192.181382 -283.429987) (xy 192.196966 -283.476668) (xy 192.204861 -283.525245) (xy 192.205356 -283.549852)
			(xy 306.744128 -283.549852) (xy 306.748088 -283.500798) (xy 306.759865 -283.453014) (xy 306.779156 -283.407738)
			(xy 306.805459 -283.366142) (xy 306.838094 -283.329305) (xy 306.876215 -283.29818) (xy 306.918836 -283.273573)
			(xy 306.964852 -283.256121) (xy 307.013071 -283.246277) (xy 307.062246 -283.244296) (xy 307.111101 -283.250228)
			(xy 307.158372 -283.26392) (xy 307.202834 -283.285018) (xy 307.243337 -283.312974) (xy 307.27883 -283.347066)
			(xy 307.308395 -283.38641) (xy 307.331266 -283.429987) (xy 307.34685 -283.476668) (xy 307.354745 -283.525245)
			(xy 307.35524 -283.549852) (xy 307.694088 -283.549852) (xy 307.698048 -283.500798) (xy 307.709825 -283.453014)
			(xy 307.729116 -283.407738) (xy 307.755419 -283.366142) (xy 307.788054 -283.329305) (xy 307.826175 -283.29818)
			(xy 307.868796 -283.273573) (xy 307.914812 -283.256121) (xy 307.963031 -283.246277) (xy 308.012206 -283.244296)
			(xy 308.061061 -283.250228) (xy 308.108332 -283.26392) (xy 308.152794 -283.285018) (xy 308.193297 -283.312974)
			(xy 308.22879 -283.347066) (xy 308.258355 -283.38641) (xy 308.281226 -283.429987) (xy 308.29681 -283.476668)
			(xy 308.304705 -283.525245) (xy 308.3052 -283.549852) (xy 422.844226 -283.549852) (xy 422.848186 -283.500798)
			(xy 422.859963 -283.453014) (xy 422.879254 -283.407738) (xy 422.905557 -283.366142) (xy 422.938192 -283.329305)
			(xy 422.976313 -283.29818) (xy 423.018934 -283.273573) (xy 423.06495 -283.256121) (xy 423.113169 -283.246277)
			(xy 423.162344 -283.244296) (xy 423.211199 -283.250228) (xy 423.25847 -283.26392) (xy 423.302932 -283.285018)
			(xy 423.343435 -283.312974) (xy 423.378928 -283.347066) (xy 423.408493 -283.38641) (xy 423.431364 -283.429987)
			(xy 423.446948 -283.476668) (xy 423.454843 -283.525245) (xy 423.455338 -283.549852) (xy 423.794186 -283.549852)
			(xy 423.798146 -283.500798) (xy 423.809923 -283.453014) (xy 423.829214 -283.407738) (xy 423.855517 -283.366142)
			(xy 423.888152 -283.329305) (xy 423.926273 -283.29818) (xy 423.968894 -283.273573) (xy 424.01491 -283.256121)
			(xy 424.063129 -283.246277) (xy 424.112304 -283.244296) (xy 424.161159 -283.250228) (xy 424.20843 -283.26392)
			(xy 424.252892 -283.285018) (xy 424.293395 -283.312974) (xy 424.328888 -283.347066) (xy 424.358453 -283.38641)
			(xy 424.381324 -283.429987) (xy 424.396908 -283.476668) (xy 424.404803 -283.525245) (xy 424.405298 -283.549852)
			(xy 424.404803 -283.574459) (xy 424.396908 -283.623036) (xy 424.381324 -283.669717) (xy 424.358453 -283.713294)
			(xy 424.328888 -283.752638) (xy 424.293395 -283.78673) (xy 424.252892 -283.814686) (xy 424.20843 -283.835784)
			(xy 424.161159 -283.849476) (xy 424.112304 -283.855408) (xy 424.063129 -283.853427) (xy 424.01491 -283.843583)
			(xy 423.968894 -283.826131) (xy 423.926273 -283.801524) (xy 423.888152 -283.770399) (xy 423.855517 -283.733562)
			(xy 423.829214 -283.691966) (xy 423.809923 -283.64669) (xy 423.798146 -283.598906) (xy 423.794186 -283.549852)
			(xy 423.455338 -283.549852) (xy 423.454843 -283.574459) (xy 423.446948 -283.623036) (xy 423.431364 -283.669717)
			(xy 423.408493 -283.713294) (xy 423.378928 -283.752638) (xy 423.343435 -283.78673) (xy 423.302932 -283.814686)
			(xy 423.25847 -283.835784) (xy 423.211199 -283.849476) (xy 423.162344 -283.855408) (xy 423.113169 -283.853427)
			(xy 423.06495 -283.843583) (xy 423.018934 -283.826131) (xy 422.976313 -283.801524) (xy 422.938192 -283.770399)
			(xy 422.905557 -283.733562) (xy 422.879254 -283.691966) (xy 422.859963 -283.64669) (xy 422.848186 -283.598906)
			(xy 422.844226 -283.549852) (xy 308.3052 -283.549852) (xy 308.304705 -283.574459) (xy 308.29681 -283.623036)
			(xy 308.281226 -283.669717) (xy 308.258355 -283.713294) (xy 308.22879 -283.752638) (xy 308.193297 -283.78673)
			(xy 308.152794 -283.814686) (xy 308.108332 -283.835784) (xy 308.061061 -283.849476) (xy 308.012206 -283.855408)
			(xy 307.963031 -283.853427) (xy 307.914812 -283.843583) (xy 307.868796 -283.826131) (xy 307.826175 -283.801524)
			(xy 307.788054 -283.770399) (xy 307.755419 -283.733562) (xy 307.729116 -283.691966) (xy 307.709825 -283.64669)
			(xy 307.698048 -283.598906) (xy 307.694088 -283.549852) (xy 307.35524 -283.549852) (xy 307.354745 -283.574459)
			(xy 307.34685 -283.623036) (xy 307.331266 -283.669717) (xy 307.308395 -283.713294) (xy 307.27883 -283.752638)
			(xy 307.243337 -283.78673) (xy 307.202834 -283.814686) (xy 307.158372 -283.835784) (xy 307.111101 -283.849476)
			(xy 307.062246 -283.855408) (xy 307.013071 -283.853427) (xy 306.964852 -283.843583) (xy 306.918836 -283.826131)
			(xy 306.876215 -283.801524) (xy 306.838094 -283.770399) (xy 306.805459 -283.733562) (xy 306.779156 -283.691966)
			(xy 306.759865 -283.64669) (xy 306.748088 -283.598906) (xy 306.744128 -283.549852) (xy 192.205356 -283.549852)
			(xy 192.204861 -283.574459) (xy 192.196966 -283.623036) (xy 192.181382 -283.669717) (xy 192.158511 -283.713294)
			(xy 192.128946 -283.752638) (xy 192.093453 -283.78673) (xy 192.05295 -283.814686) (xy 192.008488 -283.835784)
			(xy 191.961217 -283.849476) (xy 191.912362 -283.855408) (xy 191.863187 -283.853427) (xy 191.814968 -283.843583)
			(xy 191.768952 -283.826131) (xy 191.726331 -283.801524) (xy 191.68821 -283.770399) (xy 191.655575 -283.733562)
			(xy 191.629272 -283.691966) (xy 191.609981 -283.64669) (xy 191.598204 -283.598906) (xy 191.594244 -283.549852)
			(xy 191.255142 -283.549852) (xy 191.254647 -283.574459) (xy 191.246752 -283.623036) (xy 191.231168 -283.669717)
			(xy 191.208297 -283.713294) (xy 191.178732 -283.752638) (xy 191.143239 -283.78673) (xy 191.102736 -283.814686)
			(xy 191.058274 -283.835784) (xy 191.011003 -283.849476) (xy 190.962148 -283.855408) (xy 190.912973 -283.853427)
			(xy 190.864754 -283.843583) (xy 190.818738 -283.826131) (xy 190.776117 -283.801524) (xy 190.737996 -283.770399)
			(xy 190.705361 -283.733562) (xy 190.679058 -283.691966) (xy 190.659767 -283.64669) (xy 190.64799 -283.598906)
			(xy 190.64403 -283.549852) (xy 76.105258 -283.549852) (xy 76.104763 -283.574459) (xy 76.096868 -283.623036)
			(xy 76.081284 -283.669717) (xy 76.058413 -283.713294) (xy 76.028848 -283.752638) (xy 75.993355 -283.78673)
			(xy 75.952852 -283.814686) (xy 75.90839 -283.835784) (xy 75.861119 -283.849476) (xy 75.812264 -283.855408)
			(xy 75.763089 -283.853427) (xy 75.71487 -283.843583) (xy 75.668854 -283.826131) (xy 75.626233 -283.801524)
			(xy 75.588112 -283.770399) (xy 75.555477 -283.733562) (xy 75.529174 -283.691966) (xy 75.509883 -283.64669)
			(xy 75.498106 -283.598906) (xy 75.494146 -283.549852) (xy 75.155044 -283.549852) (xy 75.154549 -283.574459)
			(xy 75.146654 -283.623036) (xy 75.13107 -283.669717) (xy 75.108199 -283.713294) (xy 75.078634 -283.752638)
			(xy 75.043141 -283.78673) (xy 75.002638 -283.814686) (xy 74.958176 -283.835784) (xy 74.910905 -283.849476)
			(xy 74.86205 -283.855408) (xy 74.812875 -283.853427) (xy 74.764656 -283.843583) (xy 74.71864 -283.826131)
			(xy 74.676019 -283.801524) (xy 74.637898 -283.770399) (xy 74.605263 -283.733562) (xy 74.57896 -283.691966)
			(xy 74.559669 -283.64669) (xy 74.547892 -283.598906) (xy 74.543932 -283.549852) (xy 0.508 -283.549852)
			(xy 0.508 -284.499812) (xy 76.444106 -284.499812) (xy 76.448066 -284.450758) (xy 76.459843 -284.402974)
			(xy 76.479134 -284.357698) (xy 76.505437 -284.316102) (xy 76.538072 -284.279265) (xy 76.576193 -284.24814)
			(xy 76.618814 -284.223533) (xy 76.66483 -284.206081) (xy 76.713049 -284.196237) (xy 76.762224 -284.194256)
			(xy 76.811079 -284.200188) (xy 76.85835 -284.21388) (xy 76.902812 -284.234978) (xy 76.943315 -284.262934)
			(xy 76.978808 -284.297026) (xy 77.008373 -284.33637) (xy 77.031244 -284.379947) (xy 77.046828 -284.426628)
			(xy 77.054723 -284.475205) (xy 77.055218 -284.499812) (xy 77.394066 -284.499812) (xy 77.398026 -284.450758)
			(xy 77.409803 -284.402974) (xy 77.429094 -284.357698) (xy 77.455397 -284.316102) (xy 77.488032 -284.279265)
			(xy 77.526153 -284.24814) (xy 77.568774 -284.223533) (xy 77.61479 -284.206081) (xy 77.663009 -284.196237)
			(xy 77.712184 -284.194256) (xy 77.761039 -284.200188) (xy 77.80831 -284.21388) (xy 77.852772 -284.234978)
			(xy 77.893275 -284.262934) (xy 77.928768 -284.297026) (xy 77.958333 -284.33637) (xy 77.981204 -284.379947)
			(xy 77.996788 -284.426628) (xy 78.004683 -284.475205) (xy 78.005178 -284.499812) (xy 192.544204 -284.499812)
			(xy 192.548164 -284.450758) (xy 192.559941 -284.402974) (xy 192.579232 -284.357698) (xy 192.605535 -284.316102)
			(xy 192.63817 -284.279265) (xy 192.676291 -284.24814) (xy 192.718912 -284.223533) (xy 192.764928 -284.206081)
			(xy 192.813147 -284.196237) (xy 192.862322 -284.194256) (xy 192.911177 -284.200188) (xy 192.958448 -284.21388)
			(xy 193.00291 -284.234978) (xy 193.043413 -284.262934) (xy 193.078906 -284.297026) (xy 193.108471 -284.33637)
			(xy 193.131342 -284.379947) (xy 193.146926 -284.426628) (xy 193.154821 -284.475205) (xy 193.155316 -284.499812)
			(xy 193.494164 -284.499812) (xy 193.498124 -284.450758) (xy 193.509901 -284.402974) (xy 193.529192 -284.357698)
			(xy 193.555495 -284.316102) (xy 193.58813 -284.279265) (xy 193.626251 -284.24814) (xy 193.668872 -284.223533)
			(xy 193.714888 -284.206081) (xy 193.763107 -284.196237) (xy 193.812282 -284.194256) (xy 193.861137 -284.200188)
			(xy 193.908408 -284.21388) (xy 193.95287 -284.234978) (xy 193.993373 -284.262934) (xy 194.028866 -284.297026)
			(xy 194.058431 -284.33637) (xy 194.081302 -284.379947) (xy 194.096886 -284.426628) (xy 194.104781 -284.475205)
			(xy 194.105276 -284.499812) (xy 308.644048 -284.499812) (xy 308.648008 -284.450758) (xy 308.659785 -284.402974)
			(xy 308.679076 -284.357698) (xy 308.705379 -284.316102) (xy 308.738014 -284.279265) (xy 308.776135 -284.24814)
			(xy 308.818756 -284.223533) (xy 308.864772 -284.206081) (xy 308.912991 -284.196237) (xy 308.962166 -284.194256)
			(xy 309.011021 -284.200188) (xy 309.058292 -284.21388) (xy 309.102754 -284.234978) (xy 309.143257 -284.262934)
			(xy 309.17875 -284.297026) (xy 309.208315 -284.33637) (xy 309.231186 -284.379947) (xy 309.24677 -284.426628)
			(xy 309.254665 -284.475205) (xy 309.25516 -284.499812) (xy 309.594008 -284.499812) (xy 309.597968 -284.450758)
			(xy 309.609745 -284.402974) (xy 309.629036 -284.357698) (xy 309.655339 -284.316102) (xy 309.687974 -284.279265)
			(xy 309.726095 -284.24814) (xy 309.768716 -284.223533) (xy 309.814732 -284.206081) (xy 309.862951 -284.196237)
			(xy 309.912126 -284.194256) (xy 309.960981 -284.200188) (xy 310.008252 -284.21388) (xy 310.052714 -284.234978)
			(xy 310.093217 -284.262934) (xy 310.12871 -284.297026) (xy 310.158275 -284.33637) (xy 310.181146 -284.379947)
			(xy 310.19673 -284.426628) (xy 310.204625 -284.475205) (xy 310.20512 -284.499812) (xy 424.744146 -284.499812)
			(xy 424.748106 -284.450758) (xy 424.759883 -284.402974) (xy 424.779174 -284.357698) (xy 424.805477 -284.316102)
			(xy 424.838112 -284.279265) (xy 424.876233 -284.24814) (xy 424.918854 -284.223533) (xy 424.96487 -284.206081)
			(xy 425.013089 -284.196237) (xy 425.062264 -284.194256) (xy 425.111119 -284.200188) (xy 425.15839 -284.21388)
			(xy 425.202852 -284.234978) (xy 425.243355 -284.262934) (xy 425.278848 -284.297026) (xy 425.308413 -284.33637)
			(xy 425.331284 -284.379947) (xy 425.346868 -284.426628) (xy 425.354763 -284.475205) (xy 425.355258 -284.499812)
			(xy 425.694106 -284.499812) (xy 425.698066 -284.450758) (xy 425.709843 -284.402974) (xy 425.729134 -284.357698)
			(xy 425.755437 -284.316102) (xy 425.788072 -284.279265) (xy 425.826193 -284.24814) (xy 425.868814 -284.223533)
			(xy 425.91483 -284.206081) (xy 425.963049 -284.196237) (xy 426.012224 -284.194256) (xy 426.061079 -284.200188)
			(xy 426.10835 -284.21388) (xy 426.152812 -284.234978) (xy 426.193315 -284.262934) (xy 426.228808 -284.297026)
			(xy 426.258373 -284.33637) (xy 426.281244 -284.379947) (xy 426.296828 -284.426628) (xy 426.304723 -284.475205)
			(xy 426.305218 -284.499812) (xy 426.304723 -284.524419) (xy 426.296828 -284.572996) (xy 426.281244 -284.619677)
			(xy 426.258373 -284.663254) (xy 426.228808 -284.702598) (xy 426.193315 -284.73669) (xy 426.152812 -284.764646)
			(xy 426.10835 -284.785744) (xy 426.061079 -284.799436) (xy 426.012224 -284.805368) (xy 425.963049 -284.803387)
			(xy 425.91483 -284.793543) (xy 425.868814 -284.776091) (xy 425.826193 -284.751484) (xy 425.788072 -284.720359)
			(xy 425.755437 -284.683522) (xy 425.729134 -284.641926) (xy 425.709843 -284.59665) (xy 425.698066 -284.548866)
			(xy 425.694106 -284.499812) (xy 425.355258 -284.499812) (xy 425.354763 -284.524419) (xy 425.346868 -284.572996)
			(xy 425.331284 -284.619677) (xy 425.308413 -284.663254) (xy 425.278848 -284.702598) (xy 425.243355 -284.73669)
			(xy 425.202852 -284.764646) (xy 425.15839 -284.785744) (xy 425.111119 -284.799436) (xy 425.062264 -284.805368)
			(xy 425.013089 -284.803387) (xy 424.96487 -284.793543) (xy 424.918854 -284.776091) (xy 424.876233 -284.751484)
			(xy 424.838112 -284.720359) (xy 424.805477 -284.683522) (xy 424.779174 -284.641926) (xy 424.759883 -284.59665)
			(xy 424.748106 -284.548866) (xy 424.744146 -284.499812) (xy 310.20512 -284.499812) (xy 310.204625 -284.524419)
			(xy 310.19673 -284.572996) (xy 310.181146 -284.619677) (xy 310.158275 -284.663254) (xy 310.12871 -284.702598)
			(xy 310.093217 -284.73669) (xy 310.052714 -284.764646) (xy 310.008252 -284.785744) (xy 309.960981 -284.799436)
			(xy 309.912126 -284.805368) (xy 309.862951 -284.803387) (xy 309.814732 -284.793543) (xy 309.768716 -284.776091)
			(xy 309.726095 -284.751484) (xy 309.687974 -284.720359) (xy 309.655339 -284.683522) (xy 309.629036 -284.641926)
			(xy 309.609745 -284.59665) (xy 309.597968 -284.548866) (xy 309.594008 -284.499812) (xy 309.25516 -284.499812)
			(xy 309.254665 -284.524419) (xy 309.24677 -284.572996) (xy 309.231186 -284.619677) (xy 309.208315 -284.663254)
			(xy 309.17875 -284.702598) (xy 309.143257 -284.73669) (xy 309.102754 -284.764646) (xy 309.058292 -284.785744)
			(xy 309.011021 -284.799436) (xy 308.962166 -284.805368) (xy 308.912991 -284.803387) (xy 308.864772 -284.793543)
			(xy 308.818756 -284.776091) (xy 308.776135 -284.751484) (xy 308.738014 -284.720359) (xy 308.705379 -284.683522)
			(xy 308.679076 -284.641926) (xy 308.659785 -284.59665) (xy 308.648008 -284.548866) (xy 308.644048 -284.499812)
			(xy 194.105276 -284.499812) (xy 194.104781 -284.524419) (xy 194.096886 -284.572996) (xy 194.081302 -284.619677)
			(xy 194.058431 -284.663254) (xy 194.028866 -284.702598) (xy 193.993373 -284.73669) (xy 193.95287 -284.764646)
			(xy 193.908408 -284.785744) (xy 193.861137 -284.799436) (xy 193.812282 -284.805368) (xy 193.763107 -284.803387)
			(xy 193.714888 -284.793543) (xy 193.668872 -284.776091) (xy 193.626251 -284.751484) (xy 193.58813 -284.720359)
			(xy 193.555495 -284.683522) (xy 193.529192 -284.641926) (xy 193.509901 -284.59665) (xy 193.498124 -284.548866)
			(xy 193.494164 -284.499812) (xy 193.155316 -284.499812) (xy 193.154821 -284.524419) (xy 193.146926 -284.572996)
			(xy 193.131342 -284.619677) (xy 193.108471 -284.663254) (xy 193.078906 -284.702598) (xy 193.043413 -284.73669)
			(xy 193.00291 -284.764646) (xy 192.958448 -284.785744) (xy 192.911177 -284.799436) (xy 192.862322 -284.805368)
			(xy 192.813147 -284.803387) (xy 192.764928 -284.793543) (xy 192.718912 -284.776091) (xy 192.676291 -284.751484)
			(xy 192.63817 -284.720359) (xy 192.605535 -284.683522) (xy 192.579232 -284.641926) (xy 192.559941 -284.59665)
			(xy 192.548164 -284.548866) (xy 192.544204 -284.499812) (xy 78.005178 -284.499812) (xy 78.004683 -284.524419)
			(xy 77.996788 -284.572996) (xy 77.981204 -284.619677) (xy 77.958333 -284.663254) (xy 77.928768 -284.702598)
			(xy 77.893275 -284.73669) (xy 77.852772 -284.764646) (xy 77.80831 -284.785744) (xy 77.761039 -284.799436)
			(xy 77.712184 -284.805368) (xy 77.663009 -284.803387) (xy 77.61479 -284.793543) (xy 77.568774 -284.776091)
			(xy 77.526153 -284.751484) (xy 77.488032 -284.720359) (xy 77.455397 -284.683522) (xy 77.429094 -284.641926)
			(xy 77.409803 -284.59665) (xy 77.398026 -284.548866) (xy 77.394066 -284.499812) (xy 77.055218 -284.499812)
			(xy 77.054723 -284.524419) (xy 77.046828 -284.572996) (xy 77.031244 -284.619677) (xy 77.008373 -284.663254)
			(xy 76.978808 -284.702598) (xy 76.943315 -284.73669) (xy 76.902812 -284.764646) (xy 76.85835 -284.785744)
			(xy 76.811079 -284.799436) (xy 76.762224 -284.805368) (xy 76.713049 -284.803387) (xy 76.66483 -284.793543)
			(xy 76.618814 -284.776091) (xy 76.576193 -284.751484) (xy 76.538072 -284.720359) (xy 76.505437 -284.683522)
			(xy 76.479134 -284.641926) (xy 76.459843 -284.59665) (xy 76.448066 -284.548866) (xy 76.444106 -284.499812)
			(xy 0.508 -284.499812) (xy 0.508 -285.449772) (xy 74.543932 -285.449772) (xy 74.547892 -285.400718)
			(xy 74.559669 -285.352934) (xy 74.57896 -285.307658) (xy 74.605263 -285.266062) (xy 74.637898 -285.229225)
			(xy 74.676019 -285.1981) (xy 74.71864 -285.173493) (xy 74.764656 -285.156041) (xy 74.812875 -285.146197)
			(xy 74.86205 -285.144216) (xy 74.910905 -285.150148) (xy 74.958176 -285.16384) (xy 75.002638 -285.184938)
			(xy 75.043141 -285.212894) (xy 75.078634 -285.246986) (xy 75.108199 -285.28633) (xy 75.13107 -285.329907)
			(xy 75.146654 -285.376588) (xy 75.154549 -285.425165) (xy 75.155044 -285.449772) (xy 75.494146 -285.449772)
			(xy 75.498106 -285.400718) (xy 75.509883 -285.352934) (xy 75.529174 -285.307658) (xy 75.555477 -285.266062)
			(xy 75.588112 -285.229225) (xy 75.626233 -285.1981) (xy 75.668854 -285.173493) (xy 75.71487 -285.156041)
			(xy 75.763089 -285.146197) (xy 75.812264 -285.144216) (xy 75.861119 -285.150148) (xy 75.90839 -285.16384)
			(xy 75.952852 -285.184938) (xy 75.993355 -285.212894) (xy 76.028848 -285.246986) (xy 76.058413 -285.28633)
			(xy 76.081284 -285.329907) (xy 76.096868 -285.376588) (xy 76.104763 -285.425165) (xy 76.105258 -285.449772)
			(xy 190.64403 -285.449772) (xy 190.64799 -285.400718) (xy 190.659767 -285.352934) (xy 190.679058 -285.307658)
			(xy 190.705361 -285.266062) (xy 190.737996 -285.229225) (xy 190.776117 -285.1981) (xy 190.818738 -285.173493)
			(xy 190.864754 -285.156041) (xy 190.912973 -285.146197) (xy 190.962148 -285.144216) (xy 191.011003 -285.150148)
			(xy 191.058274 -285.16384) (xy 191.102736 -285.184938) (xy 191.143239 -285.212894) (xy 191.178732 -285.246986)
			(xy 191.208297 -285.28633) (xy 191.231168 -285.329907) (xy 191.246752 -285.376588) (xy 191.254647 -285.425165)
			(xy 191.255142 -285.449772) (xy 191.594244 -285.449772) (xy 191.598204 -285.400718) (xy 191.609981 -285.352934)
			(xy 191.629272 -285.307658) (xy 191.655575 -285.266062) (xy 191.68821 -285.229225) (xy 191.726331 -285.1981)
			(xy 191.768952 -285.173493) (xy 191.814968 -285.156041) (xy 191.863187 -285.146197) (xy 191.912362 -285.144216)
			(xy 191.961217 -285.150148) (xy 192.008488 -285.16384) (xy 192.05295 -285.184938) (xy 192.093453 -285.212894)
			(xy 192.128946 -285.246986) (xy 192.158511 -285.28633) (xy 192.181382 -285.329907) (xy 192.196966 -285.376588)
			(xy 192.204861 -285.425165) (xy 192.205356 -285.449772) (xy 306.744128 -285.449772) (xy 306.748088 -285.400718)
			(xy 306.759865 -285.352934) (xy 306.779156 -285.307658) (xy 306.805459 -285.266062) (xy 306.838094 -285.229225)
			(xy 306.876215 -285.1981) (xy 306.918836 -285.173493) (xy 306.964852 -285.156041) (xy 307.013071 -285.146197)
			(xy 307.062246 -285.144216) (xy 307.111101 -285.150148) (xy 307.158372 -285.16384) (xy 307.202834 -285.184938)
			(xy 307.243337 -285.212894) (xy 307.27883 -285.246986) (xy 307.308395 -285.28633) (xy 307.331266 -285.329907)
			(xy 307.34685 -285.376588) (xy 307.354745 -285.425165) (xy 307.35524 -285.449772) (xy 307.694088 -285.449772)
			(xy 307.698048 -285.400718) (xy 307.709825 -285.352934) (xy 307.729116 -285.307658) (xy 307.755419 -285.266062)
			(xy 307.788054 -285.229225) (xy 307.826175 -285.1981) (xy 307.868796 -285.173493) (xy 307.914812 -285.156041)
			(xy 307.963031 -285.146197) (xy 308.012206 -285.144216) (xy 308.061061 -285.150148) (xy 308.108332 -285.16384)
			(xy 308.152794 -285.184938) (xy 308.193297 -285.212894) (xy 308.22879 -285.246986) (xy 308.258355 -285.28633)
			(xy 308.281226 -285.329907) (xy 308.29681 -285.376588) (xy 308.304705 -285.425165) (xy 308.3052 -285.449772)
			(xy 422.844226 -285.449772) (xy 422.848186 -285.400718) (xy 422.859963 -285.352934) (xy 422.879254 -285.307658)
			(xy 422.905557 -285.266062) (xy 422.938192 -285.229225) (xy 422.976313 -285.1981) (xy 423.018934 -285.173493)
			(xy 423.06495 -285.156041) (xy 423.113169 -285.146197) (xy 423.162344 -285.144216) (xy 423.211199 -285.150148)
			(xy 423.25847 -285.16384) (xy 423.302932 -285.184938) (xy 423.343435 -285.212894) (xy 423.378928 -285.246986)
			(xy 423.408493 -285.28633) (xy 423.431364 -285.329907) (xy 423.446948 -285.376588) (xy 423.454843 -285.425165)
			(xy 423.455338 -285.449772) (xy 423.794186 -285.449772) (xy 423.798146 -285.400718) (xy 423.809923 -285.352934)
			(xy 423.829214 -285.307658) (xy 423.855517 -285.266062) (xy 423.888152 -285.229225) (xy 423.926273 -285.1981)
			(xy 423.968894 -285.173493) (xy 424.01491 -285.156041) (xy 424.063129 -285.146197) (xy 424.112304 -285.144216)
			(xy 424.161159 -285.150148) (xy 424.20843 -285.16384) (xy 424.252892 -285.184938) (xy 424.293395 -285.212894)
			(xy 424.328888 -285.246986) (xy 424.358453 -285.28633) (xy 424.381324 -285.329907) (xy 424.396908 -285.376588)
			(xy 424.404803 -285.425165) (xy 424.405298 -285.449772) (xy 424.404803 -285.474379) (xy 424.396908 -285.522956)
			(xy 424.381324 -285.569637) (xy 424.358453 -285.613214) (xy 424.328888 -285.652558) (xy 424.293395 -285.68665)
			(xy 424.252892 -285.714606) (xy 424.20843 -285.735704) (xy 424.161159 -285.749396) (xy 424.112304 -285.755328)
			(xy 424.063129 -285.753347) (xy 424.01491 -285.743503) (xy 423.968894 -285.726051) (xy 423.926273 -285.701444)
			(xy 423.888152 -285.670319) (xy 423.855517 -285.633482) (xy 423.829214 -285.591886) (xy 423.809923 -285.54661)
			(xy 423.798146 -285.498826) (xy 423.794186 -285.449772) (xy 423.455338 -285.449772) (xy 423.454843 -285.474379)
			(xy 423.446948 -285.522956) (xy 423.431364 -285.569637) (xy 423.408493 -285.613214) (xy 423.378928 -285.652558)
			(xy 423.343435 -285.68665) (xy 423.302932 -285.714606) (xy 423.25847 -285.735704) (xy 423.211199 -285.749396)
			(xy 423.162344 -285.755328) (xy 423.113169 -285.753347) (xy 423.06495 -285.743503) (xy 423.018934 -285.726051)
			(xy 422.976313 -285.701444) (xy 422.938192 -285.670319) (xy 422.905557 -285.633482) (xy 422.879254 -285.591886)
			(xy 422.859963 -285.54661) (xy 422.848186 -285.498826) (xy 422.844226 -285.449772) (xy 308.3052 -285.449772)
			(xy 308.304705 -285.474379) (xy 308.29681 -285.522956) (xy 308.281226 -285.569637) (xy 308.258355 -285.613214)
			(xy 308.22879 -285.652558) (xy 308.193297 -285.68665) (xy 308.152794 -285.714606) (xy 308.108332 -285.735704)
			(xy 308.061061 -285.749396) (xy 308.012206 -285.755328) (xy 307.963031 -285.753347) (xy 307.914812 -285.743503)
			(xy 307.868796 -285.726051) (xy 307.826175 -285.701444) (xy 307.788054 -285.670319) (xy 307.755419 -285.633482)
			(xy 307.729116 -285.591886) (xy 307.709825 -285.54661) (xy 307.698048 -285.498826) (xy 307.694088 -285.449772)
			(xy 307.35524 -285.449772) (xy 307.354745 -285.474379) (xy 307.34685 -285.522956) (xy 307.331266 -285.569637)
			(xy 307.308395 -285.613214) (xy 307.27883 -285.652558) (xy 307.243337 -285.68665) (xy 307.202834 -285.714606)
			(xy 307.158372 -285.735704) (xy 307.111101 -285.749396) (xy 307.062246 -285.755328) (xy 307.013071 -285.753347)
			(xy 306.964852 -285.743503) (xy 306.918836 -285.726051) (xy 306.876215 -285.701444) (xy 306.838094 -285.670319)
			(xy 306.805459 -285.633482) (xy 306.779156 -285.591886) (xy 306.759865 -285.54661) (xy 306.748088 -285.498826)
			(xy 306.744128 -285.449772) (xy 192.205356 -285.449772) (xy 192.204861 -285.474379) (xy 192.196966 -285.522956)
			(xy 192.181382 -285.569637) (xy 192.158511 -285.613214) (xy 192.128946 -285.652558) (xy 192.093453 -285.68665)
			(xy 192.05295 -285.714606) (xy 192.008488 -285.735704) (xy 191.961217 -285.749396) (xy 191.912362 -285.755328)
			(xy 191.863187 -285.753347) (xy 191.814968 -285.743503) (xy 191.768952 -285.726051) (xy 191.726331 -285.701444)
			(xy 191.68821 -285.670319) (xy 191.655575 -285.633482) (xy 191.629272 -285.591886) (xy 191.609981 -285.54661)
			(xy 191.598204 -285.498826) (xy 191.594244 -285.449772) (xy 191.255142 -285.449772) (xy 191.254647 -285.474379)
			(xy 191.246752 -285.522956) (xy 191.231168 -285.569637) (xy 191.208297 -285.613214) (xy 191.178732 -285.652558)
			(xy 191.143239 -285.68665) (xy 191.102736 -285.714606) (xy 191.058274 -285.735704) (xy 191.011003 -285.749396)
			(xy 190.962148 -285.755328) (xy 190.912973 -285.753347) (xy 190.864754 -285.743503) (xy 190.818738 -285.726051)
			(xy 190.776117 -285.701444) (xy 190.737996 -285.670319) (xy 190.705361 -285.633482) (xy 190.679058 -285.591886)
			(xy 190.659767 -285.54661) (xy 190.64799 -285.498826) (xy 190.64403 -285.449772) (xy 76.105258 -285.449772)
			(xy 76.104763 -285.474379) (xy 76.096868 -285.522956) (xy 76.081284 -285.569637) (xy 76.058413 -285.613214)
			(xy 76.028848 -285.652558) (xy 75.993355 -285.68665) (xy 75.952852 -285.714606) (xy 75.90839 -285.735704)
			(xy 75.861119 -285.749396) (xy 75.812264 -285.755328) (xy 75.763089 -285.753347) (xy 75.71487 -285.743503)
			(xy 75.668854 -285.726051) (xy 75.626233 -285.701444) (xy 75.588112 -285.670319) (xy 75.555477 -285.633482)
			(xy 75.529174 -285.591886) (xy 75.509883 -285.54661) (xy 75.498106 -285.498826) (xy 75.494146 -285.449772)
			(xy 75.155044 -285.449772) (xy 75.154549 -285.474379) (xy 75.146654 -285.522956) (xy 75.13107 -285.569637)
			(xy 75.108199 -285.613214) (xy 75.078634 -285.652558) (xy 75.043141 -285.68665) (xy 75.002638 -285.714606)
			(xy 74.958176 -285.735704) (xy 74.910905 -285.749396) (xy 74.86205 -285.755328) (xy 74.812875 -285.753347)
			(xy 74.764656 -285.743503) (xy 74.71864 -285.726051) (xy 74.676019 -285.701444) (xy 74.637898 -285.670319)
			(xy 74.605263 -285.633482) (xy 74.57896 -285.591886) (xy 74.559669 -285.54661) (xy 74.547892 -285.498826)
			(xy 74.543932 -285.449772) (xy 0.508 -285.449772) (xy 0.508 -286.399986) (xy 76.444106 -286.399986)
			(xy 76.448066 -286.350932) (xy 76.459843 -286.303148) (xy 76.479134 -286.257872) (xy 76.505437 -286.216276)
			(xy 76.538072 -286.179439) (xy 76.576193 -286.148314) (xy 76.618814 -286.123707) (xy 76.66483 -286.106255)
			(xy 76.713049 -286.096411) (xy 76.762224 -286.09443) (xy 76.811079 -286.100362) (xy 76.85835 -286.114054)
			(xy 76.902812 -286.135152) (xy 76.943315 -286.163108) (xy 76.978808 -286.1972) (xy 77.008373 -286.236544)
			(xy 77.031244 -286.280121) (xy 77.046828 -286.326802) (xy 77.054723 -286.375379) (xy 77.055218 -286.399986)
			(xy 77.394066 -286.399986) (xy 77.398026 -286.350932) (xy 77.409803 -286.303148) (xy 77.429094 -286.257872)
			(xy 77.455397 -286.216276) (xy 77.488032 -286.179439) (xy 77.526153 -286.148314) (xy 77.568774 -286.123707)
			(xy 77.61479 -286.106255) (xy 77.663009 -286.096411) (xy 77.712184 -286.09443) (xy 77.761039 -286.100362)
			(xy 77.80831 -286.114054) (xy 77.852772 -286.135152) (xy 77.893275 -286.163108) (xy 77.928768 -286.1972)
			(xy 77.958333 -286.236544) (xy 77.981204 -286.280121) (xy 77.996788 -286.326802) (xy 78.004683 -286.375379)
			(xy 78.005178 -286.399986) (xy 192.544204 -286.399986) (xy 192.548164 -286.350932) (xy 192.559941 -286.303148)
			(xy 192.579232 -286.257872) (xy 192.605535 -286.216276) (xy 192.63817 -286.179439) (xy 192.676291 -286.148314)
			(xy 192.718912 -286.123707) (xy 192.764928 -286.106255) (xy 192.813147 -286.096411) (xy 192.862322 -286.09443)
			(xy 192.911177 -286.100362) (xy 192.958448 -286.114054) (xy 193.00291 -286.135152) (xy 193.043413 -286.163108)
			(xy 193.078906 -286.1972) (xy 193.108471 -286.236544) (xy 193.131342 -286.280121) (xy 193.146926 -286.326802)
			(xy 193.154821 -286.375379) (xy 193.155316 -286.399986) (xy 193.494164 -286.399986) (xy 193.498124 -286.350932)
			(xy 193.509901 -286.303148) (xy 193.529192 -286.257872) (xy 193.555495 -286.216276) (xy 193.58813 -286.179439)
			(xy 193.626251 -286.148314) (xy 193.668872 -286.123707) (xy 193.714888 -286.106255) (xy 193.763107 -286.096411)
			(xy 193.812282 -286.09443) (xy 193.861137 -286.100362) (xy 193.908408 -286.114054) (xy 193.95287 -286.135152)
			(xy 193.993373 -286.163108) (xy 194.028866 -286.1972) (xy 194.058431 -286.236544) (xy 194.081302 -286.280121)
			(xy 194.096886 -286.326802) (xy 194.104781 -286.375379) (xy 194.105276 -286.399986) (xy 308.644048 -286.399986)
			(xy 308.648008 -286.350932) (xy 308.659785 -286.303148) (xy 308.679076 -286.257872) (xy 308.705379 -286.216276)
			(xy 308.738014 -286.179439) (xy 308.776135 -286.148314) (xy 308.818756 -286.123707) (xy 308.864772 -286.106255)
			(xy 308.912991 -286.096411) (xy 308.962166 -286.09443) (xy 309.011021 -286.100362) (xy 309.058292 -286.114054)
			(xy 309.102754 -286.135152) (xy 309.143257 -286.163108) (xy 309.17875 -286.1972) (xy 309.208315 -286.236544)
			(xy 309.231186 -286.280121) (xy 309.24677 -286.326802) (xy 309.254665 -286.375379) (xy 309.25516 -286.399986)
			(xy 309.594008 -286.399986) (xy 309.597968 -286.350932) (xy 309.609745 -286.303148) (xy 309.629036 -286.257872)
			(xy 309.655339 -286.216276) (xy 309.687974 -286.179439) (xy 309.726095 -286.148314) (xy 309.768716 -286.123707)
			(xy 309.814732 -286.106255) (xy 309.862951 -286.096411) (xy 309.912126 -286.09443) (xy 309.960981 -286.100362)
			(xy 310.008252 -286.114054) (xy 310.052714 -286.135152) (xy 310.093217 -286.163108) (xy 310.12871 -286.1972)
			(xy 310.158275 -286.236544) (xy 310.181146 -286.280121) (xy 310.19673 -286.326802) (xy 310.204625 -286.375379)
			(xy 310.20512 -286.399986) (xy 424.744146 -286.399986) (xy 424.748106 -286.350932) (xy 424.759883 -286.303148)
			(xy 424.779174 -286.257872) (xy 424.805477 -286.216276) (xy 424.838112 -286.179439) (xy 424.876233 -286.148314)
			(xy 424.918854 -286.123707) (xy 424.96487 -286.106255) (xy 425.013089 -286.096411) (xy 425.062264 -286.09443)
			(xy 425.111119 -286.100362) (xy 425.15839 -286.114054) (xy 425.202852 -286.135152) (xy 425.243355 -286.163108)
			(xy 425.278848 -286.1972) (xy 425.308413 -286.236544) (xy 425.331284 -286.280121) (xy 425.346868 -286.326802)
			(xy 425.354763 -286.375379) (xy 425.355258 -286.399986) (xy 425.694106 -286.399986) (xy 425.698066 -286.350932)
			(xy 425.709843 -286.303148) (xy 425.729134 -286.257872) (xy 425.755437 -286.216276) (xy 425.788072 -286.179439)
			(xy 425.826193 -286.148314) (xy 425.868814 -286.123707) (xy 425.91483 -286.106255) (xy 425.963049 -286.096411)
			(xy 426.012224 -286.09443) (xy 426.061079 -286.100362) (xy 426.10835 -286.114054) (xy 426.152812 -286.135152)
			(xy 426.193315 -286.163108) (xy 426.228808 -286.1972) (xy 426.258373 -286.236544) (xy 426.281244 -286.280121)
			(xy 426.296828 -286.326802) (xy 426.304723 -286.375379) (xy 426.305218 -286.399986) (xy 426.304723 -286.424593)
			(xy 426.296828 -286.47317) (xy 426.281244 -286.519851) (xy 426.258373 -286.563428) (xy 426.228808 -286.602772)
			(xy 426.193315 -286.636864) (xy 426.152812 -286.66482) (xy 426.10835 -286.685918) (xy 426.061079 -286.69961)
			(xy 426.012224 -286.705542) (xy 425.963049 -286.703561) (xy 425.91483 -286.693717) (xy 425.868814 -286.676265)
			(xy 425.826193 -286.651658) (xy 425.788072 -286.620533) (xy 425.755437 -286.583696) (xy 425.729134 -286.5421)
			(xy 425.709843 -286.496824) (xy 425.698066 -286.44904) (xy 425.694106 -286.399986) (xy 425.355258 -286.399986)
			(xy 425.354763 -286.424593) (xy 425.346868 -286.47317) (xy 425.331284 -286.519851) (xy 425.308413 -286.563428)
			(xy 425.278848 -286.602772) (xy 425.243355 -286.636864) (xy 425.202852 -286.66482) (xy 425.15839 -286.685918)
			(xy 425.111119 -286.69961) (xy 425.062264 -286.705542) (xy 425.013089 -286.703561) (xy 424.96487 -286.693717)
			(xy 424.918854 -286.676265) (xy 424.876233 -286.651658) (xy 424.838112 -286.620533) (xy 424.805477 -286.583696)
			(xy 424.779174 -286.5421) (xy 424.759883 -286.496824) (xy 424.748106 -286.44904) (xy 424.744146 -286.399986)
			(xy 310.20512 -286.399986) (xy 310.204625 -286.424593) (xy 310.19673 -286.47317) (xy 310.181146 -286.519851)
			(xy 310.158275 -286.563428) (xy 310.12871 -286.602772) (xy 310.093217 -286.636864) (xy 310.052714 -286.66482)
			(xy 310.008252 -286.685918) (xy 309.960981 -286.69961) (xy 309.912126 -286.705542) (xy 309.862951 -286.703561)
			(xy 309.814732 -286.693717) (xy 309.768716 -286.676265) (xy 309.726095 -286.651658) (xy 309.687974 -286.620533)
			(xy 309.655339 -286.583696) (xy 309.629036 -286.5421) (xy 309.609745 -286.496824) (xy 309.597968 -286.44904)
			(xy 309.594008 -286.399986) (xy 309.25516 -286.399986) (xy 309.254665 -286.424593) (xy 309.24677 -286.47317)
			(xy 309.231186 -286.519851) (xy 309.208315 -286.563428) (xy 309.17875 -286.602772) (xy 309.143257 -286.636864)
			(xy 309.102754 -286.66482) (xy 309.058292 -286.685918) (xy 309.011021 -286.69961) (xy 308.962166 -286.705542)
			(xy 308.912991 -286.703561) (xy 308.864772 -286.693717) (xy 308.818756 -286.676265) (xy 308.776135 -286.651658)
			(xy 308.738014 -286.620533) (xy 308.705379 -286.583696) (xy 308.679076 -286.5421) (xy 308.659785 -286.496824)
			(xy 308.648008 -286.44904) (xy 308.644048 -286.399986) (xy 194.105276 -286.399986) (xy 194.104781 -286.424593)
			(xy 194.096886 -286.47317) (xy 194.081302 -286.519851) (xy 194.058431 -286.563428) (xy 194.028866 -286.602772)
			(xy 193.993373 -286.636864) (xy 193.95287 -286.66482) (xy 193.908408 -286.685918) (xy 193.861137 -286.69961)
			(xy 193.812282 -286.705542) (xy 193.763107 -286.703561) (xy 193.714888 -286.693717) (xy 193.668872 -286.676265)
			(xy 193.626251 -286.651658) (xy 193.58813 -286.620533) (xy 193.555495 -286.583696) (xy 193.529192 -286.5421)
			(xy 193.509901 -286.496824) (xy 193.498124 -286.44904) (xy 193.494164 -286.399986) (xy 193.155316 -286.399986)
			(xy 193.154821 -286.424593) (xy 193.146926 -286.47317) (xy 193.131342 -286.519851) (xy 193.108471 -286.563428)
			(xy 193.078906 -286.602772) (xy 193.043413 -286.636864) (xy 193.00291 -286.66482) (xy 192.958448 -286.685918)
			(xy 192.911177 -286.69961) (xy 192.862322 -286.705542) (xy 192.813147 -286.703561) (xy 192.764928 -286.693717)
			(xy 192.718912 -286.676265) (xy 192.676291 -286.651658) (xy 192.63817 -286.620533) (xy 192.605535 -286.583696)
			(xy 192.579232 -286.5421) (xy 192.559941 -286.496824) (xy 192.548164 -286.44904) (xy 192.544204 -286.399986)
			(xy 78.005178 -286.399986) (xy 78.004683 -286.424593) (xy 77.996788 -286.47317) (xy 77.981204 -286.519851)
			(xy 77.958333 -286.563428) (xy 77.928768 -286.602772) (xy 77.893275 -286.636864) (xy 77.852772 -286.66482)
			(xy 77.80831 -286.685918) (xy 77.761039 -286.69961) (xy 77.712184 -286.705542) (xy 77.663009 -286.703561)
			(xy 77.61479 -286.693717) (xy 77.568774 -286.676265) (xy 77.526153 -286.651658) (xy 77.488032 -286.620533)
			(xy 77.455397 -286.583696) (xy 77.429094 -286.5421) (xy 77.409803 -286.496824) (xy 77.398026 -286.44904)
			(xy 77.394066 -286.399986) (xy 77.055218 -286.399986) (xy 77.054723 -286.424593) (xy 77.046828 -286.47317)
			(xy 77.031244 -286.519851) (xy 77.008373 -286.563428) (xy 76.978808 -286.602772) (xy 76.943315 -286.636864)
			(xy 76.902812 -286.66482) (xy 76.85835 -286.685918) (xy 76.811079 -286.69961) (xy 76.762224 -286.705542)
			(xy 76.713049 -286.703561) (xy 76.66483 -286.693717) (xy 76.618814 -286.676265) (xy 76.576193 -286.651658)
			(xy 76.538072 -286.620533) (xy 76.505437 -286.583696) (xy 76.479134 -286.5421) (xy 76.459843 -286.496824)
			(xy 76.448066 -286.44904) (xy 76.444106 -286.399986) (xy 0.508 -286.399986) (xy 0.508 -287.349946)
			(xy 74.543932 -287.349946) (xy 74.547892 -287.300892) (xy 74.559669 -287.253108) (xy 74.57896 -287.207832)
			(xy 74.605263 -287.166236) (xy 74.637898 -287.129399) (xy 74.676019 -287.098274) (xy 74.71864 -287.073667)
			(xy 74.764656 -287.056215) (xy 74.812875 -287.046371) (xy 74.86205 -287.04439) (xy 74.910905 -287.050322)
			(xy 74.958176 -287.064014) (xy 75.002638 -287.085112) (xy 75.043141 -287.113068) (xy 75.078634 -287.14716)
			(xy 75.108199 -287.186504) (xy 75.13107 -287.230081) (xy 75.146654 -287.276762) (xy 75.154549 -287.325339)
			(xy 75.155044 -287.349946) (xy 75.494146 -287.349946) (xy 75.498106 -287.300892) (xy 75.509883 -287.253108)
			(xy 75.529174 -287.207832) (xy 75.555477 -287.166236) (xy 75.588112 -287.129399) (xy 75.626233 -287.098274)
			(xy 75.668854 -287.073667) (xy 75.71487 -287.056215) (xy 75.763089 -287.046371) (xy 75.812264 -287.04439)
			(xy 75.861119 -287.050322) (xy 75.90839 -287.064014) (xy 75.952852 -287.085112) (xy 75.993355 -287.113068)
			(xy 76.028848 -287.14716) (xy 76.058413 -287.186504) (xy 76.081284 -287.230081) (xy 76.096868 -287.276762)
			(xy 76.104763 -287.325339) (xy 76.105258 -287.349946) (xy 190.64403 -287.349946) (xy 190.64799 -287.300892)
			(xy 190.659767 -287.253108) (xy 190.679058 -287.207832) (xy 190.705361 -287.166236) (xy 190.737996 -287.129399)
			(xy 190.776117 -287.098274) (xy 190.818738 -287.073667) (xy 190.864754 -287.056215) (xy 190.912973 -287.046371)
			(xy 190.962148 -287.04439) (xy 191.011003 -287.050322) (xy 191.058274 -287.064014) (xy 191.102736 -287.085112)
			(xy 191.143239 -287.113068) (xy 191.178732 -287.14716) (xy 191.208297 -287.186504) (xy 191.231168 -287.230081)
			(xy 191.246752 -287.276762) (xy 191.254647 -287.325339) (xy 191.255142 -287.349946) (xy 191.594244 -287.349946)
			(xy 191.598204 -287.300892) (xy 191.609981 -287.253108) (xy 191.629272 -287.207832) (xy 191.655575 -287.166236)
			(xy 191.68821 -287.129399) (xy 191.726331 -287.098274) (xy 191.768952 -287.073667) (xy 191.814968 -287.056215)
			(xy 191.863187 -287.046371) (xy 191.912362 -287.04439) (xy 191.961217 -287.050322) (xy 192.008488 -287.064014)
			(xy 192.05295 -287.085112) (xy 192.093453 -287.113068) (xy 192.128946 -287.14716) (xy 192.158511 -287.186504)
			(xy 192.181382 -287.230081) (xy 192.196966 -287.276762) (xy 192.204861 -287.325339) (xy 192.205356 -287.349946)
			(xy 306.744128 -287.349946) (xy 306.748088 -287.300892) (xy 306.759865 -287.253108) (xy 306.779156 -287.207832)
			(xy 306.805459 -287.166236) (xy 306.838094 -287.129399) (xy 306.876215 -287.098274) (xy 306.918836 -287.073667)
			(xy 306.964852 -287.056215) (xy 307.013071 -287.046371) (xy 307.062246 -287.04439) (xy 307.111101 -287.050322)
			(xy 307.158372 -287.064014) (xy 307.202834 -287.085112) (xy 307.243337 -287.113068) (xy 307.27883 -287.14716)
			(xy 307.308395 -287.186504) (xy 307.331266 -287.230081) (xy 307.34685 -287.276762) (xy 307.354745 -287.325339)
			(xy 307.35524 -287.349946) (xy 307.694088 -287.349946) (xy 307.698048 -287.300892) (xy 307.709825 -287.253108)
			(xy 307.729116 -287.207832) (xy 307.755419 -287.166236) (xy 307.788054 -287.129399) (xy 307.826175 -287.098274)
			(xy 307.868796 -287.073667) (xy 307.914812 -287.056215) (xy 307.963031 -287.046371) (xy 308.012206 -287.04439)
			(xy 308.061061 -287.050322) (xy 308.108332 -287.064014) (xy 308.152794 -287.085112) (xy 308.193297 -287.113068)
			(xy 308.22879 -287.14716) (xy 308.258355 -287.186504) (xy 308.281226 -287.230081) (xy 308.29681 -287.276762)
			(xy 308.304705 -287.325339) (xy 308.3052 -287.349946) (xy 422.844226 -287.349946) (xy 422.848186 -287.300892)
			(xy 422.859963 -287.253108) (xy 422.879254 -287.207832) (xy 422.905557 -287.166236) (xy 422.938192 -287.129399)
			(xy 422.976313 -287.098274) (xy 423.018934 -287.073667) (xy 423.06495 -287.056215) (xy 423.113169 -287.046371)
			(xy 423.162344 -287.04439) (xy 423.211199 -287.050322) (xy 423.25847 -287.064014) (xy 423.302932 -287.085112)
			(xy 423.343435 -287.113068) (xy 423.378928 -287.14716) (xy 423.408493 -287.186504) (xy 423.431364 -287.230081)
			(xy 423.446948 -287.276762) (xy 423.454843 -287.325339) (xy 423.455338 -287.349946) (xy 423.794186 -287.349946)
			(xy 423.798146 -287.300892) (xy 423.809923 -287.253108) (xy 423.829214 -287.207832) (xy 423.855517 -287.166236)
			(xy 423.888152 -287.129399) (xy 423.926273 -287.098274) (xy 423.968894 -287.073667) (xy 424.01491 -287.056215)
			(xy 424.063129 -287.046371) (xy 424.112304 -287.04439) (xy 424.161159 -287.050322) (xy 424.20843 -287.064014)
			(xy 424.252892 -287.085112) (xy 424.293395 -287.113068) (xy 424.328888 -287.14716) (xy 424.358453 -287.186504)
			(xy 424.381324 -287.230081) (xy 424.396908 -287.276762) (xy 424.404803 -287.325339) (xy 424.405298 -287.349946)
			(xy 424.404803 -287.374553) (xy 424.396908 -287.42313) (xy 424.381324 -287.469811) (xy 424.358453 -287.513388)
			(xy 424.328888 -287.552732) (xy 424.293395 -287.586824) (xy 424.252892 -287.61478) (xy 424.20843 -287.635878)
			(xy 424.161159 -287.64957) (xy 424.112304 -287.655502) (xy 424.063129 -287.653521) (xy 424.01491 -287.643677)
			(xy 423.968894 -287.626225) (xy 423.926273 -287.601618) (xy 423.888152 -287.570493) (xy 423.855517 -287.533656)
			(xy 423.829214 -287.49206) (xy 423.809923 -287.446784) (xy 423.798146 -287.399) (xy 423.794186 -287.349946)
			(xy 423.455338 -287.349946) (xy 423.454843 -287.374553) (xy 423.446948 -287.42313) (xy 423.431364 -287.469811)
			(xy 423.408493 -287.513388) (xy 423.378928 -287.552732) (xy 423.343435 -287.586824) (xy 423.302932 -287.61478)
			(xy 423.25847 -287.635878) (xy 423.211199 -287.64957) (xy 423.162344 -287.655502) (xy 423.113169 -287.653521)
			(xy 423.06495 -287.643677) (xy 423.018934 -287.626225) (xy 422.976313 -287.601618) (xy 422.938192 -287.570493)
			(xy 422.905557 -287.533656) (xy 422.879254 -287.49206) (xy 422.859963 -287.446784) (xy 422.848186 -287.399)
			(xy 422.844226 -287.349946) (xy 308.3052 -287.349946) (xy 308.304705 -287.374553) (xy 308.29681 -287.42313)
			(xy 308.281226 -287.469811) (xy 308.258355 -287.513388) (xy 308.22879 -287.552732) (xy 308.193297 -287.586824)
			(xy 308.152794 -287.61478) (xy 308.108332 -287.635878) (xy 308.061061 -287.64957) (xy 308.012206 -287.655502)
			(xy 307.963031 -287.653521) (xy 307.914812 -287.643677) (xy 307.868796 -287.626225) (xy 307.826175 -287.601618)
			(xy 307.788054 -287.570493) (xy 307.755419 -287.533656) (xy 307.729116 -287.49206) (xy 307.709825 -287.446784)
			(xy 307.698048 -287.399) (xy 307.694088 -287.349946) (xy 307.35524 -287.349946) (xy 307.354745 -287.374553)
			(xy 307.34685 -287.42313) (xy 307.331266 -287.469811) (xy 307.308395 -287.513388) (xy 307.27883 -287.552732)
			(xy 307.243337 -287.586824) (xy 307.202834 -287.61478) (xy 307.158372 -287.635878) (xy 307.111101 -287.64957)
			(xy 307.062246 -287.655502) (xy 307.013071 -287.653521) (xy 306.964852 -287.643677) (xy 306.918836 -287.626225)
			(xy 306.876215 -287.601618) (xy 306.838094 -287.570493) (xy 306.805459 -287.533656) (xy 306.779156 -287.49206)
			(xy 306.759865 -287.446784) (xy 306.748088 -287.399) (xy 306.744128 -287.349946) (xy 192.205356 -287.349946)
			(xy 192.204861 -287.374553) (xy 192.196966 -287.42313) (xy 192.181382 -287.469811) (xy 192.158511 -287.513388)
			(xy 192.128946 -287.552732) (xy 192.093453 -287.586824) (xy 192.05295 -287.61478) (xy 192.008488 -287.635878)
			(xy 191.961217 -287.64957) (xy 191.912362 -287.655502) (xy 191.863187 -287.653521) (xy 191.814968 -287.643677)
			(xy 191.768952 -287.626225) (xy 191.726331 -287.601618) (xy 191.68821 -287.570493) (xy 191.655575 -287.533656)
			(xy 191.629272 -287.49206) (xy 191.609981 -287.446784) (xy 191.598204 -287.399) (xy 191.594244 -287.349946)
			(xy 191.255142 -287.349946) (xy 191.254647 -287.374553) (xy 191.246752 -287.42313) (xy 191.231168 -287.469811)
			(xy 191.208297 -287.513388) (xy 191.178732 -287.552732) (xy 191.143239 -287.586824) (xy 191.102736 -287.61478)
			(xy 191.058274 -287.635878) (xy 191.011003 -287.64957) (xy 190.962148 -287.655502) (xy 190.912973 -287.653521)
			(xy 190.864754 -287.643677) (xy 190.818738 -287.626225) (xy 190.776117 -287.601618) (xy 190.737996 -287.570493)
			(xy 190.705361 -287.533656) (xy 190.679058 -287.49206) (xy 190.659767 -287.446784) (xy 190.64799 -287.399)
			(xy 190.64403 -287.349946) (xy 76.105258 -287.349946) (xy 76.104763 -287.374553) (xy 76.096868 -287.42313)
			(xy 76.081284 -287.469811) (xy 76.058413 -287.513388) (xy 76.028848 -287.552732) (xy 75.993355 -287.586824)
			(xy 75.952852 -287.61478) (xy 75.90839 -287.635878) (xy 75.861119 -287.64957) (xy 75.812264 -287.655502)
			(xy 75.763089 -287.653521) (xy 75.71487 -287.643677) (xy 75.668854 -287.626225) (xy 75.626233 -287.601618)
			(xy 75.588112 -287.570493) (xy 75.555477 -287.533656) (xy 75.529174 -287.49206) (xy 75.509883 -287.446784)
			(xy 75.498106 -287.399) (xy 75.494146 -287.349946) (xy 75.155044 -287.349946) (xy 75.154549 -287.374553)
			(xy 75.146654 -287.42313) (xy 75.13107 -287.469811) (xy 75.108199 -287.513388) (xy 75.078634 -287.552732)
			(xy 75.043141 -287.586824) (xy 75.002638 -287.61478) (xy 74.958176 -287.635878) (xy 74.910905 -287.64957)
			(xy 74.86205 -287.655502) (xy 74.812875 -287.653521) (xy 74.764656 -287.643677) (xy 74.71864 -287.626225)
			(xy 74.676019 -287.601618) (xy 74.637898 -287.570493) (xy 74.605263 -287.533656) (xy 74.57896 -287.49206)
			(xy 74.559669 -287.446784) (xy 74.547892 -287.399) (xy 74.543932 -287.349946) (xy 0.508 -287.349946)
			(xy 0.508 -287.850408) (xy 37.944539 -287.850408) (xy 37.944539 -287.798392) (xy 37.952677 -287.747016)
			(xy 37.968751 -287.697546) (xy 37.992366 -287.651199) (xy 38.02294 -287.609117) (xy 38.059722 -287.572337)
			(xy 38.101804 -287.541763) (xy 38.148151 -287.518148) (xy 38.197622 -287.502075) (xy 38.248998 -287.493939)
			(xy 38.275006 -287.493456) (xy 39.224966 -287.493456) (xy 39.250978 -287.493901) (xy 39.302363 -287.502035)
			(xy 39.351843 -287.518107) (xy 39.398199 -287.541722) (xy 39.44029 -287.572299) (xy 39.477079 -287.609084)
			(xy 39.50766 -287.651172) (xy 39.53128 -287.697525) (xy 39.547357 -287.747004) (xy 39.555496 -287.798388)
			(xy 39.555496 -287.850405) (xy 40.794466 -287.850405) (xy 40.794466 -287.798395) (xy 40.802602 -287.747025)
			(xy 40.818674 -287.697561) (xy 40.842285 -287.651219) (xy 40.872855 -287.609142) (xy 40.909631 -287.572364)
			(xy 40.951707 -287.541792) (xy 40.998048 -287.518179) (xy 41.047512 -287.502105) (xy 41.098881 -287.493967)
			(xy 41.124886 -287.493456) (xy 42.074846 -287.493456) (xy 42.100852 -287.493934) (xy 42.152223 -287.502077)
			(xy 42.201688 -287.518155) (xy 42.248029 -287.541773) (xy 42.290106 -287.572348) (xy 42.326882 -287.609129)
			(xy 42.357451 -287.65121) (xy 42.381063 -287.697554) (xy 42.397134 -287.747022) (xy 42.40527 -287.798394)
			(xy 42.40527 -287.850406) (xy 42.397134 -287.901778) (xy 42.381063 -287.951246) (xy 42.357451 -287.99759)
			(xy 42.326882 -288.039671) (xy 42.290106 -288.076452) (xy 42.248029 -288.107027) (xy 42.201688 -288.130645)
			(xy 42.152223 -288.146723) (xy 42.100852 -288.154866) (xy 42.074846 -288.15538) (xy 41.124886 -288.15538)
			(xy 41.098881 -288.154833) (xy 41.047512 -288.146695) (xy 40.998048 -288.130621) (xy 40.951707 -288.107008)
			(xy 40.909631 -288.076436) (xy 40.872855 -288.039658) (xy 40.842285 -287.997581) (xy 40.818674 -287.951239)
			(xy 40.802602 -287.901775) (xy 40.794466 -287.850405) (xy 39.555496 -287.850405) (xy 39.555496 -287.850412)
			(xy 39.547357 -287.901796) (xy 39.53128 -287.951275) (xy 39.50766 -287.997628) (xy 39.477079 -288.039716)
			(xy 39.44029 -288.076501) (xy 39.398199 -288.107078) (xy 39.351843 -288.130693) (xy 39.302363 -288.146765)
			(xy 39.250978 -288.154899) (xy 39.224966 -288.15538) (xy 38.275006 -288.15538) (xy 38.248998 -288.154861)
			(xy 38.197622 -288.146725) (xy 38.148151 -288.130652) (xy 38.101804 -288.107037) (xy 38.059722 -288.076463)
			(xy 38.02294 -288.039683) (xy 37.992366 -287.997601) (xy 37.968751 -287.951254) (xy 37.952677 -287.901784)
			(xy 37.944539 -287.850408) (xy 0.508 -287.850408) (xy 0.508 -288.299906) (xy 76.444106 -288.299906)
			(xy 76.448066 -288.250852) (xy 76.459843 -288.203068) (xy 76.479134 -288.157792) (xy 76.505437 -288.116196)
			(xy 76.538072 -288.079359) (xy 76.576193 -288.048234) (xy 76.618814 -288.023627) (xy 76.66483 -288.006175)
			(xy 76.713049 -287.996331) (xy 76.762224 -287.99435) (xy 76.811079 -288.000282) (xy 76.85835 -288.013974)
			(xy 76.902812 -288.035072) (xy 76.943315 -288.063028) (xy 76.978808 -288.09712) (xy 77.008373 -288.136464)
			(xy 77.031244 -288.180041) (xy 77.046828 -288.226722) (xy 77.054723 -288.275299) (xy 77.055218 -288.299906)
			(xy 77.394066 -288.299906) (xy 77.398026 -288.250852) (xy 77.409803 -288.203068) (xy 77.429094 -288.157792)
			(xy 77.455397 -288.116196) (xy 77.488032 -288.079359) (xy 77.526153 -288.048234) (xy 77.568774 -288.023627)
			(xy 77.61479 -288.006175) (xy 77.663009 -287.996331) (xy 77.712184 -287.99435) (xy 77.761039 -288.000282)
			(xy 77.80831 -288.013974) (xy 77.852772 -288.035072) (xy 77.893275 -288.063028) (xy 77.928768 -288.09712)
			(xy 77.958333 -288.136464) (xy 77.981204 -288.180041) (xy 77.996788 -288.226722) (xy 78.004683 -288.275299)
			(xy 78.005178 -288.299906) (xy 192.544204 -288.299906) (xy 192.548164 -288.250852) (xy 192.559941 -288.203068)
			(xy 192.579232 -288.157792) (xy 192.605535 -288.116196) (xy 192.63817 -288.079359) (xy 192.676291 -288.048234)
			(xy 192.718912 -288.023627) (xy 192.764928 -288.006175) (xy 192.813147 -287.996331) (xy 192.862322 -287.99435)
			(xy 192.911177 -288.000282) (xy 192.958448 -288.013974) (xy 193.00291 -288.035072) (xy 193.043413 -288.063028)
			(xy 193.078906 -288.09712) (xy 193.108471 -288.136464) (xy 193.131342 -288.180041) (xy 193.146926 -288.226722)
			(xy 193.154821 -288.275299) (xy 193.155316 -288.299906) (xy 193.494164 -288.299906) (xy 193.498124 -288.250852)
			(xy 193.509901 -288.203068) (xy 193.529192 -288.157792) (xy 193.555495 -288.116196) (xy 193.58813 -288.079359)
			(xy 193.626251 -288.048234) (xy 193.668872 -288.023627) (xy 193.714888 -288.006175) (xy 193.763107 -287.996331)
			(xy 193.812282 -287.99435) (xy 193.861137 -288.000282) (xy 193.908408 -288.013974) (xy 193.95287 -288.035072)
			(xy 193.993373 -288.063028) (xy 194.028866 -288.09712) (xy 194.058431 -288.136464) (xy 194.081302 -288.180041)
			(xy 194.096886 -288.226722) (xy 194.104781 -288.275299) (xy 194.105276 -288.299906) (xy 308.644048 -288.299906)
			(xy 308.648008 -288.250852) (xy 308.659785 -288.203068) (xy 308.679076 -288.157792) (xy 308.705379 -288.116196)
			(xy 308.738014 -288.079359) (xy 308.776135 -288.048234) (xy 308.818756 -288.023627) (xy 308.864772 -288.006175)
			(xy 308.912991 -287.996331) (xy 308.962166 -287.99435) (xy 309.011021 -288.000282) (xy 309.058292 -288.013974)
			(xy 309.102754 -288.035072) (xy 309.143257 -288.063028) (xy 309.17875 -288.09712) (xy 309.208315 -288.136464)
			(xy 309.231186 -288.180041) (xy 309.24677 -288.226722) (xy 309.254665 -288.275299) (xy 309.25516 -288.299906)
			(xy 309.594008 -288.299906) (xy 309.597968 -288.250852) (xy 309.609745 -288.203068) (xy 309.629036 -288.157792)
			(xy 309.655339 -288.116196) (xy 309.687974 -288.079359) (xy 309.726095 -288.048234) (xy 309.768716 -288.023627)
			(xy 309.814732 -288.006175) (xy 309.862951 -287.996331) (xy 309.912126 -287.99435) (xy 309.960981 -288.000282)
			(xy 310.008252 -288.013974) (xy 310.052714 -288.035072) (xy 310.093217 -288.063028) (xy 310.12871 -288.09712)
			(xy 310.158275 -288.136464) (xy 310.181146 -288.180041) (xy 310.19673 -288.226722) (xy 310.204625 -288.275299)
			(xy 310.20512 -288.299906) (xy 424.744146 -288.299906) (xy 424.748106 -288.250852) (xy 424.759883 -288.203068)
			(xy 424.779174 -288.157792) (xy 424.805477 -288.116196) (xy 424.838112 -288.079359) (xy 424.876233 -288.048234)
			(xy 424.918854 -288.023627) (xy 424.96487 -288.006175) (xy 425.013089 -287.996331) (xy 425.062264 -287.99435)
			(xy 425.111119 -288.000282) (xy 425.15839 -288.013974) (xy 425.202852 -288.035072) (xy 425.243355 -288.063028)
			(xy 425.278848 -288.09712) (xy 425.308413 -288.136464) (xy 425.331284 -288.180041) (xy 425.346868 -288.226722)
			(xy 425.354763 -288.275299) (xy 425.355258 -288.299906) (xy 425.694106 -288.299906) (xy 425.698066 -288.250852)
			(xy 425.709843 -288.203068) (xy 425.729134 -288.157792) (xy 425.755437 -288.116196) (xy 425.788072 -288.079359)
			(xy 425.826193 -288.048234) (xy 425.868814 -288.023627) (xy 425.91483 -288.006175) (xy 425.963049 -287.996331)
			(xy 426.012224 -287.99435) (xy 426.061079 -288.000282) (xy 426.10835 -288.013974) (xy 426.152812 -288.035072)
			(xy 426.193315 -288.063028) (xy 426.228808 -288.09712) (xy 426.258373 -288.136464) (xy 426.281244 -288.180041)
			(xy 426.296828 -288.226722) (xy 426.304723 -288.275299) (xy 426.305218 -288.299906) (xy 426.304723 -288.324513)
			(xy 426.296828 -288.37309) (xy 426.281244 -288.419771) (xy 426.258373 -288.463348) (xy 426.228808 -288.502692)
			(xy 426.193315 -288.536784) (xy 426.152812 -288.56474) (xy 426.10835 -288.585838) (xy 426.061079 -288.59953)
			(xy 426.012224 -288.605462) (xy 425.963049 -288.603481) (xy 425.91483 -288.593637) (xy 425.868814 -288.576185)
			(xy 425.826193 -288.551578) (xy 425.788072 -288.520453) (xy 425.755437 -288.483616) (xy 425.729134 -288.44202)
			(xy 425.709843 -288.396744) (xy 425.698066 -288.34896) (xy 425.694106 -288.299906) (xy 425.355258 -288.299906)
			(xy 425.354763 -288.324513) (xy 425.346868 -288.37309) (xy 425.331284 -288.419771) (xy 425.308413 -288.463348)
			(xy 425.278848 -288.502692) (xy 425.243355 -288.536784) (xy 425.202852 -288.56474) (xy 425.15839 -288.585838)
			(xy 425.111119 -288.59953) (xy 425.062264 -288.605462) (xy 425.013089 -288.603481) (xy 424.96487 -288.593637)
			(xy 424.918854 -288.576185) (xy 424.876233 -288.551578) (xy 424.838112 -288.520453) (xy 424.805477 -288.483616)
			(xy 424.779174 -288.44202) (xy 424.759883 -288.396744) (xy 424.748106 -288.34896) (xy 424.744146 -288.299906)
			(xy 310.20512 -288.299906) (xy 310.204625 -288.324513) (xy 310.19673 -288.37309) (xy 310.181146 -288.419771)
			(xy 310.158275 -288.463348) (xy 310.12871 -288.502692) (xy 310.093217 -288.536784) (xy 310.052714 -288.56474)
			(xy 310.008252 -288.585838) (xy 309.960981 -288.59953) (xy 309.912126 -288.605462) (xy 309.862951 -288.603481)
			(xy 309.814732 -288.593637) (xy 309.768716 -288.576185) (xy 309.726095 -288.551578) (xy 309.687974 -288.520453)
			(xy 309.655339 -288.483616) (xy 309.629036 -288.44202) (xy 309.609745 -288.396744) (xy 309.597968 -288.34896)
			(xy 309.594008 -288.299906) (xy 309.25516 -288.299906) (xy 309.254665 -288.324513) (xy 309.24677 -288.37309)
			(xy 309.231186 -288.419771) (xy 309.208315 -288.463348) (xy 309.17875 -288.502692) (xy 309.143257 -288.536784)
			(xy 309.102754 -288.56474) (xy 309.058292 -288.585838) (xy 309.011021 -288.59953) (xy 308.962166 -288.605462)
			(xy 308.912991 -288.603481) (xy 308.864772 -288.593637) (xy 308.818756 -288.576185) (xy 308.776135 -288.551578)
			(xy 308.738014 -288.520453) (xy 308.705379 -288.483616) (xy 308.679076 -288.44202) (xy 308.659785 -288.396744)
			(xy 308.648008 -288.34896) (xy 308.644048 -288.299906) (xy 194.105276 -288.299906) (xy 194.104781 -288.324513)
			(xy 194.096886 -288.37309) (xy 194.081302 -288.419771) (xy 194.058431 -288.463348) (xy 194.028866 -288.502692)
			(xy 193.993373 -288.536784) (xy 193.95287 -288.56474) (xy 193.908408 -288.585838) (xy 193.861137 -288.59953)
			(xy 193.812282 -288.605462) (xy 193.763107 -288.603481) (xy 193.714888 -288.593637) (xy 193.668872 -288.576185)
			(xy 193.626251 -288.551578) (xy 193.58813 -288.520453) (xy 193.555495 -288.483616) (xy 193.529192 -288.44202)
			(xy 193.509901 -288.396744) (xy 193.498124 -288.34896) (xy 193.494164 -288.299906) (xy 193.155316 -288.299906)
			(xy 193.154821 -288.324513) (xy 193.146926 -288.37309) (xy 193.131342 -288.419771) (xy 193.108471 -288.463348)
			(xy 193.078906 -288.502692) (xy 193.043413 -288.536784) (xy 193.00291 -288.56474) (xy 192.958448 -288.585838)
			(xy 192.911177 -288.59953) (xy 192.862322 -288.605462) (xy 192.813147 -288.603481) (xy 192.764928 -288.593637)
			(xy 192.718912 -288.576185) (xy 192.676291 -288.551578) (xy 192.63817 -288.520453) (xy 192.605535 -288.483616)
			(xy 192.579232 -288.44202) (xy 192.559941 -288.396744) (xy 192.548164 -288.34896) (xy 192.544204 -288.299906)
			(xy 78.005178 -288.299906) (xy 78.004683 -288.324513) (xy 77.996788 -288.37309) (xy 77.981204 -288.419771)
			(xy 77.958333 -288.463348) (xy 77.928768 -288.502692) (xy 77.893275 -288.536784) (xy 77.852772 -288.56474)
			(xy 77.80831 -288.585838) (xy 77.761039 -288.59953) (xy 77.712184 -288.605462) (xy 77.663009 -288.603481)
			(xy 77.61479 -288.593637) (xy 77.568774 -288.576185) (xy 77.526153 -288.551578) (xy 77.488032 -288.520453)
			(xy 77.455397 -288.483616) (xy 77.429094 -288.44202) (xy 77.409803 -288.396744) (xy 77.398026 -288.34896)
			(xy 77.394066 -288.299906) (xy 77.055218 -288.299906) (xy 77.054723 -288.324513) (xy 77.046828 -288.37309)
			(xy 77.031244 -288.419771) (xy 77.008373 -288.463348) (xy 76.978808 -288.502692) (xy 76.943315 -288.536784)
			(xy 76.902812 -288.56474) (xy 76.85835 -288.585838) (xy 76.811079 -288.59953) (xy 76.762224 -288.605462)
			(xy 76.713049 -288.603481) (xy 76.66483 -288.593637) (xy 76.618814 -288.576185) (xy 76.576193 -288.551578)
			(xy 76.538072 -288.520453) (xy 76.505437 -288.483616) (xy 76.479134 -288.44202) (xy 76.459843 -288.396744)
			(xy 76.448066 -288.34896) (xy 76.444106 -288.299906) (xy 0.508 -288.299906) (xy 0.508 -288.800413)
			(xy 36.0443 -288.800413) (xy 36.0443 -288.748387) (xy 36.052439 -288.697003) (xy 36.068516 -288.647524)
			(xy 36.092136 -288.60117) (xy 36.122718 -288.559082) (xy 36.159507 -288.522297) (xy 36.201598 -288.49172)
			(xy 36.247954 -288.468104) (xy 36.297434 -288.452031) (xy 36.348819 -288.443897) (xy 36.374832 -288.443416)
			(xy 37.324792 -288.443416) (xy 37.3508 -288.443943) (xy 37.402175 -288.452079) (xy 37.451646 -288.468151)
			(xy 37.497993 -288.491765) (xy 37.540075 -288.522339) (xy 37.576856 -288.559119) (xy 37.60743 -288.601201)
			(xy 37.631045 -288.647547) (xy 37.647119 -288.697017) (xy 37.655257 -288.748392) (xy 37.655257 -288.800408)
			(xy 37.655257 -288.800411) (xy 42.694299 -288.800411) (xy 42.694299 -288.748389) (xy 42.702438 -288.697007)
			(xy 42.718514 -288.64753) (xy 42.742132 -288.601178) (xy 42.77271 -288.559091) (xy 42.809496 -288.522306)
			(xy 42.851583 -288.491729) (xy 42.897936 -288.468111) (xy 42.947413 -288.452036) (xy 42.998795 -288.443899)
			(xy 43.024806 -288.443416) (xy 43.974766 -288.443416) (xy 44.000775 -288.443941) (xy 44.052154 -288.452074)
			(xy 44.101628 -288.468144) (xy 44.147978 -288.491757) (xy 44.190064 -288.52233) (xy 44.226848 -288.55911)
			(xy 44.257426 -288.601193) (xy 44.281043 -288.647541) (xy 44.297119 -288.697013) (xy 44.305257 -288.748391)
			(xy 44.305257 -288.800409) (xy 44.297119 -288.851787) (xy 44.281043 -288.901259) (xy 44.257426 -288.947607)
			(xy 44.226848 -288.98969) (xy 44.190064 -289.02647) (xy 44.147978 -289.057043) (xy 44.101628 -289.080656)
			(xy 44.052154 -289.096726) (xy 44.000775 -289.104859) (xy 43.974766 -289.10534) (xy 43.024806 -289.10534)
			(xy 42.998795 -289.104901) (xy 42.947413 -289.096764) (xy 42.897936 -289.080689) (xy 42.851583 -289.057071)
			(xy 42.809496 -289.026494) (xy 42.77271 -288.989709) (xy 42.742132 -288.947622) (xy 42.718514 -288.90127)
			(xy 42.702438 -288.851793) (xy 42.694299 -288.800411) (xy 37.655257 -288.800411) (xy 37.647119 -288.851783)
			(xy 37.631045 -288.901253) (xy 37.60743 -288.947599) (xy 37.576856 -288.989681) (xy 37.540075 -289.026461)
			(xy 37.497993 -289.057035) (xy 37.451646 -289.080649) (xy 37.402175 -289.096721) (xy 37.3508 -289.104857)
			(xy 37.324792 -289.10534) (xy 36.374832 -289.10534) (xy 36.348819 -289.104903) (xy 36.297434 -289.096769)
			(xy 36.247954 -289.080696) (xy 36.201598 -289.05708) (xy 36.159507 -289.026503) (xy 36.122718 -288.989718)
			(xy 36.092136 -288.94763) (xy 36.068516 -288.901276) (xy 36.052439 -288.851797) (xy 36.0443 -288.800413)
			(xy 0.508 -288.800413) (xy 0.508 -297.350788) (xy 36.044382 -297.350788) (xy 36.044382 -297.298812)
			(xy 36.052512 -297.247477) (xy 36.068572 -297.198045) (xy 36.092168 -297.151734) (xy 36.122717 -297.109685)
			(xy 36.159468 -297.072931) (xy 36.201516 -297.042379) (xy 36.247825 -297.018781) (xy 36.297255 -297.002717)
			(xy 36.34859 -296.994583) (xy 36.374578 -296.994072) (xy 37.324538 -296.994072) (xy 37.350522 -296.994624)
			(xy 37.401848 -297.002759) (xy 37.451271 -297.018822) (xy 37.497572 -297.042419) (xy 37.539613 -297.072968)
			(xy 37.576357 -297.109716) (xy 37.606901 -297.15176) (xy 37.630492 -297.198064) (xy 37.64655 -297.247489)
			(xy 37.654679 -297.298816) (xy 37.654679 -297.350784) (xy 37.654678 -297.350788) (xy 152.144482 -297.350788)
			(xy 152.144482 -297.298812) (xy 152.152612 -297.247477) (xy 152.168672 -297.198046) (xy 152.192268 -297.151735)
			(xy 152.222816 -297.109685) (xy 152.259567 -297.072932) (xy 152.301615 -297.04238) (xy 152.347923 -297.018782)
			(xy 152.397354 -297.002717) (xy 152.448688 -296.994583) (xy 152.474676 -296.994072) (xy 153.424636 -296.994072)
			(xy 153.45062 -296.994624) (xy 153.501947 -297.002759) (xy 153.55137 -297.018822) (xy 153.597671 -297.042418)
			(xy 153.639712 -297.072967) (xy 153.676457 -297.109715) (xy 153.707001 -297.151759) (xy 153.730592 -297.198064)
			(xy 153.74665 -297.247488) (xy 153.754779 -297.298816) (xy 153.754779 -297.350784) (xy 153.754778 -297.350792)
			(xy 268.244255 -297.350792) (xy 268.244255 -297.298808) (xy 268.252388 -297.247465) (xy 268.268452 -297.198025)
			(xy 268.292053 -297.151708) (xy 268.322609 -297.109653) (xy 268.359368 -297.072896) (xy 268.401425 -297.042342)
			(xy 268.447744 -297.018744) (xy 268.497184 -297.002683) (xy 268.548528 -296.994554) (xy 268.57452 -296.994072)
			(xy 269.52448 -296.994072) (xy 269.550469 -296.994594) (xy 269.601807 -297.002722) (xy 269.651241 -297.018781)
			(xy 269.697554 -297.042377) (xy 269.739606 -297.072927) (xy 269.77636 -297.109679) (xy 269.806913 -297.151729)
			(xy 269.830511 -297.198041) (xy 269.846573 -297.247474) (xy 269.854705 -297.298811) (xy 269.854705 -297.350789)
			(xy 269.854705 -297.350792) (xy 384.344355 -297.350792) (xy 384.344355 -297.298808) (xy 384.352488 -297.247465)
			(xy 384.368552 -297.198026) (xy 384.392153 -297.151709) (xy 384.422709 -297.109654) (xy 384.459467 -297.072897)
			(xy 384.501524 -297.042343) (xy 384.547842 -297.018745) (xy 384.597282 -297.002683) (xy 384.648626 -296.994554)
			(xy 384.674618 -296.994072) (xy 385.624578 -296.994072) (xy 385.650567 -296.994593) (xy 385.701905 -297.002721)
			(xy 385.751339 -297.018781) (xy 385.797653 -297.042376) (xy 385.839705 -297.072926) (xy 385.87646 -297.109678)
			(xy 385.907013 -297.151728) (xy 385.930611 -297.19804) (xy 385.946673 -297.247474) (xy 385.954805 -297.298811)
			(xy 385.954805 -297.350789) (xy 385.946673 -297.402126) (xy 385.930611 -297.45156) (xy 385.907013 -297.497872)
			(xy 385.87646 -297.539922) (xy 385.839705 -297.576674) (xy 385.797653 -297.607224) (xy 385.751339 -297.630819)
			(xy 385.701905 -297.646879) (xy 385.650567 -297.655007) (xy 385.624578 -297.655488) (xy 384.674618 -297.655488)
			(xy 384.648626 -297.655046) (xy 384.597282 -297.646917) (xy 384.547842 -297.630855) (xy 384.501524 -297.607257)
			(xy 384.459467 -297.576703) (xy 384.422709 -297.539946) (xy 384.392153 -297.497891) (xy 384.368552 -297.451574)
			(xy 384.352488 -297.402135) (xy 384.344355 -297.350792) (xy 269.854705 -297.350792) (xy 269.846573 -297.402126)
			(xy 269.830511 -297.451559) (xy 269.806913 -297.497871) (xy 269.77636 -297.539921) (xy 269.739606 -297.576673)
			(xy 269.697554 -297.607223) (xy 269.651241 -297.630819) (xy 269.601807 -297.646878) (xy 269.550469 -297.655006)
			(xy 269.52448 -297.655488) (xy 268.57452 -297.655488) (xy 268.548528 -297.655046) (xy 268.497184 -297.646917)
			(xy 268.447744 -297.630856) (xy 268.401425 -297.607258) (xy 268.359368 -297.576704) (xy 268.322609 -297.539947)
			(xy 268.292053 -297.497892) (xy 268.268452 -297.451575) (xy 268.252388 -297.402135) (xy 268.244255 -297.350792)
			(xy 153.754778 -297.350792) (xy 153.74665 -297.402112) (xy 153.730592 -297.451536) (xy 153.707001 -297.497841)
			(xy 153.676457 -297.539885) (xy 153.639712 -297.576633) (xy 153.597671 -297.607182) (xy 153.55137 -297.630778)
			(xy 153.501947 -297.646841) (xy 153.45062 -297.654976) (xy 153.424636 -297.655488) (xy 152.474676 -297.655488)
			(xy 152.448688 -297.655017) (xy 152.397354 -297.646883) (xy 152.347923 -297.630818) (xy 152.301615 -297.60722)
			(xy 152.259567 -297.576668) (xy 152.222816 -297.539915) (xy 152.192268 -297.497865) (xy 152.168672 -297.451554)
			(xy 152.152612 -297.402123) (xy 152.144482 -297.350788) (xy 37.654678 -297.350788) (xy 37.64655 -297.402111)
			(xy 37.630492 -297.451536) (xy 37.606901 -297.49784) (xy 37.576357 -297.539884) (xy 37.539613 -297.576632)
			(xy 37.497572 -297.607181) (xy 37.451271 -297.630778) (xy 37.401848 -297.646841) (xy 37.350522 -297.654976)
			(xy 37.324538 -297.655488) (xy 36.374578 -297.655488) (xy 36.34859 -297.655017) (xy 36.297255 -297.646883)
			(xy 36.247825 -297.630819) (xy 36.201516 -297.607221) (xy 36.159468 -297.576669) (xy 36.122717 -297.539915)
			(xy 36.092168 -297.497866) (xy 36.068572 -297.451555) (xy 36.052512 -297.402123) (xy 36.044382 -297.350788)
			(xy 0.508 -297.350788) (xy 0.508 -298.77569) (xy 39.369695 -298.77569) (xy 39.369695 -298.72371)
			(xy 39.377827 -298.67237) (xy 39.393891 -298.622935) (xy 39.417492 -298.576621) (xy 39.448047 -298.53457)
			(xy 39.484805 -298.497817) (xy 39.52686 -298.467268) (xy 39.573177 -298.443674) (xy 39.622615 -298.427617)
			(xy 39.673956 -298.419492) (xy 39.699946 -298.419012) (xy 40.649906 -298.419012) (xy 40.675894 -298.419482)
			(xy 40.727231 -298.427614) (xy 40.776664 -298.443676) (xy 40.822975 -298.467274) (xy 40.865025 -298.497826)
			(xy 40.901778 -298.534579) (xy 40.932329 -298.57663) (xy 40.955926 -298.622942) (xy 40.971988 -298.672375)
			(xy 40.980118 -298.723712) (xy 40.980118 -298.775685) (xy 387.669821 -298.775685) (xy 387.669821 -298.723715)
			(xy 387.677951 -298.672385) (xy 387.69401 -298.622959) (xy 387.717603 -298.576653) (xy 387.74815 -298.534608)
			(xy 387.784897 -298.497859) (xy 387.826941 -298.467311) (xy 387.873246 -298.443716) (xy 387.922671 -298.427654)
			(xy 387.974001 -298.419523) (xy 387.999986 -298.419012) (xy 388.949946 -298.419012) (xy 388.975932 -298.419485)
			(xy 389.027264 -298.427622) (xy 389.076692 -298.443688) (xy 389.122998 -298.467288) (xy 389.165042 -298.49784)
			(xy 389.20179 -298.534593) (xy 389.232337 -298.576642) (xy 389.25593 -298.622951) (xy 389.271989 -298.67238)
			(xy 389.280119 -298.723714) (xy 389.280119 -298.775686) (xy 389.271989 -298.82702) (xy 389.25593 -298.876449)
			(xy 389.232337 -298.922758) (xy 389.20179 -298.964807) (xy 389.165042 -299.00156) (xy 389.122998 -299.032112)
			(xy 389.076692 -299.055712) (xy 389.027264 -299.071778) (xy 388.975932 -299.079915) (xy 388.949946 -299.080428)
			(xy 387.999986 -299.080428) (xy 387.974001 -299.079877) (xy 387.922671 -299.071746) (xy 387.873246 -299.055684)
			(xy 387.826941 -299.032089) (xy 387.784897 -299.001541) (xy 387.74815 -298.964792) (xy 387.717603 -298.922747)
			(xy 387.69401 -298.876441) (xy 387.677951 -298.827015) (xy 387.669821 -298.775685) (xy 40.980118 -298.775685)
			(xy 40.980118 -298.775688) (xy 40.971988 -298.827025) (xy 40.955926 -298.876458) (xy 40.932329 -298.92277)
			(xy 40.901778 -298.964821) (xy 40.865025 -299.001574) (xy 40.822975 -299.032126) (xy 40.776664 -299.055724)
			(xy 40.727231 -299.071786) (xy 40.675894 -299.079918) (xy 40.649906 -299.080428) (xy 39.699946 -299.080428)
			(xy 39.673956 -299.079908) (xy 39.622615 -299.071783) (xy 39.573177 -299.055726) (xy 39.52686 -299.032132)
			(xy 39.484805 -299.001583) (xy 39.448047 -298.96483) (xy 39.417492 -298.922779) (xy 39.393891 -298.876465)
			(xy 39.377827 -298.82703) (xy 39.369695 -298.77569) (xy 0.508 -298.77569) (xy 0.508 -299.25101) (xy 36.044102 -299.25101)
			(xy 36.044102 -299.19899) (xy 36.052239 -299.147611) (xy 36.068313 -299.098138) (xy 36.091929 -299.051788)
			(xy 36.122504 -299.009703) (xy 36.159286 -298.972918) (xy 36.201369 -298.94234) (xy 36.247718 -298.918722)
			(xy 36.29719 -298.902644) (xy 36.348568 -298.894504) (xy 36.374578 -298.893992) (xy 37.324538 -298.893992)
			(xy 37.35054 -298.894597) (xy 37.401902 -298.902737) (xy 37.451358 -298.918812) (xy 37.497691 -298.942425)
			(xy 37.539761 -298.972994) (xy 37.576531 -299.009768) (xy 37.607095 -299.051841) (xy 37.630703 -299.098177)
			(xy 37.646771 -299.147635) (xy 37.654906 -299.198998) (xy 37.654906 -299.251002) (xy 37.654905 -299.25101)
			(xy 152.144202 -299.25101) (xy 152.144202 -299.19899) (xy 152.152339 -299.147612) (xy 152.168413 -299.098138)
			(xy 152.192028 -299.051788) (xy 152.222603 -299.009703) (xy 152.259385 -298.972919) (xy 152.301468 -298.942341)
			(xy 152.347816 -298.918722) (xy 152.397288 -298.902645) (xy 152.448666 -298.894504) (xy 152.474676 -298.893992)
			(xy 153.424636 -298.893992) (xy 153.450638 -298.894597) (xy 153.502 -298.902737) (xy 153.551457 -298.918811)
			(xy 153.59779 -298.942424) (xy 153.63986 -298.972993) (xy 153.67663 -299.009767) (xy 153.707195 -299.05184)
			(xy 153.730803 -299.098177) (xy 153.746871 -299.147635) (xy 153.755006 -299.198998) (xy 153.755006 -299.251002)
			(xy 153.755005 -299.251009) (xy 154.994602 -299.251009) (xy 154.994602 -299.198991) (xy 155.002739 -299.147613)
			(xy 155.018812 -299.098141) (xy 155.042426 -299.051792) (xy 155.073 -299.009707) (xy 155.10978 -298.972923)
			(xy 155.151861 -298.942345) (xy 155.198208 -298.918726) (xy 155.247678 -298.902647) (xy 155.299055 -298.894505)
			(xy 155.325064 -298.893992) (xy 156.275024 -298.893992) (xy 156.301026 -298.894596) (xy 156.35239 -298.902735)
			(xy 156.401848 -298.918808) (xy 156.448184 -298.94242) (xy 156.490255 -298.972989) (xy 156.527026 -299.009763)
			(xy 156.557593 -299.051837) (xy 156.581201 -299.098174) (xy 156.597271 -299.147633) (xy 156.605406 -299.198998)
			(xy 156.605406 -299.251002) (xy 156.605404 -299.251014) (xy 268.243976 -299.251014) (xy 268.243976 -299.198986)
			(xy 268.252115 -299.147599) (xy 268.268193 -299.098118) (xy 268.291814 -299.051761) (xy 268.322396 -299.009671)
			(xy 268.359186 -298.972883) (xy 268.401279 -298.942303) (xy 268.447637 -298.918685) (xy 268.497119 -298.90261)
			(xy 268.548506 -298.894474) (xy 268.57452 -298.893992) (xy 269.52448 -298.893992) (xy 269.550487 -298.894566)
			(xy 269.60186 -298.9027) (xy 269.651328 -298.91877) (xy 269.697673 -298.942382) (xy 269.739754 -298.972953)
			(xy 269.776534 -299.009731) (xy 269.807108 -299.05181) (xy 269.830722 -299.098153) (xy 269.846796 -299.147621)
			(xy 269.854933 -299.198993) (xy 269.854933 -299.251007) (xy 269.854932 -299.251013) (xy 271.094376 -299.251013)
			(xy 271.094376 -299.198987) (xy 271.102514 -299.147601) (xy 271.118592 -299.098121) (xy 271.142212 -299.051765)
			(xy 271.172792 -299.009675) (xy 271.209581 -298.972887) (xy 271.251672 -298.942307) (xy 271.298028 -298.918689)
			(xy 271.347509 -298.902613) (xy 271.398895 -298.894475) (xy 271.424908 -298.893992) (xy 272.374868 -298.893992)
			(xy 272.400875 -298.894565) (xy 272.45225 -298.902697) (xy 272.50172 -298.918767) (xy 272.548067 -298.942378)
			(xy 272.590149 -298.972949) (xy 272.626931 -299.009727) (xy 272.657506 -299.051806) (xy 272.681121 -299.09815)
			(xy 272.697195 -299.147619) (xy 272.705333 -299.198993) (xy 272.705333 -299.251007) (xy 272.705332 -299.251014)
			(xy 384.344076 -299.251014) (xy 384.344076 -299.198986) (xy 384.352215 -299.147599) (xy 384.368293 -299.098118)
			(xy 384.391913 -299.051762) (xy 384.422495 -299.009672) (xy 384.459285 -298.972884) (xy 384.501377 -298.942304)
			(xy 384.547735 -298.918686) (xy 384.597217 -298.902611) (xy 384.648604 -298.894474) (xy 384.674618 -298.893992)
			(xy 385.624578 -298.893992) (xy 385.650585 -298.894566) (xy 385.701958 -298.902699) (xy 385.751427 -298.91877)
			(xy 385.797772 -298.942381) (xy 385.839853 -298.972952) (xy 385.876634 -299.00973) (xy 385.907207 -299.051809)
			(xy 385.930822 -299.098153) (xy 385.946896 -299.14762) (xy 385.955033 -299.198993) (xy 385.955033 -299.251007)
			(xy 385.946896 -299.30238) (xy 385.930822 -299.351847) (xy 385.907207 -299.398191) (xy 385.876634 -299.44027)
			(xy 385.839853 -299.477048) (xy 385.797772 -299.507619) (xy 385.751427 -299.53123) (xy 385.701958 -299.547301)
			(xy 385.650585 -299.555434) (xy 385.624578 -299.555916) (xy 384.674618 -299.555916) (xy 384.648604 -299.555526)
			(xy 384.597217 -299.547389) (xy 384.547735 -299.531314) (xy 384.501377 -299.507696) (xy 384.459285 -299.477116)
			(xy 384.422495 -299.440328) (xy 384.391913 -299.398238) (xy 384.368293 -299.351882) (xy 384.352215 -299.302401)
			(xy 384.344076 -299.251014) (xy 272.705332 -299.251014) (xy 272.697195 -299.302381) (xy 272.681121 -299.35185)
			(xy 272.657506 -299.398194) (xy 272.626931 -299.440273) (xy 272.590149 -299.477051) (xy 272.548067 -299.507622)
			(xy 272.50172 -299.531233) (xy 272.45225 -299.547303) (xy 272.400875 -299.555435) (xy 272.374868 -299.555916)
			(xy 271.424908 -299.555916) (xy 271.398895 -299.555525) (xy 271.347509 -299.547387) (xy 271.298028 -299.531311)
			(xy 271.251672 -299.507693) (xy 271.209581 -299.477113) (xy 271.172792 -299.440325) (xy 271.142212 -299.398235)
			(xy 271.118592 -299.351879) (xy 271.102514 -299.302399) (xy 271.094376 -299.251013) (xy 269.854932 -299.251013)
			(xy 269.846796 -299.302379) (xy 269.830722 -299.351847) (xy 269.807108 -299.39819) (xy 269.776534 -299.440269)
			(xy 269.739754 -299.477047) (xy 269.697673 -299.507618) (xy 269.651328 -299.53123) (xy 269.60186 -299.5473)
			(xy 269.550487 -299.555434) (xy 269.52448 -299.555916) (xy 268.57452 -299.555916) (xy 268.548506 -299.555526)
			(xy 268.497119 -299.54739) (xy 268.447637 -299.531315) (xy 268.401279 -299.507697) (xy 268.359186 -299.477117)
			(xy 268.322396 -299.440329) (xy 268.291814 -299.398239) (xy 268.268193 -299.351882) (xy 268.252115 -299.302401)
			(xy 268.243976 -299.251014) (xy 156.605404 -299.251014) (xy 156.597271 -299.302367) (xy 156.581201 -299.351826)
			(xy 156.557593 -299.398163) (xy 156.527026 -299.440237) (xy 156.490255 -299.477011) (xy 156.448184 -299.50758)
			(xy 156.401848 -299.531192) (xy 156.35239 -299.547265) (xy 156.301026 -299.555404) (xy 156.275024 -299.555916)
			(xy 155.325064 -299.555916) (xy 155.299055 -299.555495) (xy 155.247678 -299.547353) (xy 155.198208 -299.531274)
			(xy 155.151861 -299.507655) (xy 155.10978 -299.477077) (xy 155.073 -299.440293) (xy 155.042426 -299.398208)
			(xy 155.018812 -299.351859) (xy 155.002739 -299.302387) (xy 154.994602 -299.251009) (xy 153.755005 -299.251009)
			(xy 153.746871 -299.302365) (xy 153.730803 -299.351823) (xy 153.707195 -299.39816) (xy 153.67663 -299.440233)
			(xy 153.63986 -299.477007) (xy 153.59779 -299.507576) (xy 153.551457 -299.531189) (xy 153.502 -299.547263)
			(xy 153.450638 -299.555403) (xy 153.424636 -299.555916) (xy 152.474676 -299.555916) (xy 152.448666 -299.555496)
			(xy 152.397288 -299.547355) (xy 152.347816 -299.531278) (xy 152.301468 -299.507659) (xy 152.259385 -299.477081)
			(xy 152.222603 -299.440297) (xy 152.192028 -299.398212) (xy 152.168413 -299.351862) (xy 152.152339 -299.302388)
			(xy 152.144202 -299.25101) (xy 37.654905 -299.25101) (xy 37.646771 -299.302365) (xy 37.630703 -299.351823)
			(xy 37.607095 -299.398159) (xy 37.576531 -299.440232) (xy 37.539761 -299.477006) (xy 37.497691 -299.507575)
			(xy 37.451358 -299.531188) (xy 37.401902 -299.547263) (xy 37.35054 -299.555403) (xy 37.324538 -299.555916)
			(xy 36.374578 -299.555916) (xy 36.348568 -299.555496) (xy 36.29719 -299.547356) (xy 36.247718 -299.531278)
			(xy 36.201369 -299.50766) (xy 36.159286 -299.477082) (xy 36.122504 -299.440297) (xy 36.091929 -299.398212)
			(xy 36.068313 -299.351862) (xy 36.052239 -299.302389) (xy 36.044102 -299.25101) (xy 0.508 -299.25101)
			(xy 0.508 -301.599854) (xy 41.294062 -301.599854) (xy 41.298022 -301.5508) (xy 41.309799 -301.503016)
			(xy 41.32909 -301.45774) (xy 41.355393 -301.416144) (xy 41.388028 -301.379307) (xy 41.426149 -301.348182)
			(xy 41.46877 -301.323575) (xy 41.514786 -301.306123) (xy 41.563005 -301.296279) (xy 41.61218 -301.294298)
			(xy 41.661035 -301.30023) (xy 41.708306 -301.313922) (xy 41.752768 -301.33502) (xy 41.793271 -301.362976)
			(xy 41.828764 -301.397068) (xy 41.858329 -301.436412) (xy 41.8812 -301.479989) (xy 41.896784 -301.52667)
			(xy 41.904679 -301.575247) (xy 41.905174 -301.599854) (xy 42.244022 -301.599854) (xy 42.247982 -301.5508)
			(xy 42.259759 -301.503016) (xy 42.27905 -301.45774) (xy 42.305353 -301.416144) (xy 42.337988 -301.379307)
			(xy 42.376109 -301.348182) (xy 42.41873 -301.323575) (xy 42.464746 -301.306123) (xy 42.512965 -301.296279)
			(xy 42.56214 -301.294298) (xy 42.610995 -301.30023) (xy 42.658266 -301.313922) (xy 42.702728 -301.33502)
			(xy 42.743231 -301.362976) (xy 42.778724 -301.397068) (xy 42.808289 -301.436412) (xy 42.83116 -301.479989)
			(xy 42.846744 -301.52667) (xy 42.854639 -301.575247) (xy 42.855134 -301.599854) (xy 154.54428 -301.599854)
			(xy 154.54824 -301.5508) (xy 154.560017 -301.503016) (xy 154.579308 -301.45774) (xy 154.605611 -301.416144)
			(xy 154.638246 -301.379307) (xy 154.676367 -301.348182) (xy 154.718988 -301.323575) (xy 154.765004 -301.306123)
			(xy 154.813223 -301.296279) (xy 154.862398 -301.294298) (xy 154.911253 -301.30023) (xy 154.958524 -301.313922)
			(xy 155.002986 -301.33502) (xy 155.043489 -301.362976) (xy 155.078982 -301.397068) (xy 155.108547 -301.436412)
			(xy 155.131418 -301.479989) (xy 155.147002 -301.52667) (xy 155.154897 -301.575247) (xy 155.155392 -301.599854)
			(xy 155.49424 -301.599854) (xy 155.4982 -301.5508) (xy 155.509977 -301.503016) (xy 155.529268 -301.45774)
			(xy 155.555571 -301.416144) (xy 155.588206 -301.379307) (xy 155.626327 -301.348182) (xy 155.668948 -301.323575)
			(xy 155.714964 -301.306123) (xy 155.763183 -301.296279) (xy 155.812358 -301.294298) (xy 155.861213 -301.30023)
			(xy 155.908484 -301.313922) (xy 155.952946 -301.33502) (xy 155.993449 -301.362976) (xy 156.028942 -301.397068)
			(xy 156.058507 -301.436412) (xy 156.081378 -301.479989) (xy 156.096962 -301.52667) (xy 156.104857 -301.575247)
			(xy 156.105352 -301.599854) (xy 157.39416 -301.599854) (xy 157.39812 -301.5508) (xy 157.409897 -301.503016)
			(xy 157.429188 -301.45774) (xy 157.455491 -301.416144) (xy 157.488126 -301.379307) (xy 157.526247 -301.348182)
			(xy 157.568868 -301.323575) (xy 157.614884 -301.306123) (xy 157.663103 -301.296279) (xy 157.712278 -301.294298)
			(xy 157.761133 -301.30023) (xy 157.808404 -301.313922) (xy 157.852866 -301.33502) (xy 157.893369 -301.362976)
			(xy 157.928862 -301.397068) (xy 157.958427 -301.436412) (xy 157.981298 -301.479989) (xy 157.996882 -301.52667)
			(xy 158.004777 -301.575247) (xy 158.005272 -301.599854) (xy 158.34412 -301.599854) (xy 158.34808 -301.5508)
			(xy 158.359857 -301.503016) (xy 158.379148 -301.45774) (xy 158.405451 -301.416144) (xy 158.438086 -301.379307)
			(xy 158.476207 -301.348182) (xy 158.518828 -301.323575) (xy 158.564844 -301.306123) (xy 158.613063 -301.296279)
			(xy 158.662238 -301.294298) (xy 158.711093 -301.30023) (xy 158.758364 -301.313922) (xy 158.802826 -301.33502)
			(xy 158.843329 -301.362976) (xy 158.878822 -301.397068) (xy 158.908387 -301.436412) (xy 158.931258 -301.479989)
			(xy 158.946842 -301.52667) (xy 158.954737 -301.575247) (xy 158.955232 -301.599854) (xy 273.494004 -301.599854)
			(xy 273.497964 -301.5508) (xy 273.509741 -301.503016) (xy 273.529032 -301.45774) (xy 273.555335 -301.416144)
			(xy 273.58797 -301.379307) (xy 273.626091 -301.348182) (xy 273.668712 -301.323575) (xy 273.714728 -301.306123)
			(xy 273.762947 -301.296279) (xy 273.812122 -301.294298) (xy 273.860977 -301.30023) (xy 273.908248 -301.313922)
			(xy 273.95271 -301.33502) (xy 273.993213 -301.362976) (xy 274.028706 -301.397068) (xy 274.058271 -301.436412)
			(xy 274.081142 -301.479989) (xy 274.096726 -301.52667) (xy 274.104621 -301.575247) (xy 274.105116 -301.599854)
			(xy 274.443964 -301.599854) (xy 274.447924 -301.5508) (xy 274.459701 -301.503016) (xy 274.478992 -301.45774)
			(xy 274.505295 -301.416144) (xy 274.53793 -301.379307) (xy 274.576051 -301.348182) (xy 274.618672 -301.323575)
			(xy 274.664688 -301.306123) (xy 274.712907 -301.296279) (xy 274.762082 -301.294298) (xy 274.810937 -301.30023)
			(xy 274.858208 -301.313922) (xy 274.90267 -301.33502) (xy 274.943173 -301.362976) (xy 274.978666 -301.397068)
			(xy 275.008231 -301.436412) (xy 275.031102 -301.479989) (xy 275.046686 -301.52667) (xy 275.054581 -301.575247)
			(xy 275.055076 -301.599854) (xy 386.744222 -301.599854) (xy 386.748182 -301.5508) (xy 386.759959 -301.503016)
			(xy 386.77925 -301.45774) (xy 386.805553 -301.416144) (xy 386.838188 -301.379307) (xy 386.876309 -301.348182)
			(xy 386.91893 -301.323575) (xy 386.964946 -301.306123) (xy 387.013165 -301.296279) (xy 387.06234 -301.294298)
			(xy 387.111195 -301.30023) (xy 387.158466 -301.313922) (xy 387.202928 -301.33502) (xy 387.243431 -301.362976)
			(xy 387.278924 -301.397068) (xy 387.308489 -301.436412) (xy 387.33136 -301.479989) (xy 387.346944 -301.52667)
			(xy 387.354839 -301.575247) (xy 387.355334 -301.599854) (xy 387.694182 -301.599854) (xy 387.698142 -301.5508)
			(xy 387.709919 -301.503016) (xy 387.72921 -301.45774) (xy 387.755513 -301.416144) (xy 387.788148 -301.379307)
			(xy 387.826269 -301.348182) (xy 387.86889 -301.323575) (xy 387.914906 -301.306123) (xy 387.963125 -301.296279)
			(xy 388.0123 -301.294298) (xy 388.061155 -301.30023) (xy 388.108426 -301.313922) (xy 388.152888 -301.33502)
			(xy 388.193391 -301.362976) (xy 388.228884 -301.397068) (xy 388.258449 -301.436412) (xy 388.28132 -301.479989)
			(xy 388.296904 -301.52667) (xy 388.304799 -301.575247) (xy 388.305294 -301.599854) (xy 389.594102 -301.599854)
			(xy 389.598062 -301.5508) (xy 389.609839 -301.503016) (xy 389.62913 -301.45774) (xy 389.655433 -301.416144)
			(xy 389.688068 -301.379307) (xy 389.726189 -301.348182) (xy 389.76881 -301.323575) (xy 389.814826 -301.306123)
			(xy 389.863045 -301.296279) (xy 389.91222 -301.294298) (xy 389.961075 -301.30023) (xy 390.008346 -301.313922)
			(xy 390.052808 -301.33502) (xy 390.093311 -301.362976) (xy 390.128804 -301.397068) (xy 390.158369 -301.436412)
			(xy 390.18124 -301.479989) (xy 390.196824 -301.52667) (xy 390.204719 -301.575247) (xy 390.205214 -301.599854)
			(xy 390.544062 -301.599854) (xy 390.548022 -301.5508) (xy 390.559799 -301.503016) (xy 390.57909 -301.45774)
			(xy 390.605393 -301.416144) (xy 390.638028 -301.379307) (xy 390.676149 -301.348182) (xy 390.71877 -301.323575)
			(xy 390.764786 -301.306123) (xy 390.813005 -301.296279) (xy 390.86218 -301.294298) (xy 390.911035 -301.30023)
			(xy 390.958306 -301.313922) (xy 391.002768 -301.33502) (xy 391.043271 -301.362976) (xy 391.078764 -301.397068)
			(xy 391.108329 -301.436412) (xy 391.1312 -301.479989) (xy 391.146784 -301.52667) (xy 391.154679 -301.575247)
			(xy 391.155174 -301.599854) (xy 391.154679 -301.624461) (xy 391.146784 -301.673038) (xy 391.1312 -301.719719)
			(xy 391.108329 -301.763296) (xy 391.078764 -301.80264) (xy 391.043271 -301.836732) (xy 391.002768 -301.864688)
			(xy 390.958306 -301.885786) (xy 390.911035 -301.899478) (xy 390.86218 -301.90541) (xy 390.813005 -301.903429)
			(xy 390.764786 -301.893585) (xy 390.71877 -301.876133) (xy 390.676149 -301.851526) (xy 390.638028 -301.820401)
			(xy 390.605393 -301.783564) (xy 390.57909 -301.741968) (xy 390.559799 -301.696692) (xy 390.548022 -301.648908)
			(xy 390.544062 -301.599854) (xy 390.205214 -301.599854) (xy 390.204719 -301.624461) (xy 390.196824 -301.673038)
			(xy 390.18124 -301.719719) (xy 390.158369 -301.763296) (xy 390.128804 -301.80264) (xy 390.093311 -301.836732)
			(xy 390.052808 -301.864688) (xy 390.008346 -301.885786) (xy 389.961075 -301.899478) (xy 389.91222 -301.90541)
			(xy 389.863045 -301.903429) (xy 389.814826 -301.893585) (xy 389.76881 -301.876133) (xy 389.726189 -301.851526)
			(xy 389.688068 -301.820401) (xy 389.655433 -301.783564) (xy 389.62913 -301.741968) (xy 389.609839 -301.696692)
			(xy 389.598062 -301.648908) (xy 389.594102 -301.599854) (xy 388.305294 -301.599854) (xy 388.304799 -301.624461)
			(xy 388.296904 -301.673038) (xy 388.28132 -301.719719) (xy 388.258449 -301.763296) (xy 388.228884 -301.80264)
			(xy 388.193391 -301.836732) (xy 388.152888 -301.864688) (xy 388.108426 -301.885786) (xy 388.061155 -301.899478)
			(xy 388.0123 -301.90541) (xy 387.963125 -301.903429) (xy 387.914906 -301.893585) (xy 387.86889 -301.876133)
			(xy 387.826269 -301.851526) (xy 387.788148 -301.820401) (xy 387.755513 -301.783564) (xy 387.72921 -301.741968)
			(xy 387.709919 -301.696692) (xy 387.698142 -301.648908) (xy 387.694182 -301.599854) (xy 387.355334 -301.599854)
			(xy 387.354839 -301.624461) (xy 387.346944 -301.673038) (xy 387.33136 -301.719719) (xy 387.308489 -301.763296)
			(xy 387.278924 -301.80264) (xy 387.243431 -301.836732) (xy 387.202928 -301.864688) (xy 387.158466 -301.885786)
			(xy 387.111195 -301.899478) (xy 387.06234 -301.90541) (xy 387.013165 -301.903429) (xy 386.964946 -301.893585)
			(xy 386.91893 -301.876133) (xy 386.876309 -301.851526) (xy 386.838188 -301.820401) (xy 386.805553 -301.783564)
			(xy 386.77925 -301.741968) (xy 386.759959 -301.696692) (xy 386.748182 -301.648908) (xy 386.744222 -301.599854)
			(xy 275.055076 -301.599854) (xy 275.054581 -301.624461) (xy 275.046686 -301.673038) (xy 275.031102 -301.719719)
			(xy 275.008231 -301.763296) (xy 274.978666 -301.80264) (xy 274.943173 -301.836732) (xy 274.90267 -301.864688)
			(xy 274.858208 -301.885786) (xy 274.810937 -301.899478) (xy 274.762082 -301.90541) (xy 274.712907 -301.903429)
			(xy 274.664688 -301.893585) (xy 274.618672 -301.876133) (xy 274.576051 -301.851526) (xy 274.53793 -301.820401)
			(xy 274.505295 -301.783564) (xy 274.478992 -301.741968) (xy 274.459701 -301.696692) (xy 274.447924 -301.648908)
			(xy 274.443964 -301.599854) (xy 274.105116 -301.599854) (xy 274.104621 -301.624461) (xy 274.096726 -301.673038)
			(xy 274.081142 -301.719719) (xy 274.058271 -301.763296) (xy 274.028706 -301.80264) (xy 273.993213 -301.836732)
			(xy 273.95271 -301.864688) (xy 273.908248 -301.885786) (xy 273.860977 -301.899478) (xy 273.812122 -301.90541)
			(xy 273.762947 -301.903429) (xy 273.714728 -301.893585) (xy 273.668712 -301.876133) (xy 273.626091 -301.851526)
			(xy 273.58797 -301.820401) (xy 273.555335 -301.783564) (xy 273.529032 -301.741968) (xy 273.509741 -301.696692)
			(xy 273.497964 -301.648908) (xy 273.494004 -301.599854) (xy 158.955232 -301.599854) (xy 158.954737 -301.624461)
			(xy 158.946842 -301.673038) (xy 158.931258 -301.719719) (xy 158.908387 -301.763296) (xy 158.878822 -301.80264)
			(xy 158.843329 -301.836732) (xy 158.802826 -301.864688) (xy 158.758364 -301.885786) (xy 158.711093 -301.899478)
			(xy 158.662238 -301.90541) (xy 158.613063 -301.903429) (xy 158.564844 -301.893585) (xy 158.518828 -301.876133)
			(xy 158.476207 -301.851526) (xy 158.438086 -301.820401) (xy 158.405451 -301.783564) (xy 158.379148 -301.741968)
			(xy 158.359857 -301.696692) (xy 158.34808 -301.648908) (xy 158.34412 -301.599854) (xy 158.005272 -301.599854)
			(xy 158.004777 -301.624461) (xy 157.996882 -301.673038) (xy 157.981298 -301.719719) (xy 157.958427 -301.763296)
			(xy 157.928862 -301.80264) (xy 157.893369 -301.836732) (xy 157.852866 -301.864688) (xy 157.808404 -301.885786)
			(xy 157.761133 -301.899478) (xy 157.712278 -301.90541) (xy 157.663103 -301.903429) (xy 157.614884 -301.893585)
			(xy 157.568868 -301.876133) (xy 157.526247 -301.851526) (xy 157.488126 -301.820401) (xy 157.455491 -301.783564)
			(xy 157.429188 -301.741968) (xy 157.409897 -301.696692) (xy 157.39812 -301.648908) (xy 157.39416 -301.599854)
			(xy 156.105352 -301.599854) (xy 156.104857 -301.624461) (xy 156.096962 -301.673038) (xy 156.081378 -301.719719)
			(xy 156.058507 -301.763296) (xy 156.028942 -301.80264) (xy 155.993449 -301.836732) (xy 155.952946 -301.864688)
			(xy 155.908484 -301.885786) (xy 155.861213 -301.899478) (xy 155.812358 -301.90541) (xy 155.763183 -301.903429)
			(xy 155.714964 -301.893585) (xy 155.668948 -301.876133) (xy 155.626327 -301.851526) (xy 155.588206 -301.820401)
			(xy 155.555571 -301.783564) (xy 155.529268 -301.741968) (xy 155.509977 -301.696692) (xy 155.4982 -301.648908)
			(xy 155.49424 -301.599854) (xy 155.155392 -301.599854) (xy 155.154897 -301.624461) (xy 155.147002 -301.673038)
			(xy 155.131418 -301.719719) (xy 155.108547 -301.763296) (xy 155.078982 -301.80264) (xy 155.043489 -301.836732)
			(xy 155.002986 -301.864688) (xy 154.958524 -301.885786) (xy 154.911253 -301.899478) (xy 154.862398 -301.90541)
			(xy 154.813223 -301.903429) (xy 154.765004 -301.893585) (xy 154.718988 -301.876133) (xy 154.676367 -301.851526)
			(xy 154.638246 -301.820401) (xy 154.605611 -301.783564) (xy 154.579308 -301.741968) (xy 154.560017 -301.696692)
			(xy 154.54824 -301.648908) (xy 154.54428 -301.599854) (xy 42.855134 -301.599854) (xy 42.854639 -301.624461)
			(xy 42.846744 -301.673038) (xy 42.83116 -301.719719) (xy 42.808289 -301.763296) (xy 42.778724 -301.80264)
			(xy 42.743231 -301.836732) (xy 42.702728 -301.864688) (xy 42.658266 -301.885786) (xy 42.610995 -301.899478)
			(xy 42.56214 -301.90541) (xy 42.512965 -301.903429) (xy 42.464746 -301.893585) (xy 42.41873 -301.876133)
			(xy 42.376109 -301.851526) (xy 42.337988 -301.820401) (xy 42.305353 -301.783564) (xy 42.27905 -301.741968)
			(xy 42.259759 -301.696692) (xy 42.247982 -301.648908) (xy 42.244022 -301.599854) (xy 41.905174 -301.599854)
			(xy 41.904679 -301.624461) (xy 41.896784 -301.673038) (xy 41.8812 -301.719719) (xy 41.858329 -301.763296)
			(xy 41.828764 -301.80264) (xy 41.793271 -301.836732) (xy 41.752768 -301.864688) (xy 41.708306 -301.885786)
			(xy 41.661035 -301.899478) (xy 41.61218 -301.90541) (xy 41.563005 -301.903429) (xy 41.514786 -301.893585)
			(xy 41.46877 -301.876133) (xy 41.426149 -301.851526) (xy 41.388028 -301.820401) (xy 41.355393 -301.783564)
			(xy 41.32909 -301.741968) (xy 41.309799 -301.696692) (xy 41.298022 -301.648908) (xy 41.294062 -301.599854)
			(xy 0.508 -301.599854) (xy 0.508 -302.549814) (xy 43.193982 -302.549814) (xy 43.197942 -302.50076)
			(xy 43.209719 -302.452976) (xy 43.22901 -302.4077) (xy 43.255313 -302.366104) (xy 43.287948 -302.329267)
			(xy 43.326069 -302.298142) (xy 43.36869 -302.273535) (xy 43.414706 -302.256083) (xy 43.462925 -302.246239)
			(xy 43.5121 -302.244258) (xy 43.560955 -302.25019) (xy 43.608226 -302.263882) (xy 43.652688 -302.28498)
			(xy 43.693191 -302.312936) (xy 43.728684 -302.347028) (xy 43.758249 -302.386372) (xy 43.78112 -302.429949)
			(xy 43.796704 -302.47663) (xy 43.804599 -302.525207) (xy 43.805094 -302.549814) (xy 44.143942 -302.549814)
			(xy 44.147902 -302.50076) (xy 44.159679 -302.452976) (xy 44.17897 -302.4077) (xy 44.205273 -302.366104)
			(xy 44.237908 -302.329267) (xy 44.276029 -302.298142) (xy 44.31865 -302.273535) (xy 44.364666 -302.256083)
			(xy 44.412885 -302.246239) (xy 44.46206 -302.244258) (xy 44.510915 -302.25019) (xy 44.558186 -302.263882)
			(xy 44.602648 -302.28498) (xy 44.643151 -302.312936) (xy 44.678644 -302.347028) (xy 44.708209 -302.386372)
			(xy 44.73108 -302.429949) (xy 44.746664 -302.47663) (xy 44.754559 -302.525207) (xy 44.755054 -302.549814)
			(xy 152.644106 -302.549814) (xy 152.648066 -302.50076) (xy 152.659843 -302.452976) (xy 152.679134 -302.4077)
			(xy 152.705437 -302.366104) (xy 152.738072 -302.329267) (xy 152.776193 -302.298142) (xy 152.818814 -302.273535)
			(xy 152.86483 -302.256083) (xy 152.913049 -302.246239) (xy 152.962224 -302.244258) (xy 153.011079 -302.25019)
			(xy 153.05835 -302.263882) (xy 153.102812 -302.28498) (xy 153.143315 -302.312936) (xy 153.178808 -302.347028)
			(xy 153.208373 -302.386372) (xy 153.231244 -302.429949) (xy 153.246828 -302.47663) (xy 153.254723 -302.525207)
			(xy 153.255218 -302.549814) (xy 153.594066 -302.549814) (xy 153.598026 -302.50076) (xy 153.609803 -302.452976)
			(xy 153.629094 -302.4077) (xy 153.655397 -302.366104) (xy 153.688032 -302.329267) (xy 153.726153 -302.298142)
			(xy 153.768774 -302.273535) (xy 153.81479 -302.256083) (xy 153.863009 -302.246239) (xy 153.912184 -302.244258)
			(xy 153.961039 -302.25019) (xy 154.00831 -302.263882) (xy 154.052772 -302.28498) (xy 154.093275 -302.312936)
			(xy 154.128768 -302.347028) (xy 154.158333 -302.386372) (xy 154.181204 -302.429949) (xy 154.196788 -302.47663)
			(xy 154.204683 -302.525207) (xy 154.205178 -302.549814) (xy 159.29408 -302.549814) (xy 159.29804 -302.50076)
			(xy 159.309817 -302.452976) (xy 159.329108 -302.4077) (xy 159.355411 -302.366104) (xy 159.388046 -302.329267)
			(xy 159.426167 -302.298142) (xy 159.468788 -302.273535) (xy 159.514804 -302.256083) (xy 159.563023 -302.246239)
			(xy 159.612198 -302.244258) (xy 159.661053 -302.25019) (xy 159.708324 -302.263882) (xy 159.752786 -302.28498)
			(xy 159.793289 -302.312936) (xy 159.828782 -302.347028) (xy 159.858347 -302.386372) (xy 159.881218 -302.429949)
			(xy 159.896802 -302.47663) (xy 159.904697 -302.525207) (xy 159.905192 -302.549814) (xy 160.24404 -302.549814)
			(xy 160.248 -302.50076) (xy 160.259777 -302.452976) (xy 160.279068 -302.4077) (xy 160.305371 -302.366104)
			(xy 160.338006 -302.329267) (xy 160.376127 -302.298142) (xy 160.418748 -302.273535) (xy 160.464764 -302.256083)
			(xy 160.512983 -302.246239) (xy 160.562158 -302.244258) (xy 160.611013 -302.25019) (xy 160.658284 -302.263882)
			(xy 160.702746 -302.28498) (xy 160.743249 -302.312936) (xy 160.778742 -302.347028) (xy 160.808307 -302.386372)
			(xy 160.831178 -302.429949) (xy 160.846762 -302.47663) (xy 160.854657 -302.525207) (xy 160.855152 -302.549814)
			(xy 275.393924 -302.549814) (xy 275.397884 -302.50076) (xy 275.409661 -302.452976) (xy 275.428952 -302.4077)
			(xy 275.455255 -302.366104) (xy 275.48789 -302.329267) (xy 275.526011 -302.298142) (xy 275.568632 -302.273535)
			(xy 275.614648 -302.256083) (xy 275.662867 -302.246239) (xy 275.712042 -302.244258) (xy 275.760897 -302.25019)
			(xy 275.808168 -302.263882) (xy 275.85263 -302.28498) (xy 275.893133 -302.312936) (xy 275.928626 -302.347028)
			(xy 275.958191 -302.386372) (xy 275.981062 -302.429949) (xy 275.996646 -302.47663) (xy 276.004541 -302.525207)
			(xy 276.005036 -302.549814) (xy 276.343884 -302.549814) (xy 276.347844 -302.50076) (xy 276.359621 -302.452976)
			(xy 276.378912 -302.4077) (xy 276.405215 -302.366104) (xy 276.43785 -302.329267) (xy 276.475971 -302.298142)
			(xy 276.518592 -302.273535) (xy 276.564608 -302.256083) (xy 276.612827 -302.246239) (xy 276.662002 -302.244258)
			(xy 276.710857 -302.25019) (xy 276.758128 -302.263882) (xy 276.80259 -302.28498) (xy 276.843093 -302.312936)
			(xy 276.878586 -302.347028) (xy 276.908151 -302.386372) (xy 276.931022 -302.429949) (xy 276.946606 -302.47663)
			(xy 276.954501 -302.525207) (xy 276.954996 -302.549814) (xy 384.844048 -302.549814) (xy 384.848008 -302.50076)
			(xy 384.859785 -302.452976) (xy 384.879076 -302.4077) (xy 384.905379 -302.366104) (xy 384.938014 -302.329267)
			(xy 384.976135 -302.298142) (xy 385.018756 -302.273535) (xy 385.064772 -302.256083) (xy 385.112991 -302.246239)
			(xy 385.162166 -302.244258) (xy 385.211021 -302.25019) (xy 385.258292 -302.263882) (xy 385.302754 -302.28498)
			(xy 385.343257 -302.312936) (xy 385.37875 -302.347028) (xy 385.408315 -302.386372) (xy 385.431186 -302.429949)
			(xy 385.44677 -302.47663) (xy 385.454665 -302.525207) (xy 385.45516 -302.549814) (xy 385.794008 -302.549814)
			(xy 385.797968 -302.50076) (xy 385.809745 -302.452976) (xy 385.829036 -302.4077) (xy 385.855339 -302.366104)
			(xy 385.887974 -302.329267) (xy 385.926095 -302.298142) (xy 385.968716 -302.273535) (xy 386.014732 -302.256083)
			(xy 386.062951 -302.246239) (xy 386.112126 -302.244258) (xy 386.160981 -302.25019) (xy 386.208252 -302.263882)
			(xy 386.252714 -302.28498) (xy 386.293217 -302.312936) (xy 386.32871 -302.347028) (xy 386.358275 -302.386372)
			(xy 386.381146 -302.429949) (xy 386.39673 -302.47663) (xy 386.404625 -302.525207) (xy 386.40512 -302.549814)
			(xy 391.494022 -302.549814) (xy 391.497982 -302.50076) (xy 391.509759 -302.452976) (xy 391.52905 -302.4077)
			(xy 391.555353 -302.366104) (xy 391.587988 -302.329267) (xy 391.626109 -302.298142) (xy 391.66873 -302.273535)
			(xy 391.714746 -302.256083) (xy 391.762965 -302.246239) (xy 391.81214 -302.244258) (xy 391.860995 -302.25019)
			(xy 391.908266 -302.263882) (xy 391.952728 -302.28498) (xy 391.993231 -302.312936) (xy 392.028724 -302.347028)
			(xy 392.058289 -302.386372) (xy 392.08116 -302.429949) (xy 392.096744 -302.47663) (xy 392.104639 -302.525207)
			(xy 392.105134 -302.549814) (xy 392.443982 -302.549814) (xy 392.447942 -302.50076) (xy 392.459719 -302.452976)
			(xy 392.47901 -302.4077) (xy 392.505313 -302.366104) (xy 392.537948 -302.329267) (xy 392.576069 -302.298142)
			(xy 392.61869 -302.273535) (xy 392.664706 -302.256083) (xy 392.712925 -302.246239) (xy 392.7621 -302.244258)
			(xy 392.810955 -302.25019) (xy 392.858226 -302.263882) (xy 392.902688 -302.28498) (xy 392.943191 -302.312936)
			(xy 392.978684 -302.347028) (xy 393.008249 -302.386372) (xy 393.03112 -302.429949) (xy 393.046704 -302.47663)
			(xy 393.054599 -302.525207) (xy 393.055094 -302.549814) (xy 393.054599 -302.574421) (xy 393.046704 -302.622998)
			(xy 393.03112 -302.669679) (xy 393.008249 -302.713256) (xy 392.978684 -302.7526) (xy 392.943191 -302.786692)
			(xy 392.902688 -302.814648) (xy 392.858226 -302.835746) (xy 392.810955 -302.849438) (xy 392.7621 -302.85537)
			(xy 392.712925 -302.853389) (xy 392.664706 -302.843545) (xy 392.61869 -302.826093) (xy 392.576069 -302.801486)
			(xy 392.537948 -302.770361) (xy 392.505313 -302.733524) (xy 392.47901 -302.691928) (xy 392.459719 -302.646652)
			(xy 392.447942 -302.598868) (xy 392.443982 -302.549814) (xy 392.105134 -302.549814) (xy 392.104639 -302.574421)
			(xy 392.096744 -302.622998) (xy 392.08116 -302.669679) (xy 392.058289 -302.713256) (xy 392.028724 -302.7526)
			(xy 391.993231 -302.786692) (xy 391.952728 -302.814648) (xy 391.908266 -302.835746) (xy 391.860995 -302.849438)
			(xy 391.81214 -302.85537) (xy 391.762965 -302.853389) (xy 391.714746 -302.843545) (xy 391.66873 -302.826093)
			(xy 391.626109 -302.801486) (xy 391.587988 -302.770361) (xy 391.555353 -302.733524) (xy 391.52905 -302.691928)
			(xy 391.509759 -302.646652) (xy 391.497982 -302.598868) (xy 391.494022 -302.549814) (xy 386.40512 -302.549814)
			(xy 386.404625 -302.574421) (xy 386.39673 -302.622998) (xy 386.381146 -302.669679) (xy 386.358275 -302.713256)
			(xy 386.32871 -302.7526) (xy 386.293217 -302.786692) (xy 386.252714 -302.814648) (xy 386.208252 -302.835746)
			(xy 386.160981 -302.849438) (xy 386.112126 -302.85537) (xy 386.062951 -302.853389) (xy 386.014732 -302.843545)
			(xy 385.968716 -302.826093) (xy 385.926095 -302.801486) (xy 385.887974 -302.770361) (xy 385.855339 -302.733524)
			(xy 385.829036 -302.691928) (xy 385.809745 -302.646652) (xy 385.797968 -302.598868) (xy 385.794008 -302.549814)
			(xy 385.45516 -302.549814) (xy 385.454665 -302.574421) (xy 385.44677 -302.622998) (xy 385.431186 -302.669679)
			(xy 385.408315 -302.713256) (xy 385.37875 -302.7526) (xy 385.343257 -302.786692) (xy 385.302754 -302.814648)
			(xy 385.258292 -302.835746) (xy 385.211021 -302.849438) (xy 385.162166 -302.85537) (xy 385.112991 -302.853389)
			(xy 385.064772 -302.843545) (xy 385.018756 -302.826093) (xy 384.976135 -302.801486) (xy 384.938014 -302.770361)
			(xy 384.905379 -302.733524) (xy 384.879076 -302.691928) (xy 384.859785 -302.646652) (xy 384.848008 -302.598868)
			(xy 384.844048 -302.549814) (xy 276.954996 -302.549814) (xy 276.954501 -302.574421) (xy 276.946606 -302.622998)
			(xy 276.931022 -302.669679) (xy 276.908151 -302.713256) (xy 276.878586 -302.7526) (xy 276.843093 -302.786692)
			(xy 276.80259 -302.814648) (xy 276.758128 -302.835746) (xy 276.710857 -302.849438) (xy 276.662002 -302.85537)
			(xy 276.612827 -302.853389) (xy 276.564608 -302.843545) (xy 276.518592 -302.826093) (xy 276.475971 -302.801486)
			(xy 276.43785 -302.770361) (xy 276.405215 -302.733524) (xy 276.378912 -302.691928) (xy 276.359621 -302.646652)
			(xy 276.347844 -302.598868) (xy 276.343884 -302.549814) (xy 276.005036 -302.549814) (xy 276.004541 -302.574421)
			(xy 275.996646 -302.622998) (xy 275.981062 -302.669679) (xy 275.958191 -302.713256) (xy 275.928626 -302.7526)
			(xy 275.893133 -302.786692) (xy 275.85263 -302.814648) (xy 275.808168 -302.835746) (xy 275.760897 -302.849438)
			(xy 275.712042 -302.85537) (xy 275.662867 -302.853389) (xy 275.614648 -302.843545) (xy 275.568632 -302.826093)
			(xy 275.526011 -302.801486) (xy 275.48789 -302.770361) (xy 275.455255 -302.733524) (xy 275.428952 -302.691928)
			(xy 275.409661 -302.646652) (xy 275.397884 -302.598868) (xy 275.393924 -302.549814) (xy 160.855152 -302.549814)
			(xy 160.854657 -302.574421) (xy 160.846762 -302.622998) (xy 160.831178 -302.669679) (xy 160.808307 -302.713256)
			(xy 160.778742 -302.7526) (xy 160.743249 -302.786692) (xy 160.702746 -302.814648) (xy 160.658284 -302.835746)
			(xy 160.611013 -302.849438) (xy 160.562158 -302.85537) (xy 160.512983 -302.853389) (xy 160.464764 -302.843545)
			(xy 160.418748 -302.826093) (xy 160.376127 -302.801486) (xy 160.338006 -302.770361) (xy 160.305371 -302.733524)
			(xy 160.279068 -302.691928) (xy 160.259777 -302.646652) (xy 160.248 -302.598868) (xy 160.24404 -302.549814)
			(xy 159.905192 -302.549814) (xy 159.904697 -302.574421) (xy 159.896802 -302.622998) (xy 159.881218 -302.669679)
			(xy 159.858347 -302.713256) (xy 159.828782 -302.7526) (xy 159.793289 -302.786692) (xy 159.752786 -302.814648)
			(xy 159.708324 -302.835746) (xy 159.661053 -302.849438) (xy 159.612198 -302.85537) (xy 159.563023 -302.853389)
			(xy 159.514804 -302.843545) (xy 159.468788 -302.826093) (xy 159.426167 -302.801486) (xy 159.388046 -302.770361)
			(xy 159.355411 -302.733524) (xy 159.329108 -302.691928) (xy 159.309817 -302.646652) (xy 159.29804 -302.598868)
			(xy 159.29408 -302.549814) (xy 154.205178 -302.549814) (xy 154.204683 -302.574421) (xy 154.196788 -302.622998)
			(xy 154.181204 -302.669679) (xy 154.158333 -302.713256) (xy 154.128768 -302.7526) (xy 154.093275 -302.786692)
			(xy 154.052772 -302.814648) (xy 154.00831 -302.835746) (xy 153.961039 -302.849438) (xy 153.912184 -302.85537)
			(xy 153.863009 -302.853389) (xy 153.81479 -302.843545) (xy 153.768774 -302.826093) (xy 153.726153 -302.801486)
			(xy 153.688032 -302.770361) (xy 153.655397 -302.733524) (xy 153.629094 -302.691928) (xy 153.609803 -302.646652)
			(xy 153.598026 -302.598868) (xy 153.594066 -302.549814) (xy 153.255218 -302.549814) (xy 153.254723 -302.574421)
			(xy 153.246828 -302.622998) (xy 153.231244 -302.669679) (xy 153.208373 -302.713256) (xy 153.178808 -302.7526)
			(xy 153.143315 -302.786692) (xy 153.102812 -302.814648) (xy 153.05835 -302.835746) (xy 153.011079 -302.849438)
			(xy 152.962224 -302.85537) (xy 152.913049 -302.853389) (xy 152.86483 -302.843545) (xy 152.818814 -302.826093)
			(xy 152.776193 -302.801486) (xy 152.738072 -302.770361) (xy 152.705437 -302.733524) (xy 152.679134 -302.691928)
			(xy 152.659843 -302.646652) (xy 152.648066 -302.598868) (xy 152.644106 -302.549814) (xy 44.755054 -302.549814)
			(xy 44.754559 -302.574421) (xy 44.746664 -302.622998) (xy 44.73108 -302.669679) (xy 44.708209 -302.713256)
			(xy 44.678644 -302.7526) (xy 44.643151 -302.786692) (xy 44.602648 -302.814648) (xy 44.558186 -302.835746)
			(xy 44.510915 -302.849438) (xy 44.46206 -302.85537) (xy 44.412885 -302.853389) (xy 44.364666 -302.843545)
			(xy 44.31865 -302.826093) (xy 44.276029 -302.801486) (xy 44.237908 -302.770361) (xy 44.205273 -302.733524)
			(xy 44.17897 -302.691928) (xy 44.159679 -302.646652) (xy 44.147902 -302.598868) (xy 44.143942 -302.549814)
			(xy 43.805094 -302.549814) (xy 43.804599 -302.574421) (xy 43.796704 -302.622998) (xy 43.78112 -302.669679)
			(xy 43.758249 -302.713256) (xy 43.728684 -302.7526) (xy 43.693191 -302.786692) (xy 43.652688 -302.814648)
			(xy 43.608226 -302.835746) (xy 43.560955 -302.849438) (xy 43.5121 -302.85537) (xy 43.462925 -302.853389)
			(xy 43.414706 -302.843545) (xy 43.36869 -302.826093) (xy 43.326069 -302.801486) (xy 43.287948 -302.770361)
			(xy 43.255313 -302.733524) (xy 43.22901 -302.691928) (xy 43.209719 -302.646652) (xy 43.197942 -302.598868)
			(xy 43.193982 -302.549814) (xy 0.508 -302.549814) (xy 0.508 -303.499774) (xy 41.294062 -303.499774)
			(xy 41.298022 -303.45072) (xy 41.309799 -303.402936) (xy 41.32909 -303.35766) (xy 41.355393 -303.316064)
			(xy 41.388028 -303.279227) (xy 41.426149 -303.248102) (xy 41.46877 -303.223495) (xy 41.514786 -303.206043)
			(xy 41.563005 -303.196199) (xy 41.61218 -303.194218) (xy 41.661035 -303.20015) (xy 41.708306 -303.213842)
			(xy 41.752768 -303.23494) (xy 41.793271 -303.262896) (xy 41.828764 -303.296988) (xy 41.858329 -303.336332)
			(xy 41.8812 -303.379909) (xy 41.896784 -303.42659) (xy 41.904679 -303.475167) (xy 41.905174 -303.499774)
			(xy 42.244022 -303.499774) (xy 42.247982 -303.45072) (xy 42.259759 -303.402936) (xy 42.27905 -303.35766)
			(xy 42.305353 -303.316064) (xy 42.337988 -303.279227) (xy 42.376109 -303.248102) (xy 42.41873 -303.223495)
			(xy 42.464746 -303.206043) (xy 42.512965 -303.196199) (xy 42.56214 -303.194218) (xy 42.610995 -303.20015)
			(xy 42.658266 -303.213842) (xy 42.702728 -303.23494) (xy 42.743231 -303.262896) (xy 42.778724 -303.296988)
			(xy 42.808289 -303.336332) (xy 42.83116 -303.379909) (xy 42.846744 -303.42659) (xy 42.854639 -303.475167)
			(xy 42.855134 -303.499774) (xy 154.54428 -303.499774) (xy 154.54824 -303.45072) (xy 154.560017 -303.402936)
			(xy 154.579308 -303.35766) (xy 154.605611 -303.316064) (xy 154.638246 -303.279227) (xy 154.676367 -303.248102)
			(xy 154.718988 -303.223495) (xy 154.765004 -303.206043) (xy 154.813223 -303.196199) (xy 154.862398 -303.194218)
			(xy 154.911253 -303.20015) (xy 154.958524 -303.213842) (xy 155.002986 -303.23494) (xy 155.043489 -303.262896)
			(xy 155.078982 -303.296988) (xy 155.108547 -303.336332) (xy 155.131418 -303.379909) (xy 155.147002 -303.42659)
			(xy 155.154897 -303.475167) (xy 155.155392 -303.499774) (xy 155.49424 -303.499774) (xy 155.4982 -303.45072)
			(xy 155.509977 -303.402936) (xy 155.529268 -303.35766) (xy 155.555571 -303.316064) (xy 155.588206 -303.279227)
			(xy 155.626327 -303.248102) (xy 155.668948 -303.223495) (xy 155.714964 -303.206043) (xy 155.763183 -303.196199)
			(xy 155.812358 -303.194218) (xy 155.861213 -303.20015) (xy 155.908484 -303.213842) (xy 155.952946 -303.23494)
			(xy 155.993449 -303.262896) (xy 156.028942 -303.296988) (xy 156.058507 -303.336332) (xy 156.081378 -303.379909)
			(xy 156.096962 -303.42659) (xy 156.104857 -303.475167) (xy 156.105352 -303.499774) (xy 157.39416 -303.499774)
			(xy 157.39812 -303.45072) (xy 157.409897 -303.402936) (xy 157.429188 -303.35766) (xy 157.455491 -303.316064)
			(xy 157.488126 -303.279227) (xy 157.526247 -303.248102) (xy 157.568868 -303.223495) (xy 157.614884 -303.206043)
			(xy 157.663103 -303.196199) (xy 157.712278 -303.194218) (xy 157.761133 -303.20015) (xy 157.808404 -303.213842)
			(xy 157.852866 -303.23494) (xy 157.893369 -303.262896) (xy 157.928862 -303.296988) (xy 157.958427 -303.336332)
			(xy 157.981298 -303.379909) (xy 157.996882 -303.42659) (xy 158.004777 -303.475167) (xy 158.005272 -303.499774)
			(xy 158.34412 -303.499774) (xy 158.34808 -303.45072) (xy 158.359857 -303.402936) (xy 158.379148 -303.35766)
			(xy 158.405451 -303.316064) (xy 158.438086 -303.279227) (xy 158.476207 -303.248102) (xy 158.518828 -303.223495)
			(xy 158.564844 -303.206043) (xy 158.613063 -303.196199) (xy 158.662238 -303.194218) (xy 158.711093 -303.20015)
			(xy 158.758364 -303.213842) (xy 158.802826 -303.23494) (xy 158.843329 -303.262896) (xy 158.878822 -303.296988)
			(xy 158.908387 -303.336332) (xy 158.931258 -303.379909) (xy 158.946842 -303.42659) (xy 158.954737 -303.475167)
			(xy 158.955232 -303.499774) (xy 273.494004 -303.499774) (xy 273.497964 -303.45072) (xy 273.509741 -303.402936)
			(xy 273.529032 -303.35766) (xy 273.555335 -303.316064) (xy 273.58797 -303.279227) (xy 273.626091 -303.248102)
			(xy 273.668712 -303.223495) (xy 273.714728 -303.206043) (xy 273.762947 -303.196199) (xy 273.812122 -303.194218)
			(xy 273.860977 -303.20015) (xy 273.908248 -303.213842) (xy 273.95271 -303.23494) (xy 273.993213 -303.262896)
			(xy 274.028706 -303.296988) (xy 274.058271 -303.336332) (xy 274.081142 -303.379909) (xy 274.096726 -303.42659)
			(xy 274.104621 -303.475167) (xy 274.105116 -303.499774) (xy 274.443964 -303.499774) (xy 274.447924 -303.45072)
			(xy 274.459701 -303.402936) (xy 274.478992 -303.35766) (xy 274.505295 -303.316064) (xy 274.53793 -303.279227)
			(xy 274.576051 -303.248102) (xy 274.618672 -303.223495) (xy 274.664688 -303.206043) (xy 274.712907 -303.196199)
			(xy 274.762082 -303.194218) (xy 274.810937 -303.20015) (xy 274.858208 -303.213842) (xy 274.90267 -303.23494)
			(xy 274.943173 -303.262896) (xy 274.978666 -303.296988) (xy 275.008231 -303.336332) (xy 275.031102 -303.379909)
			(xy 275.046686 -303.42659) (xy 275.054581 -303.475167) (xy 275.055076 -303.499774) (xy 386.744222 -303.499774)
			(xy 386.748182 -303.45072) (xy 386.759959 -303.402936) (xy 386.77925 -303.35766) (xy 386.805553 -303.316064)
			(xy 386.838188 -303.279227) (xy 386.876309 -303.248102) (xy 386.91893 -303.223495) (xy 386.964946 -303.206043)
			(xy 387.013165 -303.196199) (xy 387.06234 -303.194218) (xy 387.111195 -303.20015) (xy 387.158466 -303.213842)
			(xy 387.202928 -303.23494) (xy 387.243431 -303.262896) (xy 387.278924 -303.296988) (xy 387.308489 -303.336332)
			(xy 387.33136 -303.379909) (xy 387.346944 -303.42659) (xy 387.354839 -303.475167) (xy 387.355334 -303.499774)
			(xy 387.694182 -303.499774) (xy 387.698142 -303.45072) (xy 387.709919 -303.402936) (xy 387.72921 -303.35766)
			(xy 387.755513 -303.316064) (xy 387.788148 -303.279227) (xy 387.826269 -303.248102) (xy 387.86889 -303.223495)
			(xy 387.914906 -303.206043) (xy 387.963125 -303.196199) (xy 388.0123 -303.194218) (xy 388.061155 -303.20015)
			(xy 388.108426 -303.213842) (xy 388.152888 -303.23494) (xy 388.193391 -303.262896) (xy 388.228884 -303.296988)
			(xy 388.258449 -303.336332) (xy 388.28132 -303.379909) (xy 388.296904 -303.42659) (xy 388.304799 -303.475167)
			(xy 388.305294 -303.499774) (xy 389.594102 -303.499774) (xy 389.598062 -303.45072) (xy 389.609839 -303.402936)
			(xy 389.62913 -303.35766) (xy 389.655433 -303.316064) (xy 389.688068 -303.279227) (xy 389.726189 -303.248102)
			(xy 389.76881 -303.223495) (xy 389.814826 -303.206043) (xy 389.863045 -303.196199) (xy 389.91222 -303.194218)
			(xy 389.961075 -303.20015) (xy 390.008346 -303.213842) (xy 390.052808 -303.23494) (xy 390.093311 -303.262896)
			(xy 390.128804 -303.296988) (xy 390.158369 -303.336332) (xy 390.18124 -303.379909) (xy 390.196824 -303.42659)
			(xy 390.204719 -303.475167) (xy 390.205214 -303.499774) (xy 390.544062 -303.499774) (xy 390.548022 -303.45072)
			(xy 390.559799 -303.402936) (xy 390.57909 -303.35766) (xy 390.605393 -303.316064) (xy 390.638028 -303.279227)
			(xy 390.676149 -303.248102) (xy 390.71877 -303.223495) (xy 390.764786 -303.206043) (xy 390.813005 -303.196199)
			(xy 390.86218 -303.194218) (xy 390.911035 -303.20015) (xy 390.958306 -303.213842) (xy 391.002768 -303.23494)
			(xy 391.043271 -303.262896) (xy 391.078764 -303.296988) (xy 391.108329 -303.336332) (xy 391.1312 -303.379909)
			(xy 391.146784 -303.42659) (xy 391.154679 -303.475167) (xy 391.155174 -303.499774) (xy 391.154679 -303.524381)
			(xy 391.146784 -303.572958) (xy 391.1312 -303.619639) (xy 391.108329 -303.663216) (xy 391.078764 -303.70256)
			(xy 391.043271 -303.736652) (xy 391.002768 -303.764608) (xy 390.958306 -303.785706) (xy 390.911035 -303.799398)
			(xy 390.86218 -303.80533) (xy 390.813005 -303.803349) (xy 390.764786 -303.793505) (xy 390.71877 -303.776053)
			(xy 390.676149 -303.751446) (xy 390.638028 -303.720321) (xy 390.605393 -303.683484) (xy 390.57909 -303.641888)
			(xy 390.559799 -303.596612) (xy 390.548022 -303.548828) (xy 390.544062 -303.499774) (xy 390.205214 -303.499774)
			(xy 390.204719 -303.524381) (xy 390.196824 -303.572958) (xy 390.18124 -303.619639) (xy 390.158369 -303.663216)
			(xy 390.128804 -303.70256) (xy 390.093311 -303.736652) (xy 390.052808 -303.764608) (xy 390.008346 -303.785706)
			(xy 389.961075 -303.799398) (xy 389.91222 -303.80533) (xy 389.863045 -303.803349) (xy 389.814826 -303.793505)
			(xy 389.76881 -303.776053) (xy 389.726189 -303.751446) (xy 389.688068 -303.720321) (xy 389.655433 -303.683484)
			(xy 389.62913 -303.641888) (xy 389.609839 -303.596612) (xy 389.598062 -303.548828) (xy 389.594102 -303.499774)
			(xy 388.305294 -303.499774) (xy 388.304799 -303.524381) (xy 388.296904 -303.572958) (xy 388.28132 -303.619639)
			(xy 388.258449 -303.663216) (xy 388.228884 -303.70256) (xy 388.193391 -303.736652) (xy 388.152888 -303.764608)
			(xy 388.108426 -303.785706) (xy 388.061155 -303.799398) (xy 388.0123 -303.80533) (xy 387.963125 -303.803349)
			(xy 387.914906 -303.793505) (xy 387.86889 -303.776053) (xy 387.826269 -303.751446) (xy 387.788148 -303.720321)
			(xy 387.755513 -303.683484) (xy 387.72921 -303.641888) (xy 387.709919 -303.596612) (xy 387.698142 -303.548828)
			(xy 387.694182 -303.499774) (xy 387.355334 -303.499774) (xy 387.354839 -303.524381) (xy 387.346944 -303.572958)
			(xy 387.33136 -303.619639) (xy 387.308489 -303.663216) (xy 387.278924 -303.70256) (xy 387.243431 -303.736652)
			(xy 387.202928 -303.764608) (xy 387.158466 -303.785706) (xy 387.111195 -303.799398) (xy 387.06234 -303.80533)
			(xy 387.013165 -303.803349) (xy 386.964946 -303.793505) (xy 386.91893 -303.776053) (xy 386.876309 -303.751446)
			(xy 386.838188 -303.720321) (xy 386.805553 -303.683484) (xy 386.77925 -303.641888) (xy 386.759959 -303.596612)
			(xy 386.748182 -303.548828) (xy 386.744222 -303.499774) (xy 275.055076 -303.499774) (xy 275.054581 -303.524381)
			(xy 275.046686 -303.572958) (xy 275.031102 -303.619639) (xy 275.008231 -303.663216) (xy 274.978666 -303.70256)
			(xy 274.943173 -303.736652) (xy 274.90267 -303.764608) (xy 274.858208 -303.785706) (xy 274.810937 -303.799398)
			(xy 274.762082 -303.80533) (xy 274.712907 -303.803349) (xy 274.664688 -303.793505) (xy 274.618672 -303.776053)
			(xy 274.576051 -303.751446) (xy 274.53793 -303.720321) (xy 274.505295 -303.683484) (xy 274.478992 -303.641888)
			(xy 274.459701 -303.596612) (xy 274.447924 -303.548828) (xy 274.443964 -303.499774) (xy 274.105116 -303.499774)
			(xy 274.104621 -303.524381) (xy 274.096726 -303.572958) (xy 274.081142 -303.619639) (xy 274.058271 -303.663216)
			(xy 274.028706 -303.70256) (xy 273.993213 -303.736652) (xy 273.95271 -303.764608) (xy 273.908248 -303.785706)
			(xy 273.860977 -303.799398) (xy 273.812122 -303.80533) (xy 273.762947 -303.803349) (xy 273.714728 -303.793505)
			(xy 273.668712 -303.776053) (xy 273.626091 -303.751446) (xy 273.58797 -303.720321) (xy 273.555335 -303.683484)
			(xy 273.529032 -303.641888) (xy 273.509741 -303.596612) (xy 273.497964 -303.548828) (xy 273.494004 -303.499774)
			(xy 158.955232 -303.499774) (xy 158.954737 -303.524381) (xy 158.946842 -303.572958) (xy 158.931258 -303.619639)
			(xy 158.908387 -303.663216) (xy 158.878822 -303.70256) (xy 158.843329 -303.736652) (xy 158.802826 -303.764608)
			(xy 158.758364 -303.785706) (xy 158.711093 -303.799398) (xy 158.662238 -303.80533) (xy 158.613063 -303.803349)
			(xy 158.564844 -303.793505) (xy 158.518828 -303.776053) (xy 158.476207 -303.751446) (xy 158.438086 -303.720321)
			(xy 158.405451 -303.683484) (xy 158.379148 -303.641888) (xy 158.359857 -303.596612) (xy 158.34808 -303.548828)
			(xy 158.34412 -303.499774) (xy 158.005272 -303.499774) (xy 158.004777 -303.524381) (xy 157.996882 -303.572958)
			(xy 157.981298 -303.619639) (xy 157.958427 -303.663216) (xy 157.928862 -303.70256) (xy 157.893369 -303.736652)
			(xy 157.852866 -303.764608) (xy 157.808404 -303.785706) (xy 157.761133 -303.799398) (xy 157.712278 -303.80533)
			(xy 157.663103 -303.803349) (xy 157.614884 -303.793505) (xy 157.568868 -303.776053) (xy 157.526247 -303.751446)
			(xy 157.488126 -303.720321) (xy 157.455491 -303.683484) (xy 157.429188 -303.641888) (xy 157.409897 -303.596612)
			(xy 157.39812 -303.548828) (xy 157.39416 -303.499774) (xy 156.105352 -303.499774) (xy 156.104857 -303.524381)
			(xy 156.096962 -303.572958) (xy 156.081378 -303.619639) (xy 156.058507 -303.663216) (xy 156.028942 -303.70256)
			(xy 155.993449 -303.736652) (xy 155.952946 -303.764608) (xy 155.908484 -303.785706) (xy 155.861213 -303.799398)
			(xy 155.812358 -303.80533) (xy 155.763183 -303.803349) (xy 155.714964 -303.793505) (xy 155.668948 -303.776053)
			(xy 155.626327 -303.751446) (xy 155.588206 -303.720321) (xy 155.555571 -303.683484) (xy 155.529268 -303.641888)
			(xy 155.509977 -303.596612) (xy 155.4982 -303.548828) (xy 155.49424 -303.499774) (xy 155.155392 -303.499774)
			(xy 155.154897 -303.524381) (xy 155.147002 -303.572958) (xy 155.131418 -303.619639) (xy 155.108547 -303.663216)
			(xy 155.078982 -303.70256) (xy 155.043489 -303.736652) (xy 155.002986 -303.764608) (xy 154.958524 -303.785706)
			(xy 154.911253 -303.799398) (xy 154.862398 -303.80533) (xy 154.813223 -303.803349) (xy 154.765004 -303.793505)
			(xy 154.718988 -303.776053) (xy 154.676367 -303.751446) (xy 154.638246 -303.720321) (xy 154.605611 -303.683484)
			(xy 154.579308 -303.641888) (xy 154.560017 -303.596612) (xy 154.54824 -303.548828) (xy 154.54428 -303.499774)
			(xy 42.855134 -303.499774) (xy 42.854639 -303.524381) (xy 42.846744 -303.572958) (xy 42.83116 -303.619639)
			(xy 42.808289 -303.663216) (xy 42.778724 -303.70256) (xy 42.743231 -303.736652) (xy 42.702728 -303.764608)
			(xy 42.658266 -303.785706) (xy 42.610995 -303.799398) (xy 42.56214 -303.80533) (xy 42.512965 -303.803349)
			(xy 42.464746 -303.793505) (xy 42.41873 -303.776053) (xy 42.376109 -303.751446) (xy 42.337988 -303.720321)
			(xy 42.305353 -303.683484) (xy 42.27905 -303.641888) (xy 42.259759 -303.596612) (xy 42.247982 -303.548828)
			(xy 42.244022 -303.499774) (xy 41.905174 -303.499774) (xy 41.904679 -303.524381) (xy 41.896784 -303.572958)
			(xy 41.8812 -303.619639) (xy 41.858329 -303.663216) (xy 41.828764 -303.70256) (xy 41.793271 -303.736652)
			(xy 41.752768 -303.764608) (xy 41.708306 -303.785706) (xy 41.661035 -303.799398) (xy 41.61218 -303.80533)
			(xy 41.563005 -303.803349) (xy 41.514786 -303.793505) (xy 41.46877 -303.776053) (xy 41.426149 -303.751446)
			(xy 41.388028 -303.720321) (xy 41.355393 -303.683484) (xy 41.32909 -303.641888) (xy 41.309799 -303.596612)
			(xy 41.298022 -303.548828) (xy 41.294062 -303.499774) (xy 0.508 -303.499774) (xy 0.508 -304.449734)
			(xy 43.193982 -304.449734) (xy 43.197942 -304.40068) (xy 43.209719 -304.352896) (xy 43.22901 -304.30762)
			(xy 43.255313 -304.266024) (xy 43.287948 -304.229187) (xy 43.326069 -304.198062) (xy 43.36869 -304.173455)
			(xy 43.414706 -304.156003) (xy 43.462925 -304.146159) (xy 43.5121 -304.144178) (xy 43.560955 -304.15011)
			(xy 43.608226 -304.163802) (xy 43.652688 -304.1849) (xy 43.693191 -304.212856) (xy 43.728684 -304.246948)
			(xy 43.758249 -304.286292) (xy 43.78112 -304.329869) (xy 43.796704 -304.37655) (xy 43.804599 -304.425127)
			(xy 43.805094 -304.449734) (xy 44.143942 -304.449734) (xy 44.147902 -304.40068) (xy 44.159679 -304.352896)
			(xy 44.17897 -304.30762) (xy 44.205273 -304.266024) (xy 44.237908 -304.229187) (xy 44.276029 -304.198062)
			(xy 44.31865 -304.173455) (xy 44.364666 -304.156003) (xy 44.412885 -304.146159) (xy 44.46206 -304.144178)
			(xy 44.510915 -304.15011) (xy 44.558186 -304.163802) (xy 44.602648 -304.1849) (xy 44.643151 -304.212856)
			(xy 44.678644 -304.246948) (xy 44.708209 -304.286292) (xy 44.73108 -304.329869) (xy 44.746664 -304.37655)
			(xy 44.754559 -304.425127) (xy 44.755054 -304.449734) (xy 74.544186 -304.449734) (xy 74.548146 -304.40068)
			(xy 74.559923 -304.352896) (xy 74.579214 -304.30762) (xy 74.605517 -304.266024) (xy 74.638152 -304.229187)
			(xy 74.676273 -304.198062) (xy 74.718894 -304.173455) (xy 74.76491 -304.156003) (xy 74.813129 -304.146159)
			(xy 74.862304 -304.144178) (xy 74.911159 -304.15011) (xy 74.95843 -304.163802) (xy 75.002892 -304.1849)
			(xy 75.043395 -304.212856) (xy 75.078888 -304.246948) (xy 75.108453 -304.286292) (xy 75.131324 -304.329869)
			(xy 75.146908 -304.37655) (xy 75.154803 -304.425127) (xy 75.155298 -304.449734) (xy 75.494146 -304.449734)
			(xy 75.498106 -304.40068) (xy 75.509883 -304.352896) (xy 75.529174 -304.30762) (xy 75.555477 -304.266024)
			(xy 75.588112 -304.229187) (xy 75.626233 -304.198062) (xy 75.668854 -304.173455) (xy 75.71487 -304.156003)
			(xy 75.763089 -304.146159) (xy 75.812264 -304.144178) (xy 75.861119 -304.15011) (xy 75.90839 -304.163802)
			(xy 75.952852 -304.1849) (xy 75.993355 -304.212856) (xy 76.028848 -304.246948) (xy 76.058413 -304.286292)
			(xy 76.081284 -304.329869) (xy 76.096868 -304.37655) (xy 76.104763 -304.425127) (xy 76.105258 -304.449734)
			(xy 81.19416 -304.449734) (xy 81.19812 -304.40068) (xy 81.209897 -304.352896) (xy 81.229188 -304.30762)
			(xy 81.255491 -304.266024) (xy 81.288126 -304.229187) (xy 81.326247 -304.198062) (xy 81.368868 -304.173455)
			(xy 81.414884 -304.156003) (xy 81.463103 -304.146159) (xy 81.512278 -304.144178) (xy 81.561133 -304.15011)
			(xy 81.608404 -304.163802) (xy 81.652866 -304.1849) (xy 81.693369 -304.212856) (xy 81.728862 -304.246948)
			(xy 81.758427 -304.286292) (xy 81.781298 -304.329869) (xy 81.796882 -304.37655) (xy 81.804777 -304.425127)
			(xy 81.805272 -304.449734) (xy 82.14412 -304.449734) (xy 82.14808 -304.40068) (xy 82.159857 -304.352896)
			(xy 82.179148 -304.30762) (xy 82.205451 -304.266024) (xy 82.238086 -304.229187) (xy 82.276207 -304.198062)
			(xy 82.318828 -304.173455) (xy 82.364844 -304.156003) (xy 82.413063 -304.146159) (xy 82.462238 -304.144178)
			(xy 82.511093 -304.15011) (xy 82.558364 -304.163802) (xy 82.602826 -304.1849) (xy 82.643329 -304.212856)
			(xy 82.678822 -304.246948) (xy 82.708387 -304.286292) (xy 82.731258 -304.329869) (xy 82.746842 -304.37655)
			(xy 82.754737 -304.425127) (xy 82.755232 -304.449734) (xy 152.644106 -304.449734) (xy 152.648066 -304.40068)
			(xy 152.659843 -304.352896) (xy 152.679134 -304.30762) (xy 152.705437 -304.266024) (xy 152.738072 -304.229187)
			(xy 152.776193 -304.198062) (xy 152.818814 -304.173455) (xy 152.86483 -304.156003) (xy 152.913049 -304.146159)
			(xy 152.962224 -304.144178) (xy 153.011079 -304.15011) (xy 153.05835 -304.163802) (xy 153.102812 -304.1849)
			(xy 153.143315 -304.212856) (xy 153.178808 -304.246948) (xy 153.208373 -304.286292) (xy 153.231244 -304.329869)
			(xy 153.246828 -304.37655) (xy 153.254723 -304.425127) (xy 153.255218 -304.449734) (xy 153.594066 -304.449734)
			(xy 153.598026 -304.40068) (xy 153.609803 -304.352896) (xy 153.629094 -304.30762) (xy 153.655397 -304.266024)
			(xy 153.688032 -304.229187) (xy 153.726153 -304.198062) (xy 153.768774 -304.173455) (xy 153.81479 -304.156003)
			(xy 153.863009 -304.146159) (xy 153.912184 -304.144178) (xy 153.961039 -304.15011) (xy 154.00831 -304.163802)
			(xy 154.052772 -304.1849) (xy 154.093275 -304.212856) (xy 154.128768 -304.246948) (xy 154.158333 -304.286292)
			(xy 154.181204 -304.329869) (xy 154.196788 -304.37655) (xy 154.204683 -304.425127) (xy 154.205178 -304.449734)
			(xy 159.29408 -304.449734) (xy 159.29804 -304.40068) (xy 159.309817 -304.352896) (xy 159.329108 -304.30762)
			(xy 159.355411 -304.266024) (xy 159.388046 -304.229187) (xy 159.426167 -304.198062) (xy 159.468788 -304.173455)
			(xy 159.514804 -304.156003) (xy 159.563023 -304.146159) (xy 159.612198 -304.144178) (xy 159.661053 -304.15011)
			(xy 159.708324 -304.163802) (xy 159.752786 -304.1849) (xy 159.793289 -304.212856) (xy 159.828782 -304.246948)
			(xy 159.858347 -304.286292) (xy 159.881218 -304.329869) (xy 159.896802 -304.37655) (xy 159.904697 -304.425127)
			(xy 159.905192 -304.449734) (xy 160.24404 -304.449734) (xy 160.248 -304.40068) (xy 160.259777 -304.352896)
			(xy 160.279068 -304.30762) (xy 160.305371 -304.266024) (xy 160.338006 -304.229187) (xy 160.376127 -304.198062)
			(xy 160.418748 -304.173455) (xy 160.464764 -304.156003) (xy 160.512983 -304.146159) (xy 160.562158 -304.144178)
			(xy 160.611013 -304.15011) (xy 160.658284 -304.163802) (xy 160.702746 -304.1849) (xy 160.743249 -304.212856)
			(xy 160.778742 -304.246948) (xy 160.808307 -304.286292) (xy 160.831178 -304.329869) (xy 160.846762 -304.37655)
			(xy 160.854657 -304.425127) (xy 160.855152 -304.449734) (xy 190.644284 -304.449734) (xy 190.648244 -304.40068)
			(xy 190.660021 -304.352896) (xy 190.679312 -304.30762) (xy 190.705615 -304.266024) (xy 190.73825 -304.229187)
			(xy 190.776371 -304.198062) (xy 190.818992 -304.173455) (xy 190.865008 -304.156003) (xy 190.913227 -304.146159)
			(xy 190.962402 -304.144178) (xy 191.011257 -304.15011) (xy 191.058528 -304.163802) (xy 191.10299 -304.1849)
			(xy 191.143493 -304.212856) (xy 191.178986 -304.246948) (xy 191.208551 -304.286292) (xy 191.231422 -304.329869)
			(xy 191.247006 -304.37655) (xy 191.254901 -304.425127) (xy 191.255396 -304.449734) (xy 191.594244 -304.449734)
			(xy 191.598204 -304.40068) (xy 191.609981 -304.352896) (xy 191.629272 -304.30762) (xy 191.655575 -304.266024)
			(xy 191.68821 -304.229187) (xy 191.726331 -304.198062) (xy 191.768952 -304.173455) (xy 191.814968 -304.156003)
			(xy 191.863187 -304.146159) (xy 191.912362 -304.144178) (xy 191.961217 -304.15011) (xy 192.008488 -304.163802)
			(xy 192.05295 -304.1849) (xy 192.093453 -304.212856) (xy 192.128946 -304.246948) (xy 192.158511 -304.286292)
			(xy 192.181382 -304.329869) (xy 192.196966 -304.37655) (xy 192.204861 -304.425127) (xy 192.205356 -304.449734)
			(xy 275.393924 -304.449734) (xy 275.397884 -304.40068) (xy 275.409661 -304.352896) (xy 275.428952 -304.30762)
			(xy 275.455255 -304.266024) (xy 275.48789 -304.229187) (xy 275.526011 -304.198062) (xy 275.568632 -304.173455)
			(xy 275.614648 -304.156003) (xy 275.662867 -304.146159) (xy 275.712042 -304.144178) (xy 275.760897 -304.15011)
			(xy 275.808168 -304.163802) (xy 275.85263 -304.1849) (xy 275.893133 -304.212856) (xy 275.928626 -304.246948)
			(xy 275.958191 -304.286292) (xy 275.981062 -304.329869) (xy 275.996646 -304.37655) (xy 276.004541 -304.425127)
			(xy 276.005036 -304.449734) (xy 276.343884 -304.449734) (xy 276.347844 -304.40068) (xy 276.359621 -304.352896)
			(xy 276.378912 -304.30762) (xy 276.405215 -304.266024) (xy 276.43785 -304.229187) (xy 276.475971 -304.198062)
			(xy 276.518592 -304.173455) (xy 276.564608 -304.156003) (xy 276.612827 -304.146159) (xy 276.662002 -304.144178)
			(xy 276.710857 -304.15011) (xy 276.758128 -304.163802) (xy 276.80259 -304.1849) (xy 276.843093 -304.212856)
			(xy 276.878586 -304.246948) (xy 276.908151 -304.286292) (xy 276.931022 -304.329869) (xy 276.946606 -304.37655)
			(xy 276.954501 -304.425127) (xy 276.954996 -304.449734) (xy 306.744128 -304.449734) (xy 306.748088 -304.40068)
			(xy 306.759865 -304.352896) (xy 306.779156 -304.30762) (xy 306.805459 -304.266024) (xy 306.838094 -304.229187)
			(xy 306.876215 -304.198062) (xy 306.918836 -304.173455) (xy 306.964852 -304.156003) (xy 307.013071 -304.146159)
			(xy 307.062246 -304.144178) (xy 307.111101 -304.15011) (xy 307.158372 -304.163802) (xy 307.202834 -304.1849)
			(xy 307.243337 -304.212856) (xy 307.27883 -304.246948) (xy 307.308395 -304.286292) (xy 307.331266 -304.329869)
			(xy 307.34685 -304.37655) (xy 307.354745 -304.425127) (xy 307.35524 -304.449734) (xy 307.694088 -304.449734)
			(xy 307.698048 -304.40068) (xy 307.709825 -304.352896) (xy 307.729116 -304.30762) (xy 307.755419 -304.266024)
			(xy 307.788054 -304.229187) (xy 307.826175 -304.198062) (xy 307.868796 -304.173455) (xy 307.914812 -304.156003)
			(xy 307.963031 -304.146159) (xy 308.012206 -304.144178) (xy 308.061061 -304.15011) (xy 308.108332 -304.163802)
			(xy 308.152794 -304.1849) (xy 308.193297 -304.212856) (xy 308.22879 -304.246948) (xy 308.258355 -304.286292)
			(xy 308.281226 -304.329869) (xy 308.29681 -304.37655) (xy 308.304705 -304.425127) (xy 308.3052 -304.449734)
			(xy 313.394102 -304.449734) (xy 313.398062 -304.40068) (xy 313.409839 -304.352896) (xy 313.42913 -304.30762)
			(xy 313.455433 -304.266024) (xy 313.488068 -304.229187) (xy 313.526189 -304.198062) (xy 313.56881 -304.173455)
			(xy 313.614826 -304.156003) (xy 313.663045 -304.146159) (xy 313.71222 -304.144178) (xy 313.761075 -304.15011)
			(xy 313.808346 -304.163802) (xy 313.852808 -304.1849) (xy 313.893311 -304.212856) (xy 313.928804 -304.246948)
			(xy 313.958369 -304.286292) (xy 313.98124 -304.329869) (xy 313.996824 -304.37655) (xy 314.004719 -304.425127)
			(xy 314.005214 -304.449734) (xy 314.344062 -304.449734) (xy 314.348022 -304.40068) (xy 314.359799 -304.352896)
			(xy 314.37909 -304.30762) (xy 314.405393 -304.266024) (xy 314.438028 -304.229187) (xy 314.476149 -304.198062)
			(xy 314.51877 -304.173455) (xy 314.564786 -304.156003) (xy 314.613005 -304.146159) (xy 314.66218 -304.144178)
			(xy 314.711035 -304.15011) (xy 314.758306 -304.163802) (xy 314.802768 -304.1849) (xy 314.843271 -304.212856)
			(xy 314.878764 -304.246948) (xy 314.908329 -304.286292) (xy 314.9312 -304.329869) (xy 314.946784 -304.37655)
			(xy 314.954679 -304.425127) (xy 314.955174 -304.449734) (xy 384.844048 -304.449734) (xy 384.848008 -304.40068)
			(xy 384.859785 -304.352896) (xy 384.879076 -304.30762) (xy 384.905379 -304.266024) (xy 384.938014 -304.229187)
			(xy 384.976135 -304.198062) (xy 385.018756 -304.173455) (xy 385.064772 -304.156003) (xy 385.112991 -304.146159)
			(xy 385.162166 -304.144178) (xy 385.211021 -304.15011) (xy 385.258292 -304.163802) (xy 385.302754 -304.1849)
			(xy 385.343257 -304.212856) (xy 385.37875 -304.246948) (xy 385.408315 -304.286292) (xy 385.431186 -304.329869)
			(xy 385.44677 -304.37655) (xy 385.454665 -304.425127) (xy 385.45516 -304.449734) (xy 385.794008 -304.449734)
			(xy 385.797968 -304.40068) (xy 385.809745 -304.352896) (xy 385.829036 -304.30762) (xy 385.855339 -304.266024)
			(xy 385.887974 -304.229187) (xy 385.926095 -304.198062) (xy 385.968716 -304.173455) (xy 386.014732 -304.156003)
			(xy 386.062951 -304.146159) (xy 386.112126 -304.144178) (xy 386.160981 -304.15011) (xy 386.208252 -304.163802)
			(xy 386.252714 -304.1849) (xy 386.293217 -304.212856) (xy 386.32871 -304.246948) (xy 386.358275 -304.286292)
			(xy 386.381146 -304.329869) (xy 386.39673 -304.37655) (xy 386.404625 -304.425127) (xy 386.40512 -304.449734)
			(xy 391.494022 -304.449734) (xy 391.497982 -304.40068) (xy 391.509759 -304.352896) (xy 391.52905 -304.30762)
			(xy 391.555353 -304.266024) (xy 391.587988 -304.229187) (xy 391.626109 -304.198062) (xy 391.66873 -304.173455)
			(xy 391.714746 -304.156003) (xy 391.762965 -304.146159) (xy 391.81214 -304.144178) (xy 391.860995 -304.15011)
			(xy 391.908266 -304.163802) (xy 391.952728 -304.1849) (xy 391.993231 -304.212856) (xy 392.028724 -304.246948)
			(xy 392.058289 -304.286292) (xy 392.08116 -304.329869) (xy 392.096744 -304.37655) (xy 392.104639 -304.425127)
			(xy 392.105134 -304.449734) (xy 392.443982 -304.449734) (xy 392.447942 -304.40068) (xy 392.459719 -304.352896)
			(xy 392.47901 -304.30762) (xy 392.505313 -304.266024) (xy 392.537948 -304.229187) (xy 392.576069 -304.198062)
			(xy 392.61869 -304.173455) (xy 392.664706 -304.156003) (xy 392.712925 -304.146159) (xy 392.7621 -304.144178)
			(xy 392.810955 -304.15011) (xy 392.858226 -304.163802) (xy 392.902688 -304.1849) (xy 392.943191 -304.212856)
			(xy 392.978684 -304.246948) (xy 393.008249 -304.286292) (xy 393.03112 -304.329869) (xy 393.046704 -304.37655)
			(xy 393.054599 -304.425127) (xy 393.055094 -304.449734) (xy 422.844226 -304.449734) (xy 422.848186 -304.40068)
			(xy 422.859963 -304.352896) (xy 422.879254 -304.30762) (xy 422.905557 -304.266024) (xy 422.938192 -304.229187)
			(xy 422.976313 -304.198062) (xy 423.018934 -304.173455) (xy 423.06495 -304.156003) (xy 423.113169 -304.146159)
			(xy 423.162344 -304.144178) (xy 423.211199 -304.15011) (xy 423.25847 -304.163802) (xy 423.302932 -304.1849)
			(xy 423.343435 -304.212856) (xy 423.378928 -304.246948) (xy 423.408493 -304.286292) (xy 423.431364 -304.329869)
			(xy 423.446948 -304.37655) (xy 423.454843 -304.425127) (xy 423.455338 -304.449734) (xy 423.794186 -304.449734)
			(xy 423.798146 -304.40068) (xy 423.809923 -304.352896) (xy 423.829214 -304.30762) (xy 423.855517 -304.266024)
			(xy 423.888152 -304.229187) (xy 423.926273 -304.198062) (xy 423.968894 -304.173455) (xy 424.01491 -304.156003)
			(xy 424.063129 -304.146159) (xy 424.112304 -304.144178) (xy 424.161159 -304.15011) (xy 424.20843 -304.163802)
			(xy 424.252892 -304.1849) (xy 424.293395 -304.212856) (xy 424.328888 -304.246948) (xy 424.358453 -304.286292)
			(xy 424.381324 -304.329869) (xy 424.396908 -304.37655) (xy 424.404803 -304.425127) (xy 424.405298 -304.449734)
			(xy 424.404803 -304.474341) (xy 424.396908 -304.522918) (xy 424.381324 -304.569599) (xy 424.358453 -304.613176)
			(xy 424.328888 -304.65252) (xy 424.293395 -304.686612) (xy 424.252892 -304.714568) (xy 424.20843 -304.735666)
			(xy 424.161159 -304.749358) (xy 424.112304 -304.75529) (xy 424.063129 -304.753309) (xy 424.01491 -304.743465)
			(xy 423.968894 -304.726013) (xy 423.926273 -304.701406) (xy 423.888152 -304.670281) (xy 423.855517 -304.633444)
			(xy 423.829214 -304.591848) (xy 423.809923 -304.546572) (xy 423.798146 -304.498788) (xy 423.794186 -304.449734)
			(xy 423.455338 -304.449734) (xy 423.454843 -304.474341) (xy 423.446948 -304.522918) (xy 423.431364 -304.569599)
			(xy 423.408493 -304.613176) (xy 423.378928 -304.65252) (xy 423.343435 -304.686612) (xy 423.302932 -304.714568)
			(xy 423.25847 -304.735666) (xy 423.211199 -304.749358) (xy 423.162344 -304.75529) (xy 423.113169 -304.753309)
			(xy 423.06495 -304.743465) (xy 423.018934 -304.726013) (xy 422.976313 -304.701406) (xy 422.938192 -304.670281)
			(xy 422.905557 -304.633444) (xy 422.879254 -304.591848) (xy 422.859963 -304.546572) (xy 422.848186 -304.498788)
			(xy 422.844226 -304.449734) (xy 393.055094 -304.449734) (xy 393.054599 -304.474341) (xy 393.046704 -304.522918)
			(xy 393.03112 -304.569599) (xy 393.008249 -304.613176) (xy 392.978684 -304.65252) (xy 392.943191 -304.686612)
			(xy 392.902688 -304.714568) (xy 392.858226 -304.735666) (xy 392.810955 -304.749358) (xy 392.7621 -304.75529)
			(xy 392.712925 -304.753309) (xy 392.664706 -304.743465) (xy 392.61869 -304.726013) (xy 392.576069 -304.701406)
			(xy 392.537948 -304.670281) (xy 392.505313 -304.633444) (xy 392.47901 -304.591848) (xy 392.459719 -304.546572)
			(xy 392.447942 -304.498788) (xy 392.443982 -304.449734) (xy 392.105134 -304.449734) (xy 392.104639 -304.474341)
			(xy 392.096744 -304.522918) (xy 392.08116 -304.569599) (xy 392.058289 -304.613176) (xy 392.028724 -304.65252)
			(xy 391.993231 -304.686612) (xy 391.952728 -304.714568) (xy 391.908266 -304.735666) (xy 391.860995 -304.749358)
			(xy 391.81214 -304.75529) (xy 391.762965 -304.753309) (xy 391.714746 -304.743465) (xy 391.66873 -304.726013)
			(xy 391.626109 -304.701406) (xy 391.587988 -304.670281) (xy 391.555353 -304.633444) (xy 391.52905 -304.591848)
			(xy 391.509759 -304.546572) (xy 391.497982 -304.498788) (xy 391.494022 -304.449734) (xy 386.40512 -304.449734)
			(xy 386.404625 -304.474341) (xy 386.39673 -304.522918) (xy 386.381146 -304.569599) (xy 386.358275 -304.613176)
			(xy 386.32871 -304.65252) (xy 386.293217 -304.686612) (xy 386.252714 -304.714568) (xy 386.208252 -304.735666)
			(xy 386.160981 -304.749358) (xy 386.112126 -304.75529) (xy 386.062951 -304.753309) (xy 386.014732 -304.743465)
			(xy 385.968716 -304.726013) (xy 385.926095 -304.701406) (xy 385.887974 -304.670281) (xy 385.855339 -304.633444)
			(xy 385.829036 -304.591848) (xy 385.809745 -304.546572) (xy 385.797968 -304.498788) (xy 385.794008 -304.449734)
			(xy 385.45516 -304.449734) (xy 385.454665 -304.474341) (xy 385.44677 -304.522918) (xy 385.431186 -304.569599)
			(xy 385.408315 -304.613176) (xy 385.37875 -304.65252) (xy 385.343257 -304.686612) (xy 385.302754 -304.714568)
			(xy 385.258292 -304.735666) (xy 385.211021 -304.749358) (xy 385.162166 -304.75529) (xy 385.112991 -304.753309)
			(xy 385.064772 -304.743465) (xy 385.018756 -304.726013) (xy 384.976135 -304.701406) (xy 384.938014 -304.670281)
			(xy 384.905379 -304.633444) (xy 384.879076 -304.591848) (xy 384.859785 -304.546572) (xy 384.848008 -304.498788)
			(xy 384.844048 -304.449734) (xy 314.955174 -304.449734) (xy 314.954679 -304.474341) (xy 314.946784 -304.522918)
			(xy 314.9312 -304.569599) (xy 314.908329 -304.613176) (xy 314.878764 -304.65252) (xy 314.843271 -304.686612)
			(xy 314.802768 -304.714568) (xy 314.758306 -304.735666) (xy 314.711035 -304.749358) (xy 314.66218 -304.75529)
			(xy 314.613005 -304.753309) (xy 314.564786 -304.743465) (xy 314.51877 -304.726013) (xy 314.476149 -304.701406)
			(xy 314.438028 -304.670281) (xy 314.405393 -304.633444) (xy 314.37909 -304.591848) (xy 314.359799 -304.546572)
			(xy 314.348022 -304.498788) (xy 314.344062 -304.449734) (xy 314.005214 -304.449734) (xy 314.004719 -304.474341)
			(xy 313.996824 -304.522918) (xy 313.98124 -304.569599) (xy 313.958369 -304.613176) (xy 313.928804 -304.65252)
			(xy 313.893311 -304.686612) (xy 313.852808 -304.714568) (xy 313.808346 -304.735666) (xy 313.761075 -304.749358)
			(xy 313.71222 -304.75529) (xy 313.663045 -304.753309) (xy 313.614826 -304.743465) (xy 313.56881 -304.726013)
			(xy 313.526189 -304.701406) (xy 313.488068 -304.670281) (xy 313.455433 -304.633444) (xy 313.42913 -304.591848)
			(xy 313.409839 -304.546572) (xy 313.398062 -304.498788) (xy 313.394102 -304.449734) (xy 308.3052 -304.449734)
			(xy 308.304705 -304.474341) (xy 308.29681 -304.522918) (xy 308.281226 -304.569599) (xy 308.258355 -304.613176)
			(xy 308.22879 -304.65252) (xy 308.193297 -304.686612) (xy 308.152794 -304.714568) (xy 308.108332 -304.735666)
			(xy 308.061061 -304.749358) (xy 308.012206 -304.75529) (xy 307.963031 -304.753309) (xy 307.914812 -304.743465)
			(xy 307.868796 -304.726013) (xy 307.826175 -304.701406) (xy 307.788054 -304.670281) (xy 307.755419 -304.633444)
			(xy 307.729116 -304.591848) (xy 307.709825 -304.546572) (xy 307.698048 -304.498788) (xy 307.694088 -304.449734)
			(xy 307.35524 -304.449734) (xy 307.354745 -304.474341) (xy 307.34685 -304.522918) (xy 307.331266 -304.569599)
			(xy 307.308395 -304.613176) (xy 307.27883 -304.65252) (xy 307.243337 -304.686612) (xy 307.202834 -304.714568)
			(xy 307.158372 -304.735666) (xy 307.111101 -304.749358) (xy 307.062246 -304.75529) (xy 307.013071 -304.753309)
			(xy 306.964852 -304.743465) (xy 306.918836 -304.726013) (xy 306.876215 -304.701406) (xy 306.838094 -304.670281)
			(xy 306.805459 -304.633444) (xy 306.779156 -304.591848) (xy 306.759865 -304.546572) (xy 306.748088 -304.498788)
			(xy 306.744128 -304.449734) (xy 276.954996 -304.449734) (xy 276.954501 -304.474341) (xy 276.946606 -304.522918)
			(xy 276.931022 -304.569599) (xy 276.908151 -304.613176) (xy 276.878586 -304.65252) (xy 276.843093 -304.686612)
			(xy 276.80259 -304.714568) (xy 276.758128 -304.735666) (xy 276.710857 -304.749358) (xy 276.662002 -304.75529)
			(xy 276.612827 -304.753309) (xy 276.564608 -304.743465) (xy 276.518592 -304.726013) (xy 276.475971 -304.701406)
			(xy 276.43785 -304.670281) (xy 276.405215 -304.633444) (xy 276.378912 -304.591848) (xy 276.359621 -304.546572)
			(xy 276.347844 -304.498788) (xy 276.343884 -304.449734) (xy 276.005036 -304.449734) (xy 276.004541 -304.474341)
			(xy 275.996646 -304.522918) (xy 275.981062 -304.569599) (xy 275.958191 -304.613176) (xy 275.928626 -304.65252)
			(xy 275.893133 -304.686612) (xy 275.85263 -304.714568) (xy 275.808168 -304.735666) (xy 275.760897 -304.749358)
			(xy 275.712042 -304.75529) (xy 275.662867 -304.753309) (xy 275.614648 -304.743465) (xy 275.568632 -304.726013)
			(xy 275.526011 -304.701406) (xy 275.48789 -304.670281) (xy 275.455255 -304.633444) (xy 275.428952 -304.591848)
			(xy 275.409661 -304.546572) (xy 275.397884 -304.498788) (xy 275.393924 -304.449734) (xy 192.205356 -304.449734)
			(xy 192.204861 -304.474341) (xy 192.196966 -304.522918) (xy 192.181382 -304.569599) (xy 192.158511 -304.613176)
			(xy 192.128946 -304.65252) (xy 192.093453 -304.686612) (xy 192.05295 -304.714568) (xy 192.008488 -304.735666)
			(xy 191.961217 -304.749358) (xy 191.912362 -304.75529) (xy 191.863187 -304.753309) (xy 191.814968 -304.743465)
			(xy 191.768952 -304.726013) (xy 191.726331 -304.701406) (xy 191.68821 -304.670281) (xy 191.655575 -304.633444)
			(xy 191.629272 -304.591848) (xy 191.609981 -304.546572) (xy 191.598204 -304.498788) (xy 191.594244 -304.449734)
			(xy 191.255396 -304.449734) (xy 191.254901 -304.474341) (xy 191.247006 -304.522918) (xy 191.231422 -304.569599)
			(xy 191.208551 -304.613176) (xy 191.178986 -304.65252) (xy 191.143493 -304.686612) (xy 191.10299 -304.714568)
			(xy 191.058528 -304.735666) (xy 191.011257 -304.749358) (xy 190.962402 -304.75529) (xy 190.913227 -304.753309)
			(xy 190.865008 -304.743465) (xy 190.818992 -304.726013) (xy 190.776371 -304.701406) (xy 190.73825 -304.670281)
			(xy 190.705615 -304.633444) (xy 190.679312 -304.591848) (xy 190.660021 -304.546572) (xy 190.648244 -304.498788)
			(xy 190.644284 -304.449734) (xy 160.855152 -304.449734) (xy 160.854657 -304.474341) (xy 160.846762 -304.522918)
			(xy 160.831178 -304.569599) (xy 160.808307 -304.613176) (xy 160.778742 -304.65252) (xy 160.743249 -304.686612)
			(xy 160.702746 -304.714568) (xy 160.658284 -304.735666) (xy 160.611013 -304.749358) (xy 160.562158 -304.75529)
			(xy 160.512983 -304.753309) (xy 160.464764 -304.743465) (xy 160.418748 -304.726013) (xy 160.376127 -304.701406)
			(xy 160.338006 -304.670281) (xy 160.305371 -304.633444) (xy 160.279068 -304.591848) (xy 160.259777 -304.546572)
			(xy 160.248 -304.498788) (xy 160.24404 -304.449734) (xy 159.905192 -304.449734) (xy 159.904697 -304.474341)
			(xy 159.896802 -304.522918) (xy 159.881218 -304.569599) (xy 159.858347 -304.613176) (xy 159.828782 -304.65252)
			(xy 159.793289 -304.686612) (xy 159.752786 -304.714568) (xy 159.708324 -304.735666) (xy 159.661053 -304.749358)
			(xy 159.612198 -304.75529) (xy 159.563023 -304.753309) (xy 159.514804 -304.743465) (xy 159.468788 -304.726013)
			(xy 159.426167 -304.701406) (xy 159.388046 -304.670281) (xy 159.355411 -304.633444) (xy 159.329108 -304.591848)
			(xy 159.309817 -304.546572) (xy 159.29804 -304.498788) (xy 159.29408 -304.449734) (xy 154.205178 -304.449734)
			(xy 154.204683 -304.474341) (xy 154.196788 -304.522918) (xy 154.181204 -304.569599) (xy 154.158333 -304.613176)
			(xy 154.128768 -304.65252) (xy 154.093275 -304.686612) (xy 154.052772 -304.714568) (xy 154.00831 -304.735666)
			(xy 153.961039 -304.749358) (xy 153.912184 -304.75529) (xy 153.863009 -304.753309) (xy 153.81479 -304.743465)
			(xy 153.768774 -304.726013) (xy 153.726153 -304.701406) (xy 153.688032 -304.670281) (xy 153.655397 -304.633444)
			(xy 153.629094 -304.591848) (xy 153.609803 -304.546572) (xy 153.598026 -304.498788) (xy 153.594066 -304.449734)
			(xy 153.255218 -304.449734) (xy 153.254723 -304.474341) (xy 153.246828 -304.522918) (xy 153.231244 -304.569599)
			(xy 153.208373 -304.613176) (xy 153.178808 -304.65252) (xy 153.143315 -304.686612) (xy 153.102812 -304.714568)
			(xy 153.05835 -304.735666) (xy 153.011079 -304.749358) (xy 152.962224 -304.75529) (xy 152.913049 -304.753309)
			(xy 152.86483 -304.743465) (xy 152.818814 -304.726013) (xy 152.776193 -304.701406) (xy 152.738072 -304.670281)
			(xy 152.705437 -304.633444) (xy 152.679134 -304.591848) (xy 152.659843 -304.546572) (xy 152.648066 -304.498788)
			(xy 152.644106 -304.449734) (xy 82.755232 -304.449734) (xy 82.754737 -304.474341) (xy 82.746842 -304.522918)
			(xy 82.731258 -304.569599) (xy 82.708387 -304.613176) (xy 82.678822 -304.65252) (xy 82.643329 -304.686612)
			(xy 82.602826 -304.714568) (xy 82.558364 -304.735666) (xy 82.511093 -304.749358) (xy 82.462238 -304.75529)
			(xy 82.413063 -304.753309) (xy 82.364844 -304.743465) (xy 82.318828 -304.726013) (xy 82.276207 -304.701406)
			(xy 82.238086 -304.670281) (xy 82.205451 -304.633444) (xy 82.179148 -304.591848) (xy 82.159857 -304.546572)
			(xy 82.14808 -304.498788) (xy 82.14412 -304.449734) (xy 81.805272 -304.449734) (xy 81.804777 -304.474341)
			(xy 81.796882 -304.522918) (xy 81.781298 -304.569599) (xy 81.758427 -304.613176) (xy 81.728862 -304.65252)
			(xy 81.693369 -304.686612) (xy 81.652866 -304.714568) (xy 81.608404 -304.735666) (xy 81.561133 -304.749358)
			(xy 81.512278 -304.75529) (xy 81.463103 -304.753309) (xy 81.414884 -304.743465) (xy 81.368868 -304.726013)
			(xy 81.326247 -304.701406) (xy 81.288126 -304.670281) (xy 81.255491 -304.633444) (xy 81.229188 -304.591848)
			(xy 81.209897 -304.546572) (xy 81.19812 -304.498788) (xy 81.19416 -304.449734) (xy 76.105258 -304.449734)
			(xy 76.104763 -304.474341) (xy 76.096868 -304.522918) (xy 76.081284 -304.569599) (xy 76.058413 -304.613176)
			(xy 76.028848 -304.65252) (xy 75.993355 -304.686612) (xy 75.952852 -304.714568) (xy 75.90839 -304.735666)
			(xy 75.861119 -304.749358) (xy 75.812264 -304.75529) (xy 75.763089 -304.753309) (xy 75.71487 -304.743465)
			(xy 75.668854 -304.726013) (xy 75.626233 -304.701406) (xy 75.588112 -304.670281) (xy 75.555477 -304.633444)
			(xy 75.529174 -304.591848) (xy 75.509883 -304.546572) (xy 75.498106 -304.498788) (xy 75.494146 -304.449734)
			(xy 75.155298 -304.449734) (xy 75.154803 -304.474341) (xy 75.146908 -304.522918) (xy 75.131324 -304.569599)
			(xy 75.108453 -304.613176) (xy 75.078888 -304.65252) (xy 75.043395 -304.686612) (xy 75.002892 -304.714568)
			(xy 74.95843 -304.735666) (xy 74.911159 -304.749358) (xy 74.862304 -304.75529) (xy 74.813129 -304.753309)
			(xy 74.76491 -304.743465) (xy 74.718894 -304.726013) (xy 74.676273 -304.701406) (xy 74.638152 -304.670281)
			(xy 74.605517 -304.633444) (xy 74.579214 -304.591848) (xy 74.559923 -304.546572) (xy 74.548146 -304.498788)
			(xy 74.544186 -304.449734) (xy 44.755054 -304.449734) (xy 44.754559 -304.474341) (xy 44.746664 -304.522918)
			(xy 44.73108 -304.569599) (xy 44.708209 -304.613176) (xy 44.678644 -304.65252) (xy 44.643151 -304.686612)
			(xy 44.602648 -304.714568) (xy 44.558186 -304.735666) (xy 44.510915 -304.749358) (xy 44.46206 -304.75529)
			(xy 44.412885 -304.753309) (xy 44.364666 -304.743465) (xy 44.31865 -304.726013) (xy 44.276029 -304.701406)
			(xy 44.237908 -304.670281) (xy 44.205273 -304.633444) (xy 44.17897 -304.591848) (xy 44.159679 -304.546572)
			(xy 44.147902 -304.498788) (xy 44.143942 -304.449734) (xy 43.805094 -304.449734) (xy 43.804599 -304.474341)
			(xy 43.796704 -304.522918) (xy 43.78112 -304.569599) (xy 43.758249 -304.613176) (xy 43.728684 -304.65252)
			(xy 43.693191 -304.686612) (xy 43.652688 -304.714568) (xy 43.608226 -304.735666) (xy 43.560955 -304.749358)
			(xy 43.5121 -304.75529) (xy 43.462925 -304.753309) (xy 43.414706 -304.743465) (xy 43.36869 -304.726013)
			(xy 43.326069 -304.701406) (xy 43.287948 -304.670281) (xy 43.255313 -304.633444) (xy 43.22901 -304.591848)
			(xy 43.209719 -304.546572) (xy 43.197942 -304.498788) (xy 43.193982 -304.449734) (xy 0.508 -304.449734)
			(xy 0.508 -305.19751) (xy 17.638266 -305.19751) (xy 17.642339 -305.141851) (xy 17.654474 -305.087378)
			(xy 17.67441 -305.035252) (xy 17.701724 -304.986584) (xy 17.735832 -304.942412) (xy 17.776009 -304.903677)
			(xy 17.821397 -304.871205) (xy 17.871029 -304.845687) (xy 17.923849 -304.827668) (xy 17.978728 -304.817531)
			(xy 18.034499 -304.815493) (xy 18.089973 -304.821596) (xy 18.143966 -304.835712) (xy 18.195329 -304.857539)
			(xy 18.242967 -304.886612) (xy 18.285863 -304.922311) (xy 18.323105 -304.963875) (xy 18.353899 -305.010419)
			(xy 18.377587 -305.06095) (xy 18.393665 -305.114392) (xy 18.401791 -305.169606) (xy 18.4023 -305.19751)
			(xy 18.401791 -305.225414) (xy 18.393665 -305.280628) (xy 18.377587 -305.33407) (xy 18.353899 -305.384601)
			(xy 18.343745 -305.399948) (xy 41.294062 -305.399948) (xy 41.298022 -305.350894) (xy 41.309799 -305.30311)
			(xy 41.32909 -305.257834) (xy 41.355393 -305.216238) (xy 41.388028 -305.179401) (xy 41.426149 -305.148276)
			(xy 41.46877 -305.123669) (xy 41.514786 -305.106217) (xy 41.563005 -305.096373) (xy 41.61218 -305.094392)
			(xy 41.661035 -305.100324) (xy 41.708306 -305.114016) (xy 41.752768 -305.135114) (xy 41.793271 -305.16307)
			(xy 41.828764 -305.197162) (xy 41.858329 -305.236506) (xy 41.8812 -305.280083) (xy 41.896784 -305.326764)
			(xy 41.904679 -305.375341) (xy 41.905174 -305.399948) (xy 42.244022 -305.399948) (xy 42.247982 -305.350894)
			(xy 42.259759 -305.30311) (xy 42.27905 -305.257834) (xy 42.305353 -305.216238) (xy 42.337988 -305.179401)
			(xy 42.376109 -305.148276) (xy 42.41873 -305.123669) (xy 42.464746 -305.106217) (xy 42.512965 -305.096373)
			(xy 42.56214 -305.094392) (xy 42.610995 -305.100324) (xy 42.658266 -305.114016) (xy 42.702728 -305.135114)
			(xy 42.743231 -305.16307) (xy 42.778724 -305.197162) (xy 42.808289 -305.236506) (xy 42.83116 -305.280083)
			(xy 42.846744 -305.326764) (xy 42.854639 -305.375341) (xy 42.855134 -305.399948) (xy 76.444106 -305.399948)
			(xy 76.448066 -305.350894) (xy 76.459843 -305.30311) (xy 76.479134 -305.257834) (xy 76.505437 -305.216238)
			(xy 76.538072 -305.179401) (xy 76.576193 -305.148276) (xy 76.618814 -305.123669) (xy 76.66483 -305.106217)
			(xy 76.713049 -305.096373) (xy 76.762224 -305.094392) (xy 76.811079 -305.100324) (xy 76.85835 -305.114016)
			(xy 76.902812 -305.135114) (xy 76.943315 -305.16307) (xy 76.978808 -305.197162) (xy 77.008373 -305.236506)
			(xy 77.031244 -305.280083) (xy 77.046828 -305.326764) (xy 77.054723 -305.375341) (xy 77.055218 -305.399948)
			(xy 77.394066 -305.399948) (xy 77.398026 -305.350894) (xy 77.409803 -305.30311) (xy 77.429094 -305.257834)
			(xy 77.455397 -305.216238) (xy 77.488032 -305.179401) (xy 77.526153 -305.148276) (xy 77.568774 -305.123669)
			(xy 77.61479 -305.106217) (xy 77.663009 -305.096373) (xy 77.712184 -305.094392) (xy 77.761039 -305.100324)
			(xy 77.80831 -305.114016) (xy 77.852772 -305.135114) (xy 77.893275 -305.16307) (xy 77.928768 -305.197162)
			(xy 77.958333 -305.236506) (xy 77.981204 -305.280083) (xy 77.996788 -305.326764) (xy 78.004683 -305.375341)
			(xy 78.005178 -305.399948) (xy 79.293986 -305.399948) (xy 79.297946 -305.350894) (xy 79.309723 -305.30311)
			(xy 79.329014 -305.257834) (xy 79.355317 -305.216238) (xy 79.387952 -305.179401) (xy 79.426073 -305.148276)
			(xy 79.468694 -305.123669) (xy 79.51471 -305.106217) (xy 79.562929 -305.096373) (xy 79.612104 -305.094392)
			(xy 79.660959 -305.100324) (xy 79.70823 -305.114016) (xy 79.752692 -305.135114) (xy 79.793195 -305.16307)
			(xy 79.828688 -305.197162) (xy 79.858253 -305.236506) (xy 79.881124 -305.280083) (xy 79.896708 -305.326764)
			(xy 79.904603 -305.375341) (xy 79.905098 -305.399948) (xy 80.243946 -305.399948) (xy 80.247906 -305.350894)
			(xy 80.259683 -305.30311) (xy 80.278974 -305.257834) (xy 80.305277 -305.216238) (xy 80.337912 -305.179401)
			(xy 80.376033 -305.148276) (xy 80.418654 -305.123669) (xy 80.46467 -305.106217) (xy 80.512889 -305.096373)
			(xy 80.562064 -305.094392) (xy 80.610919 -305.100324) (xy 80.65819 -305.114016) (xy 80.702652 -305.135114)
			(xy 80.743155 -305.16307) (xy 80.778648 -305.197162) (xy 80.808213 -305.236506) (xy 80.831084 -305.280083)
			(xy 80.846668 -305.326764) (xy 80.854563 -305.375341) (xy 80.855058 -305.399948) (xy 154.54428 -305.399948)
			(xy 154.54824 -305.350894) (xy 154.560017 -305.30311) (xy 154.579308 -305.257834) (xy 154.605611 -305.216238)
			(xy 154.638246 -305.179401) (xy 154.676367 -305.148276) (xy 154.718988 -305.123669) (xy 154.765004 -305.106217)
			(xy 154.813223 -305.096373) (xy 154.862398 -305.094392) (xy 154.911253 -305.100324) (xy 154.958524 -305.114016)
			(xy 155.002986 -305.135114) (xy 155.043489 -305.16307) (xy 155.078982 -305.197162) (xy 155.108547 -305.236506)
			(xy 155.131418 -305.280083) (xy 155.147002 -305.326764) (xy 155.154897 -305.375341) (xy 155.155392 -305.399948)
			(xy 155.49424 -305.399948) (xy 155.4982 -305.350894) (xy 155.509977 -305.30311) (xy 155.529268 -305.257834)
			(xy 155.555571 -305.216238) (xy 155.588206 -305.179401) (xy 155.626327 -305.148276) (xy 155.668948 -305.123669)
			(xy 155.714964 -305.106217) (xy 155.763183 -305.096373) (xy 155.812358 -305.094392) (xy 155.861213 -305.100324)
			(xy 155.908484 -305.114016) (xy 155.952946 -305.135114) (xy 155.993449 -305.16307) (xy 156.028942 -305.197162)
			(xy 156.058507 -305.236506) (xy 156.081378 -305.280083) (xy 156.096962 -305.326764) (xy 156.104857 -305.375341)
			(xy 156.105352 -305.399948) (xy 157.39416 -305.399948) (xy 157.39812 -305.350894) (xy 157.409897 -305.30311)
			(xy 157.429188 -305.257834) (xy 157.455491 -305.216238) (xy 157.488126 -305.179401) (xy 157.526247 -305.148276)
			(xy 157.568868 -305.123669) (xy 157.614884 -305.106217) (xy 157.663103 -305.096373) (xy 157.712278 -305.094392)
			(xy 157.761133 -305.100324) (xy 157.808404 -305.114016) (xy 157.852866 -305.135114) (xy 157.893369 -305.16307)
			(xy 157.928862 -305.197162) (xy 157.958427 -305.236506) (xy 157.981298 -305.280083) (xy 157.996882 -305.326764)
			(xy 158.004777 -305.375341) (xy 158.005272 -305.399948) (xy 158.34412 -305.399948) (xy 158.34808 -305.350894)
			(xy 158.359857 -305.30311) (xy 158.379148 -305.257834) (xy 158.405451 -305.216238) (xy 158.438086 -305.179401)
			(xy 158.476207 -305.148276) (xy 158.518828 -305.123669) (xy 158.564844 -305.106217) (xy 158.613063 -305.096373)
			(xy 158.662238 -305.094392) (xy 158.711093 -305.100324) (xy 158.758364 -305.114016) (xy 158.802826 -305.135114)
			(xy 158.843329 -305.16307) (xy 158.878822 -305.197162) (xy 158.908387 -305.236506) (xy 158.931258 -305.280083)
			(xy 158.946842 -305.326764) (xy 158.954737 -305.375341) (xy 158.955232 -305.399948) (xy 192.544204 -305.399948)
			(xy 192.548164 -305.350894) (xy 192.559941 -305.30311) (xy 192.579232 -305.257834) (xy 192.605535 -305.216238)
			(xy 192.63817 -305.179401) (xy 192.676291 -305.148276) (xy 192.718912 -305.123669) (xy 192.764928 -305.106217)
			(xy 192.813147 -305.096373) (xy 192.862322 -305.094392) (xy 192.911177 -305.100324) (xy 192.958448 -305.114016)
			(xy 193.00291 -305.135114) (xy 193.043413 -305.16307) (xy 193.078906 -305.197162) (xy 193.108471 -305.236506)
			(xy 193.131342 -305.280083) (xy 193.146926 -305.326764) (xy 193.154821 -305.375341) (xy 193.155316 -305.399948)
			(xy 193.494164 -305.399948) (xy 193.498124 -305.350894) (xy 193.509901 -305.30311) (xy 193.529192 -305.257834)
			(xy 193.555495 -305.216238) (xy 193.58813 -305.179401) (xy 193.626251 -305.148276) (xy 193.668872 -305.123669)
			(xy 193.714888 -305.106217) (xy 193.763107 -305.096373) (xy 193.812282 -305.094392) (xy 193.861137 -305.100324)
			(xy 193.908408 -305.114016) (xy 193.95287 -305.135114) (xy 193.993373 -305.16307) (xy 194.028866 -305.197162)
			(xy 194.058431 -305.236506) (xy 194.081302 -305.280083) (xy 194.096886 -305.326764) (xy 194.104781 -305.375341)
			(xy 194.105276 -305.399948) (xy 273.494004 -305.399948) (xy 273.497964 -305.350894) (xy 273.509741 -305.30311)
			(xy 273.529032 -305.257834) (xy 273.555335 -305.216238) (xy 273.58797 -305.179401) (xy 273.626091 -305.148276)
			(xy 273.668712 -305.123669) (xy 273.714728 -305.106217) (xy 273.762947 -305.096373) (xy 273.812122 -305.094392)
			(xy 273.860977 -305.100324) (xy 273.908248 -305.114016) (xy 273.95271 -305.135114) (xy 273.993213 -305.16307)
			(xy 274.028706 -305.197162) (xy 274.058271 -305.236506) (xy 274.081142 -305.280083) (xy 274.096726 -305.326764)
			(xy 274.104621 -305.375341) (xy 274.105116 -305.399948) (xy 274.443964 -305.399948) (xy 274.447924 -305.350894)
			(xy 274.459701 -305.30311) (xy 274.478992 -305.257834) (xy 274.505295 -305.216238) (xy 274.53793 -305.179401)
			(xy 274.576051 -305.148276) (xy 274.618672 -305.123669) (xy 274.664688 -305.106217) (xy 274.712907 -305.096373)
			(xy 274.762082 -305.094392) (xy 274.810937 -305.100324) (xy 274.858208 -305.114016) (xy 274.90267 -305.135114)
			(xy 274.943173 -305.16307) (xy 274.978666 -305.197162) (xy 275.008231 -305.236506) (xy 275.031102 -305.280083)
			(xy 275.046686 -305.326764) (xy 275.054581 -305.375341) (xy 275.055076 -305.399948) (xy 308.644048 -305.399948)
			(xy 308.648008 -305.350894) (xy 308.659785 -305.30311) (xy 308.679076 -305.257834) (xy 308.705379 -305.216238)
			(xy 308.738014 -305.179401) (xy 308.776135 -305.148276) (xy 308.818756 -305.123669) (xy 308.864772 -305.106217)
			(xy 308.912991 -305.096373) (xy 308.962166 -305.094392) (xy 309.011021 -305.100324) (xy 309.058292 -305.114016)
			(xy 309.102754 -305.135114) (xy 309.143257 -305.16307) (xy 309.17875 -305.197162) (xy 309.208315 -305.236506)
			(xy 309.231186 -305.280083) (xy 309.24677 -305.326764) (xy 309.254665 -305.375341) (xy 309.25516 -305.399948)
			(xy 309.594008 -305.399948) (xy 309.597968 -305.350894) (xy 309.609745 -305.30311) (xy 309.629036 -305.257834)
			(xy 309.655339 -305.216238) (xy 309.687974 -305.179401) (xy 309.726095 -305.148276) (xy 309.768716 -305.123669)
			(xy 309.814732 -305.106217) (xy 309.862951 -305.096373) (xy 309.912126 -305.094392) (xy 309.960981 -305.100324)
			(xy 310.008252 -305.114016) (xy 310.052714 -305.135114) (xy 310.093217 -305.16307) (xy 310.12871 -305.197162)
			(xy 310.158275 -305.236506) (xy 310.181146 -305.280083) (xy 310.19673 -305.326764) (xy 310.204625 -305.375341)
			(xy 310.20512 -305.399948) (xy 311.493928 -305.399948) (xy 311.497888 -305.350894) (xy 311.509665 -305.30311)
			(xy 311.528956 -305.257834) (xy 311.555259 -305.216238) (xy 311.587894 -305.179401) (xy 311.626015 -305.148276)
			(xy 311.668636 -305.123669) (xy 311.714652 -305.106217) (xy 311.762871 -305.096373) (xy 311.812046 -305.094392)
			(xy 311.860901 -305.100324) (xy 311.908172 -305.114016) (xy 311.952634 -305.135114) (xy 311.993137 -305.16307)
			(xy 312.02863 -305.197162) (xy 312.058195 -305.236506) (xy 312.081066 -305.280083) (xy 312.09665 -305.326764)
			(xy 312.104545 -305.375341) (xy 312.10504 -305.399948) (xy 312.443888 -305.399948) (xy 312.447848 -305.350894)
			(xy 312.459625 -305.30311) (xy 312.478916 -305.257834) (xy 312.505219 -305.216238) (xy 312.537854 -305.179401)
			(xy 312.575975 -305.148276) (xy 312.618596 -305.123669) (xy 312.664612 -305.106217) (xy 312.712831 -305.096373)
			(xy 312.762006 -305.094392) (xy 312.810861 -305.100324) (xy 312.858132 -305.114016) (xy 312.902594 -305.135114)
			(xy 312.943097 -305.16307) (xy 312.97859 -305.197162) (xy 313.008155 -305.236506) (xy 313.031026 -305.280083)
			(xy 313.04661 -305.326764) (xy 313.054505 -305.375341) (xy 313.055 -305.399948) (xy 386.744222 -305.399948)
			(xy 386.748182 -305.350894) (xy 386.759959 -305.30311) (xy 386.77925 -305.257834) (xy 386.805553 -305.216238)
			(xy 386.838188 -305.179401) (xy 386.876309 -305.148276) (xy 386.91893 -305.123669) (xy 386.964946 -305.106217)
			(xy 387.013165 -305.096373) (xy 387.06234 -305.094392) (xy 387.111195 -305.100324) (xy 387.158466 -305.114016)
			(xy 387.202928 -305.135114) (xy 387.243431 -305.16307) (xy 387.278924 -305.197162) (xy 387.308489 -305.236506)
			(xy 387.33136 -305.280083) (xy 387.346944 -305.326764) (xy 387.354839 -305.375341) (xy 387.355334 -305.399948)
			(xy 387.694182 -305.399948) (xy 387.698142 -305.350894) (xy 387.709919 -305.30311) (xy 387.72921 -305.257834)
			(xy 387.755513 -305.216238) (xy 387.788148 -305.179401) (xy 387.826269 -305.148276) (xy 387.86889 -305.123669)
			(xy 387.914906 -305.106217) (xy 387.963125 -305.096373) (xy 388.0123 -305.094392) (xy 388.061155 -305.100324)
			(xy 388.108426 -305.114016) (xy 388.152888 -305.135114) (xy 388.193391 -305.16307) (xy 388.228884 -305.197162)
			(xy 388.258449 -305.236506) (xy 388.28132 -305.280083) (xy 388.296904 -305.326764) (xy 388.304799 -305.375341)
			(xy 388.305294 -305.399948) (xy 389.594102 -305.399948) (xy 389.598062 -305.350894) (xy 389.609839 -305.30311)
			(xy 389.62913 -305.257834) (xy 389.655433 -305.216238) (xy 389.688068 -305.179401) (xy 389.726189 -305.148276)
			(xy 389.76881 -305.123669) (xy 389.814826 -305.106217) (xy 389.863045 -305.096373) (xy 389.91222 -305.094392)
			(xy 389.961075 -305.100324) (xy 390.008346 -305.114016) (xy 390.052808 -305.135114) (xy 390.093311 -305.16307)
			(xy 390.128804 -305.197162) (xy 390.158369 -305.236506) (xy 390.18124 -305.280083) (xy 390.196824 -305.326764)
			(xy 390.204719 -305.375341) (xy 390.205214 -305.399948) (xy 390.544062 -305.399948) (xy 390.548022 -305.350894)
			(xy 390.559799 -305.30311) (xy 390.57909 -305.257834) (xy 390.605393 -305.216238) (xy 390.638028 -305.179401)
			(xy 390.676149 -305.148276) (xy 390.71877 -305.123669) (xy 390.764786 -305.106217) (xy 390.813005 -305.096373)
			(xy 390.86218 -305.094392) (xy 390.911035 -305.100324) (xy 390.958306 -305.114016) (xy 391.002768 -305.135114)
			(xy 391.043271 -305.16307) (xy 391.078764 -305.197162) (xy 391.108329 -305.236506) (xy 391.1312 -305.280083)
			(xy 391.146784 -305.326764) (xy 391.154679 -305.375341) (xy 391.155174 -305.399948) (xy 424.744146 -305.399948)
			(xy 424.748106 -305.350894) (xy 424.759883 -305.30311) (xy 424.779174 -305.257834) (xy 424.805477 -305.216238)
			(xy 424.838112 -305.179401) (xy 424.876233 -305.148276) (xy 424.918854 -305.123669) (xy 424.96487 -305.106217)
			(xy 425.013089 -305.096373) (xy 425.062264 -305.094392) (xy 425.111119 -305.100324) (xy 425.15839 -305.114016)
			(xy 425.202852 -305.135114) (xy 425.243355 -305.16307) (xy 425.278848 -305.197162) (xy 425.308413 -305.236506)
			(xy 425.331284 -305.280083) (xy 425.346868 -305.326764) (xy 425.354763 -305.375341) (xy 425.355258 -305.399948)
			(xy 425.694106 -305.399948) (xy 425.698066 -305.350894) (xy 425.709843 -305.30311) (xy 425.729134 -305.257834)
			(xy 425.755437 -305.216238) (xy 425.788072 -305.179401) (xy 425.826193 -305.148276) (xy 425.868814 -305.123669)
			(xy 425.91483 -305.106217) (xy 425.963049 -305.096373) (xy 426.012224 -305.094392) (xy 426.061079 -305.100324)
			(xy 426.10835 -305.114016) (xy 426.152812 -305.135114) (xy 426.193315 -305.16307) (xy 426.228808 -305.197162)
			(xy 426.258373 -305.236506) (xy 426.281244 -305.280083) (xy 426.296828 -305.326764) (xy 426.304723 -305.375341)
			(xy 426.305218 -305.399948) (xy 426.304723 -305.424555) (xy 426.296828 -305.473132) (xy 426.281244 -305.519813)
			(xy 426.258373 -305.56339) (xy 426.228808 -305.602734) (xy 426.193315 -305.636826) (xy 426.152812 -305.664782)
			(xy 426.10835 -305.68588) (xy 426.061079 -305.699572) (xy 426.012224 -305.705504) (xy 425.963049 -305.703523)
			(xy 425.91483 -305.693679) (xy 425.868814 -305.676227) (xy 425.826193 -305.65162) (xy 425.788072 -305.620495)
			(xy 425.755437 -305.583658) (xy 425.729134 -305.542062) (xy 425.709843 -305.496786) (xy 425.698066 -305.449002)
			(xy 425.694106 -305.399948) (xy 425.355258 -305.399948) (xy 425.354763 -305.424555) (xy 425.346868 -305.473132)
			(xy 425.331284 -305.519813) (xy 425.308413 -305.56339) (xy 425.278848 -305.602734) (xy 425.243355 -305.636826)
			(xy 425.202852 -305.664782) (xy 425.15839 -305.68588) (xy 425.111119 -305.699572) (xy 425.062264 -305.705504)
			(xy 425.013089 -305.703523) (xy 424.96487 -305.693679) (xy 424.918854 -305.676227) (xy 424.876233 -305.65162)
			(xy 424.838112 -305.620495) (xy 424.805477 -305.583658) (xy 424.779174 -305.542062) (xy 424.759883 -305.496786)
			(xy 424.748106 -305.449002) (xy 424.744146 -305.399948) (xy 391.155174 -305.399948) (xy 391.154679 -305.424555)
			(xy 391.146784 -305.473132) (xy 391.1312 -305.519813) (xy 391.108329 -305.56339) (xy 391.078764 -305.602734)
			(xy 391.043271 -305.636826) (xy 391.002768 -305.664782) (xy 390.958306 -305.68588) (xy 390.911035 -305.699572)
			(xy 390.86218 -305.705504) (xy 390.813005 -305.703523) (xy 390.764786 -305.693679) (xy 390.71877 -305.676227)
			(xy 390.676149 -305.65162) (xy 390.638028 -305.620495) (xy 390.605393 -305.583658) (xy 390.57909 -305.542062)
			(xy 390.559799 -305.496786) (xy 390.548022 -305.449002) (xy 390.544062 -305.399948) (xy 390.205214 -305.399948)
			(xy 390.204719 -305.424555) (xy 390.196824 -305.473132) (xy 390.18124 -305.519813) (xy 390.158369 -305.56339)
			(xy 390.128804 -305.602734) (xy 390.093311 -305.636826) (xy 390.052808 -305.664782) (xy 390.008346 -305.68588)
			(xy 389.961075 -305.699572) (xy 389.91222 -305.705504) (xy 389.863045 -305.703523) (xy 389.814826 -305.693679)
			(xy 389.76881 -305.676227) (xy 389.726189 -305.65162) (xy 389.688068 -305.620495) (xy 389.655433 -305.583658)
			(xy 389.62913 -305.542062) (xy 389.609839 -305.496786) (xy 389.598062 -305.449002) (xy 389.594102 -305.399948)
			(xy 388.305294 -305.399948) (xy 388.304799 -305.424555) (xy 388.296904 -305.473132) (xy 388.28132 -305.519813)
			(xy 388.258449 -305.56339) (xy 388.228884 -305.602734) (xy 388.193391 -305.636826) (xy 388.152888 -305.664782)
			(xy 388.108426 -305.68588) (xy 388.061155 -305.699572) (xy 388.0123 -305.705504) (xy 387.963125 -305.703523)
			(xy 387.914906 -305.693679) (xy 387.86889 -305.676227) (xy 387.826269 -305.65162) (xy 387.788148 -305.620495)
			(xy 387.755513 -305.583658) (xy 387.72921 -305.542062) (xy 387.709919 -305.496786) (xy 387.698142 -305.449002)
			(xy 387.694182 -305.399948) (xy 387.355334 -305.399948) (xy 387.354839 -305.424555) (xy 387.346944 -305.473132)
			(xy 387.33136 -305.519813) (xy 387.308489 -305.56339) (xy 387.278924 -305.602734) (xy 387.243431 -305.636826)
			(xy 387.202928 -305.664782) (xy 387.158466 -305.68588) (xy 387.111195 -305.699572) (xy 387.06234 -305.705504)
			(xy 387.013165 -305.703523) (xy 386.964946 -305.693679) (xy 386.91893 -305.676227) (xy 386.876309 -305.65162)
			(xy 386.838188 -305.620495) (xy 386.805553 -305.583658) (xy 386.77925 -305.542062) (xy 386.759959 -305.496786)
			(xy 386.748182 -305.449002) (xy 386.744222 -305.399948) (xy 313.055 -305.399948) (xy 313.054505 -305.424555)
			(xy 313.04661 -305.473132) (xy 313.031026 -305.519813) (xy 313.008155 -305.56339) (xy 312.97859 -305.602734)
			(xy 312.943097 -305.636826) (xy 312.902594 -305.664782) (xy 312.858132 -305.68588) (xy 312.810861 -305.699572)
			(xy 312.762006 -305.705504) (xy 312.712831 -305.703523) (xy 312.664612 -305.693679) (xy 312.618596 -305.676227)
			(xy 312.575975 -305.65162) (xy 312.537854 -305.620495) (xy 312.505219 -305.583658) (xy 312.478916 -305.542062)
			(xy 312.459625 -305.496786) (xy 312.447848 -305.449002) (xy 312.443888 -305.399948) (xy 312.10504 -305.399948)
			(xy 312.104545 -305.424555) (xy 312.09665 -305.473132) (xy 312.081066 -305.519813) (xy 312.058195 -305.56339)
			(xy 312.02863 -305.602734) (xy 311.993137 -305.636826) (xy 311.952634 -305.664782) (xy 311.908172 -305.68588)
			(xy 311.860901 -305.699572) (xy 311.812046 -305.705504) (xy 311.762871 -305.703523) (xy 311.714652 -305.693679)
			(xy 311.668636 -305.676227) (xy 311.626015 -305.65162) (xy 311.587894 -305.620495) (xy 311.555259 -305.583658)
			(xy 311.528956 -305.542062) (xy 311.509665 -305.496786) (xy 311.497888 -305.449002) (xy 311.493928 -305.399948)
			(xy 310.20512 -305.399948) (xy 310.204625 -305.424555) (xy 310.19673 -305.473132) (xy 310.181146 -305.519813)
			(xy 310.158275 -305.56339) (xy 310.12871 -305.602734) (xy 310.093217 -305.636826) (xy 310.052714 -305.664782)
			(xy 310.008252 -305.68588) (xy 309.960981 -305.699572) (xy 309.912126 -305.705504) (xy 309.862951 -305.703523)
			(xy 309.814732 -305.693679) (xy 309.768716 -305.676227) (xy 309.726095 -305.65162) (xy 309.687974 -305.620495)
			(xy 309.655339 -305.583658) (xy 309.629036 -305.542062) (xy 309.609745 -305.496786) (xy 309.597968 -305.449002)
			(xy 309.594008 -305.399948) (xy 309.25516 -305.399948) (xy 309.254665 -305.424555) (xy 309.24677 -305.473132)
			(xy 309.231186 -305.519813) (xy 309.208315 -305.56339) (xy 309.17875 -305.602734) (xy 309.143257 -305.636826)
			(xy 309.102754 -305.664782) (xy 309.058292 -305.68588) (xy 309.011021 -305.699572) (xy 308.962166 -305.705504)
			(xy 308.912991 -305.703523) (xy 308.864772 -305.693679) (xy 308.818756 -305.676227) (xy 308.776135 -305.65162)
			(xy 308.738014 -305.620495) (xy 308.705379 -305.583658) (xy 308.679076 -305.542062) (xy 308.659785 -305.496786)
			(xy 308.648008 -305.449002) (xy 308.644048 -305.399948) (xy 275.055076 -305.399948) (xy 275.054581 -305.424555)
			(xy 275.046686 -305.473132) (xy 275.031102 -305.519813) (xy 275.008231 -305.56339) (xy 274.978666 -305.602734)
			(xy 274.943173 -305.636826) (xy 274.90267 -305.664782) (xy 274.858208 -305.68588) (xy 274.810937 -305.699572)
			(xy 274.762082 -305.705504) (xy 274.712907 -305.703523) (xy 274.664688 -305.693679) (xy 274.618672 -305.676227)
			(xy 274.576051 -305.65162) (xy 274.53793 -305.620495) (xy 274.505295 -305.583658) (xy 274.478992 -305.542062)
			(xy 274.459701 -305.496786) (xy 274.447924 -305.449002) (xy 274.443964 -305.399948) (xy 274.105116 -305.399948)
			(xy 274.104621 -305.424555) (xy 274.096726 -305.473132) (xy 274.081142 -305.519813) (xy 274.058271 -305.56339)
			(xy 274.028706 -305.602734) (xy 273.993213 -305.636826) (xy 273.95271 -305.664782) (xy 273.908248 -305.68588)
			(xy 273.860977 -305.699572) (xy 273.812122 -305.705504) (xy 273.762947 -305.703523) (xy 273.714728 -305.693679)
			(xy 273.668712 -305.676227) (xy 273.626091 -305.65162) (xy 273.58797 -305.620495) (xy 273.555335 -305.583658)
			(xy 273.529032 -305.542062) (xy 273.509741 -305.496786) (xy 273.497964 -305.449002) (xy 273.494004 -305.399948)
			(xy 194.105276 -305.399948) (xy 194.104781 -305.424555) (xy 194.096886 -305.473132) (xy 194.081302 -305.519813)
			(xy 194.058431 -305.56339) (xy 194.028866 -305.602734) (xy 193.993373 -305.636826) (xy 193.95287 -305.664782)
			(xy 193.908408 -305.68588) (xy 193.861137 -305.699572) (xy 193.812282 -305.705504) (xy 193.763107 -305.703523)
			(xy 193.714888 -305.693679) (xy 193.668872 -305.676227) (xy 193.626251 -305.65162) (xy 193.58813 -305.620495)
			(xy 193.555495 -305.583658) (xy 193.529192 -305.542062) (xy 193.509901 -305.496786) (xy 193.498124 -305.449002)
			(xy 193.494164 -305.399948) (xy 193.155316 -305.399948) (xy 193.154821 -305.424555) (xy 193.146926 -305.473132)
			(xy 193.131342 -305.519813) (xy 193.108471 -305.56339) (xy 193.078906 -305.602734) (xy 193.043413 -305.636826)
			(xy 193.00291 -305.664782) (xy 192.958448 -305.68588) (xy 192.911177 -305.699572) (xy 192.862322 -305.705504)
			(xy 192.813147 -305.703523) (xy 192.764928 -305.693679) (xy 192.718912 -305.676227) (xy 192.676291 -305.65162)
			(xy 192.63817 -305.620495) (xy 192.605535 -305.583658) (xy 192.579232 -305.542062) (xy 192.559941 -305.496786)
			(xy 192.548164 -305.449002) (xy 192.544204 -305.399948) (xy 158.955232 -305.399948) (xy 158.954737 -305.424555)
			(xy 158.946842 -305.473132) (xy 158.931258 -305.519813) (xy 158.908387 -305.56339) (xy 158.878822 -305.602734)
			(xy 158.843329 -305.636826) (xy 158.802826 -305.664782) (xy 158.758364 -305.68588) (xy 158.711093 -305.699572)
			(xy 158.662238 -305.705504) (xy 158.613063 -305.703523) (xy 158.564844 -305.693679) (xy 158.518828 -305.676227)
			(xy 158.476207 -305.65162) (xy 158.438086 -305.620495) (xy 158.405451 -305.583658) (xy 158.379148 -305.542062)
			(xy 158.359857 -305.496786) (xy 158.34808 -305.449002) (xy 158.34412 -305.399948) (xy 158.005272 -305.399948)
			(xy 158.004777 -305.424555) (xy 157.996882 -305.473132) (xy 157.981298 -305.519813) (xy 157.958427 -305.56339)
			(xy 157.928862 -305.602734) (xy 157.893369 -305.636826) (xy 157.852866 -305.664782) (xy 157.808404 -305.68588)
			(xy 157.761133 -305.699572) (xy 157.712278 -305.705504) (xy 157.663103 -305.703523) (xy 157.614884 -305.693679)
			(xy 157.568868 -305.676227) (xy 157.526247 -305.65162) (xy 157.488126 -305.620495) (xy 157.455491 -305.583658)
			(xy 157.429188 -305.542062) (xy 157.409897 -305.496786) (xy 157.39812 -305.449002) (xy 157.39416 -305.399948)
			(xy 156.105352 -305.399948) (xy 156.104857 -305.424555) (xy 156.096962 -305.473132) (xy 156.081378 -305.519813)
			(xy 156.058507 -305.56339) (xy 156.028942 -305.602734) (xy 155.993449 -305.636826) (xy 155.952946 -305.664782)
			(xy 155.908484 -305.68588) (xy 155.861213 -305.699572) (xy 155.812358 -305.705504) (xy 155.763183 -305.703523)
			(xy 155.714964 -305.693679) (xy 155.668948 -305.676227) (xy 155.626327 -305.65162) (xy 155.588206 -305.620495)
			(xy 155.555571 -305.583658) (xy 155.529268 -305.542062) (xy 155.509977 -305.496786) (xy 155.4982 -305.449002)
			(xy 155.49424 -305.399948) (xy 155.155392 -305.399948) (xy 155.154897 -305.424555) (xy 155.147002 -305.473132)
			(xy 155.131418 -305.519813) (xy 155.108547 -305.56339) (xy 155.078982 -305.602734) (xy 155.043489 -305.636826)
			(xy 155.002986 -305.664782) (xy 154.958524 -305.68588) (xy 154.911253 -305.699572) (xy 154.862398 -305.705504)
			(xy 154.813223 -305.703523) (xy 154.765004 -305.693679) (xy 154.718988 -305.676227) (xy 154.676367 -305.65162)
			(xy 154.638246 -305.620495) (xy 154.605611 -305.583658) (xy 154.579308 -305.542062) (xy 154.560017 -305.496786)
			(xy 154.54824 -305.449002) (xy 154.54428 -305.399948) (xy 80.855058 -305.399948) (xy 80.854563 -305.424555)
			(xy 80.846668 -305.473132) (xy 80.831084 -305.519813) (xy 80.808213 -305.56339) (xy 80.778648 -305.602734)
			(xy 80.743155 -305.636826) (xy 80.702652 -305.664782) (xy 80.65819 -305.68588) (xy 80.610919 -305.699572)
			(xy 80.562064 -305.705504) (xy 80.512889 -305.703523) (xy 80.46467 -305.693679) (xy 80.418654 -305.676227)
			(xy 80.376033 -305.65162) (xy 80.337912 -305.620495) (xy 80.305277 -305.583658) (xy 80.278974 -305.542062)
			(xy 80.259683 -305.496786) (xy 80.247906 -305.449002) (xy 80.243946 -305.399948) (xy 79.905098 -305.399948)
			(xy 79.904603 -305.424555) (xy 79.896708 -305.473132) (xy 79.881124 -305.519813) (xy 79.858253 -305.56339)
			(xy 79.828688 -305.602734) (xy 79.793195 -305.636826) (xy 79.752692 -305.664782) (xy 79.70823 -305.68588)
			(xy 79.660959 -305.699572) (xy 79.612104 -305.705504) (xy 79.562929 -305.703523) (xy 79.51471 -305.693679)
			(xy 79.468694 -305.676227) (xy 79.426073 -305.65162) (xy 79.387952 -305.620495) (xy 79.355317 -305.583658)
			(xy 79.329014 -305.542062) (xy 79.309723 -305.496786) (xy 79.297946 -305.449002) (xy 79.293986 -305.399948)
			(xy 78.005178 -305.399948) (xy 78.004683 -305.424555) (xy 77.996788 -305.473132) (xy 77.981204 -305.519813)
			(xy 77.958333 -305.56339) (xy 77.928768 -305.602734) (xy 77.893275 -305.636826) (xy 77.852772 -305.664782)
			(xy 77.80831 -305.68588) (xy 77.761039 -305.699572) (xy 77.712184 -305.705504) (xy 77.663009 -305.703523)
			(xy 77.61479 -305.693679) (xy 77.568774 -305.676227) (xy 77.526153 -305.65162) (xy 77.488032 -305.620495)
			(xy 77.455397 -305.583658) (xy 77.429094 -305.542062) (xy 77.409803 -305.496786) (xy 77.398026 -305.449002)
			(xy 77.394066 -305.399948) (xy 77.055218 -305.399948) (xy 77.054723 -305.424555) (xy 77.046828 -305.473132)
			(xy 77.031244 -305.519813) (xy 77.008373 -305.56339) (xy 76.978808 -305.602734) (xy 76.943315 -305.636826)
			(xy 76.902812 -305.664782) (xy 76.85835 -305.68588) (xy 76.811079 -305.699572) (xy 76.762224 -305.705504)
			(xy 76.713049 -305.703523) (xy 76.66483 -305.693679) (xy 76.618814 -305.676227) (xy 76.576193 -305.65162)
			(xy 76.538072 -305.620495) (xy 76.505437 -305.583658) (xy 76.479134 -305.542062) (xy 76.459843 -305.496786)
			(xy 76.448066 -305.449002) (xy 76.444106 -305.399948) (xy 42.855134 -305.399948) (xy 42.854639 -305.424555)
			(xy 42.846744 -305.473132) (xy 42.83116 -305.519813) (xy 42.808289 -305.56339) (xy 42.778724 -305.602734)
			(xy 42.743231 -305.636826) (xy 42.702728 -305.664782) (xy 42.658266 -305.68588) (xy 42.610995 -305.699572)
			(xy 42.56214 -305.705504) (xy 42.512965 -305.703523) (xy 42.464746 -305.693679) (xy 42.41873 -305.676227)
			(xy 42.376109 -305.65162) (xy 42.337988 -305.620495) (xy 42.305353 -305.583658) (xy 42.27905 -305.542062)
			(xy 42.259759 -305.496786) (xy 42.247982 -305.449002) (xy 42.244022 -305.399948) (xy 41.905174 -305.399948)
			(xy 41.904679 -305.424555) (xy 41.896784 -305.473132) (xy 41.8812 -305.519813) (xy 41.858329 -305.56339)
			(xy 41.828764 -305.602734) (xy 41.793271 -305.636826) (xy 41.752768 -305.664782) (xy 41.708306 -305.68588)
			(xy 41.661035 -305.699572) (xy 41.61218 -305.705504) (xy 41.563005 -305.703523) (xy 41.514786 -305.693679)
			(xy 41.46877 -305.676227) (xy 41.426149 -305.65162) (xy 41.388028 -305.620495) (xy 41.355393 -305.583658)
			(xy 41.32909 -305.542062) (xy 41.309799 -305.496786) (xy 41.298022 -305.449002) (xy 41.294062 -305.399948)
			(xy 18.343745 -305.399948) (xy 18.323105 -305.431145) (xy 18.285863 -305.472709) (xy 18.242967 -305.508408)
			(xy 18.195329 -305.537481) (xy 18.143966 -305.559308) (xy 18.089973 -305.573424) (xy 18.034499 -305.579527)
			(xy 17.978728 -305.577489) (xy 17.923849 -305.567352) (xy 17.871029 -305.549333) (xy 17.821397 -305.523815)
			(xy 17.776009 -305.491343) (xy 17.735832 -305.452608) (xy 17.701724 -305.408436) (xy 17.67441 -305.359768)
			(xy 17.654474 -305.307642) (xy 17.642339 -305.253169) (xy 17.638266 -305.19751) (xy 0.508 -305.19751)
			(xy 0.508 -306.28209) (xy 17.638266 -306.28209) (xy 17.642339 -306.226431) (xy 17.654474 -306.171958)
			(xy 17.67441 -306.119832) (xy 17.701724 -306.071164) (xy 17.735832 -306.026992) (xy 17.776009 -305.988257)
			(xy 17.821397 -305.955785) (xy 17.871029 -305.930267) (xy 17.923849 -305.912248) (xy 17.978728 -305.902111)
			(xy 18.034499 -305.900073) (xy 18.089973 -305.906176) (xy 18.143966 -305.920292) (xy 18.195329 -305.942119)
			(xy 18.242967 -305.971192) (xy 18.285863 -306.006891) (xy 18.323105 -306.048455) (xy 18.353899 -306.094999)
			(xy 18.377587 -306.14553) (xy 18.393665 -306.198972) (xy 18.401791 -306.254186) (xy 18.4023 -306.28209)
			(xy 18.401791 -306.309994) (xy 18.395917 -306.349908) (xy 43.193982 -306.349908) (xy 43.197942 -306.300854)
			(xy 43.209719 -306.25307) (xy 43.22901 -306.207794) (xy 43.255313 -306.166198) (xy 43.287948 -306.129361)
			(xy 43.326069 -306.098236) (xy 43.36869 -306.073629) (xy 43.414706 -306.056177) (xy 43.462925 -306.046333)
			(xy 43.5121 -306.044352) (xy 43.560955 -306.050284) (xy 43.608226 -306.063976) (xy 43.652688 -306.085074)
			(xy 43.693191 -306.11303) (xy 43.728684 -306.147122) (xy 43.758249 -306.186466) (xy 43.78112 -306.230043)
			(xy 43.796704 -306.276724) (xy 43.804599 -306.325301) (xy 43.805094 -306.349908) (xy 44.143942 -306.349908)
			(xy 44.147902 -306.300854) (xy 44.159679 -306.25307) (xy 44.17897 -306.207794) (xy 44.205273 -306.166198)
			(xy 44.237908 -306.129361) (xy 44.276029 -306.098236) (xy 44.31865 -306.073629) (xy 44.364666 -306.056177)
			(xy 44.412885 -306.046333) (xy 44.46206 -306.044352) (xy 44.510915 -306.050284) (xy 44.558186 -306.063976)
			(xy 44.602648 -306.085074) (xy 44.643151 -306.11303) (xy 44.678644 -306.147122) (xy 44.708209 -306.186466)
			(xy 44.73108 -306.230043) (xy 44.746664 -306.276724) (xy 44.754559 -306.325301) (xy 44.755054 -306.349908)
			(xy 74.544186 -306.349908) (xy 74.548146 -306.300854) (xy 74.559923 -306.25307) (xy 74.579214 -306.207794)
			(xy 74.605517 -306.166198) (xy 74.638152 -306.129361) (xy 74.676273 -306.098236) (xy 74.718894 -306.073629)
			(xy 74.76491 -306.056177) (xy 74.813129 -306.046333) (xy 74.862304 -306.044352) (xy 74.911159 -306.050284)
			(xy 74.95843 -306.063976) (xy 75.002892 -306.085074) (xy 75.043395 -306.11303) (xy 75.078888 -306.147122)
			(xy 75.108453 -306.186466) (xy 75.131324 -306.230043) (xy 75.146908 -306.276724) (xy 75.154803 -306.325301)
			(xy 75.155298 -306.349908) (xy 75.494146 -306.349908) (xy 75.498106 -306.300854) (xy 75.509883 -306.25307)
			(xy 75.529174 -306.207794) (xy 75.555477 -306.166198) (xy 75.588112 -306.129361) (xy 75.626233 -306.098236)
			(xy 75.668854 -306.073629) (xy 75.71487 -306.056177) (xy 75.763089 -306.046333) (xy 75.812264 -306.044352)
			(xy 75.861119 -306.050284) (xy 75.90839 -306.063976) (xy 75.952852 -306.085074) (xy 75.993355 -306.11303)
			(xy 76.028848 -306.147122) (xy 76.058413 -306.186466) (xy 76.081284 -306.230043) (xy 76.096868 -306.276724)
			(xy 76.104763 -306.325301) (xy 76.105258 -306.349908) (xy 81.19416 -306.349908) (xy 81.19812 -306.300854)
			(xy 81.209897 -306.25307) (xy 81.229188 -306.207794) (xy 81.255491 -306.166198) (xy 81.288126 -306.129361)
			(xy 81.326247 -306.098236) (xy 81.368868 -306.073629) (xy 81.414884 -306.056177) (xy 81.463103 -306.046333)
			(xy 81.512278 -306.044352) (xy 81.561133 -306.050284) (xy 81.608404 -306.063976) (xy 81.652866 -306.085074)
			(xy 81.693369 -306.11303) (xy 81.728862 -306.147122) (xy 81.758427 -306.186466) (xy 81.781298 -306.230043)
			(xy 81.796882 -306.276724) (xy 81.804777 -306.325301) (xy 81.805272 -306.349908) (xy 82.14412 -306.349908)
			(xy 82.14808 -306.300854) (xy 82.159857 -306.25307) (xy 82.179148 -306.207794) (xy 82.205451 -306.166198)
			(xy 82.238086 -306.129361) (xy 82.276207 -306.098236) (xy 82.318828 -306.073629) (xy 82.364844 -306.056177)
			(xy 82.413063 -306.046333) (xy 82.462238 -306.044352) (xy 82.511093 -306.050284) (xy 82.558364 -306.063976)
			(xy 82.602826 -306.085074) (xy 82.643329 -306.11303) (xy 82.678822 -306.147122) (xy 82.708387 -306.186466)
			(xy 82.731258 -306.230043) (xy 82.746842 -306.276724) (xy 82.754737 -306.325301) (xy 82.755232 -306.349908)
			(xy 152.644106 -306.349908) (xy 152.648066 -306.300854) (xy 152.659843 -306.25307) (xy 152.679134 -306.207794)
			(xy 152.705437 -306.166198) (xy 152.738072 -306.129361) (xy 152.776193 -306.098236) (xy 152.818814 -306.073629)
			(xy 152.86483 -306.056177) (xy 152.913049 -306.046333) (xy 152.962224 -306.044352) (xy 153.011079 -306.050284)
			(xy 153.05835 -306.063976) (xy 153.102812 -306.085074) (xy 153.143315 -306.11303) (xy 153.178808 -306.147122)
			(xy 153.208373 -306.186466) (xy 153.231244 -306.230043) (xy 153.246828 -306.276724) (xy 153.254723 -306.325301)
			(xy 153.255218 -306.349908) (xy 153.594066 -306.349908) (xy 153.598026 -306.300854) (xy 153.609803 -306.25307)
			(xy 153.629094 -306.207794) (xy 153.655397 -306.166198) (xy 153.688032 -306.129361) (xy 153.726153 -306.098236)
			(xy 153.768774 -306.073629) (xy 153.81479 -306.056177) (xy 153.863009 -306.046333) (xy 153.912184 -306.044352)
			(xy 153.961039 -306.050284) (xy 154.00831 -306.063976) (xy 154.052772 -306.085074) (xy 154.093275 -306.11303)
			(xy 154.128768 -306.147122) (xy 154.158333 -306.186466) (xy 154.181204 -306.230043) (xy 154.196788 -306.276724)
			(xy 154.204683 -306.325301) (xy 154.205178 -306.349908) (xy 159.29408 -306.349908) (xy 159.29804 -306.300854)
			(xy 159.309817 -306.25307) (xy 159.329108 -306.207794) (xy 159.355411 -306.166198) (xy 159.388046 -306.129361)
			(xy 159.426167 -306.098236) (xy 159.468788 -306.073629) (xy 159.514804 -306.056177) (xy 159.563023 -306.046333)
			(xy 159.612198 -306.044352) (xy 159.661053 -306.050284) (xy 159.708324 -306.063976) (xy 159.752786 -306.085074)
			(xy 159.793289 -306.11303) (xy 159.828782 -306.147122) (xy 159.858347 -306.186466) (xy 159.881218 -306.230043)
			(xy 159.896802 -306.276724) (xy 159.904697 -306.325301) (xy 159.905192 -306.349908) (xy 160.24404 -306.349908)
			(xy 160.248 -306.300854) (xy 160.259777 -306.25307) (xy 160.279068 -306.207794) (xy 160.305371 -306.166198)
			(xy 160.338006 -306.129361) (xy 160.376127 -306.098236) (xy 160.418748 -306.073629) (xy 160.464764 -306.056177)
			(xy 160.512983 -306.046333) (xy 160.562158 -306.044352) (xy 160.611013 -306.050284) (xy 160.658284 -306.063976)
			(xy 160.702746 -306.085074) (xy 160.743249 -306.11303) (xy 160.778742 -306.147122) (xy 160.808307 -306.186466)
			(xy 160.831178 -306.230043) (xy 160.846762 -306.276724) (xy 160.854657 -306.325301) (xy 160.855152 -306.349908)
			(xy 190.644284 -306.349908) (xy 190.648244 -306.300854) (xy 190.660021 -306.25307) (xy 190.679312 -306.207794)
			(xy 190.705615 -306.166198) (xy 190.73825 -306.129361) (xy 190.776371 -306.098236) (xy 190.818992 -306.073629)
			(xy 190.865008 -306.056177) (xy 190.913227 -306.046333) (xy 190.962402 -306.044352) (xy 191.011257 -306.050284)
			(xy 191.058528 -306.063976) (xy 191.10299 -306.085074) (xy 191.143493 -306.11303) (xy 191.178986 -306.147122)
			(xy 191.208551 -306.186466) (xy 191.231422 -306.230043) (xy 191.247006 -306.276724) (xy 191.254901 -306.325301)
			(xy 191.255396 -306.349908) (xy 191.594244 -306.349908) (xy 191.598204 -306.300854) (xy 191.609981 -306.25307)
			(xy 191.629272 -306.207794) (xy 191.655575 -306.166198) (xy 191.68821 -306.129361) (xy 191.726331 -306.098236)
			(xy 191.768952 -306.073629) (xy 191.814968 -306.056177) (xy 191.863187 -306.046333) (xy 191.912362 -306.044352)
			(xy 191.961217 -306.050284) (xy 192.008488 -306.063976) (xy 192.05295 -306.085074) (xy 192.093453 -306.11303)
			(xy 192.128946 -306.147122) (xy 192.158511 -306.186466) (xy 192.181382 -306.230043) (xy 192.196966 -306.276724)
			(xy 192.204861 -306.325301) (xy 192.205356 -306.349908) (xy 275.393924 -306.349908) (xy 275.397884 -306.300854)
			(xy 275.409661 -306.25307) (xy 275.428952 -306.207794) (xy 275.455255 -306.166198) (xy 275.48789 -306.129361)
			(xy 275.526011 -306.098236) (xy 275.568632 -306.073629) (xy 275.614648 -306.056177) (xy 275.662867 -306.046333)
			(xy 275.712042 -306.044352) (xy 275.760897 -306.050284) (xy 275.808168 -306.063976) (xy 275.85263 -306.085074)
			(xy 275.893133 -306.11303) (xy 275.928626 -306.147122) (xy 275.958191 -306.186466) (xy 275.981062 -306.230043)
			(xy 275.996646 -306.276724) (xy 276.004541 -306.325301) (xy 276.005036 -306.349908) (xy 276.343884 -306.349908)
			(xy 276.347844 -306.300854) (xy 276.359621 -306.25307) (xy 276.378912 -306.207794) (xy 276.405215 -306.166198)
			(xy 276.43785 -306.129361) (xy 276.475971 -306.098236) (xy 276.518592 -306.073629) (xy 276.564608 -306.056177)
			(xy 276.612827 -306.046333) (xy 276.662002 -306.044352) (xy 276.710857 -306.050284) (xy 276.758128 -306.063976)
			(xy 276.80259 -306.085074) (xy 276.843093 -306.11303) (xy 276.878586 -306.147122) (xy 276.908151 -306.186466)
			(xy 276.931022 -306.230043) (xy 276.946606 -306.276724) (xy 276.954501 -306.325301) (xy 276.954996 -306.349908)
			(xy 306.744128 -306.349908) (xy 306.748088 -306.300854) (xy 306.759865 -306.25307) (xy 306.779156 -306.207794)
			(xy 306.805459 -306.166198) (xy 306.838094 -306.129361) (xy 306.876215 -306.098236) (xy 306.918836 -306.073629)
			(xy 306.964852 -306.056177) (xy 307.013071 -306.046333) (xy 307.062246 -306.044352) (xy 307.111101 -306.050284)
			(xy 307.158372 -306.063976) (xy 307.202834 -306.085074) (xy 307.243337 -306.11303) (xy 307.27883 -306.147122)
			(xy 307.308395 -306.186466) (xy 307.331266 -306.230043) (xy 307.34685 -306.276724) (xy 307.354745 -306.325301)
			(xy 307.35524 -306.349908) (xy 307.694088 -306.349908) (xy 307.698048 -306.300854) (xy 307.709825 -306.25307)
			(xy 307.729116 -306.207794) (xy 307.755419 -306.166198) (xy 307.788054 -306.129361) (xy 307.826175 -306.098236)
			(xy 307.868796 -306.073629) (xy 307.914812 -306.056177) (xy 307.963031 -306.046333) (xy 308.012206 -306.044352)
			(xy 308.061061 -306.050284) (xy 308.108332 -306.063976) (xy 308.152794 -306.085074) (xy 308.193297 -306.11303)
			(xy 308.22879 -306.147122) (xy 308.258355 -306.186466) (xy 308.281226 -306.230043) (xy 308.29681 -306.276724)
			(xy 308.304705 -306.325301) (xy 308.3052 -306.349908) (xy 313.394102 -306.349908) (xy 313.398062 -306.300854)
			(xy 313.409839 -306.25307) (xy 313.42913 -306.207794) (xy 313.455433 -306.166198) (xy 313.488068 -306.129361)
			(xy 313.526189 -306.098236) (xy 313.56881 -306.073629) (xy 313.614826 -306.056177) (xy 313.663045 -306.046333)
			(xy 313.71222 -306.044352) (xy 313.761075 -306.050284) (xy 313.808346 -306.063976) (xy 313.852808 -306.085074)
			(xy 313.893311 -306.11303) (xy 313.928804 -306.147122) (xy 313.958369 -306.186466) (xy 313.98124 -306.230043)
			(xy 313.996824 -306.276724) (xy 314.004719 -306.325301) (xy 314.005214 -306.349908) (xy 314.344062 -306.349908)
			(xy 314.348022 -306.300854) (xy 314.359799 -306.25307) (xy 314.37909 -306.207794) (xy 314.405393 -306.166198)
			(xy 314.438028 -306.129361) (xy 314.476149 -306.098236) (xy 314.51877 -306.073629) (xy 314.564786 -306.056177)
			(xy 314.613005 -306.046333) (xy 314.66218 -306.044352) (xy 314.711035 -306.050284) (xy 314.758306 -306.063976)
			(xy 314.802768 -306.085074) (xy 314.843271 -306.11303) (xy 314.878764 -306.147122) (xy 314.908329 -306.186466)
			(xy 314.9312 -306.230043) (xy 314.946784 -306.276724) (xy 314.954679 -306.325301) (xy 314.955174 -306.349908)
			(xy 384.844048 -306.349908) (xy 384.848008 -306.300854) (xy 384.859785 -306.25307) (xy 384.879076 -306.207794)
			(xy 384.905379 -306.166198) (xy 384.938014 -306.129361) (xy 384.976135 -306.098236) (xy 385.018756 -306.073629)
			(xy 385.064772 -306.056177) (xy 385.112991 -306.046333) (xy 385.162166 -306.044352) (xy 385.211021 -306.050284)
			(xy 385.258292 -306.063976) (xy 385.302754 -306.085074) (xy 385.343257 -306.11303) (xy 385.37875 -306.147122)
			(xy 385.408315 -306.186466) (xy 385.431186 -306.230043) (xy 385.44677 -306.276724) (xy 385.454665 -306.325301)
			(xy 385.45516 -306.349908) (xy 385.794008 -306.349908) (xy 385.797968 -306.300854) (xy 385.809745 -306.25307)
			(xy 385.829036 -306.207794) (xy 385.855339 -306.166198) (xy 385.887974 -306.129361) (xy 385.926095 -306.098236)
			(xy 385.968716 -306.073629) (xy 386.014732 -306.056177) (xy 386.062951 -306.046333) (xy 386.112126 -306.044352)
			(xy 386.160981 -306.050284) (xy 386.208252 -306.063976) (xy 386.252714 -306.085074) (xy 386.293217 -306.11303)
			(xy 386.32871 -306.147122) (xy 386.358275 -306.186466) (xy 386.381146 -306.230043) (xy 386.39673 -306.276724)
			(xy 386.404625 -306.325301) (xy 386.40512 -306.349908) (xy 391.494022 -306.349908) (xy 391.497982 -306.300854)
			(xy 391.509759 -306.25307) (xy 391.52905 -306.207794) (xy 391.555353 -306.166198) (xy 391.587988 -306.129361)
			(xy 391.626109 -306.098236) (xy 391.66873 -306.073629) (xy 391.714746 -306.056177) (xy 391.762965 -306.046333)
			(xy 391.81214 -306.044352) (xy 391.860995 -306.050284) (xy 391.908266 -306.063976) (xy 391.952728 -306.085074)
			(xy 391.993231 -306.11303) (xy 392.028724 -306.147122) (xy 392.058289 -306.186466) (xy 392.08116 -306.230043)
			(xy 392.096744 -306.276724) (xy 392.104639 -306.325301) (xy 392.105134 -306.349908) (xy 392.443982 -306.349908)
			(xy 392.447942 -306.300854) (xy 392.459719 -306.25307) (xy 392.47901 -306.207794) (xy 392.505313 -306.166198)
			(xy 392.537948 -306.129361) (xy 392.576069 -306.098236) (xy 392.61869 -306.073629) (xy 392.664706 -306.056177)
			(xy 392.712925 -306.046333) (xy 392.7621 -306.044352) (xy 392.810955 -306.050284) (xy 392.858226 -306.063976)
			(xy 392.902688 -306.085074) (xy 392.943191 -306.11303) (xy 392.978684 -306.147122) (xy 393.008249 -306.186466)
			(xy 393.03112 -306.230043) (xy 393.046704 -306.276724) (xy 393.054599 -306.325301) (xy 393.055094 -306.349908)
			(xy 422.844226 -306.349908) (xy 422.848186 -306.300854) (xy 422.859963 -306.25307) (xy 422.879254 -306.207794)
			(xy 422.905557 -306.166198) (xy 422.938192 -306.129361) (xy 422.976313 -306.098236) (xy 423.018934 -306.073629)
			(xy 423.06495 -306.056177) (xy 423.113169 -306.046333) (xy 423.162344 -306.044352) (xy 423.211199 -306.050284)
			(xy 423.25847 -306.063976) (xy 423.302932 -306.085074) (xy 423.343435 -306.11303) (xy 423.378928 -306.147122)
			(xy 423.408493 -306.186466) (xy 423.431364 -306.230043) (xy 423.446948 -306.276724) (xy 423.454843 -306.325301)
			(xy 423.455338 -306.349908) (xy 423.794186 -306.349908) (xy 423.798146 -306.300854) (xy 423.809923 -306.25307)
			(xy 423.829214 -306.207794) (xy 423.855517 -306.166198) (xy 423.888152 -306.129361) (xy 423.926273 -306.098236)
			(xy 423.968894 -306.073629) (xy 424.01491 -306.056177) (xy 424.063129 -306.046333) (xy 424.112304 -306.044352)
			(xy 424.161159 -306.050284) (xy 424.20843 -306.063976) (xy 424.252892 -306.085074) (xy 424.293395 -306.11303)
			(xy 424.328888 -306.147122) (xy 424.358453 -306.186466) (xy 424.381324 -306.230043) (xy 424.396908 -306.276724)
			(xy 424.404803 -306.325301) (xy 424.405298 -306.349908) (xy 424.404803 -306.374515) (xy 424.396908 -306.423092)
			(xy 424.381324 -306.469773) (xy 424.358453 -306.51335) (xy 424.328888 -306.552694) (xy 424.293395 -306.586786)
			(xy 424.252892 -306.614742) (xy 424.20843 -306.63584) (xy 424.161159 -306.649532) (xy 424.112304 -306.655464)
			(xy 424.063129 -306.653483) (xy 424.01491 -306.643639) (xy 423.968894 -306.626187) (xy 423.926273 -306.60158)
			(xy 423.888152 -306.570455) (xy 423.855517 -306.533618) (xy 423.829214 -306.492022) (xy 423.809923 -306.446746)
			(xy 423.798146 -306.398962) (xy 423.794186 -306.349908) (xy 423.455338 -306.349908) (xy 423.454843 -306.374515)
			(xy 423.446948 -306.423092) (xy 423.431364 -306.469773) (xy 423.408493 -306.51335) (xy 423.378928 -306.552694)
			(xy 423.343435 -306.586786) (xy 423.302932 -306.614742) (xy 423.25847 -306.63584) (xy 423.211199 -306.649532)
			(xy 423.162344 -306.655464) (xy 423.113169 -306.653483) (xy 423.06495 -306.643639) (xy 423.018934 -306.626187)
			(xy 422.976313 -306.60158) (xy 422.938192 -306.570455) (xy 422.905557 -306.533618) (xy 422.879254 -306.492022)
			(xy 422.859963 -306.446746) (xy 422.848186 -306.398962) (xy 422.844226 -306.349908) (xy 393.055094 -306.349908)
			(xy 393.054599 -306.374515) (xy 393.046704 -306.423092) (xy 393.03112 -306.469773) (xy 393.008249 -306.51335)
			(xy 392.978684 -306.552694) (xy 392.943191 -306.586786) (xy 392.902688 -306.614742) (xy 392.858226 -306.63584)
			(xy 392.810955 -306.649532) (xy 392.7621 -306.655464) (xy 392.712925 -306.653483) (xy 392.664706 -306.643639)
			(xy 392.61869 -306.626187) (xy 392.576069 -306.60158) (xy 392.537948 -306.570455) (xy 392.505313 -306.533618)
			(xy 392.47901 -306.492022) (xy 392.459719 -306.446746) (xy 392.447942 -306.398962) (xy 392.443982 -306.349908)
			(xy 392.105134 -306.349908) (xy 392.104639 -306.374515) (xy 392.096744 -306.423092) (xy 392.08116 -306.469773)
			(xy 392.058289 -306.51335) (xy 392.028724 -306.552694) (xy 391.993231 -306.586786) (xy 391.952728 -306.614742)
			(xy 391.908266 -306.63584) (xy 391.860995 -306.649532) (xy 391.81214 -306.655464) (xy 391.762965 -306.653483)
			(xy 391.714746 -306.643639) (xy 391.66873 -306.626187) (xy 391.626109 -306.60158) (xy 391.587988 -306.570455)
			(xy 391.555353 -306.533618) (xy 391.52905 -306.492022) (xy 391.509759 -306.446746) (xy 391.497982 -306.398962)
			(xy 391.494022 -306.349908) (xy 386.40512 -306.349908) (xy 386.404625 -306.374515) (xy 386.39673 -306.423092)
			(xy 386.381146 -306.469773) (xy 386.358275 -306.51335) (xy 386.32871 -306.552694) (xy 386.293217 -306.586786)
			(xy 386.252714 -306.614742) (xy 386.208252 -306.63584) (xy 386.160981 -306.649532) (xy 386.112126 -306.655464)
			(xy 386.062951 -306.653483) (xy 386.014732 -306.643639) (xy 385.968716 -306.626187) (xy 385.926095 -306.60158)
			(xy 385.887974 -306.570455) (xy 385.855339 -306.533618) (xy 385.829036 -306.492022) (xy 385.809745 -306.446746)
			(xy 385.797968 -306.398962) (xy 385.794008 -306.349908) (xy 385.45516 -306.349908) (xy 385.454665 -306.374515)
			(xy 385.44677 -306.423092) (xy 385.431186 -306.469773) (xy 385.408315 -306.51335) (xy 385.37875 -306.552694)
			(xy 385.343257 -306.586786) (xy 385.302754 -306.614742) (xy 385.258292 -306.63584) (xy 385.211021 -306.649532)
			(xy 385.162166 -306.655464) (xy 385.112991 -306.653483) (xy 385.064772 -306.643639) (xy 385.018756 -306.626187)
			(xy 384.976135 -306.60158) (xy 384.938014 -306.570455) (xy 384.905379 -306.533618) (xy 384.879076 -306.492022)
			(xy 384.859785 -306.446746) (xy 384.848008 -306.398962) (xy 384.844048 -306.349908) (xy 314.955174 -306.349908)
			(xy 314.954679 -306.374515) (xy 314.946784 -306.423092) (xy 314.9312 -306.469773) (xy 314.908329 -306.51335)
			(xy 314.878764 -306.552694) (xy 314.843271 -306.586786) (xy 314.802768 -306.614742) (xy 314.758306 -306.63584)
			(xy 314.711035 -306.649532) (xy 314.66218 -306.655464) (xy 314.613005 -306.653483) (xy 314.564786 -306.643639)
			(xy 314.51877 -306.626187) (xy 314.476149 -306.60158) (xy 314.438028 -306.570455) (xy 314.405393 -306.533618)
			(xy 314.37909 -306.492022) (xy 314.359799 -306.446746) (xy 314.348022 -306.398962) (xy 314.344062 -306.349908)
			(xy 314.005214 -306.349908) (xy 314.004719 -306.374515) (xy 313.996824 -306.423092) (xy 313.98124 -306.469773)
			(xy 313.958369 -306.51335) (xy 313.928804 -306.552694) (xy 313.893311 -306.586786) (xy 313.852808 -306.614742)
			(xy 313.808346 -306.63584) (xy 313.761075 -306.649532) (xy 313.71222 -306.655464) (xy 313.663045 -306.653483)
			(xy 313.614826 -306.643639) (xy 313.56881 -306.626187) (xy 313.526189 -306.60158) (xy 313.488068 -306.570455)
			(xy 313.455433 -306.533618) (xy 313.42913 -306.492022) (xy 313.409839 -306.446746) (xy 313.398062 -306.398962)
			(xy 313.394102 -306.349908) (xy 308.3052 -306.349908) (xy 308.304705 -306.374515) (xy 308.29681 -306.423092)
			(xy 308.281226 -306.469773) (xy 308.258355 -306.51335) (xy 308.22879 -306.552694) (xy 308.193297 -306.586786)
			(xy 308.152794 -306.614742) (xy 308.108332 -306.63584) (xy 308.061061 -306.649532) (xy 308.012206 -306.655464)
			(xy 307.963031 -306.653483) (xy 307.914812 -306.643639) (xy 307.868796 -306.626187) (xy 307.826175 -306.60158)
			(xy 307.788054 -306.570455) (xy 307.755419 -306.533618) (xy 307.729116 -306.492022) (xy 307.709825 -306.446746)
			(xy 307.698048 -306.398962) (xy 307.694088 -306.349908) (xy 307.35524 -306.349908) (xy 307.354745 -306.374515)
			(xy 307.34685 -306.423092) (xy 307.331266 -306.469773) (xy 307.308395 -306.51335) (xy 307.27883 -306.552694)
			(xy 307.243337 -306.586786) (xy 307.202834 -306.614742) (xy 307.158372 -306.63584) (xy 307.111101 -306.649532)
			(xy 307.062246 -306.655464) (xy 307.013071 -306.653483) (xy 306.964852 -306.643639) (xy 306.918836 -306.626187)
			(xy 306.876215 -306.60158) (xy 306.838094 -306.570455) (xy 306.805459 -306.533618) (xy 306.779156 -306.492022)
			(xy 306.759865 -306.446746) (xy 306.748088 -306.398962) (xy 306.744128 -306.349908) (xy 276.954996 -306.349908)
			(xy 276.954501 -306.374515) (xy 276.946606 -306.423092) (xy 276.931022 -306.469773) (xy 276.908151 -306.51335)
			(xy 276.878586 -306.552694) (xy 276.843093 -306.586786) (xy 276.80259 -306.614742) (xy 276.758128 -306.63584)
			(xy 276.710857 -306.649532) (xy 276.662002 -306.655464) (xy 276.612827 -306.653483) (xy 276.564608 -306.643639)
			(xy 276.518592 -306.626187) (xy 276.475971 -306.60158) (xy 276.43785 -306.570455) (xy 276.405215 -306.533618)
			(xy 276.378912 -306.492022) (xy 276.359621 -306.446746) (xy 276.347844 -306.398962) (xy 276.343884 -306.349908)
			(xy 276.005036 -306.349908) (xy 276.004541 -306.374515) (xy 275.996646 -306.423092) (xy 275.981062 -306.469773)
			(xy 275.958191 -306.51335) (xy 275.928626 -306.552694) (xy 275.893133 -306.586786) (xy 275.85263 -306.614742)
			(xy 275.808168 -306.63584) (xy 275.760897 -306.649532) (xy 275.712042 -306.655464) (xy 275.662867 -306.653483)
			(xy 275.614648 -306.643639) (xy 275.568632 -306.626187) (xy 275.526011 -306.60158) (xy 275.48789 -306.570455)
			(xy 275.455255 -306.533618) (xy 275.428952 -306.492022) (xy 275.409661 -306.446746) (xy 275.397884 -306.398962)
			(xy 275.393924 -306.349908) (xy 192.205356 -306.349908) (xy 192.204861 -306.374515) (xy 192.196966 -306.423092)
			(xy 192.181382 -306.469773) (xy 192.158511 -306.51335) (xy 192.128946 -306.552694) (xy 192.093453 -306.586786)
			(xy 192.05295 -306.614742) (xy 192.008488 -306.63584) (xy 191.961217 -306.649532) (xy 191.912362 -306.655464)
			(xy 191.863187 -306.653483) (xy 191.814968 -306.643639) (xy 191.768952 -306.626187) (xy 191.726331 -306.60158)
			(xy 191.68821 -306.570455) (xy 191.655575 -306.533618) (xy 191.629272 -306.492022) (xy 191.609981 -306.446746)
			(xy 191.598204 -306.398962) (xy 191.594244 -306.349908) (xy 191.255396 -306.349908) (xy 191.254901 -306.374515)
			(xy 191.247006 -306.423092) (xy 191.231422 -306.469773) (xy 191.208551 -306.51335) (xy 191.178986 -306.552694)
			(xy 191.143493 -306.586786) (xy 191.10299 -306.614742) (xy 191.058528 -306.63584) (xy 191.011257 -306.649532)
			(xy 190.962402 -306.655464) (xy 190.913227 -306.653483) (xy 190.865008 -306.643639) (xy 190.818992 -306.626187)
			(xy 190.776371 -306.60158) (xy 190.73825 -306.570455) (xy 190.705615 -306.533618) (xy 190.679312 -306.492022)
			(xy 190.660021 -306.446746) (xy 190.648244 -306.398962) (xy 190.644284 -306.349908) (xy 160.855152 -306.349908)
			(xy 160.854657 -306.374515) (xy 160.846762 -306.423092) (xy 160.831178 -306.469773) (xy 160.808307 -306.51335)
			(xy 160.778742 -306.552694) (xy 160.743249 -306.586786) (xy 160.702746 -306.614742) (xy 160.658284 -306.63584)
			(xy 160.611013 -306.649532) (xy 160.562158 -306.655464) (xy 160.512983 -306.653483) (xy 160.464764 -306.643639)
			(xy 160.418748 -306.626187) (xy 160.376127 -306.60158) (xy 160.338006 -306.570455) (xy 160.305371 -306.533618)
			(xy 160.279068 -306.492022) (xy 160.259777 -306.446746) (xy 160.248 -306.398962) (xy 160.24404 -306.349908)
			(xy 159.905192 -306.349908) (xy 159.904697 -306.374515) (xy 159.896802 -306.423092) (xy 159.881218 -306.469773)
			(xy 159.858347 -306.51335) (xy 159.828782 -306.552694) (xy 159.793289 -306.586786) (xy 159.752786 -306.614742)
			(xy 159.708324 -306.63584) (xy 159.661053 -306.649532) (xy 159.612198 -306.655464) (xy 159.563023 -306.653483)
			(xy 159.514804 -306.643639) (xy 159.468788 -306.626187) (xy 159.426167 -306.60158) (xy 159.388046 -306.570455)
			(xy 159.355411 -306.533618) (xy 159.329108 -306.492022) (xy 159.309817 -306.446746) (xy 159.29804 -306.398962)
			(xy 159.29408 -306.349908) (xy 154.205178 -306.349908) (xy 154.204683 -306.374515) (xy 154.196788 -306.423092)
			(xy 154.181204 -306.469773) (xy 154.158333 -306.51335) (xy 154.128768 -306.552694) (xy 154.093275 -306.586786)
			(xy 154.052772 -306.614742) (xy 154.00831 -306.63584) (xy 153.961039 -306.649532) (xy 153.912184 -306.655464)
			(xy 153.863009 -306.653483) (xy 153.81479 -306.643639) (xy 153.768774 -306.626187) (xy 153.726153 -306.60158)
			(xy 153.688032 -306.570455) (xy 153.655397 -306.533618) (xy 153.629094 -306.492022) (xy 153.609803 -306.446746)
			(xy 153.598026 -306.398962) (xy 153.594066 -306.349908) (xy 153.255218 -306.349908) (xy 153.254723 -306.374515)
			(xy 153.246828 -306.423092) (xy 153.231244 -306.469773) (xy 153.208373 -306.51335) (xy 153.178808 -306.552694)
			(xy 153.143315 -306.586786) (xy 153.102812 -306.614742) (xy 153.05835 -306.63584) (xy 153.011079 -306.649532)
			(xy 152.962224 -306.655464) (xy 152.913049 -306.653483) (xy 152.86483 -306.643639) (xy 152.818814 -306.626187)
			(xy 152.776193 -306.60158) (xy 152.738072 -306.570455) (xy 152.705437 -306.533618) (xy 152.679134 -306.492022)
			(xy 152.659843 -306.446746) (xy 152.648066 -306.398962) (xy 152.644106 -306.349908) (xy 82.755232 -306.349908)
			(xy 82.754737 -306.374515) (xy 82.746842 -306.423092) (xy 82.731258 -306.469773) (xy 82.708387 -306.51335)
			(xy 82.678822 -306.552694) (xy 82.643329 -306.586786) (xy 82.602826 -306.614742) (xy 82.558364 -306.63584)
			(xy 82.511093 -306.649532) (xy 82.462238 -306.655464) (xy 82.413063 -306.653483) (xy 82.364844 -306.643639)
			(xy 82.318828 -306.626187) (xy 82.276207 -306.60158) (xy 82.238086 -306.570455) (xy 82.205451 -306.533618)
			(xy 82.179148 -306.492022) (xy 82.159857 -306.446746) (xy 82.14808 -306.398962) (xy 82.14412 -306.349908)
			(xy 81.805272 -306.349908) (xy 81.804777 -306.374515) (xy 81.796882 -306.423092) (xy 81.781298 -306.469773)
			(xy 81.758427 -306.51335) (xy 81.728862 -306.552694) (xy 81.693369 -306.586786) (xy 81.652866 -306.614742)
			(xy 81.608404 -306.63584) (xy 81.561133 -306.649532) (xy 81.512278 -306.655464) (xy 81.463103 -306.653483)
			(xy 81.414884 -306.643639) (xy 81.368868 -306.626187) (xy 81.326247 -306.60158) (xy 81.288126 -306.570455)
			(xy 81.255491 -306.533618) (xy 81.229188 -306.492022) (xy 81.209897 -306.446746) (xy 81.19812 -306.398962)
			(xy 81.19416 -306.349908) (xy 76.105258 -306.349908) (xy 76.104763 -306.374515) (xy 76.096868 -306.423092)
			(xy 76.081284 -306.469773) (xy 76.058413 -306.51335) (xy 76.028848 -306.552694) (xy 75.993355 -306.586786)
			(xy 75.952852 -306.614742) (xy 75.90839 -306.63584) (xy 75.861119 -306.649532) (xy 75.812264 -306.655464)
			(xy 75.763089 -306.653483) (xy 75.71487 -306.643639) (xy 75.668854 -306.626187) (xy 75.626233 -306.60158)
			(xy 75.588112 -306.570455) (xy 75.555477 -306.533618) (xy 75.529174 -306.492022) (xy 75.509883 -306.446746)
			(xy 75.498106 -306.398962) (xy 75.494146 -306.349908) (xy 75.155298 -306.349908) (xy 75.154803 -306.374515)
			(xy 75.146908 -306.423092) (xy 75.131324 -306.469773) (xy 75.108453 -306.51335) (xy 75.078888 -306.552694)
			(xy 75.043395 -306.586786) (xy 75.002892 -306.614742) (xy 74.95843 -306.63584) (xy 74.911159 -306.649532)
			(xy 74.862304 -306.655464) (xy 74.813129 -306.653483) (xy 74.76491 -306.643639) (xy 74.718894 -306.626187)
			(xy 74.676273 -306.60158) (xy 74.638152 -306.570455) (xy 74.605517 -306.533618) (xy 74.579214 -306.492022)
			(xy 74.559923 -306.446746) (xy 74.548146 -306.398962) (xy 74.544186 -306.349908) (xy 44.755054 -306.349908)
			(xy 44.754559 -306.374515) (xy 44.746664 -306.423092) (xy 44.73108 -306.469773) (xy 44.708209 -306.51335)
			(xy 44.678644 -306.552694) (xy 44.643151 -306.586786) (xy 44.602648 -306.614742) (xy 44.558186 -306.63584)
			(xy 44.510915 -306.649532) (xy 44.46206 -306.655464) (xy 44.412885 -306.653483) (xy 44.364666 -306.643639)
			(xy 44.31865 -306.626187) (xy 44.276029 -306.60158) (xy 44.237908 -306.570455) (xy 44.205273 -306.533618)
			(xy 44.17897 -306.492022) (xy 44.159679 -306.446746) (xy 44.147902 -306.398962) (xy 44.143942 -306.349908)
			(xy 43.805094 -306.349908) (xy 43.804599 -306.374515) (xy 43.796704 -306.423092) (xy 43.78112 -306.469773)
			(xy 43.758249 -306.51335) (xy 43.728684 -306.552694) (xy 43.693191 -306.586786) (xy 43.652688 -306.614742)
			(xy 43.608226 -306.63584) (xy 43.560955 -306.649532) (xy 43.5121 -306.655464) (xy 43.462925 -306.653483)
			(xy 43.414706 -306.643639) (xy 43.36869 -306.626187) (xy 43.326069 -306.60158) (xy 43.287948 -306.570455)
			(xy 43.255313 -306.533618) (xy 43.22901 -306.492022) (xy 43.209719 -306.446746) (xy 43.197942 -306.398962)
			(xy 43.193982 -306.349908) (xy 18.395917 -306.349908) (xy 18.393665 -306.365208) (xy 18.377587 -306.41865)
			(xy 18.353899 -306.469181) (xy 18.323105 -306.515725) (xy 18.285863 -306.557289) (xy 18.242967 -306.592988)
			(xy 18.195329 -306.622061) (xy 18.143966 -306.643888) (xy 18.089973 -306.658004) (xy 18.034499 -306.664107)
			(xy 17.978728 -306.662069) (xy 17.923849 -306.651932) (xy 17.871029 -306.633913) (xy 17.821397 -306.608395)
			(xy 17.776009 -306.575923) (xy 17.735832 -306.537188) (xy 17.701724 -306.493016) (xy 17.67441 -306.444348)
			(xy 17.654474 -306.392222) (xy 17.642339 -306.337749) (xy 17.638266 -306.28209) (xy 0.508 -306.28209)
			(xy 0.508 -307.299868) (xy 41.294062 -307.299868) (xy 41.298022 -307.250814) (xy 41.309799 -307.20303)
			(xy 41.32909 -307.157754) (xy 41.355393 -307.116158) (xy 41.388028 -307.079321) (xy 41.426149 -307.048196)
			(xy 41.46877 -307.023589) (xy 41.514786 -307.006137) (xy 41.563005 -306.996293) (xy 41.61218 -306.994312)
			(xy 41.661035 -307.000244) (xy 41.708306 -307.013936) (xy 41.752768 -307.035034) (xy 41.793271 -307.06299)
			(xy 41.828764 -307.097082) (xy 41.858329 -307.136426) (xy 41.8812 -307.180003) (xy 41.896784 -307.226684)
			(xy 41.904679 -307.275261) (xy 41.905174 -307.299868) (xy 42.244022 -307.299868) (xy 42.247982 -307.250814)
			(xy 42.259759 -307.20303) (xy 42.27905 -307.157754) (xy 42.305353 -307.116158) (xy 42.337988 -307.079321)
			(xy 42.376109 -307.048196) (xy 42.41873 -307.023589) (xy 42.464746 -307.006137) (xy 42.512965 -306.996293)
			(xy 42.56214 -306.994312) (xy 42.610995 -307.000244) (xy 42.658266 -307.013936) (xy 42.702728 -307.035034)
			(xy 42.743231 -307.06299) (xy 42.778724 -307.097082) (xy 42.808289 -307.136426) (xy 42.83116 -307.180003)
			(xy 42.846744 -307.226684) (xy 42.854639 -307.275261) (xy 42.855134 -307.299868) (xy 76.444106 -307.299868)
			(xy 76.448066 -307.250814) (xy 76.459843 -307.20303) (xy 76.479134 -307.157754) (xy 76.505437 -307.116158)
			(xy 76.538072 -307.079321) (xy 76.576193 -307.048196) (xy 76.618814 -307.023589) (xy 76.66483 -307.006137)
			(xy 76.713049 -306.996293) (xy 76.762224 -306.994312) (xy 76.811079 -307.000244) (xy 76.85835 -307.013936)
			(xy 76.902812 -307.035034) (xy 76.943315 -307.06299) (xy 76.978808 -307.097082) (xy 77.008373 -307.136426)
			(xy 77.031244 -307.180003) (xy 77.046828 -307.226684) (xy 77.054723 -307.275261) (xy 77.055218 -307.299868)
			(xy 77.394066 -307.299868) (xy 77.398026 -307.250814) (xy 77.409803 -307.20303) (xy 77.429094 -307.157754)
			(xy 77.455397 -307.116158) (xy 77.488032 -307.079321) (xy 77.526153 -307.048196) (xy 77.568774 -307.023589)
			(xy 77.61479 -307.006137) (xy 77.663009 -306.996293) (xy 77.712184 -306.994312) (xy 77.761039 -307.000244)
			(xy 77.80831 -307.013936) (xy 77.852772 -307.035034) (xy 77.893275 -307.06299) (xy 77.928768 -307.097082)
			(xy 77.958333 -307.136426) (xy 77.981204 -307.180003) (xy 77.996788 -307.226684) (xy 78.004683 -307.275261)
			(xy 78.005178 -307.299868) (xy 79.293986 -307.299868) (xy 79.297946 -307.250814) (xy 79.309723 -307.20303)
			(xy 79.329014 -307.157754) (xy 79.355317 -307.116158) (xy 79.387952 -307.079321) (xy 79.426073 -307.048196)
			(xy 79.468694 -307.023589) (xy 79.51471 -307.006137) (xy 79.562929 -306.996293) (xy 79.612104 -306.994312)
			(xy 79.660959 -307.000244) (xy 79.70823 -307.013936) (xy 79.752692 -307.035034) (xy 79.793195 -307.06299)
			(xy 79.828688 -307.097082) (xy 79.858253 -307.136426) (xy 79.881124 -307.180003) (xy 79.896708 -307.226684)
			(xy 79.904603 -307.275261) (xy 79.905098 -307.299868) (xy 80.243946 -307.299868) (xy 80.247906 -307.250814)
			(xy 80.259683 -307.20303) (xy 80.278974 -307.157754) (xy 80.305277 -307.116158) (xy 80.337912 -307.079321)
			(xy 80.376033 -307.048196) (xy 80.418654 -307.023589) (xy 80.46467 -307.006137) (xy 80.512889 -306.996293)
			(xy 80.562064 -306.994312) (xy 80.610919 -307.000244) (xy 80.65819 -307.013936) (xy 80.702652 -307.035034)
			(xy 80.743155 -307.06299) (xy 80.778648 -307.097082) (xy 80.808213 -307.136426) (xy 80.831084 -307.180003)
			(xy 80.846668 -307.226684) (xy 80.854563 -307.275261) (xy 80.855058 -307.299868) (xy 154.54428 -307.299868)
			(xy 154.54824 -307.250814) (xy 154.560017 -307.20303) (xy 154.579308 -307.157754) (xy 154.605611 -307.116158)
			(xy 154.638246 -307.079321) (xy 154.676367 -307.048196) (xy 154.718988 -307.023589) (xy 154.765004 -307.006137)
			(xy 154.813223 -306.996293) (xy 154.862398 -306.994312) (xy 154.911253 -307.000244) (xy 154.958524 -307.013936)
			(xy 155.002986 -307.035034) (xy 155.043489 -307.06299) (xy 155.078982 -307.097082) (xy 155.108547 -307.136426)
			(xy 155.131418 -307.180003) (xy 155.147002 -307.226684) (xy 155.154897 -307.275261) (xy 155.155392 -307.299868)
			(xy 155.49424 -307.299868) (xy 155.4982 -307.250814) (xy 155.509977 -307.20303) (xy 155.529268 -307.157754)
			(xy 155.555571 -307.116158) (xy 155.588206 -307.079321) (xy 155.626327 -307.048196) (xy 155.668948 -307.023589)
			(xy 155.714964 -307.006137) (xy 155.763183 -306.996293) (xy 155.812358 -306.994312) (xy 155.861213 -307.000244)
			(xy 155.908484 -307.013936) (xy 155.952946 -307.035034) (xy 155.993449 -307.06299) (xy 156.028942 -307.097082)
			(xy 156.058507 -307.136426) (xy 156.081378 -307.180003) (xy 156.096962 -307.226684) (xy 156.104857 -307.275261)
			(xy 156.105352 -307.299868) (xy 157.39416 -307.299868) (xy 157.39812 -307.250814) (xy 157.409897 -307.20303)
			(xy 157.429188 -307.157754) (xy 157.455491 -307.116158) (xy 157.488126 -307.079321) (xy 157.526247 -307.048196)
			(xy 157.568868 -307.023589) (xy 157.614884 -307.006137) (xy 157.663103 -306.996293) (xy 157.712278 -306.994312)
			(xy 157.761133 -307.000244) (xy 157.808404 -307.013936) (xy 157.852866 -307.035034) (xy 157.893369 -307.06299)
			(xy 157.928862 -307.097082) (xy 157.958427 -307.136426) (xy 157.981298 -307.180003) (xy 157.996882 -307.226684)
			(xy 158.004777 -307.275261) (xy 158.005272 -307.299868) (xy 158.34412 -307.299868) (xy 158.34808 -307.250814)
			(xy 158.359857 -307.20303) (xy 158.379148 -307.157754) (xy 158.405451 -307.116158) (xy 158.438086 -307.079321)
			(xy 158.476207 -307.048196) (xy 158.518828 -307.023589) (xy 158.564844 -307.006137) (xy 158.613063 -306.996293)
			(xy 158.662238 -306.994312) (xy 158.711093 -307.000244) (xy 158.758364 -307.013936) (xy 158.802826 -307.035034)
			(xy 158.843329 -307.06299) (xy 158.878822 -307.097082) (xy 158.908387 -307.136426) (xy 158.931258 -307.180003)
			(xy 158.946842 -307.226684) (xy 158.954737 -307.275261) (xy 158.955232 -307.299868) (xy 192.544204 -307.299868)
			(xy 192.548164 -307.250814) (xy 192.559941 -307.20303) (xy 192.579232 -307.157754) (xy 192.605535 -307.116158)
			(xy 192.63817 -307.079321) (xy 192.676291 -307.048196) (xy 192.718912 -307.023589) (xy 192.764928 -307.006137)
			(xy 192.813147 -306.996293) (xy 192.862322 -306.994312) (xy 192.911177 -307.000244) (xy 192.958448 -307.013936)
			(xy 193.00291 -307.035034) (xy 193.043413 -307.06299) (xy 193.078906 -307.097082) (xy 193.108471 -307.136426)
			(xy 193.131342 -307.180003) (xy 193.146926 -307.226684) (xy 193.154821 -307.275261) (xy 193.155316 -307.299868)
			(xy 193.494164 -307.299868) (xy 193.498124 -307.250814) (xy 193.509901 -307.20303) (xy 193.529192 -307.157754)
			(xy 193.555495 -307.116158) (xy 193.58813 -307.079321) (xy 193.626251 -307.048196) (xy 193.668872 -307.023589)
			(xy 193.714888 -307.006137) (xy 193.763107 -306.996293) (xy 193.812282 -306.994312) (xy 193.861137 -307.000244)
			(xy 193.908408 -307.013936) (xy 193.95287 -307.035034) (xy 193.993373 -307.06299) (xy 194.028866 -307.097082)
			(xy 194.058431 -307.136426) (xy 194.081302 -307.180003) (xy 194.096886 -307.226684) (xy 194.104781 -307.275261)
			(xy 194.105276 -307.299868) (xy 194.104781 -307.324475) (xy 194.096886 -307.373052) (xy 194.081302 -307.419733)
			(xy 194.058431 -307.46331) (xy 194.042679 -307.484272) (xy 231.935526 -307.484272) (xy 231.939599 -307.428613)
			(xy 231.951734 -307.37414) (xy 231.97167 -307.322014) (xy 231.998984 -307.273346) (xy 232.033092 -307.229174)
			(xy 232.073269 -307.190439) (xy 232.118657 -307.157967) (xy 232.168289 -307.132449) (xy 232.221109 -307.11443)
			(xy 232.275988 -307.104293) (xy 232.331759 -307.102255) (xy 232.387233 -307.108358) (xy 232.441226 -307.122474)
			(xy 232.492589 -307.144301) (xy 232.540227 -307.173374) (xy 232.583123 -307.209073) (xy 232.620365 -307.250637)
			(xy 232.651159 -307.297181) (xy 232.674847 -307.347712) (xy 232.690925 -307.401154) (xy 232.699051 -307.456368)
			(xy 232.69956 -307.484272) (xy 248.185684 -307.484272) (xy 248.189757 -307.428613) (xy 248.201892 -307.37414)
			(xy 248.221828 -307.322014) (xy 248.249142 -307.273346) (xy 248.28325 -307.229174) (xy 248.323427 -307.190439)
			(xy 248.368815 -307.157967) (xy 248.418447 -307.132449) (xy 248.471267 -307.11443) (xy 248.526146 -307.104293)
			(xy 248.581917 -307.102255) (xy 248.637391 -307.108358) (xy 248.691384 -307.122474) (xy 248.742747 -307.144301)
			(xy 248.790385 -307.173374) (xy 248.833281 -307.209073) (xy 248.870523 -307.250637) (xy 248.901317 -307.297181)
			(xy 248.902577 -307.299868) (xy 273.494004 -307.299868) (xy 273.497964 -307.250814) (xy 273.509741 -307.20303)
			(xy 273.529032 -307.157754) (xy 273.555335 -307.116158) (xy 273.58797 -307.079321) (xy 273.626091 -307.048196)
			(xy 273.668712 -307.023589) (xy 273.714728 -307.006137) (xy 273.762947 -306.996293) (xy 273.812122 -306.994312)
			(xy 273.860977 -307.000244) (xy 273.908248 -307.013936) (xy 273.95271 -307.035034) (xy 273.993213 -307.06299)
			(xy 274.028706 -307.097082) (xy 274.058271 -307.136426) (xy 274.081142 -307.180003) (xy 274.096726 -307.226684)
			(xy 274.104621 -307.275261) (xy 274.105116 -307.299868) (xy 274.443964 -307.299868) (xy 274.447924 -307.250814)
			(xy 274.459701 -307.20303) (xy 274.478992 -307.157754) (xy 274.505295 -307.116158) (xy 274.53793 -307.079321)
			(xy 274.576051 -307.048196) (xy 274.618672 -307.023589) (xy 274.664688 -307.006137) (xy 274.712907 -306.996293)
			(xy 274.762082 -306.994312) (xy 274.810937 -307.000244) (xy 274.858208 -307.013936) (xy 274.90267 -307.035034)
			(xy 274.943173 -307.06299) (xy 274.978666 -307.097082) (xy 275.008231 -307.136426) (xy 275.031102 -307.180003)
			(xy 275.046686 -307.226684) (xy 275.054581 -307.275261) (xy 275.055076 -307.299868) (xy 308.644048 -307.299868)
			(xy 308.648008 -307.250814) (xy 308.659785 -307.20303) (xy 308.679076 -307.157754) (xy 308.705379 -307.116158)
			(xy 308.738014 -307.079321) (xy 308.776135 -307.048196) (xy 308.818756 -307.023589) (xy 308.864772 -307.006137)
			(xy 308.912991 -306.996293) (xy 308.962166 -306.994312) (xy 309.011021 -307.000244) (xy 309.058292 -307.013936)
			(xy 309.102754 -307.035034) (xy 309.143257 -307.06299) (xy 309.17875 -307.097082) (xy 309.208315 -307.136426)
			(xy 309.231186 -307.180003) (xy 309.24677 -307.226684) (xy 309.254665 -307.275261) (xy 309.25516 -307.299868)
			(xy 309.594008 -307.299868) (xy 309.597968 -307.250814) (xy 309.609745 -307.20303) (xy 309.629036 -307.157754)
			(xy 309.655339 -307.116158) (xy 309.687974 -307.079321) (xy 309.726095 -307.048196) (xy 309.768716 -307.023589)
			(xy 309.814732 -307.006137) (xy 309.862951 -306.996293) (xy 309.912126 -306.994312) (xy 309.960981 -307.000244)
			(xy 310.008252 -307.013936) (xy 310.052714 -307.035034) (xy 310.093217 -307.06299) (xy 310.12871 -307.097082)
			(xy 310.158275 -307.136426) (xy 310.181146 -307.180003) (xy 310.19673 -307.226684) (xy 310.204625 -307.275261)
			(xy 310.20512 -307.299868) (xy 311.493928 -307.299868) (xy 311.497888 -307.250814) (xy 311.509665 -307.20303)
			(xy 311.528956 -307.157754) (xy 311.555259 -307.116158) (xy 311.587894 -307.079321) (xy 311.626015 -307.048196)
			(xy 311.668636 -307.023589) (xy 311.714652 -307.006137) (xy 311.762871 -306.996293) (xy 311.812046 -306.994312)
			(xy 311.860901 -307.000244) (xy 311.908172 -307.013936) (xy 311.952634 -307.035034) (xy 311.993137 -307.06299)
			(xy 312.02863 -307.097082) (xy 312.058195 -307.136426) (xy 312.081066 -307.180003) (xy 312.09665 -307.226684)
			(xy 312.104545 -307.275261) (xy 312.10504 -307.299868) (xy 312.443888 -307.299868) (xy 312.447848 -307.250814)
			(xy 312.459625 -307.20303) (xy 312.478916 -307.157754) (xy 312.505219 -307.116158) (xy 312.537854 -307.079321)
			(xy 312.575975 -307.048196) (xy 312.618596 -307.023589) (xy 312.664612 -307.006137) (xy 312.712831 -306.996293)
			(xy 312.762006 -306.994312) (xy 312.810861 -307.000244) (xy 312.858132 -307.013936) (xy 312.902594 -307.035034)
			(xy 312.943097 -307.06299) (xy 312.97859 -307.097082) (xy 313.008155 -307.136426) (xy 313.031026 -307.180003)
			(xy 313.04661 -307.226684) (xy 313.054505 -307.275261) (xy 313.055 -307.299868) (xy 386.744222 -307.299868)
			(xy 386.748182 -307.250814) (xy 386.759959 -307.20303) (xy 386.77925 -307.157754) (xy 386.805553 -307.116158)
			(xy 386.838188 -307.079321) (xy 386.876309 -307.048196) (xy 386.91893 -307.023589) (xy 386.964946 -307.006137)
			(xy 387.013165 -306.996293) (xy 387.06234 -306.994312) (xy 387.111195 -307.000244) (xy 387.158466 -307.013936)
			(xy 387.202928 -307.035034) (xy 387.243431 -307.06299) (xy 387.278924 -307.097082) (xy 387.308489 -307.136426)
			(xy 387.33136 -307.180003) (xy 387.346944 -307.226684) (xy 387.354839 -307.275261) (xy 387.355334 -307.299868)
			(xy 387.694182 -307.299868) (xy 387.698142 -307.250814) (xy 387.709919 -307.20303) (xy 387.72921 -307.157754)
			(xy 387.755513 -307.116158) (xy 387.788148 -307.079321) (xy 387.826269 -307.048196) (xy 387.86889 -307.023589)
			(xy 387.914906 -307.006137) (xy 387.963125 -306.996293) (xy 388.0123 -306.994312) (xy 388.061155 -307.000244)
			(xy 388.108426 -307.013936) (xy 388.152888 -307.035034) (xy 388.193391 -307.06299) (xy 388.228884 -307.097082)
			(xy 388.258449 -307.136426) (xy 388.28132 -307.180003) (xy 388.296904 -307.226684) (xy 388.304799 -307.275261)
			(xy 388.305294 -307.299868) (xy 389.594102 -307.299868) (xy 389.598062 -307.250814) (xy 389.609839 -307.20303)
			(xy 389.62913 -307.157754) (xy 389.655433 -307.116158) (xy 389.688068 -307.079321) (xy 389.726189 -307.048196)
			(xy 389.76881 -307.023589) (xy 389.814826 -307.006137) (xy 389.863045 -306.996293) (xy 389.91222 -306.994312)
			(xy 389.961075 -307.000244) (xy 390.008346 -307.013936) (xy 390.052808 -307.035034) (xy 390.093311 -307.06299)
			(xy 390.128804 -307.097082) (xy 390.158369 -307.136426) (xy 390.18124 -307.180003) (xy 390.196824 -307.226684)
			(xy 390.204719 -307.275261) (xy 390.205214 -307.299868) (xy 390.544062 -307.299868) (xy 390.548022 -307.250814)
			(xy 390.559799 -307.20303) (xy 390.57909 -307.157754) (xy 390.605393 -307.116158) (xy 390.638028 -307.079321)
			(xy 390.676149 -307.048196) (xy 390.71877 -307.023589) (xy 390.764786 -307.006137) (xy 390.813005 -306.996293)
			(xy 390.86218 -306.994312) (xy 390.911035 -307.000244) (xy 390.958306 -307.013936) (xy 391.002768 -307.035034)
			(xy 391.043271 -307.06299) (xy 391.078764 -307.097082) (xy 391.108329 -307.136426) (xy 391.1312 -307.180003)
			(xy 391.146784 -307.226684) (xy 391.154679 -307.275261) (xy 391.155174 -307.299868) (xy 424.744146 -307.299868)
			(xy 424.748106 -307.250814) (xy 424.759883 -307.20303) (xy 424.779174 -307.157754) (xy 424.805477 -307.116158)
			(xy 424.838112 -307.079321) (xy 424.876233 -307.048196) (xy 424.918854 -307.023589) (xy 424.96487 -307.006137)
			(xy 425.013089 -306.996293) (xy 425.062264 -306.994312) (xy 425.111119 -307.000244) (xy 425.15839 -307.013936)
			(xy 425.202852 -307.035034) (xy 425.243355 -307.06299) (xy 425.278848 -307.097082) (xy 425.308413 -307.136426)
			(xy 425.331284 -307.180003) (xy 425.346868 -307.226684) (xy 425.354763 -307.275261) (xy 425.355258 -307.299868)
			(xy 425.694106 -307.299868) (xy 425.698066 -307.250814) (xy 425.709843 -307.20303) (xy 425.729134 -307.157754)
			(xy 425.755437 -307.116158) (xy 425.788072 -307.079321) (xy 425.826193 -307.048196) (xy 425.868814 -307.023589)
			(xy 425.91483 -307.006137) (xy 425.963049 -306.996293) (xy 426.012224 -306.994312) (xy 426.061079 -307.000244)
			(xy 426.10835 -307.013936) (xy 426.152812 -307.035034) (xy 426.193315 -307.06299) (xy 426.228808 -307.097082)
			(xy 426.258373 -307.136426) (xy 426.281244 -307.180003) (xy 426.296828 -307.226684) (xy 426.304723 -307.275261)
			(xy 426.305218 -307.299868) (xy 426.304723 -307.324475) (xy 426.296828 -307.373052) (xy 426.281244 -307.419733)
			(xy 426.258373 -307.46331) (xy 426.228808 -307.502654) (xy 426.193315 -307.536746) (xy 426.152812 -307.564702)
			(xy 426.10835 -307.5858) (xy 426.061079 -307.599492) (xy 426.012224 -307.605424) (xy 425.963049 -307.603443)
			(xy 425.91483 -307.593599) (xy 425.868814 -307.576147) (xy 425.826193 -307.55154) (xy 425.788072 -307.520415)
			(xy 425.755437 -307.483578) (xy 425.729134 -307.441982) (xy 425.709843 -307.396706) (xy 425.698066 -307.348922)
			(xy 425.694106 -307.299868) (xy 425.355258 -307.299868) (xy 425.354763 -307.324475) (xy 425.346868 -307.373052)
			(xy 425.331284 -307.419733) (xy 425.308413 -307.46331) (xy 425.278848 -307.502654) (xy 425.243355 -307.536746)
			(xy 425.202852 -307.564702) (xy 425.15839 -307.5858) (xy 425.111119 -307.599492) (xy 425.062264 -307.605424)
			(xy 425.013089 -307.603443) (xy 424.96487 -307.593599) (xy 424.918854 -307.576147) (xy 424.876233 -307.55154)
			(xy 424.838112 -307.520415) (xy 424.805477 -307.483578) (xy 424.779174 -307.441982) (xy 424.759883 -307.396706)
			(xy 424.748106 -307.348922) (xy 424.744146 -307.299868) (xy 391.155174 -307.299868) (xy 391.154679 -307.324475)
			(xy 391.146784 -307.373052) (xy 391.1312 -307.419733) (xy 391.108329 -307.46331) (xy 391.078764 -307.502654)
			(xy 391.043271 -307.536746) (xy 391.002768 -307.564702) (xy 390.958306 -307.5858) (xy 390.911035 -307.599492)
			(xy 390.86218 -307.605424) (xy 390.813005 -307.603443) (xy 390.764786 -307.593599) (xy 390.71877 -307.576147)
			(xy 390.676149 -307.55154) (xy 390.638028 -307.520415) (xy 390.605393 -307.483578) (xy 390.57909 -307.441982)
			(xy 390.559799 -307.396706) (xy 390.548022 -307.348922) (xy 390.544062 -307.299868) (xy 390.205214 -307.299868)
			(xy 390.204719 -307.324475) (xy 390.196824 -307.373052) (xy 390.18124 -307.419733) (xy 390.158369 -307.46331)
			(xy 390.128804 -307.502654) (xy 390.093311 -307.536746) (xy 390.052808 -307.564702) (xy 390.008346 -307.5858)
			(xy 389.961075 -307.599492) (xy 389.91222 -307.605424) (xy 389.863045 -307.603443) (xy 389.814826 -307.593599)
			(xy 389.76881 -307.576147) (xy 389.726189 -307.55154) (xy 389.688068 -307.520415) (xy 389.655433 -307.483578)
			(xy 389.62913 -307.441982) (xy 389.609839 -307.396706) (xy 389.598062 -307.348922) (xy 389.594102 -307.299868)
			(xy 388.305294 -307.299868) (xy 388.304799 -307.324475) (xy 388.296904 -307.373052) (xy 388.28132 -307.419733)
			(xy 388.258449 -307.46331) (xy 388.228884 -307.502654) (xy 388.193391 -307.536746) (xy 388.152888 -307.564702)
			(xy 388.108426 -307.5858) (xy 388.061155 -307.599492) (xy 388.0123 -307.605424) (xy 387.963125 -307.603443)
			(xy 387.914906 -307.593599) (xy 387.86889 -307.576147) (xy 387.826269 -307.55154) (xy 387.788148 -307.520415)
			(xy 387.755513 -307.483578) (xy 387.72921 -307.441982) (xy 387.709919 -307.396706) (xy 387.698142 -307.348922)
			(xy 387.694182 -307.299868) (xy 387.355334 -307.299868) (xy 387.354839 -307.324475) (xy 387.346944 -307.373052)
			(xy 387.33136 -307.419733) (xy 387.308489 -307.46331) (xy 387.278924 -307.502654) (xy 387.243431 -307.536746)
			(xy 387.202928 -307.564702) (xy 387.158466 -307.5858) (xy 387.111195 -307.599492) (xy 387.06234 -307.605424)
			(xy 387.013165 -307.603443) (xy 386.964946 -307.593599) (xy 386.91893 -307.576147) (xy 386.876309 -307.55154)
			(xy 386.838188 -307.520415) (xy 386.805553 -307.483578) (xy 386.77925 -307.441982) (xy 386.759959 -307.396706)
			(xy 386.748182 -307.348922) (xy 386.744222 -307.299868) (xy 313.055 -307.299868) (xy 313.054505 -307.324475)
			(xy 313.04661 -307.373052) (xy 313.031026 -307.419733) (xy 313.008155 -307.46331) (xy 312.97859 -307.502654)
			(xy 312.943097 -307.536746) (xy 312.902594 -307.564702) (xy 312.858132 -307.5858) (xy 312.810861 -307.599492)
			(xy 312.762006 -307.605424) (xy 312.712831 -307.603443) (xy 312.664612 -307.593599) (xy 312.618596 -307.576147)
			(xy 312.575975 -307.55154) (xy 312.537854 -307.520415) (xy 312.505219 -307.483578) (xy 312.478916 -307.441982)
			(xy 312.459625 -307.396706) (xy 312.447848 -307.348922) (xy 312.443888 -307.299868) (xy 312.10504 -307.299868)
			(xy 312.104545 -307.324475) (xy 312.09665 -307.373052) (xy 312.081066 -307.419733) (xy 312.058195 -307.46331)
			(xy 312.02863 -307.502654) (xy 311.993137 -307.536746) (xy 311.952634 -307.564702) (xy 311.908172 -307.5858)
			(xy 311.860901 -307.599492) (xy 311.812046 -307.605424) (xy 311.762871 -307.603443) (xy 311.714652 -307.593599)
			(xy 311.668636 -307.576147) (xy 311.626015 -307.55154) (xy 311.587894 -307.520415) (xy 311.555259 -307.483578)
			(xy 311.528956 -307.441982) (xy 311.509665 -307.396706) (xy 311.497888 -307.348922) (xy 311.493928 -307.299868)
			(xy 310.20512 -307.299868) (xy 310.204625 -307.324475) (xy 310.19673 -307.373052) (xy 310.181146 -307.419733)
			(xy 310.158275 -307.46331) (xy 310.12871 -307.502654) (xy 310.093217 -307.536746) (xy 310.052714 -307.564702)
			(xy 310.008252 -307.5858) (xy 309.960981 -307.599492) (xy 309.912126 -307.605424) (xy 309.862951 -307.603443)
			(xy 309.814732 -307.593599) (xy 309.768716 -307.576147) (xy 309.726095 -307.55154) (xy 309.687974 -307.520415)
			(xy 309.655339 -307.483578) (xy 309.629036 -307.441982) (xy 309.609745 -307.396706) (xy 309.597968 -307.348922)
			(xy 309.594008 -307.299868) (xy 309.25516 -307.299868) (xy 309.254665 -307.324475) (xy 309.24677 -307.373052)
			(xy 309.231186 -307.419733) (xy 309.208315 -307.46331) (xy 309.17875 -307.502654) (xy 309.143257 -307.536746)
			(xy 309.102754 -307.564702) (xy 309.058292 -307.5858) (xy 309.011021 -307.599492) (xy 308.962166 -307.605424)
			(xy 308.912991 -307.603443) (xy 308.864772 -307.593599) (xy 308.818756 -307.576147) (xy 308.776135 -307.55154)
			(xy 308.738014 -307.520415) (xy 308.705379 -307.483578) (xy 308.679076 -307.441982) (xy 308.659785 -307.396706)
			(xy 308.648008 -307.348922) (xy 308.644048 -307.299868) (xy 275.055076 -307.299868) (xy 275.054581 -307.324475)
			(xy 275.046686 -307.373052) (xy 275.031102 -307.419733) (xy 275.008231 -307.46331) (xy 274.978666 -307.502654)
			(xy 274.943173 -307.536746) (xy 274.90267 -307.564702) (xy 274.858208 -307.5858) (xy 274.810937 -307.599492)
			(xy 274.762082 -307.605424) (xy 274.712907 -307.603443) (xy 274.664688 -307.593599) (xy 274.618672 -307.576147)
			(xy 274.576051 -307.55154) (xy 274.53793 -307.520415) (xy 274.505295 -307.483578) (xy 274.478992 -307.441982)
			(xy 274.459701 -307.396706) (xy 274.447924 -307.348922) (xy 274.443964 -307.299868) (xy 274.105116 -307.299868)
			(xy 274.104621 -307.324475) (xy 274.096726 -307.373052) (xy 274.081142 -307.419733) (xy 274.058271 -307.46331)
			(xy 274.028706 -307.502654) (xy 273.993213 -307.536746) (xy 273.95271 -307.564702) (xy 273.908248 -307.5858)
			(xy 273.860977 -307.599492) (xy 273.812122 -307.605424) (xy 273.762947 -307.603443) (xy 273.714728 -307.593599)
			(xy 273.668712 -307.576147) (xy 273.626091 -307.55154) (xy 273.58797 -307.520415) (xy 273.555335 -307.483578)
			(xy 273.529032 -307.441982) (xy 273.509741 -307.396706) (xy 273.497964 -307.348922) (xy 273.494004 -307.299868)
			(xy 248.902577 -307.299868) (xy 248.925005 -307.347712) (xy 248.941083 -307.401154) (xy 248.949209 -307.456368)
			(xy 248.949718 -307.484272) (xy 248.949209 -307.512176) (xy 248.941083 -307.56739) (xy 248.928951 -307.607716)
			(xy 462.556604 -307.607716) (xy 462.560677 -307.552057) (xy 462.572812 -307.497584) (xy 462.592748 -307.445458)
			(xy 462.620062 -307.39679) (xy 462.65417 -307.352618) (xy 462.694347 -307.313883) (xy 462.739735 -307.281411)
			(xy 462.789367 -307.255893) (xy 462.842187 -307.237874) (xy 462.897066 -307.227737) (xy 462.952837 -307.225699)
			(xy 463.008311 -307.231802) (xy 463.062304 -307.245918) (xy 463.113667 -307.267745) (xy 463.161305 -307.296818)
			(xy 463.204201 -307.332517) (xy 463.241443 -307.374081) (xy 463.272237 -307.420625) (xy 463.295925 -307.471156)
			(xy 463.312003 -307.524598) (xy 463.320129 -307.579812) (xy 463.320638 -307.607716) (xy 463.320129 -307.63562)
			(xy 463.312003 -307.690834) (xy 463.295925 -307.744276) (xy 463.272237 -307.794807) (xy 463.241443 -307.841351)
			(xy 463.204201 -307.882915) (xy 463.161305 -307.918614) (xy 463.113667 -307.947687) (xy 463.062304 -307.969514)
			(xy 463.008311 -307.98363) (xy 462.952837 -307.989733) (xy 462.897066 -307.987695) (xy 462.842187 -307.977558)
			(xy 462.789367 -307.959539) (xy 462.739735 -307.934021) (xy 462.694347 -307.901549) (xy 462.65417 -307.862814)
			(xy 462.620062 -307.818642) (xy 462.592748 -307.769974) (xy 462.572812 -307.717848) (xy 462.560677 -307.663375)
			(xy 462.556604 -307.607716) (xy 248.928951 -307.607716) (xy 248.925005 -307.620832) (xy 248.901317 -307.671363)
			(xy 248.870523 -307.717907) (xy 248.833281 -307.759471) (xy 248.790385 -307.79517) (xy 248.742747 -307.824243)
			(xy 248.691384 -307.84607) (xy 248.637391 -307.860186) (xy 248.581917 -307.866289) (xy 248.526146 -307.864251)
			(xy 248.471267 -307.854114) (xy 248.418447 -307.836095) (xy 248.368815 -307.810577) (xy 248.323427 -307.778105)
			(xy 248.28325 -307.73937) (xy 248.249142 -307.695198) (xy 248.221828 -307.64653) (xy 248.201892 -307.594404)
			(xy 248.189757 -307.539931) (xy 248.185684 -307.484272) (xy 232.69956 -307.484272) (xy 232.699051 -307.512176)
			(xy 232.690925 -307.56739) (xy 232.674847 -307.620832) (xy 232.651159 -307.671363) (xy 232.620365 -307.717907)
			(xy 232.583123 -307.759471) (xy 232.540227 -307.79517) (xy 232.492589 -307.824243) (xy 232.441226 -307.84607)
			(xy 232.387233 -307.860186) (xy 232.331759 -307.866289) (xy 232.275988 -307.864251) (xy 232.221109 -307.854114)
			(xy 232.168289 -307.836095) (xy 232.118657 -307.810577) (xy 232.073269 -307.778105) (xy 232.033092 -307.73937)
			(xy 231.998984 -307.695198) (xy 231.97167 -307.64653) (xy 231.951734 -307.594404) (xy 231.939599 -307.539931)
			(xy 231.935526 -307.484272) (xy 194.042679 -307.484272) (xy 194.028866 -307.502654) (xy 193.993373 -307.536746)
			(xy 193.95287 -307.564702) (xy 193.908408 -307.5858) (xy 193.861137 -307.599492) (xy 193.812282 -307.605424)
			(xy 193.763107 -307.603443) (xy 193.714888 -307.593599) (xy 193.668872 -307.576147) (xy 193.626251 -307.55154)
			(xy 193.58813 -307.520415) (xy 193.555495 -307.483578) (xy 193.529192 -307.441982) (xy 193.509901 -307.396706)
			(xy 193.498124 -307.348922) (xy 193.494164 -307.299868) (xy 193.155316 -307.299868) (xy 193.154821 -307.324475)
			(xy 193.146926 -307.373052) (xy 193.131342 -307.419733) (xy 193.108471 -307.46331) (xy 193.078906 -307.502654)
			(xy 193.043413 -307.536746) (xy 193.00291 -307.564702) (xy 192.958448 -307.5858) (xy 192.911177 -307.599492)
			(xy 192.862322 -307.605424) (xy 192.813147 -307.603443) (xy 192.764928 -307.593599) (xy 192.718912 -307.576147)
			(xy 192.676291 -307.55154) (xy 192.63817 -307.520415) (xy 192.605535 -307.483578) (xy 192.579232 -307.441982)
			(xy 192.559941 -307.396706) (xy 192.548164 -307.348922) (xy 192.544204 -307.299868) (xy 158.955232 -307.299868)
			(xy 158.954737 -307.324475) (xy 158.946842 -307.373052) (xy 158.931258 -307.419733) (xy 158.908387 -307.46331)
			(xy 158.878822 -307.502654) (xy 158.843329 -307.536746) (xy 158.802826 -307.564702) (xy 158.758364 -307.5858)
			(xy 158.711093 -307.599492) (xy 158.662238 -307.605424) (xy 158.613063 -307.603443) (xy 158.564844 -307.593599)
			(xy 158.518828 -307.576147) (xy 158.476207 -307.55154) (xy 158.438086 -307.520415) (xy 158.405451 -307.483578)
			(xy 158.379148 -307.441982) (xy 158.359857 -307.396706) (xy 158.34808 -307.348922) (xy 158.34412 -307.299868)
			(xy 158.005272 -307.299868) (xy 158.004777 -307.324475) (xy 157.996882 -307.373052) (xy 157.981298 -307.419733)
			(xy 157.958427 -307.46331) (xy 157.928862 -307.502654) (xy 157.893369 -307.536746) (xy 157.852866 -307.564702)
			(xy 157.808404 -307.5858) (xy 157.761133 -307.599492) (xy 157.712278 -307.605424) (xy 157.663103 -307.603443)
			(xy 157.614884 -307.593599) (xy 157.568868 -307.576147) (xy 157.526247 -307.55154) (xy 157.488126 -307.520415)
			(xy 157.455491 -307.483578) (xy 157.429188 -307.441982) (xy 157.409897 -307.396706) (xy 157.39812 -307.348922)
			(xy 157.39416 -307.299868) (xy 156.105352 -307.299868) (xy 156.104857 -307.324475) (xy 156.096962 -307.373052)
			(xy 156.081378 -307.419733) (xy 156.058507 -307.46331) (xy 156.028942 -307.502654) (xy 155.993449 -307.536746)
			(xy 155.952946 -307.564702) (xy 155.908484 -307.5858) (xy 155.861213 -307.599492) (xy 155.812358 -307.605424)
			(xy 155.763183 -307.603443) (xy 155.714964 -307.593599) (xy 155.668948 -307.576147) (xy 155.626327 -307.55154)
			(xy 155.588206 -307.520415) (xy 155.555571 -307.483578) (xy 155.529268 -307.441982) (xy 155.509977 -307.396706)
			(xy 155.4982 -307.348922) (xy 155.49424 -307.299868) (xy 155.155392 -307.299868) (xy 155.154897 -307.324475)
			(xy 155.147002 -307.373052) (xy 155.131418 -307.419733) (xy 155.108547 -307.46331) (xy 155.078982 -307.502654)
			(xy 155.043489 -307.536746) (xy 155.002986 -307.564702) (xy 154.958524 -307.5858) (xy 154.911253 -307.599492)
			(xy 154.862398 -307.605424) (xy 154.813223 -307.603443) (xy 154.765004 -307.593599) (xy 154.718988 -307.576147)
			(xy 154.676367 -307.55154) (xy 154.638246 -307.520415) (xy 154.605611 -307.483578) (xy 154.579308 -307.441982)
			(xy 154.560017 -307.396706) (xy 154.54824 -307.348922) (xy 154.54428 -307.299868) (xy 80.855058 -307.299868)
			(xy 80.854563 -307.324475) (xy 80.846668 -307.373052) (xy 80.831084 -307.419733) (xy 80.808213 -307.46331)
			(xy 80.778648 -307.502654) (xy 80.743155 -307.536746) (xy 80.702652 -307.564702) (xy 80.65819 -307.5858)
			(xy 80.610919 -307.599492) (xy 80.562064 -307.605424) (xy 80.512889 -307.603443) (xy 80.46467 -307.593599)
			(xy 80.418654 -307.576147) (xy 80.376033 -307.55154) (xy 80.337912 -307.520415) (xy 80.305277 -307.483578)
			(xy 80.278974 -307.441982) (xy 80.259683 -307.396706) (xy 80.247906 -307.348922) (xy 80.243946 -307.299868)
			(xy 79.905098 -307.299868) (xy 79.904603 -307.324475) (xy 79.896708 -307.373052) (xy 79.881124 -307.419733)
			(xy 79.858253 -307.46331) (xy 79.828688 -307.502654) (xy 79.793195 -307.536746) (xy 79.752692 -307.564702)
			(xy 79.70823 -307.5858) (xy 79.660959 -307.599492) (xy 79.612104 -307.605424) (xy 79.562929 -307.603443)
			(xy 79.51471 -307.593599) (xy 79.468694 -307.576147) (xy 79.426073 -307.55154) (xy 79.387952 -307.520415)
			(xy 79.355317 -307.483578) (xy 79.329014 -307.441982) (xy 79.309723 -307.396706) (xy 79.297946 -307.348922)
			(xy 79.293986 -307.299868) (xy 78.005178 -307.299868) (xy 78.004683 -307.324475) (xy 77.996788 -307.373052)
			(xy 77.981204 -307.419733) (xy 77.958333 -307.46331) (xy 77.928768 -307.502654) (xy 77.893275 -307.536746)
			(xy 77.852772 -307.564702) (xy 77.80831 -307.5858) (xy 77.761039 -307.599492) (xy 77.712184 -307.605424)
			(xy 77.663009 -307.603443) (xy 77.61479 -307.593599) (xy 77.568774 -307.576147) (xy 77.526153 -307.55154)
			(xy 77.488032 -307.520415) (xy 77.455397 -307.483578) (xy 77.429094 -307.441982) (xy 77.409803 -307.396706)
			(xy 77.398026 -307.348922) (xy 77.394066 -307.299868) (xy 77.055218 -307.299868) (xy 77.054723 -307.324475)
			(xy 77.046828 -307.373052) (xy 77.031244 -307.419733) (xy 77.008373 -307.46331) (xy 76.978808 -307.502654)
			(xy 76.943315 -307.536746) (xy 76.902812 -307.564702) (xy 76.85835 -307.5858) (xy 76.811079 -307.599492)
			(xy 76.762224 -307.605424) (xy 76.713049 -307.603443) (xy 76.66483 -307.593599) (xy 76.618814 -307.576147)
			(xy 76.576193 -307.55154) (xy 76.538072 -307.520415) (xy 76.505437 -307.483578) (xy 76.479134 -307.441982)
			(xy 76.459843 -307.396706) (xy 76.448066 -307.348922) (xy 76.444106 -307.299868) (xy 42.855134 -307.299868)
			(xy 42.854639 -307.324475) (xy 42.846744 -307.373052) (xy 42.83116 -307.419733) (xy 42.808289 -307.46331)
			(xy 42.778724 -307.502654) (xy 42.743231 -307.536746) (xy 42.702728 -307.564702) (xy 42.658266 -307.5858)
			(xy 42.610995 -307.599492) (xy 42.56214 -307.605424) (xy 42.512965 -307.603443) (xy 42.464746 -307.593599)
			(xy 42.41873 -307.576147) (xy 42.376109 -307.55154) (xy 42.337988 -307.520415) (xy 42.305353 -307.483578)
			(xy 42.27905 -307.441982) (xy 42.259759 -307.396706) (xy 42.247982 -307.348922) (xy 42.244022 -307.299868)
			(xy 41.905174 -307.299868) (xy 41.904679 -307.324475) (xy 41.896784 -307.373052) (xy 41.8812 -307.419733)
			(xy 41.858329 -307.46331) (xy 41.828764 -307.502654) (xy 41.793271 -307.536746) (xy 41.752768 -307.564702)
			(xy 41.708306 -307.5858) (xy 41.661035 -307.599492) (xy 41.61218 -307.605424) (xy 41.563005 -307.603443)
			(xy 41.514786 -307.593599) (xy 41.46877 -307.576147) (xy 41.426149 -307.55154) (xy 41.388028 -307.520415)
			(xy 41.355393 -307.483578) (xy 41.32909 -307.441982) (xy 41.309799 -307.396706) (xy 41.298022 -307.348922)
			(xy 41.294062 -307.299868) (xy 0.508 -307.299868) (xy 0.508 -308.249828) (xy 43.193982 -308.249828)
			(xy 43.197942 -308.200774) (xy 43.209719 -308.15299) (xy 43.22901 -308.107714) (xy 43.255313 -308.066118)
			(xy 43.287948 -308.029281) (xy 43.326069 -307.998156) (xy 43.36869 -307.973549) (xy 43.414706 -307.956097)
			(xy 43.462925 -307.946253) (xy 43.5121 -307.944272) (xy 43.560955 -307.950204) (xy 43.608226 -307.963896)
			(xy 43.652688 -307.984994) (xy 43.693191 -308.01295) (xy 43.728684 -308.047042) (xy 43.758249 -308.086386)
			(xy 43.78112 -308.129963) (xy 43.796704 -308.176644) (xy 43.804599 -308.225221) (xy 43.805094 -308.249828)
			(xy 44.143942 -308.249828) (xy 44.147902 -308.200774) (xy 44.159679 -308.15299) (xy 44.17897 -308.107714)
			(xy 44.205273 -308.066118) (xy 44.237908 -308.029281) (xy 44.276029 -307.998156) (xy 44.31865 -307.973549)
			(xy 44.364666 -307.956097) (xy 44.412885 -307.946253) (xy 44.46206 -307.944272) (xy 44.510915 -307.950204)
			(xy 44.558186 -307.963896) (xy 44.602648 -307.984994) (xy 44.643151 -308.01295) (xy 44.678644 -308.047042)
			(xy 44.708209 -308.086386) (xy 44.73108 -308.129963) (xy 44.746664 -308.176644) (xy 44.754559 -308.225221)
			(xy 44.755054 -308.249828) (xy 74.544186 -308.249828) (xy 74.548146 -308.200774) (xy 74.559923 -308.15299)
			(xy 74.579214 -308.107714) (xy 74.605517 -308.066118) (xy 74.638152 -308.029281) (xy 74.676273 -307.998156)
			(xy 74.718894 -307.973549) (xy 74.76491 -307.956097) (xy 74.813129 -307.946253) (xy 74.862304 -307.944272)
			(xy 74.911159 -307.950204) (xy 74.95843 -307.963896) (xy 75.002892 -307.984994) (xy 75.043395 -308.01295)
			(xy 75.078888 -308.047042) (xy 75.108453 -308.086386) (xy 75.131324 -308.129963) (xy 75.146908 -308.176644)
			(xy 75.154803 -308.225221) (xy 75.155298 -308.249828) (xy 75.494146 -308.249828) (xy 75.498106 -308.200774)
			(xy 75.509883 -308.15299) (xy 75.529174 -308.107714) (xy 75.555477 -308.066118) (xy 75.588112 -308.029281)
			(xy 75.626233 -307.998156) (xy 75.668854 -307.973549) (xy 75.71487 -307.956097) (xy 75.763089 -307.946253)
			(xy 75.812264 -307.944272) (xy 75.861119 -307.950204) (xy 75.90839 -307.963896) (xy 75.952852 -307.984994)
			(xy 75.993355 -308.01295) (xy 76.028848 -308.047042) (xy 76.058413 -308.086386) (xy 76.081284 -308.129963)
			(xy 76.096868 -308.176644) (xy 76.104763 -308.225221) (xy 76.105258 -308.249828) (xy 81.19416 -308.249828)
			(xy 81.19812 -308.200774) (xy 81.209897 -308.15299) (xy 81.229188 -308.107714) (xy 81.255491 -308.066118)
			(xy 81.288126 -308.029281) (xy 81.326247 -307.998156) (xy 81.368868 -307.973549) (xy 81.414884 -307.956097)
			(xy 81.463103 -307.946253) (xy 81.512278 -307.944272) (xy 81.561133 -307.950204) (xy 81.608404 -307.963896)
			(xy 81.652866 -307.984994) (xy 81.693369 -308.01295) (xy 81.728862 -308.047042) (xy 81.758427 -308.086386)
			(xy 81.781298 -308.129963) (xy 81.796882 -308.176644) (xy 81.804777 -308.225221) (xy 81.805272 -308.249828)
			(xy 82.14412 -308.249828) (xy 82.14808 -308.200774) (xy 82.159857 -308.15299) (xy 82.179148 -308.107714)
			(xy 82.205451 -308.066118) (xy 82.238086 -308.029281) (xy 82.276207 -307.998156) (xy 82.318828 -307.973549)
			(xy 82.364844 -307.956097) (xy 82.413063 -307.946253) (xy 82.462238 -307.944272) (xy 82.511093 -307.950204)
			(xy 82.558364 -307.963896) (xy 82.602826 -307.984994) (xy 82.643329 -308.01295) (xy 82.678822 -308.047042)
			(xy 82.708387 -308.086386) (xy 82.731258 -308.129963) (xy 82.746842 -308.176644) (xy 82.754737 -308.225221)
			(xy 82.755232 -308.249828) (xy 152.644106 -308.249828) (xy 152.648066 -308.200774) (xy 152.659843 -308.15299)
			(xy 152.679134 -308.107714) (xy 152.705437 -308.066118) (xy 152.738072 -308.029281) (xy 152.776193 -307.998156)
			(xy 152.818814 -307.973549) (xy 152.86483 -307.956097) (xy 152.913049 -307.946253) (xy 152.962224 -307.944272)
			(xy 153.011079 -307.950204) (xy 153.05835 -307.963896) (xy 153.102812 -307.984994) (xy 153.143315 -308.01295)
			(xy 153.178808 -308.047042) (xy 153.208373 -308.086386) (xy 153.231244 -308.129963) (xy 153.246828 -308.176644)
			(xy 153.254723 -308.225221) (xy 153.255218 -308.249828) (xy 153.594066 -308.249828) (xy 153.598026 -308.200774)
			(xy 153.609803 -308.15299) (xy 153.629094 -308.107714) (xy 153.655397 -308.066118) (xy 153.688032 -308.029281)
			(xy 153.726153 -307.998156) (xy 153.768774 -307.973549) (xy 153.81479 -307.956097) (xy 153.863009 -307.946253)
			(xy 153.912184 -307.944272) (xy 153.961039 -307.950204) (xy 154.00831 -307.963896) (xy 154.052772 -307.984994)
			(xy 154.093275 -308.01295) (xy 154.128768 -308.047042) (xy 154.158333 -308.086386) (xy 154.181204 -308.129963)
			(xy 154.196788 -308.176644) (xy 154.204683 -308.225221) (xy 154.205178 -308.249828) (xy 159.29408 -308.249828)
			(xy 159.29804 -308.200774) (xy 159.309817 -308.15299) (xy 159.329108 -308.107714) (xy 159.355411 -308.066118)
			(xy 159.388046 -308.029281) (xy 159.426167 -307.998156) (xy 159.468788 -307.973549) (xy 159.514804 -307.956097)
			(xy 159.563023 -307.946253) (xy 159.612198 -307.944272) (xy 159.661053 -307.950204) (xy 159.708324 -307.963896)
			(xy 159.752786 -307.984994) (xy 159.793289 -308.01295) (xy 159.828782 -308.047042) (xy 159.858347 -308.086386)
			(xy 159.881218 -308.129963) (xy 159.896802 -308.176644) (xy 159.904697 -308.225221) (xy 159.905192 -308.249828)
			(xy 160.24404 -308.249828) (xy 160.248 -308.200774) (xy 160.259777 -308.15299) (xy 160.279068 -308.107714)
			(xy 160.305371 -308.066118) (xy 160.338006 -308.029281) (xy 160.376127 -307.998156) (xy 160.418748 -307.973549)
			(xy 160.464764 -307.956097) (xy 160.512983 -307.946253) (xy 160.562158 -307.944272) (xy 160.611013 -307.950204)
			(xy 160.658284 -307.963896) (xy 160.702746 -307.984994) (xy 160.743249 -308.01295) (xy 160.778742 -308.047042)
			(xy 160.808307 -308.086386) (xy 160.831178 -308.129963) (xy 160.846762 -308.176644) (xy 160.854657 -308.225221)
			(xy 160.855152 -308.249828) (xy 190.644284 -308.249828) (xy 190.648244 -308.200774) (xy 190.660021 -308.15299)
			(xy 190.679312 -308.107714) (xy 190.705615 -308.066118) (xy 190.73825 -308.029281) (xy 190.776371 -307.998156)
			(xy 190.818992 -307.973549) (xy 190.865008 -307.956097) (xy 190.913227 -307.946253) (xy 190.962402 -307.944272)
			(xy 191.011257 -307.950204) (xy 191.058528 -307.963896) (xy 191.10299 -307.984994) (xy 191.143493 -308.01295)
			(xy 191.178986 -308.047042) (xy 191.208551 -308.086386) (xy 191.231422 -308.129963) (xy 191.247006 -308.176644)
			(xy 191.254901 -308.225221) (xy 191.255396 -308.249828) (xy 191.594244 -308.249828) (xy 191.598204 -308.200774)
			(xy 191.609981 -308.15299) (xy 191.629272 -308.107714) (xy 191.655575 -308.066118) (xy 191.68821 -308.029281)
			(xy 191.726331 -307.998156) (xy 191.768952 -307.973549) (xy 191.814968 -307.956097) (xy 191.863187 -307.946253)
			(xy 191.912362 -307.944272) (xy 191.961217 -307.950204) (xy 192.008488 -307.963896) (xy 192.05295 -307.984994)
			(xy 192.093453 -308.01295) (xy 192.128946 -308.047042) (xy 192.158511 -308.086386) (xy 192.181382 -308.129963)
			(xy 192.196966 -308.176644) (xy 192.204861 -308.225221) (xy 192.205356 -308.249828) (xy 192.204861 -308.274435)
			(xy 192.196966 -308.323012) (xy 192.181382 -308.369693) (xy 192.158511 -308.41327) (xy 192.128946 -308.452614)
			(xy 192.093453 -308.486706) (xy 192.05295 -308.514662) (xy 192.008488 -308.53576) (xy 191.961217 -308.549452)
			(xy 191.912362 -308.555384) (xy 191.863187 -308.553403) (xy 191.814968 -308.543559) (xy 191.768952 -308.526107)
			(xy 191.726331 -308.5015) (xy 191.68821 -308.470375) (xy 191.655575 -308.433538) (xy 191.629272 -308.391942)
			(xy 191.609981 -308.346666) (xy 191.598204 -308.298882) (xy 191.594244 -308.249828) (xy 191.255396 -308.249828)
			(xy 191.254901 -308.274435) (xy 191.247006 -308.323012) (xy 191.231422 -308.369693) (xy 191.208551 -308.41327)
			(xy 191.178986 -308.452614) (xy 191.143493 -308.486706) (xy 191.10299 -308.514662) (xy 191.058528 -308.53576)
			(xy 191.011257 -308.549452) (xy 190.962402 -308.555384) (xy 190.913227 -308.553403) (xy 190.865008 -308.543559)
			(xy 190.818992 -308.526107) (xy 190.776371 -308.5015) (xy 190.73825 -308.470375) (xy 190.705615 -308.433538)
			(xy 190.679312 -308.391942) (xy 190.660021 -308.346666) (xy 190.648244 -308.298882) (xy 190.644284 -308.249828)
			(xy 160.855152 -308.249828) (xy 160.854657 -308.274435) (xy 160.846762 -308.323012) (xy 160.831178 -308.369693)
			(xy 160.808307 -308.41327) (xy 160.778742 -308.452614) (xy 160.743249 -308.486706) (xy 160.702746 -308.514662)
			(xy 160.658284 -308.53576) (xy 160.611013 -308.549452) (xy 160.562158 -308.555384) (xy 160.512983 -308.553403)
			(xy 160.464764 -308.543559) (xy 160.418748 -308.526107) (xy 160.376127 -308.5015) (xy 160.338006 -308.470375)
			(xy 160.305371 -308.433538) (xy 160.279068 -308.391942) (xy 160.259777 -308.346666) (xy 160.248 -308.298882)
			(xy 160.24404 -308.249828) (xy 159.905192 -308.249828) (xy 159.904697 -308.274435) (xy 159.896802 -308.323012)
			(xy 159.881218 -308.369693) (xy 159.858347 -308.41327) (xy 159.828782 -308.452614) (xy 159.793289 -308.486706)
			(xy 159.752786 -308.514662) (xy 159.708324 -308.53576) (xy 159.661053 -308.549452) (xy 159.612198 -308.555384)
			(xy 159.563023 -308.553403) (xy 159.514804 -308.543559) (xy 159.468788 -308.526107) (xy 159.426167 -308.5015)
			(xy 159.388046 -308.470375) (xy 159.355411 -308.433538) (xy 159.329108 -308.391942) (xy 159.309817 -308.346666)
			(xy 159.29804 -308.298882) (xy 159.29408 -308.249828) (xy 154.205178 -308.249828) (xy 154.204683 -308.274435)
			(xy 154.196788 -308.323012) (xy 154.181204 -308.369693) (xy 154.158333 -308.41327) (xy 154.128768 -308.452614)
			(xy 154.093275 -308.486706) (xy 154.052772 -308.514662) (xy 154.00831 -308.53576) (xy 153.961039 -308.549452)
			(xy 153.912184 -308.555384) (xy 153.863009 -308.553403) (xy 153.81479 -308.543559) (xy 153.768774 -308.526107)
			(xy 153.726153 -308.5015) (xy 153.688032 -308.470375) (xy 153.655397 -308.433538) (xy 153.629094 -308.391942)
			(xy 153.609803 -308.346666) (xy 153.598026 -308.298882) (xy 153.594066 -308.249828) (xy 153.255218 -308.249828)
			(xy 153.254723 -308.274435) (xy 153.246828 -308.323012) (xy 153.231244 -308.369693) (xy 153.208373 -308.41327)
			(xy 153.178808 -308.452614) (xy 153.143315 -308.486706) (xy 153.102812 -308.514662) (xy 153.05835 -308.53576)
			(xy 153.011079 -308.549452) (xy 152.962224 -308.555384) (xy 152.913049 -308.553403) (xy 152.86483 -308.543559)
			(xy 152.818814 -308.526107) (xy 152.776193 -308.5015) (xy 152.738072 -308.470375) (xy 152.705437 -308.433538)
			(xy 152.679134 -308.391942) (xy 152.659843 -308.346666) (xy 152.648066 -308.298882) (xy 152.644106 -308.249828)
			(xy 82.755232 -308.249828) (xy 82.754737 -308.274435) (xy 82.746842 -308.323012) (xy 82.731258 -308.369693)
			(xy 82.708387 -308.41327) (xy 82.678822 -308.452614) (xy 82.643329 -308.486706) (xy 82.602826 -308.514662)
			(xy 82.558364 -308.53576) (xy 82.511093 -308.549452) (xy 82.462238 -308.555384) (xy 82.413063 -308.553403)
			(xy 82.364844 -308.543559) (xy 82.318828 -308.526107) (xy 82.276207 -308.5015) (xy 82.238086 -308.470375)
			(xy 82.205451 -308.433538) (xy 82.179148 -308.391942) (xy 82.159857 -308.346666) (xy 82.14808 -308.298882)
			(xy 82.14412 -308.249828) (xy 81.805272 -308.249828) (xy 81.804777 -308.274435) (xy 81.796882 -308.323012)
			(xy 81.781298 -308.369693) (xy 81.758427 -308.41327) (xy 81.728862 -308.452614) (xy 81.693369 -308.486706)
			(xy 81.652866 -308.514662) (xy 81.608404 -308.53576) (xy 81.561133 -308.549452) (xy 81.512278 -308.555384)
			(xy 81.463103 -308.553403) (xy 81.414884 -308.543559) (xy 81.368868 -308.526107) (xy 81.326247 -308.5015)
			(xy 81.288126 -308.470375) (xy 81.255491 -308.433538) (xy 81.229188 -308.391942) (xy 81.209897 -308.346666)
			(xy 81.19812 -308.298882) (xy 81.19416 -308.249828) (xy 76.105258 -308.249828) (xy 76.104763 -308.274435)
			(xy 76.096868 -308.323012) (xy 76.081284 -308.369693) (xy 76.058413 -308.41327) (xy 76.028848 -308.452614)
			(xy 75.993355 -308.486706) (xy 75.952852 -308.514662) (xy 75.90839 -308.53576) (xy 75.861119 -308.549452)
			(xy 75.812264 -308.555384) (xy 75.763089 -308.553403) (xy 75.71487 -308.543559) (xy 75.668854 -308.526107)
			(xy 75.626233 -308.5015) (xy 75.588112 -308.470375) (xy 75.555477 -308.433538) (xy 75.529174 -308.391942)
			(xy 75.509883 -308.346666) (xy 75.498106 -308.298882) (xy 75.494146 -308.249828) (xy 75.155298 -308.249828)
			(xy 75.154803 -308.274435) (xy 75.146908 -308.323012) (xy 75.131324 -308.369693) (xy 75.108453 -308.41327)
			(xy 75.078888 -308.452614) (xy 75.043395 -308.486706) (xy 75.002892 -308.514662) (xy 74.95843 -308.53576)
			(xy 74.911159 -308.549452) (xy 74.862304 -308.555384) (xy 74.813129 -308.553403) (xy 74.76491 -308.543559)
			(xy 74.718894 -308.526107) (xy 74.676273 -308.5015) (xy 74.638152 -308.470375) (xy 74.605517 -308.433538)
			(xy 74.579214 -308.391942) (xy 74.559923 -308.346666) (xy 74.548146 -308.298882) (xy 74.544186 -308.249828)
			(xy 44.755054 -308.249828) (xy 44.754559 -308.274435) (xy 44.746664 -308.323012) (xy 44.73108 -308.369693)
			(xy 44.708209 -308.41327) (xy 44.678644 -308.452614) (xy 44.643151 -308.486706) (xy 44.602648 -308.514662)
			(xy 44.558186 -308.53576) (xy 44.510915 -308.549452) (xy 44.46206 -308.555384) (xy 44.412885 -308.553403)
			(xy 44.364666 -308.543559) (xy 44.31865 -308.526107) (xy 44.276029 -308.5015) (xy 44.237908 -308.470375)
			(xy 44.205273 -308.433538) (xy 44.17897 -308.391942) (xy 44.159679 -308.346666) (xy 44.147902 -308.298882)
			(xy 44.143942 -308.249828) (xy 43.805094 -308.249828) (xy 43.804599 -308.274435) (xy 43.796704 -308.323012)
			(xy 43.78112 -308.369693) (xy 43.758249 -308.41327) (xy 43.728684 -308.452614) (xy 43.693191 -308.486706)
			(xy 43.652688 -308.514662) (xy 43.608226 -308.53576) (xy 43.560955 -308.549452) (xy 43.5121 -308.555384)
			(xy 43.462925 -308.553403) (xy 43.414706 -308.543559) (xy 43.36869 -308.526107) (xy 43.326069 -308.5015)
			(xy 43.287948 -308.470375) (xy 43.255313 -308.433538) (xy 43.22901 -308.391942) (xy 43.209719 -308.346666)
			(xy 43.197942 -308.298882) (xy 43.193982 -308.249828) (xy 0.508 -308.249828) (xy 0.508 -308.568852)
			(xy 231.935526 -308.568852) (xy 231.939599 -308.513193) (xy 231.951734 -308.45872) (xy 231.97167 -308.406594)
			(xy 231.998984 -308.357926) (xy 232.033092 -308.313754) (xy 232.073269 -308.275019) (xy 232.118657 -308.242547)
			(xy 232.168289 -308.217029) (xy 232.221109 -308.19901) (xy 232.275988 -308.188873) (xy 232.331759 -308.186835)
			(xy 232.387233 -308.192938) (xy 232.441226 -308.207054) (xy 232.492589 -308.228881) (xy 232.540227 -308.257954)
			(xy 232.583123 -308.293653) (xy 232.620365 -308.335217) (xy 232.651159 -308.381761) (xy 232.674847 -308.432292)
			(xy 232.690925 -308.485734) (xy 232.699051 -308.540948) (xy 232.69956 -308.568852) (xy 248.185684 -308.568852)
			(xy 248.189757 -308.513193) (xy 248.201892 -308.45872) (xy 248.221828 -308.406594) (xy 248.249142 -308.357926)
			(xy 248.28325 -308.313754) (xy 248.323427 -308.275019) (xy 248.368815 -308.242547) (xy 248.418447 -308.217029)
			(xy 248.471267 -308.19901) (xy 248.526146 -308.188873) (xy 248.581917 -308.186835) (xy 248.637391 -308.192938)
			(xy 248.691384 -308.207054) (xy 248.742747 -308.228881) (xy 248.77707 -308.249828) (xy 275.393924 -308.249828)
			(xy 275.397884 -308.200774) (xy 275.409661 -308.15299) (xy 275.428952 -308.107714) (xy 275.455255 -308.066118)
			(xy 275.48789 -308.029281) (xy 275.526011 -307.998156) (xy 275.568632 -307.973549) (xy 275.614648 -307.956097)
			(xy 275.662867 -307.946253) (xy 275.712042 -307.944272) (xy 275.760897 -307.950204) (xy 275.808168 -307.963896)
			(xy 275.85263 -307.984994) (xy 275.893133 -308.01295) (xy 275.928626 -308.047042) (xy 275.958191 -308.086386)
			(xy 275.981062 -308.129963) (xy 275.996646 -308.176644) (xy 276.004541 -308.225221) (xy 276.005036 -308.249828)
			(xy 276.343884 -308.249828) (xy 276.347844 -308.200774) (xy 276.359621 -308.15299) (xy 276.378912 -308.107714)
			(xy 276.405215 -308.066118) (xy 276.43785 -308.029281) (xy 276.475971 -307.998156) (xy 276.518592 -307.973549)
			(xy 276.564608 -307.956097) (xy 276.612827 -307.946253) (xy 276.662002 -307.944272) (xy 276.710857 -307.950204)
			(xy 276.758128 -307.963896) (xy 276.80259 -307.984994) (xy 276.843093 -308.01295) (xy 276.878586 -308.047042)
			(xy 276.908151 -308.086386) (xy 276.931022 -308.129963) (xy 276.946606 -308.176644) (xy 276.954501 -308.225221)
			(xy 276.954996 -308.249828) (xy 306.744128 -308.249828) (xy 306.748088 -308.200774) (xy 306.759865 -308.15299)
			(xy 306.779156 -308.107714) (xy 306.805459 -308.066118) (xy 306.838094 -308.029281) (xy 306.876215 -307.998156)
			(xy 306.918836 -307.973549) (xy 306.964852 -307.956097) (xy 307.013071 -307.946253) (xy 307.062246 -307.944272)
			(xy 307.111101 -307.950204) (xy 307.158372 -307.963896) (xy 307.202834 -307.984994) (xy 307.243337 -308.01295)
			(xy 307.27883 -308.047042) (xy 307.308395 -308.086386) (xy 307.331266 -308.129963) (xy 307.34685 -308.176644)
			(xy 307.354745 -308.225221) (xy 307.35524 -308.249828) (xy 307.694088 -308.249828) (xy 307.698048 -308.200774)
			(xy 307.709825 -308.15299) (xy 307.729116 -308.107714) (xy 307.755419 -308.066118) (xy 307.788054 -308.029281)
			(xy 307.826175 -307.998156) (xy 307.868796 -307.973549) (xy 307.914812 -307.956097) (xy 307.963031 -307.946253)
			(xy 308.012206 -307.944272) (xy 308.061061 -307.950204) (xy 308.108332 -307.963896) (xy 308.152794 -307.984994)
			(xy 308.193297 -308.01295) (xy 308.22879 -308.047042) (xy 308.258355 -308.086386) (xy 308.281226 -308.129963)
			(xy 308.29681 -308.176644) (xy 308.304705 -308.225221) (xy 308.3052 -308.249828) (xy 313.394102 -308.249828)
			(xy 313.398062 -308.200774) (xy 313.409839 -308.15299) (xy 313.42913 -308.107714) (xy 313.455433 -308.066118)
			(xy 313.488068 -308.029281) (xy 313.526189 -307.998156) (xy 313.56881 -307.973549) (xy 313.614826 -307.956097)
			(xy 313.663045 -307.946253) (xy 313.71222 -307.944272) (xy 313.761075 -307.950204) (xy 313.808346 -307.963896)
			(xy 313.852808 -307.984994) (xy 313.893311 -308.01295) (xy 313.928804 -308.047042) (xy 313.958369 -308.086386)
			(xy 313.98124 -308.129963) (xy 313.996824 -308.176644) (xy 314.004719 -308.225221) (xy 314.005214 -308.249828)
			(xy 314.344062 -308.249828) (xy 314.348022 -308.200774) (xy 314.359799 -308.15299) (xy 314.37909 -308.107714)
			(xy 314.405393 -308.066118) (xy 314.438028 -308.029281) (xy 314.476149 -307.998156) (xy 314.51877 -307.973549)
			(xy 314.564786 -307.956097) (xy 314.613005 -307.946253) (xy 314.66218 -307.944272) (xy 314.711035 -307.950204)
			(xy 314.758306 -307.963896) (xy 314.802768 -307.984994) (xy 314.843271 -308.01295) (xy 314.878764 -308.047042)
			(xy 314.908329 -308.086386) (xy 314.9312 -308.129963) (xy 314.946784 -308.176644) (xy 314.954679 -308.225221)
			(xy 314.955174 -308.249828) (xy 384.844048 -308.249828) (xy 384.848008 -308.200774) (xy 384.859785 -308.15299)
			(xy 384.879076 -308.107714) (xy 384.905379 -308.066118) (xy 384.938014 -308.029281) (xy 384.976135 -307.998156)
			(xy 385.018756 -307.973549) (xy 385.064772 -307.956097) (xy 385.112991 -307.946253) (xy 385.162166 -307.944272)
			(xy 385.211021 -307.950204) (xy 385.258292 -307.963896) (xy 385.302754 -307.984994) (xy 385.343257 -308.01295)
			(xy 385.37875 -308.047042) (xy 385.408315 -308.086386) (xy 385.431186 -308.129963) (xy 385.44677 -308.176644)
			(xy 385.454665 -308.225221) (xy 385.45516 -308.249828) (xy 385.794008 -308.249828) (xy 385.797968 -308.200774)
			(xy 385.809745 -308.15299) (xy 385.829036 -308.107714) (xy 385.855339 -308.066118) (xy 385.887974 -308.029281)
			(xy 385.926095 -307.998156) (xy 385.968716 -307.973549) (xy 386.014732 -307.956097) (xy 386.062951 -307.946253)
			(xy 386.112126 -307.944272) (xy 386.160981 -307.950204) (xy 386.208252 -307.963896) (xy 386.252714 -307.984994)
			(xy 386.293217 -308.01295) (xy 386.32871 -308.047042) (xy 386.358275 -308.086386) (xy 386.381146 -308.129963)
			(xy 386.39673 -308.176644) (xy 386.404625 -308.225221) (xy 386.40512 -308.249828) (xy 391.494022 -308.249828)
			(xy 391.497982 -308.200774) (xy 391.509759 -308.15299) (xy 391.52905 -308.107714) (xy 391.555353 -308.066118)
			(xy 391.587988 -308.029281) (xy 391.626109 -307.998156) (xy 391.66873 -307.973549) (xy 391.714746 -307.956097)
			(xy 391.762965 -307.946253) (xy 391.81214 -307.944272) (xy 391.860995 -307.950204) (xy 391.908266 -307.963896)
			(xy 391.952728 -307.984994) (xy 391.993231 -308.01295) (xy 392.028724 -308.047042) (xy 392.058289 -308.086386)
			(xy 392.08116 -308.129963) (xy 392.096744 -308.176644) (xy 392.104639 -308.225221) (xy 392.105134 -308.249828)
			(xy 392.443982 -308.249828) (xy 392.447942 -308.200774) (xy 392.459719 -308.15299) (xy 392.47901 -308.107714)
			(xy 392.505313 -308.066118) (xy 392.537948 -308.029281) (xy 392.576069 -307.998156) (xy 392.61869 -307.973549)
			(xy 392.664706 -307.956097) (xy 392.712925 -307.946253) (xy 392.7621 -307.944272) (xy 392.810955 -307.950204)
			(xy 392.858226 -307.963896) (xy 392.902688 -307.984994) (xy 392.943191 -308.01295) (xy 392.978684 -308.047042)
			(xy 393.008249 -308.086386) (xy 393.03112 -308.129963) (xy 393.046704 -308.176644) (xy 393.054599 -308.225221)
			(xy 393.055094 -308.249828) (xy 422.844226 -308.249828) (xy 422.848186 -308.200774) (xy 422.859963 -308.15299)
			(xy 422.879254 -308.107714) (xy 422.905557 -308.066118) (xy 422.938192 -308.029281) (xy 422.976313 -307.998156)
			(xy 423.018934 -307.973549) (xy 423.06495 -307.956097) (xy 423.113169 -307.946253) (xy 423.162344 -307.944272)
			(xy 423.211199 -307.950204) (xy 423.25847 -307.963896) (xy 423.302932 -307.984994) (xy 423.343435 -308.01295)
			(xy 423.378928 -308.047042) (xy 423.408493 -308.086386) (xy 423.431364 -308.129963) (xy 423.446948 -308.176644)
			(xy 423.454843 -308.225221) (xy 423.455338 -308.249828) (xy 423.794186 -308.249828) (xy 423.798146 -308.200774)
			(xy 423.809923 -308.15299) (xy 423.829214 -308.107714) (xy 423.855517 -308.066118) (xy 423.888152 -308.029281)
			(xy 423.926273 -307.998156) (xy 423.968894 -307.973549) (xy 424.01491 -307.956097) (xy 424.063129 -307.946253)
			(xy 424.112304 -307.944272) (xy 424.161159 -307.950204) (xy 424.20843 -307.963896) (xy 424.252892 -307.984994)
			(xy 424.293395 -308.01295) (xy 424.328888 -308.047042) (xy 424.358453 -308.086386) (xy 424.381324 -308.129963)
			(xy 424.396908 -308.176644) (xy 424.404803 -308.225221) (xy 424.405298 -308.249828) (xy 424.404803 -308.274435)
			(xy 424.396908 -308.323012) (xy 424.381324 -308.369693) (xy 424.358453 -308.41327) (xy 424.328888 -308.452614)
			(xy 424.293395 -308.486706) (xy 424.252892 -308.514662) (xy 424.20843 -308.53576) (xy 424.161159 -308.549452)
			(xy 424.112304 -308.555384) (xy 424.063129 -308.553403) (xy 424.01491 -308.543559) (xy 423.968894 -308.526107)
			(xy 423.926273 -308.5015) (xy 423.888152 -308.470375) (xy 423.855517 -308.433538) (xy 423.829214 -308.391942)
			(xy 423.809923 -308.346666) (xy 423.798146 -308.298882) (xy 423.794186 -308.249828) (xy 423.455338 -308.249828)
			(xy 423.454843 -308.274435) (xy 423.446948 -308.323012) (xy 423.431364 -308.369693) (xy 423.408493 -308.41327)
			(xy 423.378928 -308.452614) (xy 423.343435 -308.486706) (xy 423.302932 -308.514662) (xy 423.25847 -308.53576)
			(xy 423.211199 -308.549452) (xy 423.162344 -308.555384) (xy 423.113169 -308.553403) (xy 423.06495 -308.543559)
			(xy 423.018934 -308.526107) (xy 422.976313 -308.5015) (xy 422.938192 -308.470375) (xy 422.905557 -308.433538)
			(xy 422.879254 -308.391942) (xy 422.859963 -308.346666) (xy 422.848186 -308.298882) (xy 422.844226 -308.249828)
			(xy 393.055094 -308.249828) (xy 393.054599 -308.274435) (xy 393.046704 -308.323012) (xy 393.03112 -308.369693)
			(xy 393.008249 -308.41327) (xy 392.978684 -308.452614) (xy 392.943191 -308.486706) (xy 392.902688 -308.514662)
			(xy 392.858226 -308.53576) (xy 392.810955 -308.549452) (xy 392.7621 -308.555384) (xy 392.712925 -308.553403)
			(xy 392.664706 -308.543559) (xy 392.61869 -308.526107) (xy 392.576069 -308.5015) (xy 392.537948 -308.470375)
			(xy 392.505313 -308.433538) (xy 392.47901 -308.391942) (xy 392.459719 -308.346666) (xy 392.447942 -308.298882)
			(xy 392.443982 -308.249828) (xy 392.105134 -308.249828) (xy 392.104639 -308.274435) (xy 392.096744 -308.323012)
			(xy 392.08116 -308.369693) (xy 392.058289 -308.41327) (xy 392.028724 -308.452614) (xy 391.993231 -308.486706)
			(xy 391.952728 -308.514662) (xy 391.908266 -308.53576) (xy 391.860995 -308.549452) (xy 391.81214 -308.555384)
			(xy 391.762965 -308.553403) (xy 391.714746 -308.543559) (xy 391.66873 -308.526107) (xy 391.626109 -308.5015)
			(xy 391.587988 -308.470375) (xy 391.555353 -308.433538) (xy 391.52905 -308.391942) (xy 391.509759 -308.346666)
			(xy 391.497982 -308.298882) (xy 391.494022 -308.249828) (xy 386.40512 -308.249828) (xy 386.404625 -308.274435)
			(xy 386.39673 -308.323012) (xy 386.381146 -308.369693) (xy 386.358275 -308.41327) (xy 386.32871 -308.452614)
			(xy 386.293217 -308.486706) (xy 386.252714 -308.514662) (xy 386.208252 -308.53576) (xy 386.160981 -308.549452)
			(xy 386.112126 -308.555384) (xy 386.062951 -308.553403) (xy 386.014732 -308.543559) (xy 385.968716 -308.526107)
			(xy 385.926095 -308.5015) (xy 385.887974 -308.470375) (xy 385.855339 -308.433538) (xy 385.829036 -308.391942)
			(xy 385.809745 -308.346666) (xy 385.797968 -308.298882) (xy 385.794008 -308.249828) (xy 385.45516 -308.249828)
			(xy 385.454665 -308.274435) (xy 385.44677 -308.323012) (xy 385.431186 -308.369693) (xy 385.408315 -308.41327)
			(xy 385.37875 -308.452614) (xy 385.343257 -308.486706) (xy 385.302754 -308.514662) (xy 385.258292 -308.53576)
			(xy 385.211021 -308.549452) (xy 385.162166 -308.555384) (xy 385.112991 -308.553403) (xy 385.064772 -308.543559)
			(xy 385.018756 -308.526107) (xy 384.976135 -308.5015) (xy 384.938014 -308.470375) (xy 384.905379 -308.433538)
			(xy 384.879076 -308.391942) (xy 384.859785 -308.346666) (xy 384.848008 -308.298882) (xy 384.844048 -308.249828)
			(xy 314.955174 -308.249828) (xy 314.954679 -308.274435) (xy 314.946784 -308.323012) (xy 314.9312 -308.369693)
			(xy 314.908329 -308.41327) (xy 314.878764 -308.452614) (xy 314.843271 -308.486706) (xy 314.802768 -308.514662)
			(xy 314.758306 -308.53576) (xy 314.711035 -308.549452) (xy 314.66218 -308.555384) (xy 314.613005 -308.553403)
			(xy 314.564786 -308.543559) (xy 314.51877 -308.526107) (xy 314.476149 -308.5015) (xy 314.438028 -308.470375)
			(xy 314.405393 -308.433538) (xy 314.37909 -308.391942) (xy 314.359799 -308.346666) (xy 314.348022 -308.298882)
			(xy 314.344062 -308.249828) (xy 314.005214 -308.249828) (xy 314.004719 -308.274435) (xy 313.996824 -308.323012)
			(xy 313.98124 -308.369693) (xy 313.958369 -308.41327) (xy 313.928804 -308.452614) (xy 313.893311 -308.486706)
			(xy 313.852808 -308.514662) (xy 313.808346 -308.53576) (xy 313.761075 -308.549452) (xy 313.71222 -308.555384)
			(xy 313.663045 -308.553403) (xy 313.614826 -308.543559) (xy 313.56881 -308.526107) (xy 313.526189 -308.5015)
			(xy 313.488068 -308.470375) (xy 313.455433 -308.433538) (xy 313.42913 -308.391942) (xy 313.409839 -308.346666)
			(xy 313.398062 -308.298882) (xy 313.394102 -308.249828) (xy 308.3052 -308.249828) (xy 308.304705 -308.274435)
			(xy 308.29681 -308.323012) (xy 308.281226 -308.369693) (xy 308.258355 -308.41327) (xy 308.22879 -308.452614)
			(xy 308.193297 -308.486706) (xy 308.152794 -308.514662) (xy 308.108332 -308.53576) (xy 308.061061 -308.549452)
			(xy 308.012206 -308.555384) (xy 307.963031 -308.553403) (xy 307.914812 -308.543559) (xy 307.868796 -308.526107)
			(xy 307.826175 -308.5015) (xy 307.788054 -308.470375) (xy 307.755419 -308.433538) (xy 307.729116 -308.391942)
			(xy 307.709825 -308.346666) (xy 307.698048 -308.298882) (xy 307.694088 -308.249828) (xy 307.35524 -308.249828)
			(xy 307.354745 -308.274435) (xy 307.34685 -308.323012) (xy 307.331266 -308.369693) (xy 307.308395 -308.41327)
			(xy 307.27883 -308.452614) (xy 307.243337 -308.486706) (xy 307.202834 -308.514662) (xy 307.158372 -308.53576)
			(xy 307.111101 -308.549452) (xy 307.062246 -308.555384) (xy 307.013071 -308.553403) (xy 306.964852 -308.543559)
			(xy 306.918836 -308.526107) (xy 306.876215 -308.5015) (xy 306.838094 -308.470375) (xy 306.805459 -308.433538)
			(xy 306.779156 -308.391942) (xy 306.759865 -308.346666) (xy 306.748088 -308.298882) (xy 306.744128 -308.249828)
			(xy 276.954996 -308.249828) (xy 276.954501 -308.274435) (xy 276.946606 -308.323012) (xy 276.931022 -308.369693)
			(xy 276.908151 -308.41327) (xy 276.878586 -308.452614) (xy 276.843093 -308.486706) (xy 276.80259 -308.514662)
			(xy 276.758128 -308.53576) (xy 276.710857 -308.549452) (xy 276.662002 -308.555384) (xy 276.612827 -308.553403)
			(xy 276.564608 -308.543559) (xy 276.518592 -308.526107) (xy 276.475971 -308.5015) (xy 276.43785 -308.470375)
			(xy 276.405215 -308.433538) (xy 276.378912 -308.391942) (xy 276.359621 -308.346666) (xy 276.347844 -308.298882)
			(xy 276.343884 -308.249828) (xy 276.005036 -308.249828) (xy 276.004541 -308.274435) (xy 275.996646 -308.323012)
			(xy 275.981062 -308.369693) (xy 275.958191 -308.41327) (xy 275.928626 -308.452614) (xy 275.893133 -308.486706)
			(xy 275.85263 -308.514662) (xy 275.808168 -308.53576) (xy 275.760897 -308.549452) (xy 275.712042 -308.555384)
			(xy 275.662867 -308.553403) (xy 275.614648 -308.543559) (xy 275.568632 -308.526107) (xy 275.526011 -308.5015)
			(xy 275.48789 -308.470375) (xy 275.455255 -308.433538) (xy 275.428952 -308.391942) (xy 275.409661 -308.346666)
			(xy 275.397884 -308.298882) (xy 275.393924 -308.249828) (xy 248.77707 -308.249828) (xy 248.790385 -308.257954)
			(xy 248.833281 -308.293653) (xy 248.870523 -308.335217) (xy 248.901317 -308.381761) (xy 248.925005 -308.432292)
			(xy 248.941083 -308.485734) (xy 248.949209 -308.540948) (xy 248.949718 -308.568852) (xy 248.949209 -308.596756)
			(xy 248.941083 -308.65197) (xy 248.928951 -308.692296) (xy 462.556604 -308.692296) (xy 462.560677 -308.636637)
			(xy 462.572812 -308.582164) (xy 462.592748 -308.530038) (xy 462.620062 -308.48137) (xy 462.65417 -308.437198)
			(xy 462.694347 -308.398463) (xy 462.739735 -308.365991) (xy 462.789367 -308.340473) (xy 462.842187 -308.322454)
			(xy 462.897066 -308.312317) (xy 462.952837 -308.310279) (xy 463.008311 -308.316382) (xy 463.062304 -308.330498)
			(xy 463.113667 -308.352325) (xy 463.161305 -308.381398) (xy 463.204201 -308.417097) (xy 463.241443 -308.458661)
			(xy 463.272237 -308.505205) (xy 463.295925 -308.555736) (xy 463.312003 -308.609178) (xy 463.320129 -308.664392)
			(xy 463.320638 -308.692296) (xy 463.320129 -308.7202) (xy 463.312003 -308.775414) (xy 463.295925 -308.828856)
			(xy 463.272237 -308.879387) (xy 463.241443 -308.925931) (xy 463.204201 -308.967495) (xy 463.161305 -309.003194)
			(xy 463.113667 -309.032267) (xy 463.062304 -309.054094) (xy 463.008311 -309.06821) (xy 462.952837 -309.074313)
			(xy 462.897066 -309.072275) (xy 462.842187 -309.062138) (xy 462.789367 -309.044119) (xy 462.739735 -309.018601)
			(xy 462.694347 -308.986129) (xy 462.65417 -308.947394) (xy 462.620062 -308.903222) (xy 462.592748 -308.854554)
			(xy 462.572812 -308.802428) (xy 462.560677 -308.747955) (xy 462.556604 -308.692296) (xy 248.928951 -308.692296)
			(xy 248.925005 -308.705412) (xy 248.901317 -308.755943) (xy 248.870523 -308.802487) (xy 248.833281 -308.844051)
			(xy 248.790385 -308.87975) (xy 248.742747 -308.908823) (xy 248.691384 -308.93065) (xy 248.637391 -308.944766)
			(xy 248.581917 -308.950869) (xy 248.526146 -308.948831) (xy 248.471267 -308.938694) (xy 248.418447 -308.920675)
			(xy 248.368815 -308.895157) (xy 248.323427 -308.862685) (xy 248.28325 -308.82395) (xy 248.249142 -308.779778)
			(xy 248.221828 -308.73111) (xy 248.201892 -308.678984) (xy 248.189757 -308.624511) (xy 248.185684 -308.568852)
			(xy 232.69956 -308.568852) (xy 232.699051 -308.596756) (xy 232.690925 -308.65197) (xy 232.674847 -308.705412)
			(xy 232.651159 -308.755943) (xy 232.620365 -308.802487) (xy 232.583123 -308.844051) (xy 232.540227 -308.87975)
			(xy 232.492589 -308.908823) (xy 232.441226 -308.93065) (xy 232.387233 -308.944766) (xy 232.331759 -308.950869)
			(xy 232.275988 -308.948831) (xy 232.221109 -308.938694) (xy 232.168289 -308.920675) (xy 232.118657 -308.895157)
			(xy 232.073269 -308.862685) (xy 232.033092 -308.82395) (xy 231.998984 -308.779778) (xy 231.97167 -308.73111)
			(xy 231.951734 -308.678984) (xy 231.939599 -308.624511) (xy 231.935526 -308.568852) (xy 0.508 -308.568852)
			(xy 0.508 -309.199788) (xy 41.294062 -309.199788) (xy 41.298022 -309.150734) (xy 41.309799 -309.10295)
			(xy 41.32909 -309.057674) (xy 41.355393 -309.016078) (xy 41.388028 -308.979241) (xy 41.426149 -308.948116)
			(xy 41.46877 -308.923509) (xy 41.514786 -308.906057) (xy 41.563005 -308.896213) (xy 41.61218 -308.894232)
			(xy 41.661035 -308.900164) (xy 41.708306 -308.913856) (xy 41.752768 -308.934954) (xy 41.793271 -308.96291)
			(xy 41.828764 -308.997002) (xy 41.858329 -309.036346) (xy 41.8812 -309.079923) (xy 41.896784 -309.126604)
			(xy 41.904679 -309.175181) (xy 41.905174 -309.199788) (xy 42.244022 -309.199788) (xy 42.247982 -309.150734)
			(xy 42.259759 -309.10295) (xy 42.27905 -309.057674) (xy 42.305353 -309.016078) (xy 42.337988 -308.979241)
			(xy 42.376109 -308.948116) (xy 42.41873 -308.923509) (xy 42.464746 -308.906057) (xy 42.512965 -308.896213)
			(xy 42.56214 -308.894232) (xy 42.610995 -308.900164) (xy 42.658266 -308.913856) (xy 42.702728 -308.934954)
			(xy 42.743231 -308.96291) (xy 42.778724 -308.997002) (xy 42.808289 -309.036346) (xy 42.83116 -309.079923)
			(xy 42.846744 -309.126604) (xy 42.854639 -309.175181) (xy 42.855134 -309.199788) (xy 76.444106 -309.199788)
			(xy 76.448066 -309.150734) (xy 76.459843 -309.10295) (xy 76.479134 -309.057674) (xy 76.505437 -309.016078)
			(xy 76.538072 -308.979241) (xy 76.576193 -308.948116) (xy 76.618814 -308.923509) (xy 76.66483 -308.906057)
			(xy 76.713049 -308.896213) (xy 76.762224 -308.894232) (xy 76.811079 -308.900164) (xy 76.85835 -308.913856)
			(xy 76.902812 -308.934954) (xy 76.943315 -308.96291) (xy 76.978808 -308.997002) (xy 77.008373 -309.036346)
			(xy 77.031244 -309.079923) (xy 77.046828 -309.126604) (xy 77.054723 -309.175181) (xy 77.055218 -309.199788)
			(xy 77.394066 -309.199788) (xy 77.398026 -309.150734) (xy 77.409803 -309.10295) (xy 77.429094 -309.057674)
			(xy 77.455397 -309.016078) (xy 77.488032 -308.979241) (xy 77.526153 -308.948116) (xy 77.568774 -308.923509)
			(xy 77.61479 -308.906057) (xy 77.663009 -308.896213) (xy 77.712184 -308.894232) (xy 77.761039 -308.900164)
			(xy 77.80831 -308.913856) (xy 77.852772 -308.934954) (xy 77.893275 -308.96291) (xy 77.928768 -308.997002)
			(xy 77.958333 -309.036346) (xy 77.981204 -309.079923) (xy 77.996788 -309.126604) (xy 78.004683 -309.175181)
			(xy 78.005178 -309.199788) (xy 79.293986 -309.199788) (xy 79.297946 -309.150734) (xy 79.309723 -309.10295)
			(xy 79.329014 -309.057674) (xy 79.355317 -309.016078) (xy 79.387952 -308.979241) (xy 79.426073 -308.948116)
			(xy 79.468694 -308.923509) (xy 79.51471 -308.906057) (xy 79.562929 -308.896213) (xy 79.612104 -308.894232)
			(xy 79.660959 -308.900164) (xy 79.70823 -308.913856) (xy 79.752692 -308.934954) (xy 79.793195 -308.96291)
			(xy 79.828688 -308.997002) (xy 79.858253 -309.036346) (xy 79.881124 -309.079923) (xy 79.896708 -309.126604)
			(xy 79.904603 -309.175181) (xy 79.905098 -309.199788) (xy 80.243946 -309.199788) (xy 80.247906 -309.150734)
			(xy 80.259683 -309.10295) (xy 80.278974 -309.057674) (xy 80.305277 -309.016078) (xy 80.337912 -308.979241)
			(xy 80.376033 -308.948116) (xy 80.418654 -308.923509) (xy 80.46467 -308.906057) (xy 80.512889 -308.896213)
			(xy 80.562064 -308.894232) (xy 80.610919 -308.900164) (xy 80.65819 -308.913856) (xy 80.702652 -308.934954)
			(xy 80.743155 -308.96291) (xy 80.778648 -308.997002) (xy 80.808213 -309.036346) (xy 80.831084 -309.079923)
			(xy 80.846668 -309.126604) (xy 80.854563 -309.175181) (xy 80.855058 -309.199788) (xy 154.54428 -309.199788)
			(xy 154.54824 -309.150734) (xy 154.560017 -309.10295) (xy 154.579308 -309.057674) (xy 154.605611 -309.016078)
			(xy 154.638246 -308.979241) (xy 154.676367 -308.948116) (xy 154.718988 -308.923509) (xy 154.765004 -308.906057)
			(xy 154.813223 -308.896213) (xy 154.862398 -308.894232) (xy 154.911253 -308.900164) (xy 154.958524 -308.913856)
			(xy 155.002986 -308.934954) (xy 155.043489 -308.96291) (xy 155.078982 -308.997002) (xy 155.108547 -309.036346)
			(xy 155.131418 -309.079923) (xy 155.147002 -309.126604) (xy 155.154897 -309.175181) (xy 155.155392 -309.199788)
			(xy 155.49424 -309.199788) (xy 155.4982 -309.150734) (xy 155.509977 -309.10295) (xy 155.529268 -309.057674)
			(xy 155.555571 -309.016078) (xy 155.588206 -308.979241) (xy 155.626327 -308.948116) (xy 155.668948 -308.923509)
			(xy 155.714964 -308.906057) (xy 155.763183 -308.896213) (xy 155.812358 -308.894232) (xy 155.861213 -308.900164)
			(xy 155.908484 -308.913856) (xy 155.952946 -308.934954) (xy 155.993449 -308.96291) (xy 156.028942 -308.997002)
			(xy 156.058507 -309.036346) (xy 156.081378 -309.079923) (xy 156.096962 -309.126604) (xy 156.104857 -309.175181)
			(xy 156.105352 -309.199788) (xy 157.39416 -309.199788) (xy 157.39812 -309.150734) (xy 157.409897 -309.10295)
			(xy 157.429188 -309.057674) (xy 157.455491 -309.016078) (xy 157.488126 -308.979241) (xy 157.526247 -308.948116)
			(xy 157.568868 -308.923509) (xy 157.614884 -308.906057) (xy 157.663103 -308.896213) (xy 157.712278 -308.894232)
			(xy 157.761133 -308.900164) (xy 157.808404 -308.913856) (xy 157.852866 -308.934954) (xy 157.893369 -308.96291)
			(xy 157.928862 -308.997002) (xy 157.958427 -309.036346) (xy 157.981298 -309.079923) (xy 157.996882 -309.126604)
			(xy 158.004777 -309.175181) (xy 158.005272 -309.199788) (xy 158.34412 -309.199788) (xy 158.34808 -309.150734)
			(xy 158.359857 -309.10295) (xy 158.379148 -309.057674) (xy 158.405451 -309.016078) (xy 158.438086 -308.979241)
			(xy 158.476207 -308.948116) (xy 158.518828 -308.923509) (xy 158.564844 -308.906057) (xy 158.613063 -308.896213)
			(xy 158.662238 -308.894232) (xy 158.711093 -308.900164) (xy 158.758364 -308.913856) (xy 158.802826 -308.934954)
			(xy 158.843329 -308.96291) (xy 158.878822 -308.997002) (xy 158.908387 -309.036346) (xy 158.931258 -309.079923)
			(xy 158.946842 -309.126604) (xy 158.954737 -309.175181) (xy 158.955232 -309.199788) (xy 192.544204 -309.199788)
			(xy 192.548164 -309.150734) (xy 192.559941 -309.10295) (xy 192.579232 -309.057674) (xy 192.605535 -309.016078)
			(xy 192.63817 -308.979241) (xy 192.676291 -308.948116) (xy 192.718912 -308.923509) (xy 192.764928 -308.906057)
			(xy 192.813147 -308.896213) (xy 192.862322 -308.894232) (xy 192.911177 -308.900164) (xy 192.958448 -308.913856)
			(xy 193.00291 -308.934954) (xy 193.043413 -308.96291) (xy 193.078906 -308.997002) (xy 193.108471 -309.036346)
			(xy 193.131342 -309.079923) (xy 193.146926 -309.126604) (xy 193.154821 -309.175181) (xy 193.155316 -309.199788)
			(xy 193.494164 -309.199788) (xy 193.498124 -309.150734) (xy 193.509901 -309.10295) (xy 193.529192 -309.057674)
			(xy 193.555495 -309.016078) (xy 193.58813 -308.979241) (xy 193.626251 -308.948116) (xy 193.668872 -308.923509)
			(xy 193.714888 -308.906057) (xy 193.763107 -308.896213) (xy 193.812282 -308.894232) (xy 193.861137 -308.900164)
			(xy 193.908408 -308.913856) (xy 193.95287 -308.934954) (xy 193.993373 -308.96291) (xy 194.028866 -308.997002)
			(xy 194.058431 -309.036346) (xy 194.081302 -309.079923) (xy 194.096886 -309.126604) (xy 194.104781 -309.175181)
			(xy 194.105276 -309.199788) (xy 273.494004 -309.199788) (xy 273.497964 -309.150734) (xy 273.509741 -309.10295)
			(xy 273.529032 -309.057674) (xy 273.555335 -309.016078) (xy 273.58797 -308.979241) (xy 273.626091 -308.948116)
			(xy 273.668712 -308.923509) (xy 273.714728 -308.906057) (xy 273.762947 -308.896213) (xy 273.812122 -308.894232)
			(xy 273.860977 -308.900164) (xy 273.908248 -308.913856) (xy 273.95271 -308.934954) (xy 273.993213 -308.96291)
			(xy 274.028706 -308.997002) (xy 274.058271 -309.036346) (xy 274.081142 -309.079923) (xy 274.096726 -309.126604)
			(xy 274.104621 -309.175181) (xy 274.105116 -309.199788) (xy 274.443964 -309.199788) (xy 274.447924 -309.150734)
			(xy 274.459701 -309.10295) (xy 274.478992 -309.057674) (xy 274.505295 -309.016078) (xy 274.53793 -308.979241)
			(xy 274.576051 -308.948116) (xy 274.618672 -308.923509) (xy 274.664688 -308.906057) (xy 274.712907 -308.896213)
			(xy 274.762082 -308.894232) (xy 274.810937 -308.900164) (xy 274.858208 -308.913856) (xy 274.90267 -308.934954)
			(xy 274.943173 -308.96291) (xy 274.978666 -308.997002) (xy 275.008231 -309.036346) (xy 275.031102 -309.079923)
			(xy 275.046686 -309.126604) (xy 275.054581 -309.175181) (xy 275.055076 -309.199788) (xy 308.644048 -309.199788)
			(xy 308.648008 -309.150734) (xy 308.659785 -309.10295) (xy 308.679076 -309.057674) (xy 308.705379 -309.016078)
			(xy 308.738014 -308.979241) (xy 308.776135 -308.948116) (xy 308.818756 -308.923509) (xy 308.864772 -308.906057)
			(xy 308.912991 -308.896213) (xy 308.962166 -308.894232) (xy 309.011021 -308.900164) (xy 309.058292 -308.913856)
			(xy 309.102754 -308.934954) (xy 309.143257 -308.96291) (xy 309.17875 -308.997002) (xy 309.208315 -309.036346)
			(xy 309.231186 -309.079923) (xy 309.24677 -309.126604) (xy 309.254665 -309.175181) (xy 309.25516 -309.199788)
			(xy 309.594008 -309.199788) (xy 309.597968 -309.150734) (xy 309.609745 -309.10295) (xy 309.629036 -309.057674)
			(xy 309.655339 -309.016078) (xy 309.687974 -308.979241) (xy 309.726095 -308.948116) (xy 309.768716 -308.923509)
			(xy 309.814732 -308.906057) (xy 309.862951 -308.896213) (xy 309.912126 -308.894232) (xy 309.960981 -308.900164)
			(xy 310.008252 -308.913856) (xy 310.052714 -308.934954) (xy 310.093217 -308.96291) (xy 310.12871 -308.997002)
			(xy 310.158275 -309.036346) (xy 310.181146 -309.079923) (xy 310.19673 -309.126604) (xy 310.204625 -309.175181)
			(xy 310.20512 -309.199788) (xy 311.493928 -309.199788) (xy 311.497888 -309.150734) (xy 311.509665 -309.10295)
			(xy 311.528956 -309.057674) (xy 311.555259 -309.016078) (xy 311.587894 -308.979241) (xy 311.626015 -308.948116)
			(xy 311.668636 -308.923509) (xy 311.714652 -308.906057) (xy 311.762871 -308.896213) (xy 311.812046 -308.894232)
			(xy 311.860901 -308.900164) (xy 311.908172 -308.913856) (xy 311.952634 -308.934954) (xy 311.993137 -308.96291)
			(xy 312.02863 -308.997002) (xy 312.058195 -309.036346) (xy 312.081066 -309.079923) (xy 312.09665 -309.126604)
			(xy 312.104545 -309.175181) (xy 312.10504 -309.199788) (xy 312.443888 -309.199788) (xy 312.447848 -309.150734)
			(xy 312.459625 -309.10295) (xy 312.478916 -309.057674) (xy 312.505219 -309.016078) (xy 312.537854 -308.979241)
			(xy 312.575975 -308.948116) (xy 312.618596 -308.923509) (xy 312.664612 -308.906057) (xy 312.712831 -308.896213)
			(xy 312.762006 -308.894232) (xy 312.810861 -308.900164) (xy 312.858132 -308.913856) (xy 312.902594 -308.934954)
			(xy 312.943097 -308.96291) (xy 312.97859 -308.997002) (xy 313.008155 -309.036346) (xy 313.031026 -309.079923)
			(xy 313.04661 -309.126604) (xy 313.054505 -309.175181) (xy 313.055 -309.199788) (xy 386.744222 -309.199788)
			(xy 386.748182 -309.150734) (xy 386.759959 -309.10295) (xy 386.77925 -309.057674) (xy 386.805553 -309.016078)
			(xy 386.838188 -308.979241) (xy 386.876309 -308.948116) (xy 386.91893 -308.923509) (xy 386.964946 -308.906057)
			(xy 387.013165 -308.896213) (xy 387.06234 -308.894232) (xy 387.111195 -308.900164) (xy 387.158466 -308.913856)
			(xy 387.202928 -308.934954) (xy 387.243431 -308.96291) (xy 387.278924 -308.997002) (xy 387.308489 -309.036346)
			(xy 387.33136 -309.079923) (xy 387.346944 -309.126604) (xy 387.354839 -309.175181) (xy 387.355334 -309.199788)
			(xy 387.694182 -309.199788) (xy 387.698142 -309.150734) (xy 387.709919 -309.10295) (xy 387.72921 -309.057674)
			(xy 387.755513 -309.016078) (xy 387.788148 -308.979241) (xy 387.826269 -308.948116) (xy 387.86889 -308.923509)
			(xy 387.914906 -308.906057) (xy 387.963125 -308.896213) (xy 388.0123 -308.894232) (xy 388.061155 -308.900164)
			(xy 388.108426 -308.913856) (xy 388.152888 -308.934954) (xy 388.193391 -308.96291) (xy 388.228884 -308.997002)
			(xy 388.258449 -309.036346) (xy 388.28132 -309.079923) (xy 388.296904 -309.126604) (xy 388.304799 -309.175181)
			(xy 388.305294 -309.199788) (xy 389.594102 -309.199788) (xy 389.598062 -309.150734) (xy 389.609839 -309.10295)
			(xy 389.62913 -309.057674) (xy 389.655433 -309.016078) (xy 389.688068 -308.979241) (xy 389.726189 -308.948116)
			(xy 389.76881 -308.923509) (xy 389.814826 -308.906057) (xy 389.863045 -308.896213) (xy 389.91222 -308.894232)
			(xy 389.961075 -308.900164) (xy 390.008346 -308.913856) (xy 390.052808 -308.934954) (xy 390.093311 -308.96291)
			(xy 390.128804 -308.997002) (xy 390.158369 -309.036346) (xy 390.18124 -309.079923) (xy 390.196824 -309.126604)
			(xy 390.204719 -309.175181) (xy 390.205214 -309.199788) (xy 390.544062 -309.199788) (xy 390.548022 -309.150734)
			(xy 390.559799 -309.10295) (xy 390.57909 -309.057674) (xy 390.605393 -309.016078) (xy 390.638028 -308.979241)
			(xy 390.676149 -308.948116) (xy 390.71877 -308.923509) (xy 390.764786 -308.906057) (xy 390.813005 -308.896213)
			(xy 390.86218 -308.894232) (xy 390.911035 -308.900164) (xy 390.958306 -308.913856) (xy 391.002768 -308.934954)
			(xy 391.043271 -308.96291) (xy 391.078764 -308.997002) (xy 391.108329 -309.036346) (xy 391.1312 -309.079923)
			(xy 391.146784 -309.126604) (xy 391.154679 -309.175181) (xy 391.155174 -309.199788) (xy 424.744146 -309.199788)
			(xy 424.748106 -309.150734) (xy 424.759883 -309.10295) (xy 424.779174 -309.057674) (xy 424.805477 -309.016078)
			(xy 424.838112 -308.979241) (xy 424.876233 -308.948116) (xy 424.918854 -308.923509) (xy 424.96487 -308.906057)
			(xy 425.013089 -308.896213) (xy 425.062264 -308.894232) (xy 425.111119 -308.900164) (xy 425.15839 -308.913856)
			(xy 425.202852 -308.934954) (xy 425.243355 -308.96291) (xy 425.278848 -308.997002) (xy 425.308413 -309.036346)
			(xy 425.331284 -309.079923) (xy 425.346868 -309.126604) (xy 425.354763 -309.175181) (xy 425.355258 -309.199788)
			(xy 425.694106 -309.199788) (xy 425.698066 -309.150734) (xy 425.709843 -309.10295) (xy 425.729134 -309.057674)
			(xy 425.755437 -309.016078) (xy 425.788072 -308.979241) (xy 425.826193 -308.948116) (xy 425.868814 -308.923509)
			(xy 425.91483 -308.906057) (xy 425.963049 -308.896213) (xy 426.012224 -308.894232) (xy 426.061079 -308.900164)
			(xy 426.10835 -308.913856) (xy 426.152812 -308.934954) (xy 426.193315 -308.96291) (xy 426.228808 -308.997002)
			(xy 426.258373 -309.036346) (xy 426.281244 -309.079923) (xy 426.296828 -309.126604) (xy 426.304723 -309.175181)
			(xy 426.305218 -309.199788) (xy 426.304723 -309.224395) (xy 426.296828 -309.272972) (xy 426.281244 -309.319653)
			(xy 426.258373 -309.36323) (xy 426.228808 -309.402574) (xy 426.193315 -309.436666) (xy 426.152812 -309.464622)
			(xy 426.10835 -309.48572) (xy 426.061079 -309.499412) (xy 426.012224 -309.505344) (xy 425.963049 -309.503363)
			(xy 425.91483 -309.493519) (xy 425.868814 -309.476067) (xy 425.826193 -309.45146) (xy 425.788072 -309.420335)
			(xy 425.755437 -309.383498) (xy 425.729134 -309.341902) (xy 425.709843 -309.296626) (xy 425.698066 -309.248842)
			(xy 425.694106 -309.199788) (xy 425.355258 -309.199788) (xy 425.354763 -309.224395) (xy 425.346868 -309.272972)
			(xy 425.331284 -309.319653) (xy 425.308413 -309.36323) (xy 425.278848 -309.402574) (xy 425.243355 -309.436666)
			(xy 425.202852 -309.464622) (xy 425.15839 -309.48572) (xy 425.111119 -309.499412) (xy 425.062264 -309.505344)
			(xy 425.013089 -309.503363) (xy 424.96487 -309.493519) (xy 424.918854 -309.476067) (xy 424.876233 -309.45146)
			(xy 424.838112 -309.420335) (xy 424.805477 -309.383498) (xy 424.779174 -309.341902) (xy 424.759883 -309.296626)
			(xy 424.748106 -309.248842) (xy 424.744146 -309.199788) (xy 391.155174 -309.199788) (xy 391.154679 -309.224395)
			(xy 391.146784 -309.272972) (xy 391.1312 -309.319653) (xy 391.108329 -309.36323) (xy 391.078764 -309.402574)
			(xy 391.043271 -309.436666) (xy 391.002768 -309.464622) (xy 390.958306 -309.48572) (xy 390.911035 -309.499412)
			(xy 390.86218 -309.505344) (xy 390.813005 -309.503363) (xy 390.764786 -309.493519) (xy 390.71877 -309.476067)
			(xy 390.676149 -309.45146) (xy 390.638028 -309.420335) (xy 390.605393 -309.383498) (xy 390.57909 -309.341902)
			(xy 390.559799 -309.296626) (xy 390.548022 -309.248842) (xy 390.544062 -309.199788) (xy 390.205214 -309.199788)
			(xy 390.204719 -309.224395) (xy 390.196824 -309.272972) (xy 390.18124 -309.319653) (xy 390.158369 -309.36323)
			(xy 390.128804 -309.402574) (xy 390.093311 -309.436666) (xy 390.052808 -309.464622) (xy 390.008346 -309.48572)
			(xy 389.961075 -309.499412) (xy 389.91222 -309.505344) (xy 389.863045 -309.503363) (xy 389.814826 -309.493519)
			(xy 389.76881 -309.476067) (xy 389.726189 -309.45146) (xy 389.688068 -309.420335) (xy 389.655433 -309.383498)
			(xy 389.62913 -309.341902) (xy 389.609839 -309.296626) (xy 389.598062 -309.248842) (xy 389.594102 -309.199788)
			(xy 388.305294 -309.199788) (xy 388.304799 -309.224395) (xy 388.296904 -309.272972) (xy 388.28132 -309.319653)
			(xy 388.258449 -309.36323) (xy 388.228884 -309.402574) (xy 388.193391 -309.436666) (xy 388.152888 -309.464622)
			(xy 388.108426 -309.48572) (xy 388.061155 -309.499412) (xy 388.0123 -309.505344) (xy 387.963125 -309.503363)
			(xy 387.914906 -309.493519) (xy 387.86889 -309.476067) (xy 387.826269 -309.45146) (xy 387.788148 -309.420335)
			(xy 387.755513 -309.383498) (xy 387.72921 -309.341902) (xy 387.709919 -309.296626) (xy 387.698142 -309.248842)
			(xy 387.694182 -309.199788) (xy 387.355334 -309.199788) (xy 387.354839 -309.224395) (xy 387.346944 -309.272972)
			(xy 387.33136 -309.319653) (xy 387.308489 -309.36323) (xy 387.278924 -309.402574) (xy 387.243431 -309.436666)
			(xy 387.202928 -309.464622) (xy 387.158466 -309.48572) (xy 387.111195 -309.499412) (xy 387.06234 -309.505344)
			(xy 387.013165 -309.503363) (xy 386.964946 -309.493519) (xy 386.91893 -309.476067) (xy 386.876309 -309.45146)
			(xy 386.838188 -309.420335) (xy 386.805553 -309.383498) (xy 386.77925 -309.341902) (xy 386.759959 -309.296626)
			(xy 386.748182 -309.248842) (xy 386.744222 -309.199788) (xy 313.055 -309.199788) (xy 313.054505 -309.224395)
			(xy 313.04661 -309.272972) (xy 313.031026 -309.319653) (xy 313.008155 -309.36323) (xy 312.97859 -309.402574)
			(xy 312.943097 -309.436666) (xy 312.902594 -309.464622) (xy 312.858132 -309.48572) (xy 312.810861 -309.499412)
			(xy 312.762006 -309.505344) (xy 312.712831 -309.503363) (xy 312.664612 -309.493519) (xy 312.618596 -309.476067)
			(xy 312.575975 -309.45146) (xy 312.537854 -309.420335) (xy 312.505219 -309.383498) (xy 312.478916 -309.341902)
			(xy 312.459625 -309.296626) (xy 312.447848 -309.248842) (xy 312.443888 -309.199788) (xy 312.10504 -309.199788)
			(xy 312.104545 -309.224395) (xy 312.09665 -309.272972) (xy 312.081066 -309.319653) (xy 312.058195 -309.36323)
			(xy 312.02863 -309.402574) (xy 311.993137 -309.436666) (xy 311.952634 -309.464622) (xy 311.908172 -309.48572)
			(xy 311.860901 -309.499412) (xy 311.812046 -309.505344) (xy 311.762871 -309.503363) (xy 311.714652 -309.493519)
			(xy 311.668636 -309.476067) (xy 311.626015 -309.45146) (xy 311.587894 -309.420335) (xy 311.555259 -309.383498)
			(xy 311.528956 -309.341902) (xy 311.509665 -309.296626) (xy 311.497888 -309.248842) (xy 311.493928 -309.199788)
			(xy 310.20512 -309.199788) (xy 310.204625 -309.224395) (xy 310.19673 -309.272972) (xy 310.181146 -309.319653)
			(xy 310.158275 -309.36323) (xy 310.12871 -309.402574) (xy 310.093217 -309.436666) (xy 310.052714 -309.464622)
			(xy 310.008252 -309.48572) (xy 309.960981 -309.499412) (xy 309.912126 -309.505344) (xy 309.862951 -309.503363)
			(xy 309.814732 -309.493519) (xy 309.768716 -309.476067) (xy 309.726095 -309.45146) (xy 309.687974 -309.420335)
			(xy 309.655339 -309.383498) (xy 309.629036 -309.341902) (xy 309.609745 -309.296626) (xy 309.597968 -309.248842)
			(xy 309.594008 -309.199788) (xy 309.25516 -309.199788) (xy 309.254665 -309.224395) (xy 309.24677 -309.272972)
			(xy 309.231186 -309.319653) (xy 309.208315 -309.36323) (xy 309.17875 -309.402574) (xy 309.143257 -309.436666)
			(xy 309.102754 -309.464622) (xy 309.058292 -309.48572) (xy 309.011021 -309.499412) (xy 308.962166 -309.505344)
			(xy 308.912991 -309.503363) (xy 308.864772 -309.493519) (xy 308.818756 -309.476067) (xy 308.776135 -309.45146)
			(xy 308.738014 -309.420335) (xy 308.705379 -309.383498) (xy 308.679076 -309.341902) (xy 308.659785 -309.296626)
			(xy 308.648008 -309.248842) (xy 308.644048 -309.199788) (xy 275.055076 -309.199788) (xy 275.054581 -309.224395)
			(xy 275.046686 -309.272972) (xy 275.031102 -309.319653) (xy 275.008231 -309.36323) (xy 274.978666 -309.402574)
			(xy 274.943173 -309.436666) (xy 274.90267 -309.464622) (xy 274.858208 -309.48572) (xy 274.810937 -309.499412)
			(xy 274.762082 -309.505344) (xy 274.712907 -309.503363) (xy 274.664688 -309.493519) (xy 274.618672 -309.476067)
			(xy 274.576051 -309.45146) (xy 274.53793 -309.420335) (xy 274.505295 -309.383498) (xy 274.478992 -309.341902)
			(xy 274.459701 -309.296626) (xy 274.447924 -309.248842) (xy 274.443964 -309.199788) (xy 274.105116 -309.199788)
			(xy 274.104621 -309.224395) (xy 274.096726 -309.272972) (xy 274.081142 -309.319653) (xy 274.058271 -309.36323)
			(xy 274.028706 -309.402574) (xy 273.993213 -309.436666) (xy 273.95271 -309.464622) (xy 273.908248 -309.48572)
			(xy 273.860977 -309.499412) (xy 273.812122 -309.505344) (xy 273.762947 -309.503363) (xy 273.714728 -309.493519)
			(xy 273.668712 -309.476067) (xy 273.626091 -309.45146) (xy 273.58797 -309.420335) (xy 273.555335 -309.383498)
			(xy 273.529032 -309.341902) (xy 273.509741 -309.296626) (xy 273.497964 -309.248842) (xy 273.494004 -309.199788)
			(xy 194.105276 -309.199788) (xy 194.104781 -309.224395) (xy 194.096886 -309.272972) (xy 194.081302 -309.319653)
			(xy 194.058431 -309.36323) (xy 194.028866 -309.402574) (xy 193.993373 -309.436666) (xy 193.95287 -309.464622)
			(xy 193.908408 -309.48572) (xy 193.861137 -309.499412) (xy 193.812282 -309.505344) (xy 193.763107 -309.503363)
			(xy 193.714888 -309.493519) (xy 193.668872 -309.476067) (xy 193.626251 -309.45146) (xy 193.58813 -309.420335)
			(xy 193.555495 -309.383498) (xy 193.529192 -309.341902) (xy 193.509901 -309.296626) (xy 193.498124 -309.248842)
			(xy 193.494164 -309.199788) (xy 193.155316 -309.199788) (xy 193.154821 -309.224395) (xy 193.146926 -309.272972)
			(xy 193.131342 -309.319653) (xy 193.108471 -309.36323) (xy 193.078906 -309.402574) (xy 193.043413 -309.436666)
			(xy 193.00291 -309.464622) (xy 192.958448 -309.48572) (xy 192.911177 -309.499412) (xy 192.862322 -309.505344)
			(xy 192.813147 -309.503363) (xy 192.764928 -309.493519) (xy 192.718912 -309.476067) (xy 192.676291 -309.45146)
			(xy 192.63817 -309.420335) (xy 192.605535 -309.383498) (xy 192.579232 -309.341902) (xy 192.559941 -309.296626)
			(xy 192.548164 -309.248842) (xy 192.544204 -309.199788) (xy 158.955232 -309.199788) (xy 158.954737 -309.224395)
			(xy 158.946842 -309.272972) (xy 158.931258 -309.319653) (xy 158.908387 -309.36323) (xy 158.878822 -309.402574)
			(xy 158.843329 -309.436666) (xy 158.802826 -309.464622) (xy 158.758364 -309.48572) (xy 158.711093 -309.499412)
			(xy 158.662238 -309.505344) (xy 158.613063 -309.503363) (xy 158.564844 -309.493519) (xy 158.518828 -309.476067)
			(xy 158.476207 -309.45146) (xy 158.438086 -309.420335) (xy 158.405451 -309.383498) (xy 158.379148 -309.341902)
			(xy 158.359857 -309.296626) (xy 158.34808 -309.248842) (xy 158.34412 -309.199788) (xy 158.005272 -309.199788)
			(xy 158.004777 -309.224395) (xy 157.996882 -309.272972) (xy 157.981298 -309.319653) (xy 157.958427 -309.36323)
			(xy 157.928862 -309.402574) (xy 157.893369 -309.436666) (xy 157.852866 -309.464622) (xy 157.808404 -309.48572)
			(xy 157.761133 -309.499412) (xy 157.712278 -309.505344) (xy 157.663103 -309.503363) (xy 157.614884 -309.493519)
			(xy 157.568868 -309.476067) (xy 157.526247 -309.45146) (xy 157.488126 -309.420335) (xy 157.455491 -309.383498)
			(xy 157.429188 -309.341902) (xy 157.409897 -309.296626) (xy 157.39812 -309.248842) (xy 157.39416 -309.199788)
			(xy 156.105352 -309.199788) (xy 156.104857 -309.224395) (xy 156.096962 -309.272972) (xy 156.081378 -309.319653)
			(xy 156.058507 -309.36323) (xy 156.028942 -309.402574) (xy 155.993449 -309.436666) (xy 155.952946 -309.464622)
			(xy 155.908484 -309.48572) (xy 155.861213 -309.499412) (xy 155.812358 -309.505344) (xy 155.763183 -309.503363)
			(xy 155.714964 -309.493519) (xy 155.668948 -309.476067) (xy 155.626327 -309.45146) (xy 155.588206 -309.420335)
			(xy 155.555571 -309.383498) (xy 155.529268 -309.341902) (xy 155.509977 -309.296626) (xy 155.4982 -309.248842)
			(xy 155.49424 -309.199788) (xy 155.155392 -309.199788) (xy 155.154897 -309.224395) (xy 155.147002 -309.272972)
			(xy 155.131418 -309.319653) (xy 155.108547 -309.36323) (xy 155.078982 -309.402574) (xy 155.043489 -309.436666)
			(xy 155.002986 -309.464622) (xy 154.958524 -309.48572) (xy 154.911253 -309.499412) (xy 154.862398 -309.505344)
			(xy 154.813223 -309.503363) (xy 154.765004 -309.493519) (xy 154.718988 -309.476067) (xy 154.676367 -309.45146)
			(xy 154.638246 -309.420335) (xy 154.605611 -309.383498) (xy 154.579308 -309.341902) (xy 154.560017 -309.296626)
			(xy 154.54824 -309.248842) (xy 154.54428 -309.199788) (xy 80.855058 -309.199788) (xy 80.854563 -309.224395)
			(xy 80.846668 -309.272972) (xy 80.831084 -309.319653) (xy 80.808213 -309.36323) (xy 80.778648 -309.402574)
			(xy 80.743155 -309.436666) (xy 80.702652 -309.464622) (xy 80.65819 -309.48572) (xy 80.610919 -309.499412)
			(xy 80.562064 -309.505344) (xy 80.512889 -309.503363) (xy 80.46467 -309.493519) (xy 80.418654 -309.476067)
			(xy 80.376033 -309.45146) (xy 80.337912 -309.420335) (xy 80.305277 -309.383498) (xy 80.278974 -309.341902)
			(xy 80.259683 -309.296626) (xy 80.247906 -309.248842) (xy 80.243946 -309.199788) (xy 79.905098 -309.199788)
			(xy 79.904603 -309.224395) (xy 79.896708 -309.272972) (xy 79.881124 -309.319653) (xy 79.858253 -309.36323)
			(xy 79.828688 -309.402574) (xy 79.793195 -309.436666) (xy 79.752692 -309.464622) (xy 79.70823 -309.48572)
			(xy 79.660959 -309.499412) (xy 79.612104 -309.505344) (xy 79.562929 -309.503363) (xy 79.51471 -309.493519)
			(xy 79.468694 -309.476067) (xy 79.426073 -309.45146) (xy 79.387952 -309.420335) (xy 79.355317 -309.383498)
			(xy 79.329014 -309.341902) (xy 79.309723 -309.296626) (xy 79.297946 -309.248842) (xy 79.293986 -309.199788)
			(xy 78.005178 -309.199788) (xy 78.004683 -309.224395) (xy 77.996788 -309.272972) (xy 77.981204 -309.319653)
			(xy 77.958333 -309.36323) (xy 77.928768 -309.402574) (xy 77.893275 -309.436666) (xy 77.852772 -309.464622)
			(xy 77.80831 -309.48572) (xy 77.761039 -309.499412) (xy 77.712184 -309.505344) (xy 77.663009 -309.503363)
			(xy 77.61479 -309.493519) (xy 77.568774 -309.476067) (xy 77.526153 -309.45146) (xy 77.488032 -309.420335)
			(xy 77.455397 -309.383498) (xy 77.429094 -309.341902) (xy 77.409803 -309.296626) (xy 77.398026 -309.248842)
			(xy 77.394066 -309.199788) (xy 77.055218 -309.199788) (xy 77.054723 -309.224395) (xy 77.046828 -309.272972)
			(xy 77.031244 -309.319653) (xy 77.008373 -309.36323) (xy 76.978808 -309.402574) (xy 76.943315 -309.436666)
			(xy 76.902812 -309.464622) (xy 76.85835 -309.48572) (xy 76.811079 -309.499412) (xy 76.762224 -309.505344)
			(xy 76.713049 -309.503363) (xy 76.66483 -309.493519) (xy 76.618814 -309.476067) (xy 76.576193 -309.45146)
			(xy 76.538072 -309.420335) (xy 76.505437 -309.383498) (xy 76.479134 -309.341902) (xy 76.459843 -309.296626)
			(xy 76.448066 -309.248842) (xy 76.444106 -309.199788) (xy 42.855134 -309.199788) (xy 42.854639 -309.224395)
			(xy 42.846744 -309.272972) (xy 42.83116 -309.319653) (xy 42.808289 -309.36323) (xy 42.778724 -309.402574)
			(xy 42.743231 -309.436666) (xy 42.702728 -309.464622) (xy 42.658266 -309.48572) (xy 42.610995 -309.499412)
			(xy 42.56214 -309.505344) (xy 42.512965 -309.503363) (xy 42.464746 -309.493519) (xy 42.41873 -309.476067)
			(xy 42.376109 -309.45146) (xy 42.337988 -309.420335) (xy 42.305353 -309.383498) (xy 42.27905 -309.341902)
			(xy 42.259759 -309.296626) (xy 42.247982 -309.248842) (xy 42.244022 -309.199788) (xy 41.905174 -309.199788)
			(xy 41.904679 -309.224395) (xy 41.896784 -309.272972) (xy 41.8812 -309.319653) (xy 41.858329 -309.36323)
			(xy 41.828764 -309.402574) (xy 41.793271 -309.436666) (xy 41.752768 -309.464622) (xy 41.708306 -309.48572)
			(xy 41.661035 -309.499412) (xy 41.61218 -309.505344) (xy 41.563005 -309.503363) (xy 41.514786 -309.493519)
			(xy 41.46877 -309.476067) (xy 41.426149 -309.45146) (xy 41.388028 -309.420335) (xy 41.355393 -309.383498)
			(xy 41.32909 -309.341902) (xy 41.309799 -309.296626) (xy 41.298022 -309.248842) (xy 41.294062 -309.199788)
			(xy 0.508 -309.199788) (xy 0.508 -310.149748) (xy 81.19416 -310.149748) (xy 81.19812 -310.100694)
			(xy 81.209897 -310.05291) (xy 81.229188 -310.007634) (xy 81.255491 -309.966038) (xy 81.288126 -309.929201)
			(xy 81.326247 -309.898076) (xy 81.368868 -309.873469) (xy 81.414884 -309.856017) (xy 81.463103 -309.846173)
			(xy 81.512278 -309.844192) (xy 81.561133 -309.850124) (xy 81.608404 -309.863816) (xy 81.652866 -309.884914)
			(xy 81.693369 -309.91287) (xy 81.728862 -309.946962) (xy 81.758427 -309.986306) (xy 81.781298 -310.029883)
			(xy 81.796882 -310.076564) (xy 81.804777 -310.125141) (xy 81.805272 -310.149748) (xy 82.14412 -310.149748)
			(xy 82.14808 -310.100694) (xy 82.159857 -310.05291) (xy 82.179148 -310.007634) (xy 82.205451 -309.966038)
			(xy 82.238086 -309.929201) (xy 82.276207 -309.898076) (xy 82.318828 -309.873469) (xy 82.364844 -309.856017)
			(xy 82.413063 -309.846173) (xy 82.462238 -309.844192) (xy 82.511093 -309.850124) (xy 82.558364 -309.863816)
			(xy 82.602826 -309.884914) (xy 82.643329 -309.91287) (xy 82.678822 -309.946962) (xy 82.708387 -309.986306)
			(xy 82.731258 -310.029883) (xy 82.746842 -310.076564) (xy 82.754737 -310.125141) (xy 82.755232 -310.149748)
			(xy 152.644106 -310.149748) (xy 152.648066 -310.100694) (xy 152.659843 -310.05291) (xy 152.679134 -310.007634)
			(xy 152.705437 -309.966038) (xy 152.738072 -309.929201) (xy 152.776193 -309.898076) (xy 152.818814 -309.873469)
			(xy 152.86483 -309.856017) (xy 152.913049 -309.846173) (xy 152.962224 -309.844192) (xy 153.011079 -309.850124)
			(xy 153.05835 -309.863816) (xy 153.102812 -309.884914) (xy 153.143315 -309.91287) (xy 153.178808 -309.946962)
			(xy 153.208373 -309.986306) (xy 153.231244 -310.029883) (xy 153.246828 -310.076564) (xy 153.254723 -310.125141)
			(xy 153.255218 -310.149748) (xy 153.594066 -310.149748) (xy 153.598026 -310.100694) (xy 153.609803 -310.05291)
			(xy 153.629094 -310.007634) (xy 153.655397 -309.966038) (xy 153.688032 -309.929201) (xy 153.726153 -309.898076)
			(xy 153.768774 -309.873469) (xy 153.81479 -309.856017) (xy 153.863009 -309.846173) (xy 153.912184 -309.844192)
			(xy 153.961039 -309.850124) (xy 154.00831 -309.863816) (xy 154.052772 -309.884914) (xy 154.093275 -309.91287)
			(xy 154.128768 -309.946962) (xy 154.158333 -309.986306) (xy 154.181204 -310.029883) (xy 154.196788 -310.076564)
			(xy 154.204683 -310.125141) (xy 154.205178 -310.149748) (xy 313.394102 -310.149748) (xy 313.398062 -310.100694)
			(xy 313.409839 -310.05291) (xy 313.42913 -310.007634) (xy 313.455433 -309.966038) (xy 313.488068 -309.929201)
			(xy 313.526189 -309.898076) (xy 313.56881 -309.873469) (xy 313.614826 -309.856017) (xy 313.663045 -309.846173)
			(xy 313.71222 -309.844192) (xy 313.761075 -309.850124) (xy 313.808346 -309.863816) (xy 313.852808 -309.884914)
			(xy 313.893311 -309.91287) (xy 313.928804 -309.946962) (xy 313.958369 -309.986306) (xy 313.98124 -310.029883)
			(xy 313.996824 -310.076564) (xy 314.004719 -310.125141) (xy 314.005214 -310.149748) (xy 314.344062 -310.149748)
			(xy 314.348022 -310.100694) (xy 314.359799 -310.05291) (xy 314.37909 -310.007634) (xy 314.405393 -309.966038)
			(xy 314.438028 -309.929201) (xy 314.476149 -309.898076) (xy 314.51877 -309.873469) (xy 314.564786 -309.856017)
			(xy 314.613005 -309.846173) (xy 314.66218 -309.844192) (xy 314.711035 -309.850124) (xy 314.758306 -309.863816)
			(xy 314.802768 -309.884914) (xy 314.843271 -309.91287) (xy 314.878764 -309.946962) (xy 314.908329 -309.986306)
			(xy 314.9312 -310.029883) (xy 314.946784 -310.076564) (xy 314.954679 -310.125141) (xy 314.955174 -310.149748)
			(xy 384.844048 -310.149748) (xy 384.848008 -310.100694) (xy 384.859785 -310.05291) (xy 384.879076 -310.007634)
			(xy 384.905379 -309.966038) (xy 384.938014 -309.929201) (xy 384.976135 -309.898076) (xy 385.018756 -309.873469)
			(xy 385.064772 -309.856017) (xy 385.112991 -309.846173) (xy 385.162166 -309.844192) (xy 385.211021 -309.850124)
			(xy 385.258292 -309.863816) (xy 385.302754 -309.884914) (xy 385.343257 -309.91287) (xy 385.37875 -309.946962)
			(xy 385.408315 -309.986306) (xy 385.431186 -310.029883) (xy 385.44677 -310.076564) (xy 385.454665 -310.125141)
			(xy 385.45516 -310.149748) (xy 385.794008 -310.149748) (xy 385.797968 -310.100694) (xy 385.809745 -310.05291)
			(xy 385.829036 -310.007634) (xy 385.855339 -309.966038) (xy 385.887974 -309.929201) (xy 385.926095 -309.898076)
			(xy 385.968716 -309.873469) (xy 386.014732 -309.856017) (xy 386.062951 -309.846173) (xy 386.112126 -309.844192)
			(xy 386.160981 -309.850124) (xy 386.208252 -309.863816) (xy 386.252714 -309.884914) (xy 386.293217 -309.91287)
			(xy 386.32871 -309.946962) (xy 386.358275 -309.986306) (xy 386.381146 -310.029883) (xy 386.39673 -310.076564)
			(xy 386.404625 -310.125141) (xy 386.40512 -310.149748) (xy 386.404625 -310.174355) (xy 386.39673 -310.222932)
			(xy 386.381146 -310.269613) (xy 386.358275 -310.31319) (xy 386.32871 -310.352534) (xy 386.293217 -310.386626)
			(xy 386.252714 -310.414582) (xy 386.208252 -310.43568) (xy 386.160981 -310.449372) (xy 386.112126 -310.455304)
			(xy 386.062951 -310.453323) (xy 386.014732 -310.443479) (xy 385.968716 -310.426027) (xy 385.926095 -310.40142)
			(xy 385.887974 -310.370295) (xy 385.855339 -310.333458) (xy 385.829036 -310.291862) (xy 385.809745 -310.246586)
			(xy 385.797968 -310.198802) (xy 385.794008 -310.149748) (xy 385.45516 -310.149748) (xy 385.454665 -310.174355)
			(xy 385.44677 -310.222932) (xy 385.431186 -310.269613) (xy 385.408315 -310.31319) (xy 385.37875 -310.352534)
			(xy 385.343257 -310.386626) (xy 385.302754 -310.414582) (xy 385.258292 -310.43568) (xy 385.211021 -310.449372)
			(xy 385.162166 -310.455304) (xy 385.112991 -310.453323) (xy 385.064772 -310.443479) (xy 385.018756 -310.426027)
			(xy 384.976135 -310.40142) (xy 384.938014 -310.370295) (xy 384.905379 -310.333458) (xy 384.879076 -310.291862)
			(xy 384.859785 -310.246586) (xy 384.848008 -310.198802) (xy 384.844048 -310.149748) (xy 314.955174 -310.149748)
			(xy 314.954679 -310.174355) (xy 314.946784 -310.222932) (xy 314.9312 -310.269613) (xy 314.908329 -310.31319)
			(xy 314.878764 -310.352534) (xy 314.843271 -310.386626) (xy 314.802768 -310.414582) (xy 314.758306 -310.43568)
			(xy 314.711035 -310.449372) (xy 314.66218 -310.455304) (xy 314.613005 -310.453323) (xy 314.564786 -310.443479)
			(xy 314.51877 -310.426027) (xy 314.476149 -310.40142) (xy 314.438028 -310.370295) (xy 314.405393 -310.333458)
			(xy 314.37909 -310.291862) (xy 314.359799 -310.246586) (xy 314.348022 -310.198802) (xy 314.344062 -310.149748)
			(xy 314.005214 -310.149748) (xy 314.004719 -310.174355) (xy 313.996824 -310.222932) (xy 313.98124 -310.269613)
			(xy 313.958369 -310.31319) (xy 313.928804 -310.352534) (xy 313.893311 -310.386626) (xy 313.852808 -310.414582)
			(xy 313.808346 -310.43568) (xy 313.761075 -310.449372) (xy 313.71222 -310.455304) (xy 313.663045 -310.453323)
			(xy 313.614826 -310.443479) (xy 313.56881 -310.426027) (xy 313.526189 -310.40142) (xy 313.488068 -310.370295)
			(xy 313.455433 -310.333458) (xy 313.42913 -310.291862) (xy 313.409839 -310.246586) (xy 313.398062 -310.198802)
			(xy 313.394102 -310.149748) (xy 154.205178 -310.149748) (xy 154.204683 -310.174355) (xy 154.196788 -310.222932)
			(xy 154.181204 -310.269613) (xy 154.158333 -310.31319) (xy 154.128768 -310.352534) (xy 154.093275 -310.386626)
			(xy 154.052772 -310.414582) (xy 154.00831 -310.43568) (xy 153.961039 -310.449372) (xy 153.912184 -310.455304)
			(xy 153.863009 -310.453323) (xy 153.81479 -310.443479) (xy 153.768774 -310.426027) (xy 153.726153 -310.40142)
			(xy 153.688032 -310.370295) (xy 153.655397 -310.333458) (xy 153.629094 -310.291862) (xy 153.609803 -310.246586)
			(xy 153.598026 -310.198802) (xy 153.594066 -310.149748) (xy 153.255218 -310.149748) (xy 153.254723 -310.174355)
			(xy 153.246828 -310.222932) (xy 153.231244 -310.269613) (xy 153.208373 -310.31319) (xy 153.178808 -310.352534)
			(xy 153.143315 -310.386626) (xy 153.102812 -310.414582) (xy 153.05835 -310.43568) (xy 153.011079 -310.449372)
			(xy 152.962224 -310.455304) (xy 152.913049 -310.453323) (xy 152.86483 -310.443479) (xy 152.818814 -310.426027)
			(xy 152.776193 -310.40142) (xy 152.738072 -310.370295) (xy 152.705437 -310.333458) (xy 152.679134 -310.291862)
			(xy 152.659843 -310.246586) (xy 152.648066 -310.198802) (xy 152.644106 -310.149748) (xy 82.755232 -310.149748)
			(xy 82.754737 -310.174355) (xy 82.746842 -310.222932) (xy 82.731258 -310.269613) (xy 82.708387 -310.31319)
			(xy 82.678822 -310.352534) (xy 82.643329 -310.386626) (xy 82.602826 -310.414582) (xy 82.558364 -310.43568)
			(xy 82.511093 -310.449372) (xy 82.462238 -310.455304) (xy 82.413063 -310.453323) (xy 82.364844 -310.443479)
			(xy 82.318828 -310.426027) (xy 82.276207 -310.40142) (xy 82.238086 -310.370295) (xy 82.205451 -310.333458)
			(xy 82.179148 -310.291862) (xy 82.159857 -310.246586) (xy 82.14808 -310.198802) (xy 82.14412 -310.149748)
			(xy 81.805272 -310.149748) (xy 81.804777 -310.174355) (xy 81.796882 -310.222932) (xy 81.781298 -310.269613)
			(xy 81.758427 -310.31319) (xy 81.728862 -310.352534) (xy 81.693369 -310.386626) (xy 81.652866 -310.414582)
			(xy 81.608404 -310.43568) (xy 81.561133 -310.449372) (xy 81.512278 -310.455304) (xy 81.463103 -310.453323)
			(xy 81.414884 -310.443479) (xy 81.368868 -310.426027) (xy 81.326247 -310.40142) (xy 81.288126 -310.370295)
			(xy 81.255491 -310.333458) (xy 81.229188 -310.291862) (xy 81.209897 -310.246586) (xy 81.19812 -310.198802)
			(xy 81.19416 -310.149748) (xy 0.508 -310.149748) (xy 0.508 -311.099962) (xy 39.394142 -311.099962)
			(xy 39.398102 -311.050908) (xy 39.409879 -311.003124) (xy 39.42917 -310.957848) (xy 39.455473 -310.916252)
			(xy 39.488108 -310.879415) (xy 39.526229 -310.84829) (xy 39.56885 -310.823683) (xy 39.614866 -310.806231)
			(xy 39.663085 -310.796387) (xy 39.71226 -310.794406) (xy 39.761115 -310.800338) (xy 39.808386 -310.81403)
			(xy 39.852848 -310.835128) (xy 39.893351 -310.863084) (xy 39.928844 -310.897176) (xy 39.958409 -310.93652)
			(xy 39.98128 -310.980097) (xy 39.996864 -311.026778) (xy 40.004759 -311.075355) (xy 40.005254 -311.099962)
			(xy 41.294062 -311.099962) (xy 41.298022 -311.050908) (xy 41.309799 -311.003124) (xy 41.32909 -310.957848)
			(xy 41.355393 -310.916252) (xy 41.388028 -310.879415) (xy 41.426149 -310.84829) (xy 41.46877 -310.823683)
			(xy 41.514786 -310.806231) (xy 41.563005 -310.796387) (xy 41.61218 -310.794406) (xy 41.661035 -310.800338)
			(xy 41.708306 -310.81403) (xy 41.752768 -310.835128) (xy 41.793271 -310.863084) (xy 41.828764 -310.897176)
			(xy 41.858329 -310.93652) (xy 41.8812 -310.980097) (xy 41.896784 -311.026778) (xy 41.904679 -311.075355)
			(xy 41.905174 -311.099962) (xy 43.193982 -311.099962) (xy 43.197942 -311.050908) (xy 43.209719 -311.003124)
			(xy 43.22901 -310.957848) (xy 43.255313 -310.916252) (xy 43.287948 -310.879415) (xy 43.326069 -310.84829)
			(xy 43.36869 -310.823683) (xy 43.414706 -310.806231) (xy 43.462925 -310.796387) (xy 43.5121 -310.794406)
			(xy 43.560955 -310.800338) (xy 43.608226 -310.81403) (xy 43.652688 -310.835128) (xy 43.693191 -310.863084)
			(xy 43.728684 -310.897176) (xy 43.758249 -310.93652) (xy 43.78112 -310.980097) (xy 43.796704 -311.026778)
			(xy 43.804599 -311.075355) (xy 43.805094 -311.099962) (xy 45.094156 -311.099962) (xy 45.098116 -311.050908)
			(xy 45.109893 -311.003124) (xy 45.129184 -310.957848) (xy 45.155487 -310.916252) (xy 45.188122 -310.879415)
			(xy 45.226243 -310.84829) (xy 45.268864 -310.823683) (xy 45.31488 -310.806231) (xy 45.363099 -310.796387)
			(xy 45.412274 -310.794406) (xy 45.461129 -310.800338) (xy 45.5084 -310.81403) (xy 45.552862 -310.835128)
			(xy 45.593365 -310.863084) (xy 45.628858 -310.897176) (xy 45.658423 -310.93652) (xy 45.681294 -310.980097)
			(xy 45.696878 -311.026778) (xy 45.704773 -311.075355) (xy 45.705268 -311.099962) (xy 46.994076 -311.099962)
			(xy 46.998036 -311.050908) (xy 47.009813 -311.003124) (xy 47.029104 -310.957848) (xy 47.055407 -310.916252)
			(xy 47.088042 -310.879415) (xy 47.126163 -310.84829) (xy 47.168784 -310.823683) (xy 47.2148 -310.806231)
			(xy 47.263019 -310.796387) (xy 47.312194 -310.794406) (xy 47.361049 -310.800338) (xy 47.40832 -310.81403)
			(xy 47.452782 -310.835128) (xy 47.493285 -310.863084) (xy 47.528778 -310.897176) (xy 47.558343 -310.93652)
			(xy 47.581214 -310.980097) (xy 47.596798 -311.026778) (xy 47.604693 -311.075355) (xy 47.605188 -311.099962)
			(xy 48.893996 -311.099962) (xy 48.897956 -311.050908) (xy 48.909733 -311.003124) (xy 48.929024 -310.957848)
			(xy 48.955327 -310.916252) (xy 48.987962 -310.879415) (xy 49.026083 -310.84829) (xy 49.068704 -310.823683)
			(xy 49.11472 -310.806231) (xy 49.162939 -310.796387) (xy 49.212114 -310.794406) (xy 49.260969 -310.800338)
			(xy 49.30824 -310.81403) (xy 49.352702 -310.835128) (xy 49.393205 -310.863084) (xy 49.428698 -310.897176)
			(xy 49.458263 -310.93652) (xy 49.481134 -310.980097) (xy 49.496718 -311.026778) (xy 49.504613 -311.075355)
			(xy 49.505108 -311.099962) (xy 50.79417 -311.099962) (xy 50.79813 -311.050908) (xy 50.809907 -311.003124)
			(xy 50.829198 -310.957848) (xy 50.855501 -310.916252) (xy 50.888136 -310.879415) (xy 50.926257 -310.84829)
			(xy 50.968878 -310.823683) (xy 51.014894 -310.806231) (xy 51.063113 -310.796387) (xy 51.112288 -310.794406)
			(xy 51.161143 -310.800338) (xy 51.208414 -310.81403) (xy 51.252876 -310.835128) (xy 51.293379 -310.863084)
			(xy 51.328872 -310.897176) (xy 51.358437 -310.93652) (xy 51.381308 -310.980097) (xy 51.396892 -311.026778)
			(xy 51.404787 -311.075355) (xy 51.405282 -311.099962) (xy 52.69409 -311.099962) (xy 52.69805 -311.050908)
			(xy 52.709827 -311.003124) (xy 52.729118 -310.957848) (xy 52.755421 -310.916252) (xy 52.788056 -310.879415)
			(xy 52.826177 -310.84829) (xy 52.868798 -310.823683) (xy 52.914814 -310.806231) (xy 52.963033 -310.796387)
			(xy 53.012208 -310.794406) (xy 53.061063 -310.800338) (xy 53.108334 -310.81403) (xy 53.152796 -310.835128)
			(xy 53.193299 -310.863084) (xy 53.228792 -310.897176) (xy 53.258357 -310.93652) (xy 53.281228 -310.980097)
			(xy 53.296812 -311.026778) (xy 53.304707 -311.075355) (xy 53.305202 -311.099962) (xy 54.59401 -311.099962)
			(xy 54.59797 -311.050908) (xy 54.609747 -311.003124) (xy 54.629038 -310.957848) (xy 54.655341 -310.916252)
			(xy 54.687976 -310.879415) (xy 54.726097 -310.84829) (xy 54.768718 -310.823683) (xy 54.814734 -310.806231)
			(xy 54.862953 -310.796387) (xy 54.912128 -310.794406) (xy 54.960983 -310.800338) (xy 55.008254 -310.81403)
			(xy 55.052716 -310.835128) (xy 55.093219 -310.863084) (xy 55.128712 -310.897176) (xy 55.158277 -310.93652)
			(xy 55.181148 -310.980097) (xy 55.196732 -311.026778) (xy 55.204627 -311.075355) (xy 55.205122 -311.099962)
			(xy 56.494184 -311.099962) (xy 56.498144 -311.050908) (xy 56.509921 -311.003124) (xy 56.529212 -310.957848)
			(xy 56.555515 -310.916252) (xy 56.58815 -310.879415) (xy 56.626271 -310.84829) (xy 56.668892 -310.823683)
			(xy 56.714908 -310.806231) (xy 56.763127 -310.796387) (xy 56.812302 -310.794406) (xy 56.861157 -310.800338)
			(xy 56.908428 -310.81403) (xy 56.95289 -310.835128) (xy 56.993393 -310.863084) (xy 57.028886 -310.897176)
			(xy 57.058451 -310.93652) (xy 57.081322 -310.980097) (xy 57.096906 -311.026778) (xy 57.104801 -311.075355)
			(xy 57.105296 -311.099962) (xy 58.394104 -311.099962) (xy 58.398064 -311.050908) (xy 58.409841 -311.003124)
			(xy 58.429132 -310.957848) (xy 58.455435 -310.916252) (xy 58.48807 -310.879415) (xy 58.526191 -310.84829)
			(xy 58.568812 -310.823683) (xy 58.614828 -310.806231) (xy 58.663047 -310.796387) (xy 58.712222 -310.794406)
			(xy 58.761077 -310.800338) (xy 58.808348 -310.81403) (xy 58.85281 -310.835128) (xy 58.893313 -310.863084)
			(xy 58.928806 -310.897176) (xy 58.958371 -310.93652) (xy 58.981242 -310.980097) (xy 58.996826 -311.026778)
			(xy 59.004721 -311.075355) (xy 59.005216 -311.099962) (xy 60.294024 -311.099962) (xy 60.297984 -311.050908)
			(xy 60.309761 -311.003124) (xy 60.329052 -310.957848) (xy 60.355355 -310.916252) (xy 60.38799 -310.879415)
			(xy 60.426111 -310.84829) (xy 60.468732 -310.823683) (xy 60.514748 -310.806231) (xy 60.562967 -310.796387)
			(xy 60.612142 -310.794406) (xy 60.660997 -310.800338) (xy 60.708268 -310.81403) (xy 60.75273 -310.835128)
			(xy 60.793233 -310.863084) (xy 60.828726 -310.897176) (xy 60.858291 -310.93652) (xy 60.881162 -310.980097)
			(xy 60.896746 -311.026778) (xy 60.904641 -311.075355) (xy 60.905136 -311.099962) (xy 62.193944 -311.099962)
			(xy 62.197904 -311.050908) (xy 62.209681 -311.003124) (xy 62.228972 -310.957848) (xy 62.255275 -310.916252)
			(xy 62.28791 -310.879415) (xy 62.326031 -310.84829) (xy 62.368652 -310.823683) (xy 62.414668 -310.806231)
			(xy 62.462887 -310.796387) (xy 62.512062 -310.794406) (xy 62.560917 -310.800338) (xy 62.608188 -310.81403)
			(xy 62.65265 -310.835128) (xy 62.693153 -310.863084) (xy 62.728646 -310.897176) (xy 62.758211 -310.93652)
			(xy 62.781082 -310.980097) (xy 62.796666 -311.026778) (xy 62.804561 -311.075355) (xy 62.805056 -311.099962)
			(xy 64.094118 -311.099962) (xy 64.098078 -311.050908) (xy 64.109855 -311.003124) (xy 64.129146 -310.957848)
			(xy 64.155449 -310.916252) (xy 64.188084 -310.879415) (xy 64.226205 -310.84829) (xy 64.268826 -310.823683)
			(xy 64.314842 -310.806231) (xy 64.363061 -310.796387) (xy 64.412236 -310.794406) (xy 64.461091 -310.800338)
			(xy 64.508362 -310.81403) (xy 64.552824 -310.835128) (xy 64.593327 -310.863084) (xy 64.62882 -310.897176)
			(xy 64.658385 -310.93652) (xy 64.681256 -310.980097) (xy 64.69684 -311.026778) (xy 64.704735 -311.075355)
			(xy 64.70523 -311.099962) (xy 65.994038 -311.099962) (xy 65.997998 -311.050908) (xy 66.009775 -311.003124)
			(xy 66.029066 -310.957848) (xy 66.055369 -310.916252) (xy 66.088004 -310.879415) (xy 66.126125 -310.84829)
			(xy 66.168746 -310.823683) (xy 66.214762 -310.806231) (xy 66.262981 -310.796387) (xy 66.312156 -310.794406)
			(xy 66.361011 -310.800338) (xy 66.408282 -310.81403) (xy 66.452744 -310.835128) (xy 66.493247 -310.863084)
			(xy 66.52874 -310.897176) (xy 66.558305 -310.93652) (xy 66.581176 -310.980097) (xy 66.59676 -311.026778)
			(xy 66.604655 -311.075355) (xy 66.60515 -311.099962) (xy 67.893958 -311.099962) (xy 67.897918 -311.050908)
			(xy 67.909695 -311.003124) (xy 67.928986 -310.957848) (xy 67.955289 -310.916252) (xy 67.987924 -310.879415)
			(xy 68.026045 -310.84829) (xy 68.068666 -310.823683) (xy 68.114682 -310.806231) (xy 68.162901 -310.796387)
			(xy 68.212076 -310.794406) (xy 68.260931 -310.800338) (xy 68.308202 -310.81403) (xy 68.352664 -310.835128)
			(xy 68.393167 -310.863084) (xy 68.42866 -310.897176) (xy 68.458225 -310.93652) (xy 68.481096 -310.980097)
			(xy 68.49668 -311.026778) (xy 68.504575 -311.075355) (xy 68.50507 -311.099962) (xy 69.794132 -311.099962)
			(xy 69.798092 -311.050908) (xy 69.809869 -311.003124) (xy 69.82916 -310.957848) (xy 69.855463 -310.916252)
			(xy 69.888098 -310.879415) (xy 69.926219 -310.84829) (xy 69.96884 -310.823683) (xy 70.014856 -310.806231)
			(xy 70.063075 -310.796387) (xy 70.11225 -310.794406) (xy 70.161105 -310.800338) (xy 70.208376 -310.81403)
			(xy 70.252838 -310.835128) (xy 70.293341 -310.863084) (xy 70.328834 -310.897176) (xy 70.358399 -310.93652)
			(xy 70.38127 -310.980097) (xy 70.396854 -311.026778) (xy 70.404749 -311.075355) (xy 70.405244 -311.099962)
			(xy 71.694052 -311.099962) (xy 71.698012 -311.050908) (xy 71.709789 -311.003124) (xy 71.72908 -310.957848)
			(xy 71.755383 -310.916252) (xy 71.788018 -310.879415) (xy 71.826139 -310.84829) (xy 71.86876 -310.823683)
			(xy 71.914776 -310.806231) (xy 71.962995 -310.796387) (xy 72.01217 -310.794406) (xy 72.061025 -310.800338)
			(xy 72.108296 -310.81403) (xy 72.152758 -310.835128) (xy 72.193261 -310.863084) (xy 72.228754 -310.897176)
			(xy 72.258319 -310.93652) (xy 72.28119 -310.980097) (xy 72.296774 -311.026778) (xy 72.304669 -311.075355)
			(xy 72.305164 -311.099962) (xy 73.593972 -311.099962) (xy 73.597932 -311.050908) (xy 73.609709 -311.003124)
			(xy 73.629 -310.957848) (xy 73.655303 -310.916252) (xy 73.687938 -310.879415) (xy 73.726059 -310.84829)
			(xy 73.76868 -310.823683) (xy 73.814696 -310.806231) (xy 73.862915 -310.796387) (xy 73.91209 -310.794406)
			(xy 73.960945 -310.800338) (xy 74.008216 -310.81403) (xy 74.052678 -310.835128) (xy 74.093181 -310.863084)
			(xy 74.128674 -310.897176) (xy 74.158239 -310.93652) (xy 74.18111 -310.980097) (xy 74.196694 -311.026778)
			(xy 74.204589 -311.075355) (xy 74.205084 -311.099962) (xy 75.494146 -311.099962) (xy 75.498106 -311.050908)
			(xy 75.509883 -311.003124) (xy 75.529174 -310.957848) (xy 75.555477 -310.916252) (xy 75.588112 -310.879415)
			(xy 75.626233 -310.84829) (xy 75.668854 -310.823683) (xy 75.71487 -310.806231) (xy 75.763089 -310.796387)
			(xy 75.812264 -310.794406) (xy 75.861119 -310.800338) (xy 75.90839 -310.81403) (xy 75.952852 -310.835128)
			(xy 75.993355 -310.863084) (xy 76.028848 -310.897176) (xy 76.058413 -310.93652) (xy 76.081284 -310.980097)
			(xy 76.096868 -311.026778) (xy 76.104763 -311.075355) (xy 76.105258 -311.099962) (xy 77.394066 -311.099962)
			(xy 77.398026 -311.050908) (xy 77.409803 -311.003124) (xy 77.429094 -310.957848) (xy 77.455397 -310.916252)
			(xy 77.488032 -310.879415) (xy 77.526153 -310.84829) (xy 77.568774 -310.823683) (xy 77.61479 -310.806231)
			(xy 77.663009 -310.796387) (xy 77.712184 -310.794406) (xy 77.761039 -310.800338) (xy 77.80831 -310.81403)
			(xy 77.852772 -310.835128) (xy 77.893275 -310.863084) (xy 77.928768 -310.897176) (xy 77.958333 -310.93652)
			(xy 77.981204 -310.980097) (xy 77.996788 -311.026778) (xy 78.004683 -311.075355) (xy 78.005178 -311.099962)
			(xy 79.293986 -311.099962) (xy 79.297946 -311.050908) (xy 79.309723 -311.003124) (xy 79.329014 -310.957848)
			(xy 79.355317 -310.916252) (xy 79.387952 -310.879415) (xy 79.426073 -310.84829) (xy 79.468694 -310.823683)
			(xy 79.51471 -310.806231) (xy 79.562929 -310.796387) (xy 79.612104 -310.794406) (xy 79.660959 -310.800338)
			(xy 79.70823 -310.81403) (xy 79.752692 -310.835128) (xy 79.793195 -310.863084) (xy 79.828688 -310.897176)
			(xy 79.858253 -310.93652) (xy 79.881124 -310.980097) (xy 79.896708 -311.026778) (xy 79.904603 -311.075355)
			(xy 79.905098 -311.099962) (xy 155.49424 -311.099962) (xy 155.4982 -311.050908) (xy 155.509977 -311.003124)
			(xy 155.529268 -310.957848) (xy 155.555571 -310.916252) (xy 155.588206 -310.879415) (xy 155.626327 -310.84829)
			(xy 155.668948 -310.823683) (xy 155.714964 -310.806231) (xy 155.763183 -310.796387) (xy 155.812358 -310.794406)
			(xy 155.861213 -310.800338) (xy 155.908484 -310.81403) (xy 155.952946 -310.835128) (xy 155.993449 -310.863084)
			(xy 156.028942 -310.897176) (xy 156.058507 -310.93652) (xy 156.081378 -310.980097) (xy 156.096962 -311.026778)
			(xy 156.104857 -311.075355) (xy 156.105352 -311.099962) (xy 157.39416 -311.099962) (xy 157.39812 -311.050908)
			(xy 157.409897 -311.003124) (xy 157.429188 -310.957848) (xy 157.455491 -310.916252) (xy 157.488126 -310.879415)
			(xy 157.526247 -310.84829) (xy 157.568868 -310.823683) (xy 157.614884 -310.806231) (xy 157.663103 -310.796387)
			(xy 157.712278 -310.794406) (xy 157.761133 -310.800338) (xy 157.808404 -310.81403) (xy 157.852866 -310.835128)
			(xy 157.893369 -310.863084) (xy 157.928862 -310.897176) (xy 157.958427 -310.93652) (xy 157.981298 -310.980097)
			(xy 157.996882 -311.026778) (xy 158.004777 -311.075355) (xy 158.005272 -311.099962) (xy 159.29408 -311.099962)
			(xy 159.29804 -311.050908) (xy 159.309817 -311.003124) (xy 159.329108 -310.957848) (xy 159.355411 -310.916252)
			(xy 159.388046 -310.879415) (xy 159.426167 -310.84829) (xy 159.468788 -310.823683) (xy 159.514804 -310.806231)
			(xy 159.563023 -310.796387) (xy 159.612198 -310.794406) (xy 159.661053 -310.800338) (xy 159.708324 -310.81403)
			(xy 159.752786 -310.835128) (xy 159.793289 -310.863084) (xy 159.828782 -310.897176) (xy 159.858347 -310.93652)
			(xy 159.881218 -310.980097) (xy 159.896802 -311.026778) (xy 159.904697 -311.075355) (xy 159.905192 -311.099962)
			(xy 161.194254 -311.099962) (xy 161.198214 -311.050908) (xy 161.209991 -311.003124) (xy 161.229282 -310.957848)
			(xy 161.255585 -310.916252) (xy 161.28822 -310.879415) (xy 161.326341 -310.84829) (xy 161.368962 -310.823683)
			(xy 161.414978 -310.806231) (xy 161.463197 -310.796387) (xy 161.512372 -310.794406) (xy 161.561227 -310.800338)
			(xy 161.608498 -310.81403) (xy 161.65296 -310.835128) (xy 161.693463 -310.863084) (xy 161.728956 -310.897176)
			(xy 161.758521 -310.93652) (xy 161.781392 -310.980097) (xy 161.796976 -311.026778) (xy 161.804871 -311.075355)
			(xy 161.805366 -311.099962) (xy 163.094174 -311.099962) (xy 163.098134 -311.050908) (xy 163.109911 -311.003124)
			(xy 163.129202 -310.957848) (xy 163.155505 -310.916252) (xy 163.18814 -310.879415) (xy 163.226261 -310.84829)
			(xy 163.268882 -310.823683) (xy 163.314898 -310.806231) (xy 163.363117 -310.796387) (xy 163.412292 -310.794406)
			(xy 163.461147 -310.800338) (xy 163.508418 -310.81403) (xy 163.55288 -310.835128) (xy 163.593383 -310.863084)
			(xy 163.628876 -310.897176) (xy 163.658441 -310.93652) (xy 163.681312 -310.980097) (xy 163.696896 -311.026778)
			(xy 163.704791 -311.075355) (xy 163.705286 -311.099962) (xy 164.994094 -311.099962) (xy 164.998054 -311.050908)
			(xy 165.009831 -311.003124) (xy 165.029122 -310.957848) (xy 165.055425 -310.916252) (xy 165.08806 -310.879415)
			(xy 165.126181 -310.84829) (xy 165.168802 -310.823683) (xy 165.214818 -310.806231) (xy 165.263037 -310.796387)
			(xy 165.312212 -310.794406) (xy 165.361067 -310.800338) (xy 165.408338 -310.81403) (xy 165.4528 -310.835128)
			(xy 165.493303 -310.863084) (xy 165.528796 -310.897176) (xy 165.558361 -310.93652) (xy 165.581232 -310.980097)
			(xy 165.596816 -311.026778) (xy 165.604711 -311.075355) (xy 165.605206 -311.099962) (xy 166.894268 -311.099962)
			(xy 166.898228 -311.050908) (xy 166.910005 -311.003124) (xy 166.929296 -310.957848) (xy 166.955599 -310.916252)
			(xy 166.988234 -310.879415) (xy 167.026355 -310.84829) (xy 167.068976 -310.823683) (xy 167.114992 -310.806231)
			(xy 167.163211 -310.796387) (xy 167.212386 -310.794406) (xy 167.261241 -310.800338) (xy 167.308512 -310.81403)
			(xy 167.352974 -310.835128) (xy 167.393477 -310.863084) (xy 167.42897 -310.897176) (xy 167.458535 -310.93652)
			(xy 167.481406 -310.980097) (xy 167.49699 -311.026778) (xy 167.504885 -311.075355) (xy 167.50538 -311.099962)
			(xy 168.794188 -311.099962) (xy 168.798148 -311.050908) (xy 168.809925 -311.003124) (xy 168.829216 -310.957848)
			(xy 168.855519 -310.916252) (xy 168.888154 -310.879415) (xy 168.926275 -310.84829) (xy 168.968896 -310.823683)
			(xy 169.014912 -310.806231) (xy 169.063131 -310.796387) (xy 169.112306 -310.794406) (xy 169.161161 -310.800338)
			(xy 169.208432 -310.81403) (xy 169.252894 -310.835128) (xy 169.293397 -310.863084) (xy 169.32889 -310.897176)
			(xy 169.358455 -310.93652) (xy 169.381326 -310.980097) (xy 169.39691 -311.026778) (xy 169.404805 -311.075355)
			(xy 169.4053 -311.099962) (xy 170.694108 -311.099962) (xy 170.698068 -311.050908) (xy 170.709845 -311.003124)
			(xy 170.729136 -310.957848) (xy 170.755439 -310.916252) (xy 170.788074 -310.879415) (xy 170.826195 -310.84829)
			(xy 170.868816 -310.823683) (xy 170.914832 -310.806231) (xy 170.963051 -310.796387) (xy 171.012226 -310.794406)
			(xy 171.061081 -310.800338) (xy 171.108352 -310.81403) (xy 171.152814 -310.835128) (xy 171.193317 -310.863084)
			(xy 171.22881 -310.897176) (xy 171.258375 -310.93652) (xy 171.281246 -310.980097) (xy 171.29683 -311.026778)
			(xy 171.304725 -311.075355) (xy 171.30522 -311.099962) (xy 172.594282 -311.099962) (xy 172.598242 -311.050908)
			(xy 172.610019 -311.003124) (xy 172.62931 -310.957848) (xy 172.655613 -310.916252) (xy 172.688248 -310.879415)
			(xy 172.726369 -310.84829) (xy 172.76899 -310.823683) (xy 172.815006 -310.806231) (xy 172.863225 -310.796387)
			(xy 172.9124 -310.794406) (xy 172.961255 -310.800338) (xy 173.008526 -310.81403) (xy 173.052988 -310.835128)
			(xy 173.093491 -310.863084) (xy 173.128984 -310.897176) (xy 173.158549 -310.93652) (xy 173.18142 -310.980097)
			(xy 173.197004 -311.026778) (xy 173.204899 -311.075355) (xy 173.205394 -311.099962) (xy 174.494202 -311.099962)
			(xy 174.498162 -311.050908) (xy 174.509939 -311.003124) (xy 174.52923 -310.957848) (xy 174.555533 -310.916252)
			(xy 174.588168 -310.879415) (xy 174.626289 -310.84829) (xy 174.66891 -310.823683) (xy 174.714926 -310.806231)
			(xy 174.763145 -310.796387) (xy 174.81232 -310.794406) (xy 174.861175 -310.800338) (xy 174.908446 -310.81403)
			(xy 174.952908 -310.835128) (xy 174.993411 -310.863084) (xy 175.028904 -310.897176) (xy 175.058469 -310.93652)
			(xy 175.08134 -310.980097) (xy 175.096924 -311.026778) (xy 175.104819 -311.075355) (xy 175.105314 -311.099962)
			(xy 176.394122 -311.099962) (xy 176.398082 -311.050908) (xy 176.409859 -311.003124) (xy 176.42915 -310.957848)
			(xy 176.455453 -310.916252) (xy 176.488088 -310.879415) (xy 176.526209 -310.84829) (xy 176.56883 -310.823683)
			(xy 176.614846 -310.806231) (xy 176.663065 -310.796387) (xy 176.71224 -310.794406) (xy 176.761095 -310.800338)
			(xy 176.808366 -310.81403) (xy 176.852828 -310.835128) (xy 176.893331 -310.863084) (xy 176.928824 -310.897176)
			(xy 176.958389 -310.93652) (xy 176.98126 -310.980097) (xy 176.996844 -311.026778) (xy 177.004739 -311.075355)
			(xy 177.005234 -311.099962) (xy 178.294042 -311.099962) (xy 178.298002 -311.050908) (xy 178.309779 -311.003124)
			(xy 178.32907 -310.957848) (xy 178.355373 -310.916252) (xy 178.388008 -310.879415) (xy 178.426129 -310.84829)
			(xy 178.46875 -310.823683) (xy 178.514766 -310.806231) (xy 178.562985 -310.796387) (xy 178.61216 -310.794406)
			(xy 178.661015 -310.800338) (xy 178.708286 -310.81403) (xy 178.752748 -310.835128) (xy 178.793251 -310.863084)
			(xy 178.828744 -310.897176) (xy 178.858309 -310.93652) (xy 178.88118 -310.980097) (xy 178.896764 -311.026778)
			(xy 178.904659 -311.075355) (xy 178.905154 -311.099962) (xy 180.194216 -311.099962) (xy 180.198176 -311.050908)
			(xy 180.209953 -311.003124) (xy 180.229244 -310.957848) (xy 180.255547 -310.916252) (xy 180.288182 -310.879415)
			(xy 180.326303 -310.84829) (xy 180.368924 -310.823683) (xy 180.41494 -310.806231) (xy 180.463159 -310.796387)
			(xy 180.512334 -310.794406) (xy 180.561189 -310.800338) (xy 180.60846 -310.81403) (xy 180.652922 -310.835128)
			(xy 180.693425 -310.863084) (xy 180.728918 -310.897176) (xy 180.758483 -310.93652) (xy 180.781354 -310.980097)
			(xy 180.796938 -311.026778) (xy 180.804833 -311.075355) (xy 180.805328 -311.099962) (xy 182.094136 -311.099962)
			(xy 182.098096 -311.050908) (xy 182.109873 -311.003124) (xy 182.129164 -310.957848) (xy 182.155467 -310.916252)
			(xy 182.188102 -310.879415) (xy 182.226223 -310.84829) (xy 182.268844 -310.823683) (xy 182.31486 -310.806231)
			(xy 182.363079 -310.796387) (xy 182.412254 -310.794406) (xy 182.461109 -310.800338) (xy 182.50838 -310.81403)
			(xy 182.552842 -310.835128) (xy 182.593345 -310.863084) (xy 182.628838 -310.897176) (xy 182.658403 -310.93652)
			(xy 182.681274 -310.980097) (xy 182.696858 -311.026778) (xy 182.704753 -311.075355) (xy 182.705248 -311.099962)
			(xy 183.994056 -311.099962) (xy 183.998016 -311.050908) (xy 184.009793 -311.003124) (xy 184.029084 -310.957848)
			(xy 184.055387 -310.916252) (xy 184.088022 -310.879415) (xy 184.126143 -310.84829) (xy 184.168764 -310.823683)
			(xy 184.21478 -310.806231) (xy 184.262999 -310.796387) (xy 184.312174 -310.794406) (xy 184.361029 -310.800338)
			(xy 184.4083 -310.81403) (xy 184.452762 -310.835128) (xy 184.493265 -310.863084) (xy 184.528758 -310.897176)
			(xy 184.558323 -310.93652) (xy 184.581194 -310.980097) (xy 184.596778 -311.026778) (xy 184.604673 -311.075355)
			(xy 184.605168 -311.099962) (xy 185.89423 -311.099962) (xy 185.89819 -311.050908) (xy 185.909967 -311.003124)
			(xy 185.929258 -310.957848) (xy 185.955561 -310.916252) (xy 185.988196 -310.879415) (xy 186.026317 -310.84829)
			(xy 186.068938 -310.823683) (xy 186.114954 -310.806231) (xy 186.163173 -310.796387) (xy 186.212348 -310.794406)
			(xy 186.261203 -310.800338) (xy 186.308474 -310.81403) (xy 186.352936 -310.835128) (xy 186.393439 -310.863084)
			(xy 186.428932 -310.897176) (xy 186.458497 -310.93652) (xy 186.481368 -310.980097) (xy 186.496952 -311.026778)
			(xy 186.504847 -311.075355) (xy 186.505342 -311.099962) (xy 187.79415 -311.099962) (xy 187.79811 -311.050908)
			(xy 187.809887 -311.003124) (xy 187.829178 -310.957848) (xy 187.855481 -310.916252) (xy 187.888116 -310.879415)
			(xy 187.926237 -310.84829) (xy 187.968858 -310.823683) (xy 188.014874 -310.806231) (xy 188.063093 -310.796387)
			(xy 188.112268 -310.794406) (xy 188.161123 -310.800338) (xy 188.208394 -310.81403) (xy 188.252856 -310.835128)
			(xy 188.293359 -310.863084) (xy 188.328852 -310.897176) (xy 188.358417 -310.93652) (xy 188.381288 -310.980097)
			(xy 188.396872 -311.026778) (xy 188.404767 -311.075355) (xy 188.405262 -311.099962) (xy 189.69407 -311.099962)
			(xy 189.69803 -311.050908) (xy 189.709807 -311.003124) (xy 189.729098 -310.957848) (xy 189.755401 -310.916252)
			(xy 189.788036 -310.879415) (xy 189.826157 -310.84829) (xy 189.868778 -310.823683) (xy 189.914794 -310.806231)
			(xy 189.963013 -310.796387) (xy 190.012188 -310.794406) (xy 190.061043 -310.800338) (xy 190.108314 -310.81403)
			(xy 190.152776 -310.835128) (xy 190.193279 -310.863084) (xy 190.228772 -310.897176) (xy 190.258337 -310.93652)
			(xy 190.281208 -310.980097) (xy 190.296792 -311.026778) (xy 190.304687 -311.075355) (xy 190.305182 -311.099962)
			(xy 191.594244 -311.099962) (xy 191.598204 -311.050908) (xy 191.609981 -311.003124) (xy 191.629272 -310.957848)
			(xy 191.655575 -310.916252) (xy 191.68821 -310.879415) (xy 191.726331 -310.84829) (xy 191.768952 -310.823683)
			(xy 191.814968 -310.806231) (xy 191.863187 -310.796387) (xy 191.912362 -310.794406) (xy 191.961217 -310.800338)
			(xy 192.008488 -310.81403) (xy 192.05295 -310.835128) (xy 192.093453 -310.863084) (xy 192.128946 -310.897176)
			(xy 192.158511 -310.93652) (xy 192.181382 -310.980097) (xy 192.196966 -311.026778) (xy 192.204861 -311.075355)
			(xy 192.205356 -311.099962) (xy 193.494164 -311.099962) (xy 193.498124 -311.050908) (xy 193.509901 -311.003124)
			(xy 193.529192 -310.957848) (xy 193.555495 -310.916252) (xy 193.58813 -310.879415) (xy 193.626251 -310.84829)
			(xy 193.668872 -310.823683) (xy 193.714888 -310.806231) (xy 193.763107 -310.796387) (xy 193.812282 -310.794406)
			(xy 193.861137 -310.800338) (xy 193.908408 -310.81403) (xy 193.95287 -310.835128) (xy 193.993373 -310.863084)
			(xy 194.028866 -310.897176) (xy 194.058431 -310.93652) (xy 194.081302 -310.980097) (xy 194.096886 -311.026778)
			(xy 194.104781 -311.075355) (xy 194.105276 -311.099962) (xy 195.394084 -311.099962) (xy 195.398044 -311.050908)
			(xy 195.409821 -311.003124) (xy 195.429112 -310.957848) (xy 195.455415 -310.916252) (xy 195.48805 -310.879415)
			(xy 195.526171 -310.84829) (xy 195.568792 -310.823683) (xy 195.614808 -310.806231) (xy 195.663027 -310.796387)
			(xy 195.712202 -310.794406) (xy 195.761057 -310.800338) (xy 195.808328 -310.81403) (xy 195.85279 -310.835128)
			(xy 195.893293 -310.863084) (xy 195.928786 -310.897176) (xy 195.958351 -310.93652) (xy 195.981222 -310.980097)
			(xy 195.996806 -311.026778) (xy 196.004701 -311.075355) (xy 196.005196 -311.099962) (xy 271.594084 -311.099962)
			(xy 271.598044 -311.050908) (xy 271.609821 -311.003124) (xy 271.629112 -310.957848) (xy 271.655415 -310.916252)
			(xy 271.68805 -310.879415) (xy 271.726171 -310.84829) (xy 271.768792 -310.823683) (xy 271.814808 -310.806231)
			(xy 271.863027 -310.796387) (xy 271.912202 -310.794406) (xy 271.961057 -310.800338) (xy 272.008328 -310.81403)
			(xy 272.05279 -310.835128) (xy 272.093293 -310.863084) (xy 272.128786 -310.897176) (xy 272.158351 -310.93652)
			(xy 272.181222 -310.980097) (xy 272.196806 -311.026778) (xy 272.204701 -311.075355) (xy 272.205196 -311.099962)
			(xy 273.494004 -311.099962) (xy 273.497964 -311.050908) (xy 273.509741 -311.003124) (xy 273.529032 -310.957848)
			(xy 273.555335 -310.916252) (xy 273.58797 -310.879415) (xy 273.626091 -310.84829) (xy 273.668712 -310.823683)
			(xy 273.714728 -310.806231) (xy 273.762947 -310.796387) (xy 273.812122 -310.794406) (xy 273.860977 -310.800338)
			(xy 273.908248 -310.81403) (xy 273.95271 -310.835128) (xy 273.993213 -310.863084) (xy 274.028706 -310.897176)
			(xy 274.058271 -310.93652) (xy 274.081142 -310.980097) (xy 274.096726 -311.026778) (xy 274.104621 -311.075355)
			(xy 274.105116 -311.099962) (xy 275.393924 -311.099962) (xy 275.397884 -311.050908) (xy 275.409661 -311.003124)
			(xy 275.428952 -310.957848) (xy 275.455255 -310.916252) (xy 275.48789 -310.879415) (xy 275.526011 -310.84829)
			(xy 275.568632 -310.823683) (xy 275.614648 -310.806231) (xy 275.662867 -310.796387) (xy 275.712042 -310.794406)
			(xy 275.760897 -310.800338) (xy 275.808168 -310.81403) (xy 275.85263 -310.835128) (xy 275.893133 -310.863084)
			(xy 275.928626 -310.897176) (xy 275.958191 -310.93652) (xy 275.981062 -310.980097) (xy 275.996646 -311.026778)
			(xy 276.004541 -311.075355) (xy 276.005036 -311.099962) (xy 277.294098 -311.099962) (xy 277.298058 -311.050908)
			(xy 277.309835 -311.003124) (xy 277.329126 -310.957848) (xy 277.355429 -310.916252) (xy 277.388064 -310.879415)
			(xy 277.426185 -310.84829) (xy 277.468806 -310.823683) (xy 277.514822 -310.806231) (xy 277.563041 -310.796387)
			(xy 277.612216 -310.794406) (xy 277.661071 -310.800338) (xy 277.708342 -310.81403) (xy 277.752804 -310.835128)
			(xy 277.793307 -310.863084) (xy 277.8288 -310.897176) (xy 277.858365 -310.93652) (xy 277.881236 -310.980097)
			(xy 277.89682 -311.026778) (xy 277.904715 -311.075355) (xy 277.90521 -311.099962) (xy 279.194018 -311.099962)
			(xy 279.197978 -311.050908) (xy 279.209755 -311.003124) (xy 279.229046 -310.957848) (xy 279.255349 -310.916252)
			(xy 279.287984 -310.879415) (xy 279.326105 -310.84829) (xy 279.368726 -310.823683) (xy 279.414742 -310.806231)
			(xy 279.462961 -310.796387) (xy 279.512136 -310.794406) (xy 279.560991 -310.800338) (xy 279.608262 -310.81403)
			(xy 279.652724 -310.835128) (xy 279.693227 -310.863084) (xy 279.72872 -310.897176) (xy 279.758285 -310.93652)
			(xy 279.781156 -310.980097) (xy 279.79674 -311.026778) (xy 279.804635 -311.075355) (xy 279.80513 -311.099962)
			(xy 281.093938 -311.099962) (xy 281.097898 -311.050908) (xy 281.109675 -311.003124) (xy 281.128966 -310.957848)
			(xy 281.155269 -310.916252) (xy 281.187904 -310.879415) (xy 281.226025 -310.84829) (xy 281.268646 -310.823683)
			(xy 281.314662 -310.806231) (xy 281.362881 -310.796387) (xy 281.412056 -310.794406) (xy 281.460911 -310.800338)
			(xy 281.508182 -310.81403) (xy 281.552644 -310.835128) (xy 281.593147 -310.863084) (xy 281.62864 -310.897176)
			(xy 281.658205 -310.93652) (xy 281.681076 -310.980097) (xy 281.69666 -311.026778) (xy 281.704555 -311.075355)
			(xy 281.70505 -311.099962) (xy 282.994112 -311.099962) (xy 282.998072 -311.050908) (xy 283.009849 -311.003124)
			(xy 283.02914 -310.957848) (xy 283.055443 -310.916252) (xy 283.088078 -310.879415) (xy 283.126199 -310.84829)
			(xy 283.16882 -310.823683) (xy 283.214836 -310.806231) (xy 283.263055 -310.796387) (xy 283.31223 -310.794406)
			(xy 283.361085 -310.800338) (xy 283.408356 -310.81403) (xy 283.452818 -310.835128) (xy 283.493321 -310.863084)
			(xy 283.528814 -310.897176) (xy 283.558379 -310.93652) (xy 283.58125 -310.980097) (xy 283.596834 -311.026778)
			(xy 283.604729 -311.075355) (xy 283.605224 -311.099962) (xy 284.894032 -311.099962) (xy 284.897992 -311.050908)
			(xy 284.909769 -311.003124) (xy 284.92906 -310.957848) (xy 284.955363 -310.916252) (xy 284.987998 -310.879415)
			(xy 285.026119 -310.84829) (xy 285.06874 -310.823683) (xy 285.114756 -310.806231) (xy 285.162975 -310.796387)
			(xy 285.21215 -310.794406) (xy 285.261005 -310.800338) (xy 285.308276 -310.81403) (xy 285.352738 -310.835128)
			(xy 285.393241 -310.863084) (xy 285.428734 -310.897176) (xy 285.458299 -310.93652) (xy 285.48117 -310.980097)
			(xy 285.496754 -311.026778) (xy 285.504649 -311.075355) (xy 285.505144 -311.099962) (xy 286.793952 -311.099962)
			(xy 286.797912 -311.050908) (xy 286.809689 -311.003124) (xy 286.82898 -310.957848) (xy 286.855283 -310.916252)
			(xy 286.887918 -310.879415) (xy 286.926039 -310.84829) (xy 286.96866 -310.823683) (xy 287.014676 -310.806231)
			(xy 287.062895 -310.796387) (xy 287.11207 -310.794406) (xy 287.160925 -310.800338) (xy 287.208196 -310.81403)
			(xy 287.252658 -310.835128) (xy 287.293161 -310.863084) (xy 287.328654 -310.897176) (xy 287.358219 -310.93652)
			(xy 287.38109 -310.980097) (xy 287.396674 -311.026778) (xy 287.404569 -311.075355) (xy 287.405064 -311.099962)
			(xy 288.694126 -311.099962) (xy 288.698086 -311.050908) (xy 288.709863 -311.003124) (xy 288.729154 -310.957848)
			(xy 288.755457 -310.916252) (xy 288.788092 -310.879415) (xy 288.826213 -310.84829) (xy 288.868834 -310.823683)
			(xy 288.91485 -310.806231) (xy 288.963069 -310.796387) (xy 289.012244 -310.794406) (xy 289.061099 -310.800338)
			(xy 289.10837 -310.81403) (xy 289.152832 -310.835128) (xy 289.193335 -310.863084) (xy 289.228828 -310.897176)
			(xy 289.258393 -310.93652) (xy 289.281264 -310.980097) (xy 289.296848 -311.026778) (xy 289.304743 -311.075355)
			(xy 289.305238 -311.099962) (xy 290.594046 -311.099962) (xy 290.598006 -311.050908) (xy 290.609783 -311.003124)
			(xy 290.629074 -310.957848) (xy 290.655377 -310.916252) (xy 290.688012 -310.879415) (xy 290.726133 -310.84829)
			(xy 290.768754 -310.823683) (xy 290.81477 -310.806231) (xy 290.862989 -310.796387) (xy 290.912164 -310.794406)
			(xy 290.961019 -310.800338) (xy 291.00829 -310.81403) (xy 291.052752 -310.835128) (xy 291.093255 -310.863084)
			(xy 291.128748 -310.897176) (xy 291.158313 -310.93652) (xy 291.181184 -310.980097) (xy 291.196768 -311.026778)
			(xy 291.204663 -311.075355) (xy 291.205158 -311.099962) (xy 292.493966 -311.099962) (xy 292.497926 -311.050908)
			(xy 292.509703 -311.003124) (xy 292.528994 -310.957848) (xy 292.555297 -310.916252) (xy 292.587932 -310.879415)
			(xy 292.626053 -310.84829) (xy 292.668674 -310.823683) (xy 292.71469 -310.806231) (xy 292.762909 -310.796387)
			(xy 292.812084 -310.794406) (xy 292.860939 -310.800338) (xy 292.90821 -310.81403) (xy 292.952672 -310.835128)
			(xy 292.993175 -310.863084) (xy 293.028668 -310.897176) (xy 293.058233 -310.93652) (xy 293.081104 -310.980097)
			(xy 293.096688 -311.026778) (xy 293.104583 -311.075355) (xy 293.105078 -311.099962) (xy 294.393886 -311.099962)
			(xy 294.397846 -311.050908) (xy 294.409623 -311.003124) (xy 294.428914 -310.957848) (xy 294.455217 -310.916252)
			(xy 294.487852 -310.879415) (xy 294.525973 -310.84829) (xy 294.568594 -310.823683) (xy 294.61461 -310.806231)
			(xy 294.662829 -310.796387) (xy 294.712004 -310.794406) (xy 294.760859 -310.800338) (xy 294.80813 -310.81403)
			(xy 294.852592 -310.835128) (xy 294.893095 -310.863084) (xy 294.928588 -310.897176) (xy 294.958153 -310.93652)
			(xy 294.981024 -310.980097) (xy 294.996608 -311.026778) (xy 295.004503 -311.075355) (xy 295.004998 -311.099962)
			(xy 296.29406 -311.099962) (xy 296.29802 -311.050908) (xy 296.309797 -311.003124) (xy 296.329088 -310.957848)
			(xy 296.355391 -310.916252) (xy 296.388026 -310.879415) (xy 296.426147 -310.84829) (xy 296.468768 -310.823683)
			(xy 296.514784 -310.806231) (xy 296.563003 -310.796387) (xy 296.612178 -310.794406) (xy 296.661033 -310.800338)
			(xy 296.708304 -310.81403) (xy 296.752766 -310.835128) (xy 296.793269 -310.863084) (xy 296.828762 -310.897176)
			(xy 296.858327 -310.93652) (xy 296.881198 -310.980097) (xy 296.896782 -311.026778) (xy 296.904677 -311.075355)
			(xy 296.905172 -311.099962) (xy 298.19398 -311.099962) (xy 298.19794 -311.050908) (xy 298.209717 -311.003124)
			(xy 298.229008 -310.957848) (xy 298.255311 -310.916252) (xy 298.287946 -310.879415) (xy 298.326067 -310.84829)
			(xy 298.368688 -310.823683) (xy 298.414704 -310.806231) (xy 298.462923 -310.796387) (xy 298.512098 -310.794406)
			(xy 298.560953 -310.800338) (xy 298.608224 -310.81403) (xy 298.652686 -310.835128) (xy 298.693189 -310.863084)
			(xy 298.728682 -310.897176) (xy 298.758247 -310.93652) (xy 298.781118 -310.980097) (xy 298.796702 -311.026778)
			(xy 298.804597 -311.075355) (xy 298.805092 -311.099962) (xy 300.0939 -311.099962) (xy 300.09786 -311.050908)
			(xy 300.109637 -311.003124) (xy 300.128928 -310.957848) (xy 300.155231 -310.916252) (xy 300.187866 -310.879415)
			(xy 300.225987 -310.84829) (xy 300.268608 -310.823683) (xy 300.314624 -310.806231) (xy 300.362843 -310.796387)
			(xy 300.412018 -310.794406) (xy 300.460873 -310.800338) (xy 300.508144 -310.81403) (xy 300.552606 -310.835128)
			(xy 300.593109 -310.863084) (xy 300.628602 -310.897176) (xy 300.658167 -310.93652) (xy 300.681038 -310.980097)
			(xy 300.696622 -311.026778) (xy 300.704517 -311.075355) (xy 300.705012 -311.099962) (xy 301.994074 -311.099962)
			(xy 301.998034 -311.050908) (xy 302.009811 -311.003124) (xy 302.029102 -310.957848) (xy 302.055405 -310.916252)
			(xy 302.08804 -310.879415) (xy 302.126161 -310.84829) (xy 302.168782 -310.823683) (xy 302.214798 -310.806231)
			(xy 302.263017 -310.796387) (xy 302.312192 -310.794406) (xy 302.361047 -310.800338) (xy 302.408318 -310.81403)
			(xy 302.45278 -310.835128) (xy 302.493283 -310.863084) (xy 302.528776 -310.897176) (xy 302.558341 -310.93652)
			(xy 302.581212 -310.980097) (xy 302.596796 -311.026778) (xy 302.604691 -311.075355) (xy 302.605186 -311.099962)
			(xy 303.893994 -311.099962) (xy 303.897954 -311.050908) (xy 303.909731 -311.003124) (xy 303.929022 -310.957848)
			(xy 303.955325 -310.916252) (xy 303.98796 -310.879415) (xy 304.026081 -310.84829) (xy 304.068702 -310.823683)
			(xy 304.114718 -310.806231) (xy 304.162937 -310.796387) (xy 304.212112 -310.794406) (xy 304.260967 -310.800338)
			(xy 304.308238 -310.81403) (xy 304.3527 -310.835128) (xy 304.393203 -310.863084) (xy 304.428696 -310.897176)
			(xy 304.458261 -310.93652) (xy 304.481132 -310.980097) (xy 304.496716 -311.026778) (xy 304.504611 -311.075355)
			(xy 304.505106 -311.099962) (xy 305.793914 -311.099962) (xy 305.797874 -311.050908) (xy 305.809651 -311.003124)
			(xy 305.828942 -310.957848) (xy 305.855245 -310.916252) (xy 305.88788 -310.879415) (xy 305.926001 -310.84829)
			(xy 305.968622 -310.823683) (xy 306.014638 -310.806231) (xy 306.062857 -310.796387) (xy 306.112032 -310.794406)
			(xy 306.160887 -310.800338) (xy 306.208158 -310.81403) (xy 306.25262 -310.835128) (xy 306.293123 -310.863084)
			(xy 306.328616 -310.897176) (xy 306.358181 -310.93652) (xy 306.381052 -310.980097) (xy 306.396636 -311.026778)
			(xy 306.404531 -311.075355) (xy 306.405026 -311.099962) (xy 307.694088 -311.099962) (xy 307.698048 -311.050908)
			(xy 307.709825 -311.003124) (xy 307.729116 -310.957848) (xy 307.755419 -310.916252) (xy 307.788054 -310.879415)
			(xy 307.826175 -310.84829) (xy 307.868796 -310.823683) (xy 307.914812 -310.806231) (xy 307.963031 -310.796387)
			(xy 308.012206 -310.794406) (xy 308.061061 -310.800338) (xy 308.108332 -310.81403) (xy 308.152794 -310.835128)
			(xy 308.193297 -310.863084) (xy 308.22879 -310.897176) (xy 308.258355 -310.93652) (xy 308.281226 -310.980097)
			(xy 308.29681 -311.026778) (xy 308.304705 -311.075355) (xy 308.3052 -311.099962) (xy 309.594008 -311.099962)
			(xy 309.597968 -311.050908) (xy 309.609745 -311.003124) (xy 309.629036 -310.957848) (xy 309.655339 -310.916252)
			(xy 309.687974 -310.879415) (xy 309.726095 -310.84829) (xy 309.768716 -310.823683) (xy 309.814732 -310.806231)
			(xy 309.862951 -310.796387) (xy 309.912126 -310.794406) (xy 309.960981 -310.800338) (xy 310.008252 -310.81403)
			(xy 310.052714 -310.835128) (xy 310.093217 -310.863084) (xy 310.12871 -310.897176) (xy 310.158275 -310.93652)
			(xy 310.181146 -310.980097) (xy 310.19673 -311.026778) (xy 310.204625 -311.075355) (xy 310.20512 -311.099962)
			(xy 311.493928 -311.099962) (xy 311.497888 -311.050908) (xy 311.509665 -311.003124) (xy 311.528956 -310.957848)
			(xy 311.555259 -310.916252) (xy 311.587894 -310.879415) (xy 311.626015 -310.84829) (xy 311.668636 -310.823683)
			(xy 311.714652 -310.806231) (xy 311.762871 -310.796387) (xy 311.812046 -310.794406) (xy 311.860901 -310.800338)
			(xy 311.908172 -310.81403) (xy 311.952634 -310.835128) (xy 311.993137 -310.863084) (xy 312.02863 -310.897176)
			(xy 312.058195 -310.93652) (xy 312.081066 -310.980097) (xy 312.09665 -311.026778) (xy 312.104545 -311.075355)
			(xy 312.10504 -311.099962) (xy 387.694182 -311.099962) (xy 387.698142 -311.050908) (xy 387.709919 -311.003124)
			(xy 387.72921 -310.957848) (xy 387.755513 -310.916252) (xy 387.788148 -310.879415) (xy 387.826269 -310.84829)
			(xy 387.86889 -310.823683) (xy 387.914906 -310.806231) (xy 387.963125 -310.796387) (xy 388.0123 -310.794406)
			(xy 388.061155 -310.800338) (xy 388.108426 -310.81403) (xy 388.152888 -310.835128) (xy 388.193391 -310.863084)
			(xy 388.228884 -310.897176) (xy 388.258449 -310.93652) (xy 388.28132 -310.980097) (xy 388.296904 -311.026778)
			(xy 388.304799 -311.075355) (xy 388.305294 -311.099962) (xy 389.594102 -311.099962) (xy 389.598062 -311.050908)
			(xy 389.609839 -311.003124) (xy 389.62913 -310.957848) (xy 389.655433 -310.916252) (xy 389.688068 -310.879415)
			(xy 389.726189 -310.84829) (xy 389.76881 -310.823683) (xy 389.814826 -310.806231) (xy 389.863045 -310.796387)
			(xy 389.91222 -310.794406) (xy 389.961075 -310.800338) (xy 390.008346 -310.81403) (xy 390.052808 -310.835128)
			(xy 390.093311 -310.863084) (xy 390.128804 -310.897176) (xy 390.158369 -310.93652) (xy 390.18124 -310.980097)
			(xy 390.196824 -311.026778) (xy 390.204719 -311.075355) (xy 390.205214 -311.099962) (xy 391.494022 -311.099962)
			(xy 391.497982 -311.050908) (xy 391.509759 -311.003124) (xy 391.52905 -310.957848) (xy 391.555353 -310.916252)
			(xy 391.587988 -310.879415) (xy 391.626109 -310.84829) (xy 391.66873 -310.823683) (xy 391.714746 -310.806231)
			(xy 391.762965 -310.796387) (xy 391.81214 -310.794406) (xy 391.860995 -310.800338) (xy 391.908266 -310.81403)
			(xy 391.952728 -310.835128) (xy 391.993231 -310.863084) (xy 392.028724 -310.897176) (xy 392.058289 -310.93652)
			(xy 392.08116 -310.980097) (xy 392.096744 -311.026778) (xy 392.104639 -311.075355) (xy 392.105134 -311.099962)
			(xy 393.394196 -311.099962) (xy 393.398156 -311.050908) (xy 393.409933 -311.003124) (xy 393.429224 -310.957848)
			(xy 393.455527 -310.916252) (xy 393.488162 -310.879415) (xy 393.526283 -310.84829) (xy 393.568904 -310.823683)
			(xy 393.61492 -310.806231) (xy 393.663139 -310.796387) (xy 393.712314 -310.794406) (xy 393.761169 -310.800338)
			(xy 393.80844 -310.81403) (xy 393.852902 -310.835128) (xy 393.893405 -310.863084) (xy 393.928898 -310.897176)
			(xy 393.958463 -310.93652) (xy 393.981334 -310.980097) (xy 393.996918 -311.026778) (xy 394.004813 -311.075355)
			(xy 394.005308 -311.099962) (xy 395.294116 -311.099962) (xy 395.298076 -311.050908) (xy 395.309853 -311.003124)
			(xy 395.329144 -310.957848) (xy 395.355447 -310.916252) (xy 395.388082 -310.879415) (xy 395.426203 -310.84829)
			(xy 395.468824 -310.823683) (xy 395.51484 -310.806231) (xy 395.563059 -310.796387) (xy 395.612234 -310.794406)
			(xy 395.661089 -310.800338) (xy 395.70836 -310.81403) (xy 395.752822 -310.835128) (xy 395.793325 -310.863084)
			(xy 395.828818 -310.897176) (xy 395.858383 -310.93652) (xy 395.881254 -310.980097) (xy 395.896838 -311.026778)
			(xy 395.904733 -311.075355) (xy 395.905228 -311.099962) (xy 397.194036 -311.099962) (xy 397.197996 -311.050908)
			(xy 397.209773 -311.003124) (xy 397.229064 -310.957848) (xy 397.255367 -310.916252) (xy 397.288002 -310.879415)
			(xy 397.326123 -310.84829) (xy 397.368744 -310.823683) (xy 397.41476 -310.806231) (xy 397.462979 -310.796387)
			(xy 397.512154 -310.794406) (xy 397.561009 -310.800338) (xy 397.60828 -310.81403) (xy 397.652742 -310.835128)
			(xy 397.693245 -310.863084) (xy 397.728738 -310.897176) (xy 397.758303 -310.93652) (xy 397.781174 -310.980097)
			(xy 397.796758 -311.026778) (xy 397.804653 -311.075355) (xy 397.805148 -311.099962) (xy 399.09421 -311.099962)
			(xy 399.09817 -311.050908) (xy 399.109947 -311.003124) (xy 399.129238 -310.957848) (xy 399.155541 -310.916252)
			(xy 399.188176 -310.879415) (xy 399.226297 -310.84829) (xy 399.268918 -310.823683) (xy 399.314934 -310.806231)
			(xy 399.363153 -310.796387) (xy 399.412328 -310.794406) (xy 399.461183 -310.800338) (xy 399.508454 -310.81403)
			(xy 399.552916 -310.835128) (xy 399.593419 -310.863084) (xy 399.628912 -310.897176) (xy 399.658477 -310.93652)
			(xy 399.681348 -310.980097) (xy 399.696932 -311.026778) (xy 399.704827 -311.075355) (xy 399.705322 -311.099962)
			(xy 400.99413 -311.099962) (xy 400.99809 -311.050908) (xy 401.009867 -311.003124) (xy 401.029158 -310.957848)
			(xy 401.055461 -310.916252) (xy 401.088096 -310.879415) (xy 401.126217 -310.84829) (xy 401.168838 -310.823683)
			(xy 401.214854 -310.806231) (xy 401.263073 -310.796387) (xy 401.312248 -310.794406) (xy 401.361103 -310.800338)
			(xy 401.408374 -310.81403) (xy 401.452836 -310.835128) (xy 401.493339 -310.863084) (xy 401.528832 -310.897176)
			(xy 401.558397 -310.93652) (xy 401.581268 -310.980097) (xy 401.596852 -311.026778) (xy 401.604747 -311.075355)
			(xy 401.605242 -311.099962) (xy 402.89405 -311.099962) (xy 402.89801 -311.050908) (xy 402.909787 -311.003124)
			(xy 402.929078 -310.957848) (xy 402.955381 -310.916252) (xy 402.988016 -310.879415) (xy 403.026137 -310.84829)
			(xy 403.068758 -310.823683) (xy 403.114774 -310.806231) (xy 403.162993 -310.796387) (xy 403.212168 -310.794406)
			(xy 403.261023 -310.800338) (xy 403.308294 -310.81403) (xy 403.352756 -310.835128) (xy 403.393259 -310.863084)
			(xy 403.428752 -310.897176) (xy 403.458317 -310.93652) (xy 403.481188 -310.980097) (xy 403.496772 -311.026778)
			(xy 403.504667 -311.075355) (xy 403.505162 -311.099962) (xy 404.794224 -311.099962) (xy 404.798184 -311.050908)
			(xy 404.809961 -311.003124) (xy 404.829252 -310.957848) (xy 404.855555 -310.916252) (xy 404.88819 -310.879415)
			(xy 404.926311 -310.84829) (xy 404.968932 -310.823683) (xy 405.014948 -310.806231) (xy 405.063167 -310.796387)
			(xy 405.112342 -310.794406) (xy 405.161197 -310.800338) (xy 405.208468 -310.81403) (xy 405.25293 -310.835128)
			(xy 405.293433 -310.863084) (xy 405.328926 -310.897176) (xy 405.358491 -310.93652) (xy 405.381362 -310.980097)
			(xy 405.396946 -311.026778) (xy 405.404841 -311.075355) (xy 405.405336 -311.099962) (xy 406.694144 -311.099962)
			(xy 406.698104 -311.050908) (xy 406.709881 -311.003124) (xy 406.729172 -310.957848) (xy 406.755475 -310.916252)
			(xy 406.78811 -310.879415) (xy 406.826231 -310.84829) (xy 406.868852 -310.823683) (xy 406.914868 -310.806231)
			(xy 406.963087 -310.796387) (xy 407.012262 -310.794406) (xy 407.061117 -310.800338) (xy 407.108388 -310.81403)
			(xy 407.15285 -310.835128) (xy 407.193353 -310.863084) (xy 407.228846 -310.897176) (xy 407.258411 -310.93652)
			(xy 407.281282 -310.980097) (xy 407.296866 -311.026778) (xy 407.304761 -311.075355) (xy 407.305256 -311.099962)
			(xy 408.594064 -311.099962) (xy 408.598024 -311.050908) (xy 408.609801 -311.003124) (xy 408.629092 -310.957848)
			(xy 408.655395 -310.916252) (xy 408.68803 -310.879415) (xy 408.726151 -310.84829) (xy 408.768772 -310.823683)
			(xy 408.814788 -310.806231) (xy 408.863007 -310.796387) (xy 408.912182 -310.794406) (xy 408.961037 -310.800338)
			(xy 409.008308 -310.81403) (xy 409.05277 -310.835128) (xy 409.093273 -310.863084) (xy 409.128766 -310.897176)
			(xy 409.158331 -310.93652) (xy 409.181202 -310.980097) (xy 409.196786 -311.026778) (xy 409.204681 -311.075355)
			(xy 409.205176 -311.099962) (xy 410.493984 -311.099962) (xy 410.497944 -311.050908) (xy 410.509721 -311.003124)
			(xy 410.529012 -310.957848) (xy 410.555315 -310.916252) (xy 410.58795 -310.879415) (xy 410.626071 -310.84829)
			(xy 410.668692 -310.823683) (xy 410.714708 -310.806231) (xy 410.762927 -310.796387) (xy 410.812102 -310.794406)
			(xy 410.860957 -310.800338) (xy 410.908228 -310.81403) (xy 410.95269 -310.835128) (xy 410.993193 -310.863084)
			(xy 411.028686 -310.897176) (xy 411.058251 -310.93652) (xy 411.081122 -310.980097) (xy 411.096706 -311.026778)
			(xy 411.104601 -311.075355) (xy 411.105096 -311.099962) (xy 412.394158 -311.099962) (xy 412.398118 -311.050908)
			(xy 412.409895 -311.003124) (xy 412.429186 -310.957848) (xy 412.455489 -310.916252) (xy 412.488124 -310.879415)
			(xy 412.526245 -310.84829) (xy 412.568866 -310.823683) (xy 412.614882 -310.806231) (xy 412.663101 -310.796387)
			(xy 412.712276 -310.794406) (xy 412.761131 -310.800338) (xy 412.808402 -310.81403) (xy 412.852864 -310.835128)
			(xy 412.893367 -310.863084) (xy 412.92886 -310.897176) (xy 412.958425 -310.93652) (xy 412.981296 -310.980097)
			(xy 412.99688 -311.026778) (xy 413.004775 -311.075355) (xy 413.00527 -311.099962) (xy 414.294078 -311.099962)
			(xy 414.298038 -311.050908) (xy 414.309815 -311.003124) (xy 414.329106 -310.957848) (xy 414.355409 -310.916252)
			(xy 414.388044 -310.879415) (xy 414.426165 -310.84829) (xy 414.468786 -310.823683) (xy 414.514802 -310.806231)
			(xy 414.563021 -310.796387) (xy 414.612196 -310.794406) (xy 414.661051 -310.800338) (xy 414.708322 -310.81403)
			(xy 414.752784 -310.835128) (xy 414.793287 -310.863084) (xy 414.82878 -310.897176) (xy 414.858345 -310.93652)
			(xy 414.881216 -310.980097) (xy 414.8968 -311.026778) (xy 414.904695 -311.075355) (xy 414.90519 -311.099962)
			(xy 416.193998 -311.099962) (xy 416.197958 -311.050908) (xy 416.209735 -311.003124) (xy 416.229026 -310.957848)
			(xy 416.255329 -310.916252) (xy 416.287964 -310.879415) (xy 416.326085 -310.84829) (xy 416.368706 -310.823683)
			(xy 416.414722 -310.806231) (xy 416.462941 -310.796387) (xy 416.512116 -310.794406) (xy 416.560971 -310.800338)
			(xy 416.608242 -310.81403) (xy 416.652704 -310.835128) (xy 416.693207 -310.863084) (xy 416.7287 -310.897176)
			(xy 416.758265 -310.93652) (xy 416.781136 -310.980097) (xy 416.79672 -311.026778) (xy 416.804615 -311.075355)
			(xy 416.80511 -311.099962) (xy 418.094172 -311.099962) (xy 418.098132 -311.050908) (xy 418.109909 -311.003124)
			(xy 418.1292 -310.957848) (xy 418.155503 -310.916252) (xy 418.188138 -310.879415) (xy 418.226259 -310.84829)
			(xy 418.26888 -310.823683) (xy 418.314896 -310.806231) (xy 418.363115 -310.796387) (xy 418.41229 -310.794406)
			(xy 418.461145 -310.800338) (xy 418.508416 -310.81403) (xy 418.552878 -310.835128) (xy 418.593381 -310.863084)
			(xy 418.628874 -310.897176) (xy 418.658439 -310.93652) (xy 418.68131 -310.980097) (xy 418.696894 -311.026778)
			(xy 418.704789 -311.075355) (xy 418.705284 -311.099962) (xy 419.994092 -311.099962) (xy 419.998052 -311.050908)
			(xy 420.009829 -311.003124) (xy 420.02912 -310.957848) (xy 420.055423 -310.916252) (xy 420.088058 -310.879415)
			(xy 420.126179 -310.84829) (xy 420.1688 -310.823683) (xy 420.214816 -310.806231) (xy 420.263035 -310.796387)
			(xy 420.31221 -310.794406) (xy 420.361065 -310.800338) (xy 420.408336 -310.81403) (xy 420.452798 -310.835128)
			(xy 420.493301 -310.863084) (xy 420.528794 -310.897176) (xy 420.558359 -310.93652) (xy 420.58123 -310.980097)
			(xy 420.596814 -311.026778) (xy 420.604709 -311.075355) (xy 420.605204 -311.099962) (xy 421.894012 -311.099962)
			(xy 421.897972 -311.050908) (xy 421.909749 -311.003124) (xy 421.92904 -310.957848) (xy 421.955343 -310.916252)
			(xy 421.987978 -310.879415) (xy 422.026099 -310.84829) (xy 422.06872 -310.823683) (xy 422.114736 -310.806231)
			(xy 422.162955 -310.796387) (xy 422.21213 -310.794406) (xy 422.260985 -310.800338) (xy 422.308256 -310.81403)
			(xy 422.352718 -310.835128) (xy 422.393221 -310.863084) (xy 422.428714 -310.897176) (xy 422.458279 -310.93652)
			(xy 422.48115 -310.980097) (xy 422.496734 -311.026778) (xy 422.504629 -311.075355) (xy 422.505124 -311.099962)
			(xy 423.794186 -311.099962) (xy 423.798146 -311.050908) (xy 423.809923 -311.003124) (xy 423.829214 -310.957848)
			(xy 423.855517 -310.916252) (xy 423.888152 -310.879415) (xy 423.926273 -310.84829) (xy 423.968894 -310.823683)
			(xy 424.01491 -310.806231) (xy 424.063129 -310.796387) (xy 424.112304 -310.794406) (xy 424.161159 -310.800338)
			(xy 424.20843 -310.81403) (xy 424.252892 -310.835128) (xy 424.293395 -310.863084) (xy 424.328888 -310.897176)
			(xy 424.358453 -310.93652) (xy 424.381324 -310.980097) (xy 424.396908 -311.026778) (xy 424.404803 -311.075355)
			(xy 424.405298 -311.099962) (xy 425.694106 -311.099962) (xy 425.698066 -311.050908) (xy 425.709843 -311.003124)
			(xy 425.729134 -310.957848) (xy 425.755437 -310.916252) (xy 425.788072 -310.879415) (xy 425.826193 -310.84829)
			(xy 425.868814 -310.823683) (xy 425.91483 -310.806231) (xy 425.963049 -310.796387) (xy 426.012224 -310.794406)
			(xy 426.061079 -310.800338) (xy 426.10835 -310.81403) (xy 426.152812 -310.835128) (xy 426.193315 -310.863084)
			(xy 426.228808 -310.897176) (xy 426.258373 -310.93652) (xy 426.281244 -310.980097) (xy 426.296828 -311.026778)
			(xy 426.304723 -311.075355) (xy 426.305218 -311.099962) (xy 427.594026 -311.099962) (xy 427.597986 -311.050908)
			(xy 427.609763 -311.003124) (xy 427.629054 -310.957848) (xy 427.655357 -310.916252) (xy 427.687992 -310.879415)
			(xy 427.726113 -310.84829) (xy 427.768734 -310.823683) (xy 427.81475 -310.806231) (xy 427.862969 -310.796387)
			(xy 427.912144 -310.794406) (xy 427.960999 -310.800338) (xy 428.00827 -310.81403) (xy 428.052732 -310.835128)
			(xy 428.093235 -310.863084) (xy 428.128728 -310.897176) (xy 428.158293 -310.93652) (xy 428.181164 -310.980097)
			(xy 428.196748 -311.026778) (xy 428.204643 -311.075355) (xy 428.205138 -311.099962) (xy 428.204643 -311.124569)
			(xy 428.196748 -311.173146) (xy 428.181164 -311.219827) (xy 428.158293 -311.263404) (xy 428.128728 -311.302748)
			(xy 428.093235 -311.33684) (xy 428.052732 -311.364796) (xy 428.00827 -311.385894) (xy 427.960999 -311.399586)
			(xy 427.912144 -311.405518) (xy 427.862969 -311.403537) (xy 427.81475 -311.393693) (xy 427.768734 -311.376241)
			(xy 427.726113 -311.351634) (xy 427.687992 -311.320509) (xy 427.655357 -311.283672) (xy 427.629054 -311.242076)
			(xy 427.609763 -311.1968) (xy 427.597986 -311.149016) (xy 427.594026 -311.099962) (xy 426.305218 -311.099962)
			(xy 426.304723 -311.124569) (xy 426.296828 -311.173146) (xy 426.281244 -311.219827) (xy 426.258373 -311.263404)
			(xy 426.228808 -311.302748) (xy 426.193315 -311.33684) (xy 426.152812 -311.364796) (xy 426.10835 -311.385894)
			(xy 426.061079 -311.399586) (xy 426.012224 -311.405518) (xy 425.963049 -311.403537) (xy 425.91483 -311.393693)
			(xy 425.868814 -311.376241) (xy 425.826193 -311.351634) (xy 425.788072 -311.320509) (xy 425.755437 -311.283672)
			(xy 425.729134 -311.242076) (xy 425.709843 -311.1968) (xy 425.698066 -311.149016) (xy 425.694106 -311.099962)
			(xy 424.405298 -311.099962) (xy 424.404803 -311.124569) (xy 424.396908 -311.173146) (xy 424.381324 -311.219827)
			(xy 424.358453 -311.263404) (xy 424.328888 -311.302748) (xy 424.293395 -311.33684) (xy 424.252892 -311.364796)
			(xy 424.20843 -311.385894) (xy 424.161159 -311.399586) (xy 424.112304 -311.405518) (xy 424.063129 -311.403537)
			(xy 424.01491 -311.393693) (xy 423.968894 -311.376241) (xy 423.926273 -311.351634) (xy 423.888152 -311.320509)
			(xy 423.855517 -311.283672) (xy 423.829214 -311.242076) (xy 423.809923 -311.1968) (xy 423.798146 -311.149016)
			(xy 423.794186 -311.099962) (xy 422.505124 -311.099962) (xy 422.504629 -311.124569) (xy 422.496734 -311.173146)
			(xy 422.48115 -311.219827) (xy 422.458279 -311.263404) (xy 422.428714 -311.302748) (xy 422.393221 -311.33684)
			(xy 422.352718 -311.364796) (xy 422.308256 -311.385894) (xy 422.260985 -311.399586) (xy 422.21213 -311.405518)
			(xy 422.162955 -311.403537) (xy 422.114736 -311.393693) (xy 422.06872 -311.376241) (xy 422.026099 -311.351634)
			(xy 421.987978 -311.320509) (xy 421.955343 -311.283672) (xy 421.92904 -311.242076) (xy 421.909749 -311.1968)
			(xy 421.897972 -311.149016) (xy 421.894012 -311.099962) (xy 420.605204 -311.099962) (xy 420.604709 -311.124569)
			(xy 420.596814 -311.173146) (xy 420.58123 -311.219827) (xy 420.558359 -311.263404) (xy 420.528794 -311.302748)
			(xy 420.493301 -311.33684) (xy 420.452798 -311.364796) (xy 420.408336 -311.385894) (xy 420.361065 -311.399586)
			(xy 420.31221 -311.405518) (xy 420.263035 -311.403537) (xy 420.214816 -311.393693) (xy 420.1688 -311.376241)
			(xy 420.126179 -311.351634) (xy 420.088058 -311.320509) (xy 420.055423 -311.283672) (xy 420.02912 -311.242076)
			(xy 420.009829 -311.1968) (xy 419.998052 -311.149016) (xy 419.994092 -311.099962) (xy 418.705284 -311.099962)
			(xy 418.704789 -311.124569) (xy 418.696894 -311.173146) (xy 418.68131 -311.219827) (xy 418.658439 -311.263404)
			(xy 418.628874 -311.302748) (xy 418.593381 -311.33684) (xy 418.552878 -311.364796) (xy 418.508416 -311.385894)
			(xy 418.461145 -311.399586) (xy 418.41229 -311.405518) (xy 418.363115 -311.403537) (xy 418.314896 -311.393693)
			(xy 418.26888 -311.376241) (xy 418.226259 -311.351634) (xy 418.188138 -311.320509) (xy 418.155503 -311.283672)
			(xy 418.1292 -311.242076) (xy 418.109909 -311.1968) (xy 418.098132 -311.149016) (xy 418.094172 -311.099962)
			(xy 416.80511 -311.099962) (xy 416.804615 -311.124569) (xy 416.79672 -311.173146) (xy 416.781136 -311.219827)
			(xy 416.758265 -311.263404) (xy 416.7287 -311.302748) (xy 416.693207 -311.33684) (xy 416.652704 -311.364796)
			(xy 416.608242 -311.385894) (xy 416.560971 -311.399586) (xy 416.512116 -311.405518) (xy 416.462941 -311.403537)
			(xy 416.414722 -311.393693) (xy 416.368706 -311.376241) (xy 416.326085 -311.351634) (xy 416.287964 -311.320509)
			(xy 416.255329 -311.283672) (xy 416.229026 -311.242076) (xy 416.209735 -311.1968) (xy 416.197958 -311.149016)
			(xy 416.193998 -311.099962) (xy 414.90519 -311.099962) (xy 414.904695 -311.124569) (xy 414.8968 -311.173146)
			(xy 414.881216 -311.219827) (xy 414.858345 -311.263404) (xy 414.82878 -311.302748) (xy 414.793287 -311.33684)
			(xy 414.752784 -311.364796) (xy 414.708322 -311.385894) (xy 414.661051 -311.399586) (xy 414.612196 -311.405518)
			(xy 414.563021 -311.403537) (xy 414.514802 -311.393693) (xy 414.468786 -311.376241) (xy 414.426165 -311.351634)
			(xy 414.388044 -311.320509) (xy 414.355409 -311.283672) (xy 414.329106 -311.242076) (xy 414.309815 -311.1968)
			(xy 414.298038 -311.149016) (xy 414.294078 -311.099962) (xy 413.00527 -311.099962) (xy 413.004775 -311.124569)
			(xy 412.99688 -311.173146) (xy 412.981296 -311.219827) (xy 412.958425 -311.263404) (xy 412.92886 -311.302748)
			(xy 412.893367 -311.33684) (xy 412.852864 -311.364796) (xy 412.808402 -311.385894) (xy 412.761131 -311.399586)
			(xy 412.712276 -311.405518) (xy 412.663101 -311.403537) (xy 412.614882 -311.393693) (xy 412.568866 -311.376241)
			(xy 412.526245 -311.351634) (xy 412.488124 -311.320509) (xy 412.455489 -311.283672) (xy 412.429186 -311.242076)
			(xy 412.409895 -311.1968) (xy 412.398118 -311.149016) (xy 412.394158 -311.099962) (xy 411.105096 -311.099962)
			(xy 411.104601 -311.124569) (xy 411.096706 -311.173146) (xy 411.081122 -311.219827) (xy 411.058251 -311.263404)
			(xy 411.028686 -311.302748) (xy 410.993193 -311.33684) (xy 410.95269 -311.364796) (xy 410.908228 -311.385894)
			(xy 410.860957 -311.399586) (xy 410.812102 -311.405518) (xy 410.762927 -311.403537) (xy 410.714708 -311.393693)
			(xy 410.668692 -311.376241) (xy 410.626071 -311.351634) (xy 410.58795 -311.320509) (xy 410.555315 -311.283672)
			(xy 410.529012 -311.242076) (xy 410.509721 -311.1968) (xy 410.497944 -311.149016) (xy 410.493984 -311.099962)
			(xy 409.205176 -311.099962) (xy 409.204681 -311.124569) (xy 409.196786 -311.173146) (xy 409.181202 -311.219827)
			(xy 409.158331 -311.263404) (xy 409.128766 -311.302748) (xy 409.093273 -311.33684) (xy 409.05277 -311.364796)
			(xy 409.008308 -311.385894) (xy 408.961037 -311.399586) (xy 408.912182 -311.405518) (xy 408.863007 -311.403537)
			(xy 408.814788 -311.393693) (xy 408.768772 -311.376241) (xy 408.726151 -311.351634) (xy 408.68803 -311.320509)
			(xy 408.655395 -311.283672) (xy 408.629092 -311.242076) (xy 408.609801 -311.1968) (xy 408.598024 -311.149016)
			(xy 408.594064 -311.099962) (xy 407.305256 -311.099962) (xy 407.304761 -311.124569) (xy 407.296866 -311.173146)
			(xy 407.281282 -311.219827) (xy 407.258411 -311.263404) (xy 407.228846 -311.302748) (xy 407.193353 -311.33684)
			(xy 407.15285 -311.364796) (xy 407.108388 -311.385894) (xy 407.061117 -311.399586) (xy 407.012262 -311.405518)
			(xy 406.963087 -311.403537) (xy 406.914868 -311.393693) (xy 406.868852 -311.376241) (xy 406.826231 -311.351634)
			(xy 406.78811 -311.320509) (xy 406.755475 -311.283672) (xy 406.729172 -311.242076) (xy 406.709881 -311.1968)
			(xy 406.698104 -311.149016) (xy 406.694144 -311.099962) (xy 405.405336 -311.099962) (xy 405.404841 -311.124569)
			(xy 405.396946 -311.173146) (xy 405.381362 -311.219827) (xy 405.358491 -311.263404) (xy 405.328926 -311.302748)
			(xy 405.293433 -311.33684) (xy 405.25293 -311.364796) (xy 405.208468 -311.385894) (xy 405.161197 -311.399586)
			(xy 405.112342 -311.405518) (xy 405.063167 -311.403537) (xy 405.014948 -311.393693) (xy 404.968932 -311.376241)
			(xy 404.926311 -311.351634) (xy 404.88819 -311.320509) (xy 404.855555 -311.283672) (xy 404.829252 -311.242076)
			(xy 404.809961 -311.1968) (xy 404.798184 -311.149016) (xy 404.794224 -311.099962) (xy 403.505162 -311.099962)
			(xy 403.504667 -311.124569) (xy 403.496772 -311.173146) (xy 403.481188 -311.219827) (xy 403.458317 -311.263404)
			(xy 403.428752 -311.302748) (xy 403.393259 -311.33684) (xy 403.352756 -311.364796) (xy 403.308294 -311.385894)
			(xy 403.261023 -311.399586) (xy 403.212168 -311.405518) (xy 403.162993 -311.403537) (xy 403.114774 -311.393693)
			(xy 403.068758 -311.376241) (xy 403.026137 -311.351634) (xy 402.988016 -311.320509) (xy 402.955381 -311.283672)
			(xy 402.929078 -311.242076) (xy 402.909787 -311.1968) (xy 402.89801 -311.149016) (xy 402.89405 -311.099962)
			(xy 401.605242 -311.099962) (xy 401.604747 -311.124569) (xy 401.596852 -311.173146) (xy 401.581268 -311.219827)
			(xy 401.558397 -311.263404) (xy 401.528832 -311.302748) (xy 401.493339 -311.33684) (xy 401.452836 -311.364796)
			(xy 401.408374 -311.385894) (xy 401.361103 -311.399586) (xy 401.312248 -311.405518) (xy 401.263073 -311.403537)
			(xy 401.214854 -311.393693) (xy 401.168838 -311.376241) (xy 401.126217 -311.351634) (xy 401.088096 -311.320509)
			(xy 401.055461 -311.283672) (xy 401.029158 -311.242076) (xy 401.009867 -311.1968) (xy 400.99809 -311.149016)
			(xy 400.99413 -311.099962) (xy 399.705322 -311.099962) (xy 399.704827 -311.124569) (xy 399.696932 -311.173146)
			(xy 399.681348 -311.219827) (xy 399.658477 -311.263404) (xy 399.628912 -311.302748) (xy 399.593419 -311.33684)
			(xy 399.552916 -311.364796) (xy 399.508454 -311.385894) (xy 399.461183 -311.399586) (xy 399.412328 -311.405518)
			(xy 399.363153 -311.403537) (xy 399.314934 -311.393693) (xy 399.268918 -311.376241) (xy 399.226297 -311.351634)
			(xy 399.188176 -311.320509) (xy 399.155541 -311.283672) (xy 399.129238 -311.242076) (xy 399.109947 -311.1968)
			(xy 399.09817 -311.149016) (xy 399.09421 -311.099962) (xy 397.805148 -311.099962) (xy 397.804653 -311.124569)
			(xy 397.796758 -311.173146) (xy 397.781174 -311.219827) (xy 397.758303 -311.263404) (xy 397.728738 -311.302748)
			(xy 397.693245 -311.33684) (xy 397.652742 -311.364796) (xy 397.60828 -311.385894) (xy 397.561009 -311.399586)
			(xy 397.512154 -311.405518) (xy 397.462979 -311.403537) (xy 397.41476 -311.393693) (xy 397.368744 -311.376241)
			(xy 397.326123 -311.351634) (xy 397.288002 -311.320509) (xy 397.255367 -311.283672) (xy 397.229064 -311.242076)
			(xy 397.209773 -311.1968) (xy 397.197996 -311.149016) (xy 397.194036 -311.099962) (xy 395.905228 -311.099962)
			(xy 395.904733 -311.124569) (xy 395.896838 -311.173146) (xy 395.881254 -311.219827) (xy 395.858383 -311.263404)
			(xy 395.828818 -311.302748) (xy 395.793325 -311.33684) (xy 395.752822 -311.364796) (xy 395.70836 -311.385894)
			(xy 395.661089 -311.399586) (xy 395.612234 -311.405518) (xy 395.563059 -311.403537) (xy 395.51484 -311.393693)
			(xy 395.468824 -311.376241) (xy 395.426203 -311.351634) (xy 395.388082 -311.320509) (xy 395.355447 -311.283672)
			(xy 395.329144 -311.242076) (xy 395.309853 -311.1968) (xy 395.298076 -311.149016) (xy 395.294116 -311.099962)
			(xy 394.005308 -311.099962) (xy 394.004813 -311.124569) (xy 393.996918 -311.173146) (xy 393.981334 -311.219827)
			(xy 393.958463 -311.263404) (xy 393.928898 -311.302748) (xy 393.893405 -311.33684) (xy 393.852902 -311.364796)
			(xy 393.80844 -311.385894) (xy 393.761169 -311.399586) (xy 393.712314 -311.405518) (xy 393.663139 -311.403537)
			(xy 393.61492 -311.393693) (xy 393.568904 -311.376241) (xy 393.526283 -311.351634) (xy 393.488162 -311.320509)
			(xy 393.455527 -311.283672) (xy 393.429224 -311.242076) (xy 393.409933 -311.1968) (xy 393.398156 -311.149016)
			(xy 393.394196 -311.099962) (xy 392.105134 -311.099962) (xy 392.104639 -311.124569) (xy 392.096744 -311.173146)
			(xy 392.08116 -311.219827) (xy 392.058289 -311.263404) (xy 392.028724 -311.302748) (xy 391.993231 -311.33684)
			(xy 391.952728 -311.364796) (xy 391.908266 -311.385894) (xy 391.860995 -311.399586) (xy 391.81214 -311.405518)
			(xy 391.762965 -311.403537) (xy 391.714746 -311.393693) (xy 391.66873 -311.376241) (xy 391.626109 -311.351634)
			(xy 391.587988 -311.320509) (xy 391.555353 -311.283672) (xy 391.52905 -311.242076) (xy 391.509759 -311.1968)
			(xy 391.497982 -311.149016) (xy 391.494022 -311.099962) (xy 390.205214 -311.099962) (xy 390.204719 -311.124569)
			(xy 390.196824 -311.173146) (xy 390.18124 -311.219827) (xy 390.158369 -311.263404) (xy 390.128804 -311.302748)
			(xy 390.093311 -311.33684) (xy 390.052808 -311.364796) (xy 390.008346 -311.385894) (xy 389.961075 -311.399586)
			(xy 389.91222 -311.405518) (xy 389.863045 -311.403537) (xy 389.814826 -311.393693) (xy 389.76881 -311.376241)
			(xy 389.726189 -311.351634) (xy 389.688068 -311.320509) (xy 389.655433 -311.283672) (xy 389.62913 -311.242076)
			(xy 389.609839 -311.1968) (xy 389.598062 -311.149016) (xy 389.594102 -311.099962) (xy 388.305294 -311.099962)
			(xy 388.304799 -311.124569) (xy 388.296904 -311.173146) (xy 388.28132 -311.219827) (xy 388.258449 -311.263404)
			(xy 388.228884 -311.302748) (xy 388.193391 -311.33684) (xy 388.152888 -311.364796) (xy 388.108426 -311.385894)
			(xy 388.061155 -311.399586) (xy 388.0123 -311.405518) (xy 387.963125 -311.403537) (xy 387.914906 -311.393693)
			(xy 387.86889 -311.376241) (xy 387.826269 -311.351634) (xy 387.788148 -311.320509) (xy 387.755513 -311.283672)
			(xy 387.72921 -311.242076) (xy 387.709919 -311.1968) (xy 387.698142 -311.149016) (xy 387.694182 -311.099962)
			(xy 312.10504 -311.099962) (xy 312.104545 -311.124569) (xy 312.09665 -311.173146) (xy 312.081066 -311.219827)
			(xy 312.058195 -311.263404) (xy 312.02863 -311.302748) (xy 311.993137 -311.33684) (xy 311.952634 -311.364796)
			(xy 311.908172 -311.385894) (xy 311.860901 -311.399586) (xy 311.812046 -311.405518) (xy 311.762871 -311.403537)
			(xy 311.714652 -311.393693) (xy 311.668636 -311.376241) (xy 311.626015 -311.351634) (xy 311.587894 -311.320509)
			(xy 311.555259 -311.283672) (xy 311.528956 -311.242076) (xy 311.509665 -311.1968) (xy 311.497888 -311.149016)
			(xy 311.493928 -311.099962) (xy 310.20512 -311.099962) (xy 310.204625 -311.124569) (xy 310.19673 -311.173146)
			(xy 310.181146 -311.219827) (xy 310.158275 -311.263404) (xy 310.12871 -311.302748) (xy 310.093217 -311.33684)
			(xy 310.052714 -311.364796) (xy 310.008252 -311.385894) (xy 309.960981 -311.399586) (xy 309.912126 -311.405518)
			(xy 309.862951 -311.403537) (xy 309.814732 -311.393693) (xy 309.768716 -311.376241) (xy 309.726095 -311.351634)
			(xy 309.687974 -311.320509) (xy 309.655339 -311.283672) (xy 309.629036 -311.242076) (xy 309.609745 -311.1968)
			(xy 309.597968 -311.149016) (xy 309.594008 -311.099962) (xy 308.3052 -311.099962) (xy 308.304705 -311.124569)
			(xy 308.29681 -311.173146) (xy 308.281226 -311.219827) (xy 308.258355 -311.263404) (xy 308.22879 -311.302748)
			(xy 308.193297 -311.33684) (xy 308.152794 -311.364796) (xy 308.108332 -311.385894) (xy 308.061061 -311.399586)
			(xy 308.012206 -311.405518) (xy 307.963031 -311.403537) (xy 307.914812 -311.393693) (xy 307.868796 -311.376241)
			(xy 307.826175 -311.351634) (xy 307.788054 -311.320509) (xy 307.755419 -311.283672) (xy 307.729116 -311.242076)
			(xy 307.709825 -311.1968) (xy 307.698048 -311.149016) (xy 307.694088 -311.099962) (xy 306.405026 -311.099962)
			(xy 306.404531 -311.124569) (xy 306.396636 -311.173146) (xy 306.381052 -311.219827) (xy 306.358181 -311.263404)
			(xy 306.328616 -311.302748) (xy 306.293123 -311.33684) (xy 306.25262 -311.364796) (xy 306.208158 -311.385894)
			(xy 306.160887 -311.399586) (xy 306.112032 -311.405518) (xy 306.062857 -311.403537) (xy 306.014638 -311.393693)
			(xy 305.968622 -311.376241) (xy 305.926001 -311.351634) (xy 305.88788 -311.320509) (xy 305.855245 -311.283672)
			(xy 305.828942 -311.242076) (xy 305.809651 -311.1968) (xy 305.797874 -311.149016) (xy 305.793914 -311.099962)
			(xy 304.505106 -311.099962) (xy 304.504611 -311.124569) (xy 304.496716 -311.173146) (xy 304.481132 -311.219827)
			(xy 304.458261 -311.263404) (xy 304.428696 -311.302748) (xy 304.393203 -311.33684) (xy 304.3527 -311.364796)
			(xy 304.308238 -311.385894) (xy 304.260967 -311.399586) (xy 304.212112 -311.405518) (xy 304.162937 -311.403537)
			(xy 304.114718 -311.393693) (xy 304.068702 -311.376241) (xy 304.026081 -311.351634) (xy 303.98796 -311.320509)
			(xy 303.955325 -311.283672) (xy 303.929022 -311.242076) (xy 303.909731 -311.1968) (xy 303.897954 -311.149016)
			(xy 303.893994 -311.099962) (xy 302.605186 -311.099962) (xy 302.604691 -311.124569) (xy 302.596796 -311.173146)
			(xy 302.581212 -311.219827) (xy 302.558341 -311.263404) (xy 302.528776 -311.302748) (xy 302.493283 -311.33684)
			(xy 302.45278 -311.364796) (xy 302.408318 -311.385894) (xy 302.361047 -311.399586) (xy 302.312192 -311.405518)
			(xy 302.263017 -311.403537) (xy 302.214798 -311.393693) (xy 302.168782 -311.376241) (xy 302.126161 -311.351634)
			(xy 302.08804 -311.320509) (xy 302.055405 -311.283672) (xy 302.029102 -311.242076) (xy 302.009811 -311.1968)
			(xy 301.998034 -311.149016) (xy 301.994074 -311.099962) (xy 300.705012 -311.099962) (xy 300.704517 -311.124569)
			(xy 300.696622 -311.173146) (xy 300.681038 -311.219827) (xy 300.658167 -311.263404) (xy 300.628602 -311.302748)
			(xy 300.593109 -311.33684) (xy 300.552606 -311.364796) (xy 300.508144 -311.385894) (xy 300.460873 -311.399586)
			(xy 300.412018 -311.405518) (xy 300.362843 -311.403537) (xy 300.314624 -311.393693) (xy 300.268608 -311.376241)
			(xy 300.225987 -311.351634) (xy 300.187866 -311.320509) (xy 300.155231 -311.283672) (xy 300.128928 -311.242076)
			(xy 300.109637 -311.1968) (xy 300.09786 -311.149016) (xy 300.0939 -311.099962) (xy 298.805092 -311.099962)
			(xy 298.804597 -311.124569) (xy 298.796702 -311.173146) (xy 298.781118 -311.219827) (xy 298.758247 -311.263404)
			(xy 298.728682 -311.302748) (xy 298.693189 -311.33684) (xy 298.652686 -311.364796) (xy 298.608224 -311.385894)
			(xy 298.560953 -311.399586) (xy 298.512098 -311.405518) (xy 298.462923 -311.403537) (xy 298.414704 -311.393693)
			(xy 298.368688 -311.376241) (xy 298.326067 -311.351634) (xy 298.287946 -311.320509) (xy 298.255311 -311.283672)
			(xy 298.229008 -311.242076) (xy 298.209717 -311.1968) (xy 298.19794 -311.149016) (xy 298.19398 -311.099962)
			(xy 296.905172 -311.099962) (xy 296.904677 -311.124569) (xy 296.896782 -311.173146) (xy 296.881198 -311.219827)
			(xy 296.858327 -311.263404) (xy 296.828762 -311.302748) (xy 296.793269 -311.33684) (xy 296.752766 -311.364796)
			(xy 296.708304 -311.385894) (xy 296.661033 -311.399586) (xy 296.612178 -311.405518) (xy 296.563003 -311.403537)
			(xy 296.514784 -311.393693) (xy 296.468768 -311.376241) (xy 296.426147 -311.351634) (xy 296.388026 -311.320509)
			(xy 296.355391 -311.283672) (xy 296.329088 -311.242076) (xy 296.309797 -311.1968) (xy 296.29802 -311.149016)
			(xy 296.29406 -311.099962) (xy 295.004998 -311.099962) (xy 295.004503 -311.124569) (xy 294.996608 -311.173146)
			(xy 294.981024 -311.219827) (xy 294.958153 -311.263404) (xy 294.928588 -311.302748) (xy 294.893095 -311.33684)
			(xy 294.852592 -311.364796) (xy 294.80813 -311.385894) (xy 294.760859 -311.399586) (xy 294.712004 -311.405518)
			(xy 294.662829 -311.403537) (xy 294.61461 -311.393693) (xy 294.568594 -311.376241) (xy 294.525973 -311.351634)
			(xy 294.487852 -311.320509) (xy 294.455217 -311.283672) (xy 294.428914 -311.242076) (xy 294.409623 -311.1968)
			(xy 294.397846 -311.149016) (xy 294.393886 -311.099962) (xy 293.105078 -311.099962) (xy 293.104583 -311.124569)
			(xy 293.096688 -311.173146) (xy 293.081104 -311.219827) (xy 293.058233 -311.263404) (xy 293.028668 -311.302748)
			(xy 292.993175 -311.33684) (xy 292.952672 -311.364796) (xy 292.90821 -311.385894) (xy 292.860939 -311.399586)
			(xy 292.812084 -311.405518) (xy 292.762909 -311.403537) (xy 292.71469 -311.393693) (xy 292.668674 -311.376241)
			(xy 292.626053 -311.351634) (xy 292.587932 -311.320509) (xy 292.555297 -311.283672) (xy 292.528994 -311.242076)
			(xy 292.509703 -311.1968) (xy 292.497926 -311.149016) (xy 292.493966 -311.099962) (xy 291.205158 -311.099962)
			(xy 291.204663 -311.124569) (xy 291.196768 -311.173146) (xy 291.181184 -311.219827) (xy 291.158313 -311.263404)
			(xy 291.128748 -311.302748) (xy 291.093255 -311.33684) (xy 291.052752 -311.364796) (xy 291.00829 -311.385894)
			(xy 290.961019 -311.399586) (xy 290.912164 -311.405518) (xy 290.862989 -311.403537) (xy 290.81477 -311.393693)
			(xy 290.768754 -311.376241) (xy 290.726133 -311.351634) (xy 290.688012 -311.320509) (xy 290.655377 -311.283672)
			(xy 290.629074 -311.242076) (xy 290.609783 -311.1968) (xy 290.598006 -311.149016) (xy 290.594046 -311.099962)
			(xy 289.305238 -311.099962) (xy 289.304743 -311.124569) (xy 289.296848 -311.173146) (xy 289.281264 -311.219827)
			(xy 289.258393 -311.263404) (xy 289.228828 -311.302748) (xy 289.193335 -311.33684) (xy 289.152832 -311.364796)
			(xy 289.10837 -311.385894) (xy 289.061099 -311.399586) (xy 289.012244 -311.405518) (xy 288.963069 -311.403537)
			(xy 288.91485 -311.393693) (xy 288.868834 -311.376241) (xy 288.826213 -311.351634) (xy 288.788092 -311.320509)
			(xy 288.755457 -311.283672) (xy 288.729154 -311.242076) (xy 288.709863 -311.1968) (xy 288.698086 -311.149016)
			(xy 288.694126 -311.099962) (xy 287.405064 -311.099962) (xy 287.404569 -311.124569) (xy 287.396674 -311.173146)
			(xy 287.38109 -311.219827) (xy 287.358219 -311.263404) (xy 287.328654 -311.302748) (xy 287.293161 -311.33684)
			(xy 287.252658 -311.364796) (xy 287.208196 -311.385894) (xy 287.160925 -311.399586) (xy 287.11207 -311.405518)
			(xy 287.062895 -311.403537) (xy 287.014676 -311.393693) (xy 286.96866 -311.376241) (xy 286.926039 -311.351634)
			(xy 286.887918 -311.320509) (xy 286.855283 -311.283672) (xy 286.82898 -311.242076) (xy 286.809689 -311.1968)
			(xy 286.797912 -311.149016) (xy 286.793952 -311.099962) (xy 285.505144 -311.099962) (xy 285.504649 -311.124569)
			(xy 285.496754 -311.173146) (xy 285.48117 -311.219827) (xy 285.458299 -311.263404) (xy 285.428734 -311.302748)
			(xy 285.393241 -311.33684) (xy 285.352738 -311.364796) (xy 285.308276 -311.385894) (xy 285.261005 -311.399586)
			(xy 285.21215 -311.405518) (xy 285.162975 -311.403537) (xy 285.114756 -311.393693) (xy 285.06874 -311.376241)
			(xy 285.026119 -311.351634) (xy 284.987998 -311.320509) (xy 284.955363 -311.283672) (xy 284.92906 -311.242076)
			(xy 284.909769 -311.1968) (xy 284.897992 -311.149016) (xy 284.894032 -311.099962) (xy 283.605224 -311.099962)
			(xy 283.604729 -311.124569) (xy 283.596834 -311.173146) (xy 283.58125 -311.219827) (xy 283.558379 -311.263404)
			(xy 283.528814 -311.302748) (xy 283.493321 -311.33684) (xy 283.452818 -311.364796) (xy 283.408356 -311.385894)
			(xy 283.361085 -311.399586) (xy 283.31223 -311.405518) (xy 283.263055 -311.403537) (xy 283.214836 -311.393693)
			(xy 283.16882 -311.376241) (xy 283.126199 -311.351634) (xy 283.088078 -311.320509) (xy 283.055443 -311.283672)
			(xy 283.02914 -311.242076) (xy 283.009849 -311.1968) (xy 282.998072 -311.149016) (xy 282.994112 -311.099962)
			(xy 281.70505 -311.099962) (xy 281.704555 -311.124569) (xy 281.69666 -311.173146) (xy 281.681076 -311.219827)
			(xy 281.658205 -311.263404) (xy 281.62864 -311.302748) (xy 281.593147 -311.33684) (xy 281.552644 -311.364796)
			(xy 281.508182 -311.385894) (xy 281.460911 -311.399586) (xy 281.412056 -311.405518) (xy 281.362881 -311.403537)
			(xy 281.314662 -311.393693) (xy 281.268646 -311.376241) (xy 281.226025 -311.351634) (xy 281.187904 -311.320509)
			(xy 281.155269 -311.283672) (xy 281.128966 -311.242076) (xy 281.109675 -311.1968) (xy 281.097898 -311.149016)
			(xy 281.093938 -311.099962) (xy 279.80513 -311.099962) (xy 279.804635 -311.124569) (xy 279.79674 -311.173146)
			(xy 279.781156 -311.219827) (xy 279.758285 -311.263404) (xy 279.72872 -311.302748) (xy 279.693227 -311.33684)
			(xy 279.652724 -311.364796) (xy 279.608262 -311.385894) (xy 279.560991 -311.399586) (xy 279.512136 -311.405518)
			(xy 279.462961 -311.403537) (xy 279.414742 -311.393693) (xy 279.368726 -311.376241) (xy 279.326105 -311.351634)
			(xy 279.287984 -311.320509) (xy 279.255349 -311.283672) (xy 279.229046 -311.242076) (xy 279.209755 -311.1968)
			(xy 279.197978 -311.149016) (xy 279.194018 -311.099962) (xy 277.90521 -311.099962) (xy 277.904715 -311.124569)
			(xy 277.89682 -311.173146) (xy 277.881236 -311.219827) (xy 277.858365 -311.263404) (xy 277.8288 -311.302748)
			(xy 277.793307 -311.33684) (xy 277.752804 -311.364796) (xy 277.708342 -311.385894) (xy 277.661071 -311.399586)
			(xy 277.612216 -311.405518) (xy 277.563041 -311.403537) (xy 277.514822 -311.393693) (xy 277.468806 -311.376241)
			(xy 277.426185 -311.351634) (xy 277.388064 -311.320509) (xy 277.355429 -311.283672) (xy 277.329126 -311.242076)
			(xy 277.309835 -311.1968) (xy 277.298058 -311.149016) (xy 277.294098 -311.099962) (xy 276.005036 -311.099962)
			(xy 276.004541 -311.124569) (xy 275.996646 -311.173146) (xy 275.981062 -311.219827) (xy 275.958191 -311.263404)
			(xy 275.928626 -311.302748) (xy 275.893133 -311.33684) (xy 275.85263 -311.364796) (xy 275.808168 -311.385894)
			(xy 275.760897 -311.399586) (xy 275.712042 -311.405518) (xy 275.662867 -311.403537) (xy 275.614648 -311.393693)
			(xy 275.568632 -311.376241) (xy 275.526011 -311.351634) (xy 275.48789 -311.320509) (xy 275.455255 -311.283672)
			(xy 275.428952 -311.242076) (xy 275.409661 -311.1968) (xy 275.397884 -311.149016) (xy 275.393924 -311.099962)
			(xy 274.105116 -311.099962) (xy 274.104621 -311.124569) (xy 274.096726 -311.173146) (xy 274.081142 -311.219827)
			(xy 274.058271 -311.263404) (xy 274.028706 -311.302748) (xy 273.993213 -311.33684) (xy 273.95271 -311.364796)
			(xy 273.908248 -311.385894) (xy 273.860977 -311.399586) (xy 273.812122 -311.405518) (xy 273.762947 -311.403537)
			(xy 273.714728 -311.393693) (xy 273.668712 -311.376241) (xy 273.626091 -311.351634) (xy 273.58797 -311.320509)
			(xy 273.555335 -311.283672) (xy 273.529032 -311.242076) (xy 273.509741 -311.1968) (xy 273.497964 -311.149016)
			(xy 273.494004 -311.099962) (xy 272.205196 -311.099962) (xy 272.204701 -311.124569) (xy 272.196806 -311.173146)
			(xy 272.181222 -311.219827) (xy 272.158351 -311.263404) (xy 272.128786 -311.302748) (xy 272.093293 -311.33684)
			(xy 272.05279 -311.364796) (xy 272.008328 -311.385894) (xy 271.961057 -311.399586) (xy 271.912202 -311.405518)
			(xy 271.863027 -311.403537) (xy 271.814808 -311.393693) (xy 271.768792 -311.376241) (xy 271.726171 -311.351634)
			(xy 271.68805 -311.320509) (xy 271.655415 -311.283672) (xy 271.629112 -311.242076) (xy 271.609821 -311.1968)
			(xy 271.598044 -311.149016) (xy 271.594084 -311.099962) (xy 196.005196 -311.099962) (xy 196.004701 -311.124569)
			(xy 195.996806 -311.173146) (xy 195.981222 -311.219827) (xy 195.958351 -311.263404) (xy 195.928786 -311.302748)
			(xy 195.893293 -311.33684) (xy 195.85279 -311.364796) (xy 195.808328 -311.385894) (xy 195.761057 -311.399586)
			(xy 195.712202 -311.405518) (xy 195.663027 -311.403537) (xy 195.614808 -311.393693) (xy 195.568792 -311.376241)
			(xy 195.526171 -311.351634) (xy 195.48805 -311.320509) (xy 195.455415 -311.283672) (xy 195.429112 -311.242076)
			(xy 195.409821 -311.1968) (xy 195.398044 -311.149016) (xy 195.394084 -311.099962) (xy 194.105276 -311.099962)
			(xy 194.104781 -311.124569) (xy 194.096886 -311.173146) (xy 194.081302 -311.219827) (xy 194.058431 -311.263404)
			(xy 194.028866 -311.302748) (xy 193.993373 -311.33684) (xy 193.95287 -311.364796) (xy 193.908408 -311.385894)
			(xy 193.861137 -311.399586) (xy 193.812282 -311.405518) (xy 193.763107 -311.403537) (xy 193.714888 -311.393693)
			(xy 193.668872 -311.376241) (xy 193.626251 -311.351634) (xy 193.58813 -311.320509) (xy 193.555495 -311.283672)
			(xy 193.529192 -311.242076) (xy 193.509901 -311.1968) (xy 193.498124 -311.149016) (xy 193.494164 -311.099962)
			(xy 192.205356 -311.099962) (xy 192.204861 -311.124569) (xy 192.196966 -311.173146) (xy 192.181382 -311.219827)
			(xy 192.158511 -311.263404) (xy 192.128946 -311.302748) (xy 192.093453 -311.33684) (xy 192.05295 -311.364796)
			(xy 192.008488 -311.385894) (xy 191.961217 -311.399586) (xy 191.912362 -311.405518) (xy 191.863187 -311.403537)
			(xy 191.814968 -311.393693) (xy 191.768952 -311.376241) (xy 191.726331 -311.351634) (xy 191.68821 -311.320509)
			(xy 191.655575 -311.283672) (xy 191.629272 -311.242076) (xy 191.609981 -311.1968) (xy 191.598204 -311.149016)
			(xy 191.594244 -311.099962) (xy 190.305182 -311.099962) (xy 190.304687 -311.124569) (xy 190.296792 -311.173146)
			(xy 190.281208 -311.219827) (xy 190.258337 -311.263404) (xy 190.228772 -311.302748) (xy 190.193279 -311.33684)
			(xy 190.152776 -311.364796) (xy 190.108314 -311.385894) (xy 190.061043 -311.399586) (xy 190.012188 -311.405518)
			(xy 189.963013 -311.403537) (xy 189.914794 -311.393693) (xy 189.868778 -311.376241) (xy 189.826157 -311.351634)
			(xy 189.788036 -311.320509) (xy 189.755401 -311.283672) (xy 189.729098 -311.242076) (xy 189.709807 -311.1968)
			(xy 189.69803 -311.149016) (xy 189.69407 -311.099962) (xy 188.405262 -311.099962) (xy 188.404767 -311.124569)
			(xy 188.396872 -311.173146) (xy 188.381288 -311.219827) (xy 188.358417 -311.263404) (xy 188.328852 -311.302748)
			(xy 188.293359 -311.33684) (xy 188.252856 -311.364796) (xy 188.208394 -311.385894) (xy 188.161123 -311.399586)
			(xy 188.112268 -311.405518) (xy 188.063093 -311.403537) (xy 188.014874 -311.393693) (xy 187.968858 -311.376241)
			(xy 187.926237 -311.351634) (xy 187.888116 -311.320509) (xy 187.855481 -311.283672) (xy 187.829178 -311.242076)
			(xy 187.809887 -311.1968) (xy 187.79811 -311.149016) (xy 187.79415 -311.099962) (xy 186.505342 -311.099962)
			(xy 186.504847 -311.124569) (xy 186.496952 -311.173146) (xy 186.481368 -311.219827) (xy 186.458497 -311.263404)
			(xy 186.428932 -311.302748) (xy 186.393439 -311.33684) (xy 186.352936 -311.364796) (xy 186.308474 -311.385894)
			(xy 186.261203 -311.399586) (xy 186.212348 -311.405518) (xy 186.163173 -311.403537) (xy 186.114954 -311.393693)
			(xy 186.068938 -311.376241) (xy 186.026317 -311.351634) (xy 185.988196 -311.320509) (xy 185.955561 -311.283672)
			(xy 185.929258 -311.242076) (xy 185.909967 -311.1968) (xy 185.89819 -311.149016) (xy 185.89423 -311.099962)
			(xy 184.605168 -311.099962) (xy 184.604673 -311.124569) (xy 184.596778 -311.173146) (xy 184.581194 -311.219827)
			(xy 184.558323 -311.263404) (xy 184.528758 -311.302748) (xy 184.493265 -311.33684) (xy 184.452762 -311.364796)
			(xy 184.4083 -311.385894) (xy 184.361029 -311.399586) (xy 184.312174 -311.405518) (xy 184.262999 -311.403537)
			(xy 184.21478 -311.393693) (xy 184.168764 -311.376241) (xy 184.126143 -311.351634) (xy 184.088022 -311.320509)
			(xy 184.055387 -311.283672) (xy 184.029084 -311.242076) (xy 184.009793 -311.1968) (xy 183.998016 -311.149016)
			(xy 183.994056 -311.099962) (xy 182.705248 -311.099962) (xy 182.704753 -311.124569) (xy 182.696858 -311.173146)
			(xy 182.681274 -311.219827) (xy 182.658403 -311.263404) (xy 182.628838 -311.302748) (xy 182.593345 -311.33684)
			(xy 182.552842 -311.364796) (xy 182.50838 -311.385894) (xy 182.461109 -311.399586) (xy 182.412254 -311.405518)
			(xy 182.363079 -311.403537) (xy 182.31486 -311.393693) (xy 182.268844 -311.376241) (xy 182.226223 -311.351634)
			(xy 182.188102 -311.320509) (xy 182.155467 -311.283672) (xy 182.129164 -311.242076) (xy 182.109873 -311.1968)
			(xy 182.098096 -311.149016) (xy 182.094136 -311.099962) (xy 180.805328 -311.099962) (xy 180.804833 -311.124569)
			(xy 180.796938 -311.173146) (xy 180.781354 -311.219827) (xy 180.758483 -311.263404) (xy 180.728918 -311.302748)
			(xy 180.693425 -311.33684) (xy 180.652922 -311.364796) (xy 180.60846 -311.385894) (xy 180.561189 -311.399586)
			(xy 180.512334 -311.405518) (xy 180.463159 -311.403537) (xy 180.41494 -311.393693) (xy 180.368924 -311.376241)
			(xy 180.326303 -311.351634) (xy 180.288182 -311.320509) (xy 180.255547 -311.283672) (xy 180.229244 -311.242076)
			(xy 180.209953 -311.1968) (xy 180.198176 -311.149016) (xy 180.194216 -311.099962) (xy 178.905154 -311.099962)
			(xy 178.904659 -311.124569) (xy 178.896764 -311.173146) (xy 178.88118 -311.219827) (xy 178.858309 -311.263404)
			(xy 178.828744 -311.302748) (xy 178.793251 -311.33684) (xy 178.752748 -311.364796) (xy 178.708286 -311.385894)
			(xy 178.661015 -311.399586) (xy 178.61216 -311.405518) (xy 178.562985 -311.403537) (xy 178.514766 -311.393693)
			(xy 178.46875 -311.376241) (xy 178.426129 -311.351634) (xy 178.388008 -311.320509) (xy 178.355373 -311.283672)
			(xy 178.32907 -311.242076) (xy 178.309779 -311.1968) (xy 178.298002 -311.149016) (xy 178.294042 -311.099962)
			(xy 177.005234 -311.099962) (xy 177.004739 -311.124569) (xy 176.996844 -311.173146) (xy 176.98126 -311.219827)
			(xy 176.958389 -311.263404) (xy 176.928824 -311.302748) (xy 176.893331 -311.33684) (xy 176.852828 -311.364796)
			(xy 176.808366 -311.385894) (xy 176.761095 -311.399586) (xy 176.71224 -311.405518) (xy 176.663065 -311.403537)
			(xy 176.614846 -311.393693) (xy 176.56883 -311.376241) (xy 176.526209 -311.351634) (xy 176.488088 -311.320509)
			(xy 176.455453 -311.283672) (xy 176.42915 -311.242076) (xy 176.409859 -311.1968) (xy 176.398082 -311.149016)
			(xy 176.394122 -311.099962) (xy 175.105314 -311.099962) (xy 175.104819 -311.124569) (xy 175.096924 -311.173146)
			(xy 175.08134 -311.219827) (xy 175.058469 -311.263404) (xy 175.028904 -311.302748) (xy 174.993411 -311.33684)
			(xy 174.952908 -311.364796) (xy 174.908446 -311.385894) (xy 174.861175 -311.399586) (xy 174.81232 -311.405518)
			(xy 174.763145 -311.403537) (xy 174.714926 -311.393693) (xy 174.66891 -311.376241) (xy 174.626289 -311.351634)
			(xy 174.588168 -311.320509) (xy 174.555533 -311.283672) (xy 174.52923 -311.242076) (xy 174.509939 -311.1968)
			(xy 174.498162 -311.149016) (xy 174.494202 -311.099962) (xy 173.205394 -311.099962) (xy 173.204899 -311.124569)
			(xy 173.197004 -311.173146) (xy 173.18142 -311.219827) (xy 173.158549 -311.263404) (xy 173.128984 -311.302748)
			(xy 173.093491 -311.33684) (xy 173.052988 -311.364796) (xy 173.008526 -311.385894) (xy 172.961255 -311.399586)
			(xy 172.9124 -311.405518) (xy 172.863225 -311.403537) (xy 172.815006 -311.393693) (xy 172.76899 -311.376241)
			(xy 172.726369 -311.351634) (xy 172.688248 -311.320509) (xy 172.655613 -311.283672) (xy 172.62931 -311.242076)
			(xy 172.610019 -311.1968) (xy 172.598242 -311.149016) (xy 172.594282 -311.099962) (xy 171.30522 -311.099962)
			(xy 171.304725 -311.124569) (xy 171.29683 -311.173146) (xy 171.281246 -311.219827) (xy 171.258375 -311.263404)
			(xy 171.22881 -311.302748) (xy 171.193317 -311.33684) (xy 171.152814 -311.364796) (xy 171.108352 -311.385894)
			(xy 171.061081 -311.399586) (xy 171.012226 -311.405518) (xy 170.963051 -311.403537) (xy 170.914832 -311.393693)
			(xy 170.868816 -311.376241) (xy 170.826195 -311.351634) (xy 170.788074 -311.320509) (xy 170.755439 -311.283672)
			(xy 170.729136 -311.242076) (xy 170.709845 -311.1968) (xy 170.698068 -311.149016) (xy 170.694108 -311.099962)
			(xy 169.4053 -311.099962) (xy 169.404805 -311.124569) (xy 169.39691 -311.173146) (xy 169.381326 -311.219827)
			(xy 169.358455 -311.263404) (xy 169.32889 -311.302748) (xy 169.293397 -311.33684) (xy 169.252894 -311.364796)
			(xy 169.208432 -311.385894) (xy 169.161161 -311.399586) (xy 169.112306 -311.405518) (xy 169.063131 -311.403537)
			(xy 169.014912 -311.393693) (xy 168.968896 -311.376241) (xy 168.926275 -311.351634) (xy 168.888154 -311.320509)
			(xy 168.855519 -311.283672) (xy 168.829216 -311.242076) (xy 168.809925 -311.1968) (xy 168.798148 -311.149016)
			(xy 168.794188 -311.099962) (xy 167.50538 -311.099962) (xy 167.504885 -311.124569) (xy 167.49699 -311.173146)
			(xy 167.481406 -311.219827) (xy 167.458535 -311.263404) (xy 167.42897 -311.302748) (xy 167.393477 -311.33684)
			(xy 167.352974 -311.364796) (xy 167.308512 -311.385894) (xy 167.261241 -311.399586) (xy 167.212386 -311.405518)
			(xy 167.163211 -311.403537) (xy 167.114992 -311.393693) (xy 167.068976 -311.376241) (xy 167.026355 -311.351634)
			(xy 166.988234 -311.320509) (xy 166.955599 -311.283672) (xy 166.929296 -311.242076) (xy 166.910005 -311.1968)
			(xy 166.898228 -311.149016) (xy 166.894268 -311.099962) (xy 165.605206 -311.099962) (xy 165.604711 -311.124569)
			(xy 165.596816 -311.173146) (xy 165.581232 -311.219827) (xy 165.558361 -311.263404) (xy 165.528796 -311.302748)
			(xy 165.493303 -311.33684) (xy 165.4528 -311.364796) (xy 165.408338 -311.385894) (xy 165.361067 -311.399586)
			(xy 165.312212 -311.405518) (xy 165.263037 -311.403537) (xy 165.214818 -311.393693) (xy 165.168802 -311.376241)
			(xy 165.126181 -311.351634) (xy 165.08806 -311.320509) (xy 165.055425 -311.283672) (xy 165.029122 -311.242076)
			(xy 165.009831 -311.1968) (xy 164.998054 -311.149016) (xy 164.994094 -311.099962) (xy 163.705286 -311.099962)
			(xy 163.704791 -311.124569) (xy 163.696896 -311.173146) (xy 163.681312 -311.219827) (xy 163.658441 -311.263404)
			(xy 163.628876 -311.302748) (xy 163.593383 -311.33684) (xy 163.55288 -311.364796) (xy 163.508418 -311.385894)
			(xy 163.461147 -311.399586) (xy 163.412292 -311.405518) (xy 163.363117 -311.403537) (xy 163.314898 -311.393693)
			(xy 163.268882 -311.376241) (xy 163.226261 -311.351634) (xy 163.18814 -311.320509) (xy 163.155505 -311.283672)
			(xy 163.129202 -311.242076) (xy 163.109911 -311.1968) (xy 163.098134 -311.149016) (xy 163.094174 -311.099962)
			(xy 161.805366 -311.099962) (xy 161.804871 -311.124569) (xy 161.796976 -311.173146) (xy 161.781392 -311.219827)
			(xy 161.758521 -311.263404) (xy 161.728956 -311.302748) (xy 161.693463 -311.33684) (xy 161.65296 -311.364796)
			(xy 161.608498 -311.385894) (xy 161.561227 -311.399586) (xy 161.512372 -311.405518) (xy 161.463197 -311.403537)
			(xy 161.414978 -311.393693) (xy 161.368962 -311.376241) (xy 161.326341 -311.351634) (xy 161.28822 -311.320509)
			(xy 161.255585 -311.283672) (xy 161.229282 -311.242076) (xy 161.209991 -311.1968) (xy 161.198214 -311.149016)
			(xy 161.194254 -311.099962) (xy 159.905192 -311.099962) (xy 159.904697 -311.124569) (xy 159.896802 -311.173146)
			(xy 159.881218 -311.219827) (xy 159.858347 -311.263404) (xy 159.828782 -311.302748) (xy 159.793289 -311.33684)
			(xy 159.752786 -311.364796) (xy 159.708324 -311.385894) (xy 159.661053 -311.399586) (xy 159.612198 -311.405518)
			(xy 159.563023 -311.403537) (xy 159.514804 -311.393693) (xy 159.468788 -311.376241) (xy 159.426167 -311.351634)
			(xy 159.388046 -311.320509) (xy 159.355411 -311.283672) (xy 159.329108 -311.242076) (xy 159.309817 -311.1968)
			(xy 159.29804 -311.149016) (xy 159.29408 -311.099962) (xy 158.005272 -311.099962) (xy 158.004777 -311.124569)
			(xy 157.996882 -311.173146) (xy 157.981298 -311.219827) (xy 157.958427 -311.263404) (xy 157.928862 -311.302748)
			(xy 157.893369 -311.33684) (xy 157.852866 -311.364796) (xy 157.808404 -311.385894) (xy 157.761133 -311.399586)
			(xy 157.712278 -311.405518) (xy 157.663103 -311.403537) (xy 157.614884 -311.393693) (xy 157.568868 -311.376241)
			(xy 157.526247 -311.351634) (xy 157.488126 -311.320509) (xy 157.455491 -311.283672) (xy 157.429188 -311.242076)
			(xy 157.409897 -311.1968) (xy 157.39812 -311.149016) (xy 157.39416 -311.099962) (xy 156.105352 -311.099962)
			(xy 156.104857 -311.124569) (xy 156.096962 -311.173146) (xy 156.081378 -311.219827) (xy 156.058507 -311.263404)
			(xy 156.028942 -311.302748) (xy 155.993449 -311.33684) (xy 155.952946 -311.364796) (xy 155.908484 -311.385894)
			(xy 155.861213 -311.399586) (xy 155.812358 -311.405518) (xy 155.763183 -311.403537) (xy 155.714964 -311.393693)
			(xy 155.668948 -311.376241) (xy 155.626327 -311.351634) (xy 155.588206 -311.320509) (xy 155.555571 -311.283672)
			(xy 155.529268 -311.242076) (xy 155.509977 -311.1968) (xy 155.4982 -311.149016) (xy 155.49424 -311.099962)
			(xy 79.905098 -311.099962) (xy 79.904603 -311.124569) (xy 79.896708 -311.173146) (xy 79.881124 -311.219827)
			(xy 79.858253 -311.263404) (xy 79.828688 -311.302748) (xy 79.793195 -311.33684) (xy 79.752692 -311.364796)
			(xy 79.70823 -311.385894) (xy 79.660959 -311.399586) (xy 79.612104 -311.405518) (xy 79.562929 -311.403537)
			(xy 79.51471 -311.393693) (xy 79.468694 -311.376241) (xy 79.426073 -311.351634) (xy 79.387952 -311.320509)
			(xy 79.355317 -311.283672) (xy 79.329014 -311.242076) (xy 79.309723 -311.1968) (xy 79.297946 -311.149016)
			(xy 79.293986 -311.099962) (xy 78.005178 -311.099962) (xy 78.004683 -311.124569) (xy 77.996788 -311.173146)
			(xy 77.981204 -311.219827) (xy 77.958333 -311.263404) (xy 77.928768 -311.302748) (xy 77.893275 -311.33684)
			(xy 77.852772 -311.364796) (xy 77.80831 -311.385894) (xy 77.761039 -311.399586) (xy 77.712184 -311.405518)
			(xy 77.663009 -311.403537) (xy 77.61479 -311.393693) (xy 77.568774 -311.376241) (xy 77.526153 -311.351634)
			(xy 77.488032 -311.320509) (xy 77.455397 -311.283672) (xy 77.429094 -311.242076) (xy 77.409803 -311.1968)
			(xy 77.398026 -311.149016) (xy 77.394066 -311.099962) (xy 76.105258 -311.099962) (xy 76.104763 -311.124569)
			(xy 76.096868 -311.173146) (xy 76.081284 -311.219827) (xy 76.058413 -311.263404) (xy 76.028848 -311.302748)
			(xy 75.993355 -311.33684) (xy 75.952852 -311.364796) (xy 75.90839 -311.385894) (xy 75.861119 -311.399586)
			(xy 75.812264 -311.405518) (xy 75.763089 -311.403537) (xy 75.71487 -311.393693) (xy 75.668854 -311.376241)
			(xy 75.626233 -311.351634) (xy 75.588112 -311.320509) (xy 75.555477 -311.283672) (xy 75.529174 -311.242076)
			(xy 75.509883 -311.1968) (xy 75.498106 -311.149016) (xy 75.494146 -311.099962) (xy 74.205084 -311.099962)
			(xy 74.204589 -311.124569) (xy 74.196694 -311.173146) (xy 74.18111 -311.219827) (xy 74.158239 -311.263404)
			(xy 74.128674 -311.302748) (xy 74.093181 -311.33684) (xy 74.052678 -311.364796) (xy 74.008216 -311.385894)
			(xy 73.960945 -311.399586) (xy 73.91209 -311.405518) (xy 73.862915 -311.403537) (xy 73.814696 -311.393693)
			(xy 73.76868 -311.376241) (xy 73.726059 -311.351634) (xy 73.687938 -311.320509) (xy 73.655303 -311.283672)
			(xy 73.629 -311.242076) (xy 73.609709 -311.1968) (xy 73.597932 -311.149016) (xy 73.593972 -311.099962)
			(xy 72.305164 -311.099962) (xy 72.304669 -311.124569) (xy 72.296774 -311.173146) (xy 72.28119 -311.219827)
			(xy 72.258319 -311.263404) (xy 72.228754 -311.302748) (xy 72.193261 -311.33684) (xy 72.152758 -311.364796)
			(xy 72.108296 -311.385894) (xy 72.061025 -311.399586) (xy 72.01217 -311.405518) (xy 71.962995 -311.403537)
			(xy 71.914776 -311.393693) (xy 71.86876 -311.376241) (xy 71.826139 -311.351634) (xy 71.788018 -311.320509)
			(xy 71.755383 -311.283672) (xy 71.72908 -311.242076) (xy 71.709789 -311.1968) (xy 71.698012 -311.149016)
			(xy 71.694052 -311.099962) (xy 70.405244 -311.099962) (xy 70.404749 -311.124569) (xy 70.396854 -311.173146)
			(xy 70.38127 -311.219827) (xy 70.358399 -311.263404) (xy 70.328834 -311.302748) (xy 70.293341 -311.33684)
			(xy 70.252838 -311.364796) (xy 70.208376 -311.385894) (xy 70.161105 -311.399586) (xy 70.11225 -311.405518)
			(xy 70.063075 -311.403537) (xy 70.014856 -311.393693) (xy 69.96884 -311.376241) (xy 69.926219 -311.351634)
			(xy 69.888098 -311.320509) (xy 69.855463 -311.283672) (xy 69.82916 -311.242076) (xy 69.809869 -311.1968)
			(xy 69.798092 -311.149016) (xy 69.794132 -311.099962) (xy 68.50507 -311.099962) (xy 68.504575 -311.124569)
			(xy 68.49668 -311.173146) (xy 68.481096 -311.219827) (xy 68.458225 -311.263404) (xy 68.42866 -311.302748)
			(xy 68.393167 -311.33684) (xy 68.352664 -311.364796) (xy 68.308202 -311.385894) (xy 68.260931 -311.399586)
			(xy 68.212076 -311.405518) (xy 68.162901 -311.403537) (xy 68.114682 -311.393693) (xy 68.068666 -311.376241)
			(xy 68.026045 -311.351634) (xy 67.987924 -311.320509) (xy 67.955289 -311.283672) (xy 67.928986 -311.242076)
			(xy 67.909695 -311.1968) (xy 67.897918 -311.149016) (xy 67.893958 -311.099962) (xy 66.60515 -311.099962)
			(xy 66.604655 -311.124569) (xy 66.59676 -311.173146) (xy 66.581176 -311.219827) (xy 66.558305 -311.263404)
			(xy 66.52874 -311.302748) (xy 66.493247 -311.33684) (xy 66.452744 -311.364796) (xy 66.408282 -311.385894)
			(xy 66.361011 -311.399586) (xy 66.312156 -311.405518) (xy 66.262981 -311.403537) (xy 66.214762 -311.393693)
			(xy 66.168746 -311.376241) (xy 66.126125 -311.351634) (xy 66.088004 -311.320509) (xy 66.055369 -311.283672)
			(xy 66.029066 -311.242076) (xy 66.009775 -311.1968) (xy 65.997998 -311.149016) (xy 65.994038 -311.099962)
			(xy 64.70523 -311.099962) (xy 64.704735 -311.124569) (xy 64.69684 -311.173146) (xy 64.681256 -311.219827)
			(xy 64.658385 -311.263404) (xy 64.62882 -311.302748) (xy 64.593327 -311.33684) (xy 64.552824 -311.364796)
			(xy 64.508362 -311.385894) (xy 64.461091 -311.399586) (xy 64.412236 -311.405518) (xy 64.363061 -311.403537)
			(xy 64.314842 -311.393693) (xy 64.268826 -311.376241) (xy 64.226205 -311.351634) (xy 64.188084 -311.320509)
			(xy 64.155449 -311.283672) (xy 64.129146 -311.242076) (xy 64.109855 -311.1968) (xy 64.098078 -311.149016)
			(xy 64.094118 -311.099962) (xy 62.805056 -311.099962) (xy 62.804561 -311.124569) (xy 62.796666 -311.173146)
			(xy 62.781082 -311.219827) (xy 62.758211 -311.263404) (xy 62.728646 -311.302748) (xy 62.693153 -311.33684)
			(xy 62.65265 -311.364796) (xy 62.608188 -311.385894) (xy 62.560917 -311.399586) (xy 62.512062 -311.405518)
			(xy 62.462887 -311.403537) (xy 62.414668 -311.393693) (xy 62.368652 -311.376241) (xy 62.326031 -311.351634)
			(xy 62.28791 -311.320509) (xy 62.255275 -311.283672) (xy 62.228972 -311.242076) (xy 62.209681 -311.1968)
			(xy 62.197904 -311.149016) (xy 62.193944 -311.099962) (xy 60.905136 -311.099962) (xy 60.904641 -311.124569)
			(xy 60.896746 -311.173146) (xy 60.881162 -311.219827) (xy 60.858291 -311.263404) (xy 60.828726 -311.302748)
			(xy 60.793233 -311.33684) (xy 60.75273 -311.364796) (xy 60.708268 -311.385894) (xy 60.660997 -311.399586)
			(xy 60.612142 -311.405518) (xy 60.562967 -311.403537) (xy 60.514748 -311.393693) (xy 60.468732 -311.376241)
			(xy 60.426111 -311.351634) (xy 60.38799 -311.320509) (xy 60.355355 -311.283672) (xy 60.329052 -311.242076)
			(xy 60.309761 -311.1968) (xy 60.297984 -311.149016) (xy 60.294024 -311.099962) (xy 59.005216 -311.099962)
			(xy 59.004721 -311.124569) (xy 58.996826 -311.173146) (xy 58.981242 -311.219827) (xy 58.958371 -311.263404)
			(xy 58.928806 -311.302748) (xy 58.893313 -311.33684) (xy 58.85281 -311.364796) (xy 58.808348 -311.385894)
			(xy 58.761077 -311.399586) (xy 58.712222 -311.405518) (xy 58.663047 -311.403537) (xy 58.614828 -311.393693)
			(xy 58.568812 -311.376241) (xy 58.526191 -311.351634) (xy 58.48807 -311.320509) (xy 58.455435 -311.283672)
			(xy 58.429132 -311.242076) (xy 58.409841 -311.1968) (xy 58.398064 -311.149016) (xy 58.394104 -311.099962)
			(xy 57.105296 -311.099962) (xy 57.104801 -311.124569) (xy 57.096906 -311.173146) (xy 57.081322 -311.219827)
			(xy 57.058451 -311.263404) (xy 57.028886 -311.302748) (xy 56.993393 -311.33684) (xy 56.95289 -311.364796)
			(xy 56.908428 -311.385894) (xy 56.861157 -311.399586) (xy 56.812302 -311.405518) (xy 56.763127 -311.403537)
			(xy 56.714908 -311.393693) (xy 56.668892 -311.376241) (xy 56.626271 -311.351634) (xy 56.58815 -311.320509)
			(xy 56.555515 -311.283672) (xy 56.529212 -311.242076) (xy 56.509921 -311.1968) (xy 56.498144 -311.149016)
			(xy 56.494184 -311.099962) (xy 55.205122 -311.099962) (xy 55.204627 -311.124569) (xy 55.196732 -311.173146)
			(xy 55.181148 -311.219827) (xy 55.158277 -311.263404) (xy 55.128712 -311.302748) (xy 55.093219 -311.33684)
			(xy 55.052716 -311.364796) (xy 55.008254 -311.385894) (xy 54.960983 -311.399586) (xy 54.912128 -311.405518)
			(xy 54.862953 -311.403537) (xy 54.814734 -311.393693) (xy 54.768718 -311.376241) (xy 54.726097 -311.351634)
			(xy 54.687976 -311.320509) (xy 54.655341 -311.283672) (xy 54.629038 -311.242076) (xy 54.609747 -311.1968)
			(xy 54.59797 -311.149016) (xy 54.59401 -311.099962) (xy 53.305202 -311.099962) (xy 53.304707 -311.124569)
			(xy 53.296812 -311.173146) (xy 53.281228 -311.219827) (xy 53.258357 -311.263404) (xy 53.228792 -311.302748)
			(xy 53.193299 -311.33684) (xy 53.152796 -311.364796) (xy 53.108334 -311.385894) (xy 53.061063 -311.399586)
			(xy 53.012208 -311.405518) (xy 52.963033 -311.403537) (xy 52.914814 -311.393693) (xy 52.868798 -311.376241)
			(xy 52.826177 -311.351634) (xy 52.788056 -311.320509) (xy 52.755421 -311.283672) (xy 52.729118 -311.242076)
			(xy 52.709827 -311.1968) (xy 52.69805 -311.149016) (xy 52.69409 -311.099962) (xy 51.405282 -311.099962)
			(xy 51.404787 -311.124569) (xy 51.396892 -311.173146) (xy 51.381308 -311.219827) (xy 51.358437 -311.263404)
			(xy 51.328872 -311.302748) (xy 51.293379 -311.33684) (xy 51.252876 -311.364796) (xy 51.208414 -311.385894)
			(xy 51.161143 -311.399586) (xy 51.112288 -311.405518) (xy 51.063113 -311.403537) (xy 51.014894 -311.393693)
			(xy 50.968878 -311.376241) (xy 50.926257 -311.351634) (xy 50.888136 -311.320509) (xy 50.855501 -311.283672)
			(xy 50.829198 -311.242076) (xy 50.809907 -311.1968) (xy 50.79813 -311.149016) (xy 50.79417 -311.099962)
			(xy 49.505108 -311.099962) (xy 49.504613 -311.124569) (xy 49.496718 -311.173146) (xy 49.481134 -311.219827)
			(xy 49.458263 -311.263404) (xy 49.428698 -311.302748) (xy 49.393205 -311.33684) (xy 49.352702 -311.364796)
			(xy 49.30824 -311.385894) (xy 49.260969 -311.399586) (xy 49.212114 -311.405518) (xy 49.162939 -311.403537)
			(xy 49.11472 -311.393693) (xy 49.068704 -311.376241) (xy 49.026083 -311.351634) (xy 48.987962 -311.320509)
			(xy 48.955327 -311.283672) (xy 48.929024 -311.242076) (xy 48.909733 -311.1968) (xy 48.897956 -311.149016)
			(xy 48.893996 -311.099962) (xy 47.605188 -311.099962) (xy 47.604693 -311.124569) (xy 47.596798 -311.173146)
			(xy 47.581214 -311.219827) (xy 47.558343 -311.263404) (xy 47.528778 -311.302748) (xy 47.493285 -311.33684)
			(xy 47.452782 -311.364796) (xy 47.40832 -311.385894) (xy 47.361049 -311.399586) (xy 47.312194 -311.405518)
			(xy 47.263019 -311.403537) (xy 47.2148 -311.393693) (xy 47.168784 -311.376241) (xy 47.126163 -311.351634)
			(xy 47.088042 -311.320509) (xy 47.055407 -311.283672) (xy 47.029104 -311.242076) (xy 47.009813 -311.1968)
			(xy 46.998036 -311.149016) (xy 46.994076 -311.099962) (xy 45.705268 -311.099962) (xy 45.704773 -311.124569)
			(xy 45.696878 -311.173146) (xy 45.681294 -311.219827) (xy 45.658423 -311.263404) (xy 45.628858 -311.302748)
			(xy 45.593365 -311.33684) (xy 45.552862 -311.364796) (xy 45.5084 -311.385894) (xy 45.461129 -311.399586)
			(xy 45.412274 -311.405518) (xy 45.363099 -311.403537) (xy 45.31488 -311.393693) (xy 45.268864 -311.376241)
			(xy 45.226243 -311.351634) (xy 45.188122 -311.320509) (xy 45.155487 -311.283672) (xy 45.129184 -311.242076)
			(xy 45.109893 -311.1968) (xy 45.098116 -311.149016) (xy 45.094156 -311.099962) (xy 43.805094 -311.099962)
			(xy 43.804599 -311.124569) (xy 43.796704 -311.173146) (xy 43.78112 -311.219827) (xy 43.758249 -311.263404)
			(xy 43.728684 -311.302748) (xy 43.693191 -311.33684) (xy 43.652688 -311.364796) (xy 43.608226 -311.385894)
			(xy 43.560955 -311.399586) (xy 43.5121 -311.405518) (xy 43.462925 -311.403537) (xy 43.414706 -311.393693)
			(xy 43.36869 -311.376241) (xy 43.326069 -311.351634) (xy 43.287948 -311.320509) (xy 43.255313 -311.283672)
			(xy 43.22901 -311.242076) (xy 43.209719 -311.1968) (xy 43.197942 -311.149016) (xy 43.193982 -311.099962)
			(xy 41.905174 -311.099962) (xy 41.904679 -311.124569) (xy 41.896784 -311.173146) (xy 41.8812 -311.219827)
			(xy 41.858329 -311.263404) (xy 41.828764 -311.302748) (xy 41.793271 -311.33684) (xy 41.752768 -311.364796)
			(xy 41.708306 -311.385894) (xy 41.661035 -311.399586) (xy 41.61218 -311.405518) (xy 41.563005 -311.403537)
			(xy 41.514786 -311.393693) (xy 41.46877 -311.376241) (xy 41.426149 -311.351634) (xy 41.388028 -311.320509)
			(xy 41.355393 -311.283672) (xy 41.32909 -311.242076) (xy 41.309799 -311.1968) (xy 41.298022 -311.149016)
			(xy 41.294062 -311.099962) (xy 40.005254 -311.099962) (xy 40.004759 -311.124569) (xy 39.996864 -311.173146)
			(xy 39.98128 -311.219827) (xy 39.958409 -311.263404) (xy 39.928844 -311.302748) (xy 39.893351 -311.33684)
			(xy 39.852848 -311.364796) (xy 39.808386 -311.385894) (xy 39.761115 -311.399586) (xy 39.71226 -311.405518)
			(xy 39.663085 -311.403537) (xy 39.614866 -311.393693) (xy 39.56885 -311.376241) (xy 39.526229 -311.351634)
			(xy 39.488108 -311.320509) (xy 39.455473 -311.283672) (xy 39.42917 -311.242076) (xy 39.409879 -311.1968)
			(xy 39.398102 -311.149016) (xy 39.394142 -311.099962) (xy 0.508 -311.099962) (xy 0.508 -312.049922)
			(xy 36.544008 -312.049922) (xy 36.547968 -312.000868) (xy 36.559745 -311.953084) (xy 36.579036 -311.907808)
			(xy 36.605339 -311.866212) (xy 36.637974 -311.829375) (xy 36.676095 -311.79825) (xy 36.718716 -311.773643)
			(xy 36.764732 -311.756191) (xy 36.812951 -311.746347) (xy 36.862126 -311.744366) (xy 36.910981 -311.750298)
			(xy 36.958252 -311.76399) (xy 37.002714 -311.785088) (xy 37.043217 -311.813044) (xy 37.07871 -311.847136)
			(xy 37.108275 -311.88648) (xy 37.131146 -311.930057) (xy 37.14673 -311.976738) (xy 37.154625 -312.025315)
			(xy 37.15512 -312.049922) (xy 37.493968 -312.049922) (xy 37.497928 -312.000868) (xy 37.509705 -311.953084)
			(xy 37.528996 -311.907808) (xy 37.555299 -311.866212) (xy 37.587934 -311.829375) (xy 37.626055 -311.79825)
			(xy 37.668676 -311.773643) (xy 37.714692 -311.756191) (xy 37.762911 -311.746347) (xy 37.812086 -311.744366)
			(xy 37.860941 -311.750298) (xy 37.908212 -311.76399) (xy 37.952674 -311.785088) (xy 37.993177 -311.813044)
			(xy 38.02867 -311.847136) (xy 38.058235 -311.88648) (xy 38.081106 -311.930057) (xy 38.09669 -311.976738)
			(xy 38.104585 -312.025315) (xy 38.10508 -312.049922) (xy 39.394142 -312.049922) (xy 39.398102 -312.000868)
			(xy 39.409879 -311.953084) (xy 39.42917 -311.907808) (xy 39.455473 -311.866212) (xy 39.488108 -311.829375)
			(xy 39.526229 -311.79825) (xy 39.56885 -311.773643) (xy 39.614866 -311.756191) (xy 39.663085 -311.746347)
			(xy 39.71226 -311.744366) (xy 39.761115 -311.750298) (xy 39.808386 -311.76399) (xy 39.852848 -311.785088)
			(xy 39.893351 -311.813044) (xy 39.928844 -311.847136) (xy 39.958409 -311.88648) (xy 39.98128 -311.930057)
			(xy 39.996864 -311.976738) (xy 40.004759 -312.025315) (xy 40.005254 -312.049922) (xy 41.294062 -312.049922)
			(xy 41.298022 -312.000868) (xy 41.309799 -311.953084) (xy 41.32909 -311.907808) (xy 41.355393 -311.866212)
			(xy 41.388028 -311.829375) (xy 41.426149 -311.79825) (xy 41.46877 -311.773643) (xy 41.514786 -311.756191)
			(xy 41.563005 -311.746347) (xy 41.61218 -311.744366) (xy 41.661035 -311.750298) (xy 41.708306 -311.76399)
			(xy 41.752768 -311.785088) (xy 41.793271 -311.813044) (xy 41.828764 -311.847136) (xy 41.858329 -311.88648)
			(xy 41.8812 -311.930057) (xy 41.896784 -311.976738) (xy 41.904679 -312.025315) (xy 41.905174 -312.049922)
			(xy 43.193982 -312.049922) (xy 43.197942 -312.000868) (xy 43.209719 -311.953084) (xy 43.22901 -311.907808)
			(xy 43.255313 -311.866212) (xy 43.287948 -311.829375) (xy 43.326069 -311.79825) (xy 43.36869 -311.773643)
			(xy 43.414706 -311.756191) (xy 43.462925 -311.746347) (xy 43.5121 -311.744366) (xy 43.560955 -311.750298)
			(xy 43.608226 -311.76399) (xy 43.652688 -311.785088) (xy 43.693191 -311.813044) (xy 43.728684 -311.847136)
			(xy 43.758249 -311.88648) (xy 43.78112 -311.930057) (xy 43.796704 -311.976738) (xy 43.804599 -312.025315)
			(xy 43.805094 -312.049922) (xy 45.094156 -312.049922) (xy 45.098116 -312.000868) (xy 45.109893 -311.953084)
			(xy 45.129184 -311.907808) (xy 45.155487 -311.866212) (xy 45.188122 -311.829375) (xy 45.226243 -311.79825)
			(xy 45.268864 -311.773643) (xy 45.31488 -311.756191) (xy 45.363099 -311.746347) (xy 45.412274 -311.744366)
			(xy 45.461129 -311.750298) (xy 45.5084 -311.76399) (xy 45.552862 -311.785088) (xy 45.593365 -311.813044)
			(xy 45.628858 -311.847136) (xy 45.658423 -311.88648) (xy 45.681294 -311.930057) (xy 45.696878 -311.976738)
			(xy 45.704773 -312.025315) (xy 45.705268 -312.049922) (xy 46.994076 -312.049922) (xy 46.998036 -312.000868)
			(xy 47.009813 -311.953084) (xy 47.029104 -311.907808) (xy 47.055407 -311.866212) (xy 47.088042 -311.829375)
			(xy 47.126163 -311.79825) (xy 47.168784 -311.773643) (xy 47.2148 -311.756191) (xy 47.263019 -311.746347)
			(xy 47.312194 -311.744366) (xy 47.361049 -311.750298) (xy 47.40832 -311.76399) (xy 47.452782 -311.785088)
			(xy 47.493285 -311.813044) (xy 47.528778 -311.847136) (xy 47.558343 -311.88648) (xy 47.581214 -311.930057)
			(xy 47.596798 -311.976738) (xy 47.604693 -312.025315) (xy 47.605188 -312.049922) (xy 48.893996 -312.049922)
			(xy 48.897956 -312.000868) (xy 48.909733 -311.953084) (xy 48.929024 -311.907808) (xy 48.955327 -311.866212)
			(xy 48.987962 -311.829375) (xy 49.026083 -311.79825) (xy 49.068704 -311.773643) (xy 49.11472 -311.756191)
			(xy 49.162939 -311.746347) (xy 49.212114 -311.744366) (xy 49.260969 -311.750298) (xy 49.30824 -311.76399)
			(xy 49.352702 -311.785088) (xy 49.393205 -311.813044) (xy 49.428698 -311.847136) (xy 49.458263 -311.88648)
			(xy 49.481134 -311.930057) (xy 49.496718 -311.976738) (xy 49.504613 -312.025315) (xy 49.505108 -312.049922)
			(xy 50.79417 -312.049922) (xy 50.79813 -312.000868) (xy 50.809907 -311.953084) (xy 50.829198 -311.907808)
			(xy 50.855501 -311.866212) (xy 50.888136 -311.829375) (xy 50.926257 -311.79825) (xy 50.968878 -311.773643)
			(xy 51.014894 -311.756191) (xy 51.063113 -311.746347) (xy 51.112288 -311.744366) (xy 51.161143 -311.750298)
			(xy 51.208414 -311.76399) (xy 51.252876 -311.785088) (xy 51.293379 -311.813044) (xy 51.328872 -311.847136)
			(xy 51.358437 -311.88648) (xy 51.381308 -311.930057) (xy 51.396892 -311.976738) (xy 51.404787 -312.025315)
			(xy 51.405282 -312.049922) (xy 52.69409 -312.049922) (xy 52.69805 -312.000868) (xy 52.709827 -311.953084)
			(xy 52.729118 -311.907808) (xy 52.755421 -311.866212) (xy 52.788056 -311.829375) (xy 52.826177 -311.79825)
			(xy 52.868798 -311.773643) (xy 52.914814 -311.756191) (xy 52.963033 -311.746347) (xy 53.012208 -311.744366)
			(xy 53.061063 -311.750298) (xy 53.108334 -311.76399) (xy 53.152796 -311.785088) (xy 53.193299 -311.813044)
			(xy 53.228792 -311.847136) (xy 53.258357 -311.88648) (xy 53.281228 -311.930057) (xy 53.296812 -311.976738)
			(xy 53.304707 -312.025315) (xy 53.305202 -312.049922) (xy 54.59401 -312.049922) (xy 54.59797 -312.000868)
			(xy 54.609747 -311.953084) (xy 54.629038 -311.907808) (xy 54.655341 -311.866212) (xy 54.687976 -311.829375)
			(xy 54.726097 -311.79825) (xy 54.768718 -311.773643) (xy 54.814734 -311.756191) (xy 54.862953 -311.746347)
			(xy 54.912128 -311.744366) (xy 54.960983 -311.750298) (xy 55.008254 -311.76399) (xy 55.052716 -311.785088)
			(xy 55.093219 -311.813044) (xy 55.128712 -311.847136) (xy 55.158277 -311.88648) (xy 55.181148 -311.930057)
			(xy 55.196732 -311.976738) (xy 55.204627 -312.025315) (xy 55.205122 -312.049922) (xy 56.494184 -312.049922)
			(xy 56.498144 -312.000868) (xy 56.509921 -311.953084) (xy 56.529212 -311.907808) (xy 56.555515 -311.866212)
			(xy 56.58815 -311.829375) (xy 56.626271 -311.79825) (xy 56.668892 -311.773643) (xy 56.714908 -311.756191)
			(xy 56.763127 -311.746347) (xy 56.812302 -311.744366) (xy 56.861157 -311.750298) (xy 56.908428 -311.76399)
			(xy 56.95289 -311.785088) (xy 56.993393 -311.813044) (xy 57.028886 -311.847136) (xy 57.058451 -311.88648)
			(xy 57.081322 -311.930057) (xy 57.096906 -311.976738) (xy 57.104801 -312.025315) (xy 57.105296 -312.049922)
			(xy 58.394104 -312.049922) (xy 58.398064 -312.000868) (xy 58.409841 -311.953084) (xy 58.429132 -311.907808)
			(xy 58.455435 -311.866212) (xy 58.48807 -311.829375) (xy 58.526191 -311.79825) (xy 58.568812 -311.773643)
			(xy 58.614828 -311.756191) (xy 58.663047 -311.746347) (xy 58.712222 -311.744366) (xy 58.761077 -311.750298)
			(xy 58.808348 -311.76399) (xy 58.85281 -311.785088) (xy 58.893313 -311.813044) (xy 58.928806 -311.847136)
			(xy 58.958371 -311.88648) (xy 58.981242 -311.930057) (xy 58.996826 -311.976738) (xy 59.004721 -312.025315)
			(xy 59.005216 -312.049922) (xy 60.294024 -312.049922) (xy 60.297984 -312.000868) (xy 60.309761 -311.953084)
			(xy 60.329052 -311.907808) (xy 60.355355 -311.866212) (xy 60.38799 -311.829375) (xy 60.426111 -311.79825)
			(xy 60.468732 -311.773643) (xy 60.514748 -311.756191) (xy 60.562967 -311.746347) (xy 60.612142 -311.744366)
			(xy 60.660997 -311.750298) (xy 60.708268 -311.76399) (xy 60.75273 -311.785088) (xy 60.793233 -311.813044)
			(xy 60.828726 -311.847136) (xy 60.858291 -311.88648) (xy 60.881162 -311.930057) (xy 60.896746 -311.976738)
			(xy 60.904641 -312.025315) (xy 60.905136 -312.049922) (xy 62.193944 -312.049922) (xy 62.197904 -312.000868)
			(xy 62.209681 -311.953084) (xy 62.228972 -311.907808) (xy 62.255275 -311.866212) (xy 62.28791 -311.829375)
			(xy 62.326031 -311.79825) (xy 62.368652 -311.773643) (xy 62.414668 -311.756191) (xy 62.462887 -311.746347)
			(xy 62.512062 -311.744366) (xy 62.560917 -311.750298) (xy 62.608188 -311.76399) (xy 62.65265 -311.785088)
			(xy 62.693153 -311.813044) (xy 62.728646 -311.847136) (xy 62.758211 -311.88648) (xy 62.781082 -311.930057)
			(xy 62.796666 -311.976738) (xy 62.804561 -312.025315) (xy 62.805056 -312.049922) (xy 64.094118 -312.049922)
			(xy 64.098078 -312.000868) (xy 64.109855 -311.953084) (xy 64.129146 -311.907808) (xy 64.155449 -311.866212)
			(xy 64.188084 -311.829375) (xy 64.226205 -311.79825) (xy 64.268826 -311.773643) (xy 64.314842 -311.756191)
			(xy 64.363061 -311.746347) (xy 64.412236 -311.744366) (xy 64.461091 -311.750298) (xy 64.508362 -311.76399)
			(xy 64.552824 -311.785088) (xy 64.593327 -311.813044) (xy 64.62882 -311.847136) (xy 64.658385 -311.88648)
			(xy 64.681256 -311.930057) (xy 64.69684 -311.976738) (xy 64.704735 -312.025315) (xy 64.70523 -312.049922)
			(xy 65.994038 -312.049922) (xy 65.997998 -312.000868) (xy 66.009775 -311.953084) (xy 66.029066 -311.907808)
			(xy 66.055369 -311.866212) (xy 66.088004 -311.829375) (xy 66.126125 -311.79825) (xy 66.168746 -311.773643)
			(xy 66.214762 -311.756191) (xy 66.262981 -311.746347) (xy 66.312156 -311.744366) (xy 66.361011 -311.750298)
			(xy 66.408282 -311.76399) (xy 66.452744 -311.785088) (xy 66.493247 -311.813044) (xy 66.52874 -311.847136)
			(xy 66.558305 -311.88648) (xy 66.581176 -311.930057) (xy 66.59676 -311.976738) (xy 66.604655 -312.025315)
			(xy 66.60515 -312.049922) (xy 67.893958 -312.049922) (xy 67.897918 -312.000868) (xy 67.909695 -311.953084)
			(xy 67.928986 -311.907808) (xy 67.955289 -311.866212) (xy 67.987924 -311.829375) (xy 68.026045 -311.79825)
			(xy 68.068666 -311.773643) (xy 68.114682 -311.756191) (xy 68.162901 -311.746347) (xy 68.212076 -311.744366)
			(xy 68.260931 -311.750298) (xy 68.308202 -311.76399) (xy 68.352664 -311.785088) (xy 68.393167 -311.813044)
			(xy 68.42866 -311.847136) (xy 68.458225 -311.88648) (xy 68.481096 -311.930057) (xy 68.49668 -311.976738)
			(xy 68.504575 -312.025315) (xy 68.50507 -312.049922) (xy 69.794132 -312.049922) (xy 69.798092 -312.000868)
			(xy 69.809869 -311.953084) (xy 69.82916 -311.907808) (xy 69.855463 -311.866212) (xy 69.888098 -311.829375)
			(xy 69.926219 -311.79825) (xy 69.96884 -311.773643) (xy 70.014856 -311.756191) (xy 70.063075 -311.746347)
			(xy 70.11225 -311.744366) (xy 70.161105 -311.750298) (xy 70.208376 -311.76399) (xy 70.252838 -311.785088)
			(xy 70.293341 -311.813044) (xy 70.328834 -311.847136) (xy 70.358399 -311.88648) (xy 70.38127 -311.930057)
			(xy 70.396854 -311.976738) (xy 70.404749 -312.025315) (xy 70.405244 -312.049922) (xy 71.694052 -312.049922)
			(xy 71.698012 -312.000868) (xy 71.709789 -311.953084) (xy 71.72908 -311.907808) (xy 71.755383 -311.866212)
			(xy 71.788018 -311.829375) (xy 71.826139 -311.79825) (xy 71.86876 -311.773643) (xy 71.914776 -311.756191)
			(xy 71.962995 -311.746347) (xy 72.01217 -311.744366) (xy 72.061025 -311.750298) (xy 72.108296 -311.76399)
			(xy 72.152758 -311.785088) (xy 72.193261 -311.813044) (xy 72.228754 -311.847136) (xy 72.258319 -311.88648)
			(xy 72.28119 -311.930057) (xy 72.296774 -311.976738) (xy 72.304669 -312.025315) (xy 72.305164 -312.049922)
			(xy 73.593972 -312.049922) (xy 73.597932 -312.000868) (xy 73.609709 -311.953084) (xy 73.629 -311.907808)
			(xy 73.655303 -311.866212) (xy 73.687938 -311.829375) (xy 73.726059 -311.79825) (xy 73.76868 -311.773643)
			(xy 73.814696 -311.756191) (xy 73.862915 -311.746347) (xy 73.91209 -311.744366) (xy 73.960945 -311.750298)
			(xy 74.008216 -311.76399) (xy 74.052678 -311.785088) (xy 74.093181 -311.813044) (xy 74.128674 -311.847136)
			(xy 74.158239 -311.88648) (xy 74.18111 -311.930057) (xy 74.196694 -311.976738) (xy 74.204589 -312.025315)
			(xy 74.205084 -312.049922) (xy 75.494146 -312.049922) (xy 75.498106 -312.000868) (xy 75.509883 -311.953084)
			(xy 75.529174 -311.907808) (xy 75.555477 -311.866212) (xy 75.588112 -311.829375) (xy 75.626233 -311.79825)
			(xy 75.668854 -311.773643) (xy 75.71487 -311.756191) (xy 75.763089 -311.746347) (xy 75.812264 -311.744366)
			(xy 75.861119 -311.750298) (xy 75.90839 -311.76399) (xy 75.952852 -311.785088) (xy 75.993355 -311.813044)
			(xy 76.028848 -311.847136) (xy 76.058413 -311.88648) (xy 76.081284 -311.930057) (xy 76.096868 -311.976738)
			(xy 76.104763 -312.025315) (xy 76.105258 -312.049922) (xy 77.394066 -312.049922) (xy 77.398026 -312.000868)
			(xy 77.409803 -311.953084) (xy 77.429094 -311.907808) (xy 77.455397 -311.866212) (xy 77.488032 -311.829375)
			(xy 77.526153 -311.79825) (xy 77.568774 -311.773643) (xy 77.61479 -311.756191) (xy 77.663009 -311.746347)
			(xy 77.712184 -311.744366) (xy 77.761039 -311.750298) (xy 77.80831 -311.76399) (xy 77.852772 -311.785088)
			(xy 77.893275 -311.813044) (xy 77.928768 -311.847136) (xy 77.958333 -311.88648) (xy 77.981204 -311.930057)
			(xy 77.996788 -311.976738) (xy 78.004683 -312.025315) (xy 78.005178 -312.049922) (xy 79.293986 -312.049922)
			(xy 79.297946 -312.000868) (xy 79.309723 -311.953084) (xy 79.329014 -311.907808) (xy 79.355317 -311.866212)
			(xy 79.387952 -311.829375) (xy 79.426073 -311.79825) (xy 79.468694 -311.773643) (xy 79.51471 -311.756191)
			(xy 79.562929 -311.746347) (xy 79.612104 -311.744366) (xy 79.660959 -311.750298) (xy 79.70823 -311.76399)
			(xy 79.752692 -311.785088) (xy 79.793195 -311.813044) (xy 79.828688 -311.847136) (xy 79.858253 -311.88648)
			(xy 79.881124 -311.930057) (xy 79.896708 -311.976738) (xy 79.904603 -312.025315) (xy 79.905098 -312.049922)
			(xy 81.19416 -312.049922) (xy 81.19812 -312.000868) (xy 81.209897 -311.953084) (xy 81.229188 -311.907808)
			(xy 81.255491 -311.866212) (xy 81.288126 -311.829375) (xy 81.326247 -311.79825) (xy 81.368868 -311.773643)
			(xy 81.414884 -311.756191) (xy 81.463103 -311.746347) (xy 81.512278 -311.744366) (xy 81.561133 -311.750298)
			(xy 81.608404 -311.76399) (xy 81.652866 -311.785088) (xy 81.693369 -311.813044) (xy 81.728862 -311.847136)
			(xy 81.758427 -311.88648) (xy 81.781298 -311.930057) (xy 81.796882 -311.976738) (xy 81.804777 -312.025315)
			(xy 81.805272 -312.049922) (xy 82.14412 -312.049922) (xy 82.14808 -312.000868) (xy 82.159857 -311.953084)
			(xy 82.179148 -311.907808) (xy 82.205451 -311.866212) (xy 82.238086 -311.829375) (xy 82.276207 -311.79825)
			(xy 82.318828 -311.773643) (xy 82.364844 -311.756191) (xy 82.413063 -311.746347) (xy 82.462238 -311.744366)
			(xy 82.511093 -311.750298) (xy 82.558364 -311.76399) (xy 82.602826 -311.785088) (xy 82.643329 -311.813044)
			(xy 82.678822 -311.847136) (xy 82.708387 -311.88648) (xy 82.731258 -311.930057) (xy 82.746842 -311.976738)
			(xy 82.754737 -312.025315) (xy 82.755232 -312.049922) (xy 152.644106 -312.049922) (xy 152.648066 -312.000868)
			(xy 152.659843 -311.953084) (xy 152.679134 -311.907808) (xy 152.705437 -311.866212) (xy 152.738072 -311.829375)
			(xy 152.776193 -311.79825) (xy 152.818814 -311.773643) (xy 152.86483 -311.756191) (xy 152.913049 -311.746347)
			(xy 152.962224 -311.744366) (xy 153.011079 -311.750298) (xy 153.05835 -311.76399) (xy 153.102812 -311.785088)
			(xy 153.143315 -311.813044) (xy 153.178808 -311.847136) (xy 153.208373 -311.88648) (xy 153.231244 -311.930057)
			(xy 153.246828 -311.976738) (xy 153.254723 -312.025315) (xy 153.255218 -312.049922) (xy 153.594066 -312.049922)
			(xy 153.598026 -312.000868) (xy 153.609803 -311.953084) (xy 153.629094 -311.907808) (xy 153.655397 -311.866212)
			(xy 153.688032 -311.829375) (xy 153.726153 -311.79825) (xy 153.768774 -311.773643) (xy 153.81479 -311.756191)
			(xy 153.863009 -311.746347) (xy 153.912184 -311.744366) (xy 153.961039 -311.750298) (xy 154.00831 -311.76399)
			(xy 154.052772 -311.785088) (xy 154.093275 -311.813044) (xy 154.128768 -311.847136) (xy 154.158333 -311.88648)
			(xy 154.181204 -311.930057) (xy 154.196788 -311.976738) (xy 154.204683 -312.025315) (xy 154.205178 -312.049922)
			(xy 155.49424 -312.049922) (xy 155.4982 -312.000868) (xy 155.509977 -311.953084) (xy 155.529268 -311.907808)
			(xy 155.555571 -311.866212) (xy 155.588206 -311.829375) (xy 155.626327 -311.79825) (xy 155.668948 -311.773643)
			(xy 155.714964 -311.756191) (xy 155.763183 -311.746347) (xy 155.812358 -311.744366) (xy 155.861213 -311.750298)
			(xy 155.908484 -311.76399) (xy 155.952946 -311.785088) (xy 155.993449 -311.813044) (xy 156.028942 -311.847136)
			(xy 156.058507 -311.88648) (xy 156.081378 -311.930057) (xy 156.096962 -311.976738) (xy 156.104857 -312.025315)
			(xy 156.105352 -312.049922) (xy 157.39416 -312.049922) (xy 157.39812 -312.000868) (xy 157.409897 -311.953084)
			(xy 157.429188 -311.907808) (xy 157.455491 -311.866212) (xy 157.488126 -311.829375) (xy 157.526247 -311.79825)
			(xy 157.568868 -311.773643) (xy 157.614884 -311.756191) (xy 157.663103 -311.746347) (xy 157.712278 -311.744366)
			(xy 157.761133 -311.750298) (xy 157.808404 -311.76399) (xy 157.852866 -311.785088) (xy 157.893369 -311.813044)
			(xy 157.928862 -311.847136) (xy 157.958427 -311.88648) (xy 157.981298 -311.930057) (xy 157.996882 -311.976738)
			(xy 158.004777 -312.025315) (xy 158.005272 -312.049922) (xy 159.29408 -312.049922) (xy 159.29804 -312.000868)
			(xy 159.309817 -311.953084) (xy 159.329108 -311.907808) (xy 159.355411 -311.866212) (xy 159.388046 -311.829375)
			(xy 159.426167 -311.79825) (xy 159.468788 -311.773643) (xy 159.514804 -311.756191) (xy 159.563023 -311.746347)
			(xy 159.612198 -311.744366) (xy 159.661053 -311.750298) (xy 159.708324 -311.76399) (xy 159.752786 -311.785088)
			(xy 159.793289 -311.813044) (xy 159.828782 -311.847136) (xy 159.858347 -311.88648) (xy 159.881218 -311.930057)
			(xy 159.896802 -311.976738) (xy 159.904697 -312.025315) (xy 159.905192 -312.049922) (xy 161.194254 -312.049922)
			(xy 161.198214 -312.000868) (xy 161.209991 -311.953084) (xy 161.229282 -311.907808) (xy 161.255585 -311.866212)
			(xy 161.28822 -311.829375) (xy 161.326341 -311.79825) (xy 161.368962 -311.773643) (xy 161.414978 -311.756191)
			(xy 161.463197 -311.746347) (xy 161.512372 -311.744366) (xy 161.561227 -311.750298) (xy 161.608498 -311.76399)
			(xy 161.65296 -311.785088) (xy 161.693463 -311.813044) (xy 161.728956 -311.847136) (xy 161.758521 -311.88648)
			(xy 161.781392 -311.930057) (xy 161.796976 -311.976738) (xy 161.804871 -312.025315) (xy 161.805366 -312.049922)
			(xy 163.094174 -312.049922) (xy 163.098134 -312.000868) (xy 163.109911 -311.953084) (xy 163.129202 -311.907808)
			(xy 163.155505 -311.866212) (xy 163.18814 -311.829375) (xy 163.226261 -311.79825) (xy 163.268882 -311.773643)
			(xy 163.314898 -311.756191) (xy 163.363117 -311.746347) (xy 163.412292 -311.744366) (xy 163.461147 -311.750298)
			(xy 163.508418 -311.76399) (xy 163.55288 -311.785088) (xy 163.593383 -311.813044) (xy 163.628876 -311.847136)
			(xy 163.658441 -311.88648) (xy 163.681312 -311.930057) (xy 163.696896 -311.976738) (xy 163.704791 -312.025315)
			(xy 163.705286 -312.049922) (xy 164.994094 -312.049922) (xy 164.998054 -312.000868) (xy 165.009831 -311.953084)
			(xy 165.029122 -311.907808) (xy 165.055425 -311.866212) (xy 165.08806 -311.829375) (xy 165.126181 -311.79825)
			(xy 165.168802 -311.773643) (xy 165.214818 -311.756191) (xy 165.263037 -311.746347) (xy 165.312212 -311.744366)
			(xy 165.361067 -311.750298) (xy 165.408338 -311.76399) (xy 165.4528 -311.785088) (xy 165.493303 -311.813044)
			(xy 165.528796 -311.847136) (xy 165.558361 -311.88648) (xy 165.581232 -311.930057) (xy 165.596816 -311.976738)
			(xy 165.604711 -312.025315) (xy 165.605206 -312.049922) (xy 166.894268 -312.049922) (xy 166.898228 -312.000868)
			(xy 166.910005 -311.953084) (xy 166.929296 -311.907808) (xy 166.955599 -311.866212) (xy 166.988234 -311.829375)
			(xy 167.026355 -311.79825) (xy 167.068976 -311.773643) (xy 167.114992 -311.756191) (xy 167.163211 -311.746347)
			(xy 167.212386 -311.744366) (xy 167.261241 -311.750298) (xy 167.308512 -311.76399) (xy 167.352974 -311.785088)
			(xy 167.393477 -311.813044) (xy 167.42897 -311.847136) (xy 167.458535 -311.88648) (xy 167.481406 -311.930057)
			(xy 167.49699 -311.976738) (xy 167.504885 -312.025315) (xy 167.50538 -312.049922) (xy 168.794188 -312.049922)
			(xy 168.798148 -312.000868) (xy 168.809925 -311.953084) (xy 168.829216 -311.907808) (xy 168.855519 -311.866212)
			(xy 168.888154 -311.829375) (xy 168.926275 -311.79825) (xy 168.968896 -311.773643) (xy 169.014912 -311.756191)
			(xy 169.063131 -311.746347) (xy 169.112306 -311.744366) (xy 169.161161 -311.750298) (xy 169.208432 -311.76399)
			(xy 169.252894 -311.785088) (xy 169.293397 -311.813044) (xy 169.32889 -311.847136) (xy 169.358455 -311.88648)
			(xy 169.381326 -311.930057) (xy 169.39691 -311.976738) (xy 169.404805 -312.025315) (xy 169.4053 -312.049922)
			(xy 170.694108 -312.049922) (xy 170.698068 -312.000868) (xy 170.709845 -311.953084) (xy 170.729136 -311.907808)
			(xy 170.755439 -311.866212) (xy 170.788074 -311.829375) (xy 170.826195 -311.79825) (xy 170.868816 -311.773643)
			(xy 170.914832 -311.756191) (xy 170.963051 -311.746347) (xy 171.012226 -311.744366) (xy 171.061081 -311.750298)
			(xy 171.108352 -311.76399) (xy 171.152814 -311.785088) (xy 171.193317 -311.813044) (xy 171.22881 -311.847136)
			(xy 171.258375 -311.88648) (xy 171.281246 -311.930057) (xy 171.29683 -311.976738) (xy 171.304725 -312.025315)
			(xy 171.30522 -312.049922) (xy 172.594282 -312.049922) (xy 172.598242 -312.000868) (xy 172.610019 -311.953084)
			(xy 172.62931 -311.907808) (xy 172.655613 -311.866212) (xy 172.688248 -311.829375) (xy 172.726369 -311.79825)
			(xy 172.76899 -311.773643) (xy 172.815006 -311.756191) (xy 172.863225 -311.746347) (xy 172.9124 -311.744366)
			(xy 172.961255 -311.750298) (xy 173.008526 -311.76399) (xy 173.052988 -311.785088) (xy 173.093491 -311.813044)
			(xy 173.128984 -311.847136) (xy 173.158549 -311.88648) (xy 173.18142 -311.930057) (xy 173.197004 -311.976738)
			(xy 173.204899 -312.025315) (xy 173.205394 -312.049922) (xy 174.494202 -312.049922) (xy 174.498162 -312.000868)
			(xy 174.509939 -311.953084) (xy 174.52923 -311.907808) (xy 174.555533 -311.866212) (xy 174.588168 -311.829375)
			(xy 174.626289 -311.79825) (xy 174.66891 -311.773643) (xy 174.714926 -311.756191) (xy 174.763145 -311.746347)
			(xy 174.81232 -311.744366) (xy 174.861175 -311.750298) (xy 174.908446 -311.76399) (xy 174.952908 -311.785088)
			(xy 174.993411 -311.813044) (xy 175.028904 -311.847136) (xy 175.058469 -311.88648) (xy 175.08134 -311.930057)
			(xy 175.096924 -311.976738) (xy 175.104819 -312.025315) (xy 175.105314 -312.049922) (xy 176.394122 -312.049922)
			(xy 176.398082 -312.000868) (xy 176.409859 -311.953084) (xy 176.42915 -311.907808) (xy 176.455453 -311.866212)
			(xy 176.488088 -311.829375) (xy 176.526209 -311.79825) (xy 176.56883 -311.773643) (xy 176.614846 -311.756191)
			(xy 176.663065 -311.746347) (xy 176.71224 -311.744366) (xy 176.761095 -311.750298) (xy 176.808366 -311.76399)
			(xy 176.852828 -311.785088) (xy 176.893331 -311.813044) (xy 176.928824 -311.847136) (xy 176.958389 -311.88648)
			(xy 176.98126 -311.930057) (xy 176.996844 -311.976738) (xy 177.004739 -312.025315) (xy 177.005234 -312.049922)
			(xy 178.294042 -312.049922) (xy 178.298002 -312.000868) (xy 178.309779 -311.953084) (xy 178.32907 -311.907808)
			(xy 178.355373 -311.866212) (xy 178.388008 -311.829375) (xy 178.426129 -311.79825) (xy 178.46875 -311.773643)
			(xy 178.514766 -311.756191) (xy 178.562985 -311.746347) (xy 178.61216 -311.744366) (xy 178.661015 -311.750298)
			(xy 178.708286 -311.76399) (xy 178.752748 -311.785088) (xy 178.793251 -311.813044) (xy 178.828744 -311.847136)
			(xy 178.858309 -311.88648) (xy 178.88118 -311.930057) (xy 178.896764 -311.976738) (xy 178.904659 -312.025315)
			(xy 178.905154 -312.049922) (xy 180.194216 -312.049922) (xy 180.198176 -312.000868) (xy 180.209953 -311.953084)
			(xy 180.229244 -311.907808) (xy 180.255547 -311.866212) (xy 180.288182 -311.829375) (xy 180.326303 -311.79825)
			(xy 180.368924 -311.773643) (xy 180.41494 -311.756191) (xy 180.463159 -311.746347) (xy 180.512334 -311.744366)
			(xy 180.561189 -311.750298) (xy 180.60846 -311.76399) (xy 180.652922 -311.785088) (xy 180.693425 -311.813044)
			(xy 180.728918 -311.847136) (xy 180.758483 -311.88648) (xy 180.781354 -311.930057) (xy 180.796938 -311.976738)
			(xy 180.804833 -312.025315) (xy 180.805328 -312.049922) (xy 182.094136 -312.049922) (xy 182.098096 -312.000868)
			(xy 182.109873 -311.953084) (xy 182.129164 -311.907808) (xy 182.155467 -311.866212) (xy 182.188102 -311.829375)
			(xy 182.226223 -311.79825) (xy 182.268844 -311.773643) (xy 182.31486 -311.756191) (xy 182.363079 -311.746347)
			(xy 182.412254 -311.744366) (xy 182.461109 -311.750298) (xy 182.50838 -311.76399) (xy 182.552842 -311.785088)
			(xy 182.593345 -311.813044) (xy 182.628838 -311.847136) (xy 182.658403 -311.88648) (xy 182.681274 -311.930057)
			(xy 182.696858 -311.976738) (xy 182.704753 -312.025315) (xy 182.705248 -312.049922) (xy 183.994056 -312.049922)
			(xy 183.998016 -312.000868) (xy 184.009793 -311.953084) (xy 184.029084 -311.907808) (xy 184.055387 -311.866212)
			(xy 184.088022 -311.829375) (xy 184.126143 -311.79825) (xy 184.168764 -311.773643) (xy 184.21478 -311.756191)
			(xy 184.262999 -311.746347) (xy 184.312174 -311.744366) (xy 184.361029 -311.750298) (xy 184.4083 -311.76399)
			(xy 184.452762 -311.785088) (xy 184.493265 -311.813044) (xy 184.528758 -311.847136) (xy 184.558323 -311.88648)
			(xy 184.581194 -311.930057) (xy 184.596778 -311.976738) (xy 184.604673 -312.025315) (xy 184.605168 -312.049922)
			(xy 185.89423 -312.049922) (xy 185.89819 -312.000868) (xy 185.909967 -311.953084) (xy 185.929258 -311.907808)
			(xy 185.955561 -311.866212) (xy 185.988196 -311.829375) (xy 186.026317 -311.79825) (xy 186.068938 -311.773643)
			(xy 186.114954 -311.756191) (xy 186.163173 -311.746347) (xy 186.212348 -311.744366) (xy 186.261203 -311.750298)
			(xy 186.308474 -311.76399) (xy 186.352936 -311.785088) (xy 186.393439 -311.813044) (xy 186.428932 -311.847136)
			(xy 186.458497 -311.88648) (xy 186.481368 -311.930057) (xy 186.496952 -311.976738) (xy 186.504847 -312.025315)
			(xy 186.505342 -312.049922) (xy 187.79415 -312.049922) (xy 187.79811 -312.000868) (xy 187.809887 -311.953084)
			(xy 187.829178 -311.907808) (xy 187.855481 -311.866212) (xy 187.888116 -311.829375) (xy 187.926237 -311.79825)
			(xy 187.968858 -311.773643) (xy 188.014874 -311.756191) (xy 188.063093 -311.746347) (xy 188.112268 -311.744366)
			(xy 188.161123 -311.750298) (xy 188.208394 -311.76399) (xy 188.252856 -311.785088) (xy 188.293359 -311.813044)
			(xy 188.328852 -311.847136) (xy 188.358417 -311.88648) (xy 188.381288 -311.930057) (xy 188.396872 -311.976738)
			(xy 188.404767 -312.025315) (xy 188.405262 -312.049922) (xy 189.69407 -312.049922) (xy 189.69803 -312.000868)
			(xy 189.709807 -311.953084) (xy 189.729098 -311.907808) (xy 189.755401 -311.866212) (xy 189.788036 -311.829375)
			(xy 189.826157 -311.79825) (xy 189.868778 -311.773643) (xy 189.914794 -311.756191) (xy 189.963013 -311.746347)
			(xy 190.012188 -311.744366) (xy 190.061043 -311.750298) (xy 190.108314 -311.76399) (xy 190.152776 -311.785088)
			(xy 190.193279 -311.813044) (xy 190.228772 -311.847136) (xy 190.258337 -311.88648) (xy 190.281208 -311.930057)
			(xy 190.296792 -311.976738) (xy 190.304687 -312.025315) (xy 190.305182 -312.049922) (xy 191.594244 -312.049922)
			(xy 191.598204 -312.000868) (xy 191.609981 -311.953084) (xy 191.629272 -311.907808) (xy 191.655575 -311.866212)
			(xy 191.68821 -311.829375) (xy 191.726331 -311.79825) (xy 191.768952 -311.773643) (xy 191.814968 -311.756191)
			(xy 191.863187 -311.746347) (xy 191.912362 -311.744366) (xy 191.961217 -311.750298) (xy 192.008488 -311.76399)
			(xy 192.05295 -311.785088) (xy 192.093453 -311.813044) (xy 192.128946 -311.847136) (xy 192.158511 -311.88648)
			(xy 192.181382 -311.930057) (xy 192.196966 -311.976738) (xy 192.204861 -312.025315) (xy 192.205356 -312.049922)
			(xy 193.494164 -312.049922) (xy 193.498124 -312.000868) (xy 193.509901 -311.953084) (xy 193.529192 -311.907808)
			(xy 193.555495 -311.866212) (xy 193.58813 -311.829375) (xy 193.626251 -311.79825) (xy 193.668872 -311.773643)
			(xy 193.714888 -311.756191) (xy 193.763107 -311.746347) (xy 193.812282 -311.744366) (xy 193.861137 -311.750298)
			(xy 193.908408 -311.76399) (xy 193.95287 -311.785088) (xy 193.993373 -311.813044) (xy 194.028866 -311.847136)
			(xy 194.058431 -311.88648) (xy 194.081302 -311.930057) (xy 194.096886 -311.976738) (xy 194.104781 -312.025315)
			(xy 194.105276 -312.049922) (xy 195.394084 -312.049922) (xy 195.398044 -312.000868) (xy 195.409821 -311.953084)
			(xy 195.429112 -311.907808) (xy 195.455415 -311.866212) (xy 195.48805 -311.829375) (xy 195.526171 -311.79825)
			(xy 195.568792 -311.773643) (xy 195.614808 -311.756191) (xy 195.663027 -311.746347) (xy 195.712202 -311.744366)
			(xy 195.761057 -311.750298) (xy 195.808328 -311.76399) (xy 195.85279 -311.785088) (xy 195.893293 -311.813044)
			(xy 195.928786 -311.847136) (xy 195.958351 -311.88648) (xy 195.981222 -311.930057) (xy 195.996806 -311.976738)
			(xy 196.004701 -312.025315) (xy 196.005196 -312.049922) (xy 197.294258 -312.049922) (xy 197.298218 -312.000868)
			(xy 197.309995 -311.953084) (xy 197.329286 -311.907808) (xy 197.355589 -311.866212) (xy 197.388224 -311.829375)
			(xy 197.426345 -311.79825) (xy 197.468966 -311.773643) (xy 197.514982 -311.756191) (xy 197.563201 -311.746347)
			(xy 197.612376 -311.744366) (xy 197.661231 -311.750298) (xy 197.708502 -311.76399) (xy 197.752964 -311.785088)
			(xy 197.793467 -311.813044) (xy 197.82896 -311.847136) (xy 197.858525 -311.88648) (xy 197.881396 -311.930057)
			(xy 197.89698 -311.976738) (xy 197.904875 -312.025315) (xy 197.90537 -312.049922) (xy 198.244218 -312.049922)
			(xy 198.248178 -312.000868) (xy 198.259955 -311.953084) (xy 198.279246 -311.907808) (xy 198.305549 -311.866212)
			(xy 198.338184 -311.829375) (xy 198.376305 -311.79825) (xy 198.418926 -311.773643) (xy 198.464942 -311.756191)
			(xy 198.513161 -311.746347) (xy 198.562336 -311.744366) (xy 198.611191 -311.750298) (xy 198.658462 -311.76399)
			(xy 198.702924 -311.785088) (xy 198.743427 -311.813044) (xy 198.77892 -311.847136) (xy 198.808485 -311.88648)
			(xy 198.831356 -311.930057) (xy 198.84694 -311.976738) (xy 198.854835 -312.025315) (xy 198.85533 -312.049922)
			(xy 268.74395 -312.049922) (xy 268.74791 -312.000868) (xy 268.759687 -311.953084) (xy 268.778978 -311.907808)
			(xy 268.805281 -311.866212) (xy 268.837916 -311.829375) (xy 268.876037 -311.79825) (xy 268.918658 -311.773643)
			(xy 268.964674 -311.756191) (xy 269.012893 -311.746347) (xy 269.062068 -311.744366) (xy 269.110923 -311.750298)
			(xy 269.158194 -311.76399) (xy 269.202656 -311.785088) (xy 269.243159 -311.813044) (xy 269.278652 -311.847136)
			(xy 269.308217 -311.88648) (xy 269.331088 -311.930057) (xy 269.346672 -311.976738) (xy 269.354567 -312.025315)
			(xy 269.355062 -312.049922) (xy 269.69391 -312.049922) (xy 269.69787 -312.000868) (xy 269.709647 -311.953084)
			(xy 269.728938 -311.907808) (xy 269.755241 -311.866212) (xy 269.787876 -311.829375) (xy 269.825997 -311.79825)
			(xy 269.868618 -311.773643) (xy 269.914634 -311.756191) (xy 269.962853 -311.746347) (xy 270.012028 -311.744366)
			(xy 270.060883 -311.750298) (xy 270.108154 -311.76399) (xy 270.152616 -311.785088) (xy 270.193119 -311.813044)
			(xy 270.228612 -311.847136) (xy 270.258177 -311.88648) (xy 270.281048 -311.930057) (xy 270.296632 -311.976738)
			(xy 270.304527 -312.025315) (xy 270.305022 -312.049922) (xy 271.594084 -312.049922) (xy 271.598044 -312.000868)
			(xy 271.609821 -311.953084) (xy 271.629112 -311.907808) (xy 271.655415 -311.866212) (xy 271.68805 -311.829375)
			(xy 271.726171 -311.79825) (xy 271.768792 -311.773643) (xy 271.814808 -311.756191) (xy 271.863027 -311.746347)
			(xy 271.912202 -311.744366) (xy 271.961057 -311.750298) (xy 272.008328 -311.76399) (xy 272.05279 -311.785088)
			(xy 272.093293 -311.813044) (xy 272.128786 -311.847136) (xy 272.158351 -311.88648) (xy 272.181222 -311.930057)
			(xy 272.196806 -311.976738) (xy 272.204701 -312.025315) (xy 272.205196 -312.049922) (xy 273.494004 -312.049922)
			(xy 273.497964 -312.000868) (xy 273.509741 -311.953084) (xy 273.529032 -311.907808) (xy 273.555335 -311.866212)
			(xy 273.58797 -311.829375) (xy 273.626091 -311.79825) (xy 273.668712 -311.773643) (xy 273.714728 -311.756191)
			(xy 273.762947 -311.746347) (xy 273.812122 -311.744366) (xy 273.860977 -311.750298) (xy 273.908248 -311.76399)
			(xy 273.95271 -311.785088) (xy 273.993213 -311.813044) (xy 274.028706 -311.847136) (xy 274.058271 -311.88648)
			(xy 274.081142 -311.930057) (xy 274.096726 -311.976738) (xy 274.104621 -312.025315) (xy 274.105116 -312.049922)
			(xy 275.393924 -312.049922) (xy 275.397884 -312.000868) (xy 275.409661 -311.953084) (xy 275.428952 -311.907808)
			(xy 275.455255 -311.866212) (xy 275.48789 -311.829375) (xy 275.526011 -311.79825) (xy 275.568632 -311.773643)
			(xy 275.614648 -311.756191) (xy 275.662867 -311.746347) (xy 275.712042 -311.744366) (xy 275.760897 -311.750298)
			(xy 275.808168 -311.76399) (xy 275.85263 -311.785088) (xy 275.893133 -311.813044) (xy 275.928626 -311.847136)
			(xy 275.958191 -311.88648) (xy 275.981062 -311.930057) (xy 275.996646 -311.976738) (xy 276.004541 -312.025315)
			(xy 276.005036 -312.049922) (xy 277.294098 -312.049922) (xy 277.298058 -312.000868) (xy 277.309835 -311.953084)
			(xy 277.329126 -311.907808) (xy 277.355429 -311.866212) (xy 277.388064 -311.829375) (xy 277.426185 -311.79825)
			(xy 277.468806 -311.773643) (xy 277.514822 -311.756191) (xy 277.563041 -311.746347) (xy 277.612216 -311.744366)
			(xy 277.661071 -311.750298) (xy 277.708342 -311.76399) (xy 277.752804 -311.785088) (xy 277.793307 -311.813044)
			(xy 277.8288 -311.847136) (xy 277.858365 -311.88648) (xy 277.881236 -311.930057) (xy 277.89682 -311.976738)
			(xy 277.904715 -312.025315) (xy 277.90521 -312.049922) (xy 279.194018 -312.049922) (xy 279.197978 -312.000868)
			(xy 279.209755 -311.953084) (xy 279.229046 -311.907808) (xy 279.255349 -311.866212) (xy 279.287984 -311.829375)
			(xy 279.326105 -311.79825) (xy 279.368726 -311.773643) (xy 279.414742 -311.756191) (xy 279.462961 -311.746347)
			(xy 279.512136 -311.744366) (xy 279.560991 -311.750298) (xy 279.608262 -311.76399) (xy 279.652724 -311.785088)
			(xy 279.693227 -311.813044) (xy 279.72872 -311.847136) (xy 279.758285 -311.88648) (xy 279.781156 -311.930057)
			(xy 279.79674 -311.976738) (xy 279.804635 -312.025315) (xy 279.80513 -312.049922) (xy 281.093938 -312.049922)
			(xy 281.097898 -312.000868) (xy 281.109675 -311.953084) (xy 281.128966 -311.907808) (xy 281.155269 -311.866212)
			(xy 281.187904 -311.829375) (xy 281.226025 -311.79825) (xy 281.268646 -311.773643) (xy 281.314662 -311.756191)
			(xy 281.362881 -311.746347) (xy 281.412056 -311.744366) (xy 281.460911 -311.750298) (xy 281.508182 -311.76399)
			(xy 281.552644 -311.785088) (xy 281.593147 -311.813044) (xy 281.62864 -311.847136) (xy 281.658205 -311.88648)
			(xy 281.681076 -311.930057) (xy 281.69666 -311.976738) (xy 281.704555 -312.025315) (xy 281.70505 -312.049922)
			(xy 282.994112 -312.049922) (xy 282.998072 -312.000868) (xy 283.009849 -311.953084) (xy 283.02914 -311.907808)
			(xy 283.055443 -311.866212) (xy 283.088078 -311.829375) (xy 283.126199 -311.79825) (xy 283.16882 -311.773643)
			(xy 283.214836 -311.756191) (xy 283.263055 -311.746347) (xy 283.31223 -311.744366) (xy 283.361085 -311.750298)
			(xy 283.408356 -311.76399) (xy 283.452818 -311.785088) (xy 283.493321 -311.813044) (xy 283.528814 -311.847136)
			(xy 283.558379 -311.88648) (xy 283.58125 -311.930057) (xy 283.596834 -311.976738) (xy 283.604729 -312.025315)
			(xy 283.605224 -312.049922) (xy 284.894032 -312.049922) (xy 284.897992 -312.000868) (xy 284.909769 -311.953084)
			(xy 284.92906 -311.907808) (xy 284.955363 -311.866212) (xy 284.987998 -311.829375) (xy 285.026119 -311.79825)
			(xy 285.06874 -311.773643) (xy 285.114756 -311.756191) (xy 285.162975 -311.746347) (xy 285.21215 -311.744366)
			(xy 285.261005 -311.750298) (xy 285.308276 -311.76399) (xy 285.352738 -311.785088) (xy 285.393241 -311.813044)
			(xy 285.428734 -311.847136) (xy 285.458299 -311.88648) (xy 285.48117 -311.930057) (xy 285.496754 -311.976738)
			(xy 285.504649 -312.025315) (xy 285.505144 -312.049922) (xy 286.793952 -312.049922) (xy 286.797912 -312.000868)
			(xy 286.809689 -311.953084) (xy 286.82898 -311.907808) (xy 286.855283 -311.866212) (xy 286.887918 -311.829375)
			(xy 286.926039 -311.79825) (xy 286.96866 -311.773643) (xy 287.014676 -311.756191) (xy 287.062895 -311.746347)
			(xy 287.11207 -311.744366) (xy 287.160925 -311.750298) (xy 287.208196 -311.76399) (xy 287.252658 -311.785088)
			(xy 287.293161 -311.813044) (xy 287.328654 -311.847136) (xy 287.358219 -311.88648) (xy 287.38109 -311.930057)
			(xy 287.396674 -311.976738) (xy 287.404569 -312.025315) (xy 287.405064 -312.049922) (xy 288.694126 -312.049922)
			(xy 288.698086 -312.000868) (xy 288.709863 -311.953084) (xy 288.729154 -311.907808) (xy 288.755457 -311.866212)
			(xy 288.788092 -311.829375) (xy 288.826213 -311.79825) (xy 288.868834 -311.773643) (xy 288.91485 -311.756191)
			(xy 288.963069 -311.746347) (xy 289.012244 -311.744366) (xy 289.061099 -311.750298) (xy 289.10837 -311.76399)
			(xy 289.152832 -311.785088) (xy 289.193335 -311.813044) (xy 289.228828 -311.847136) (xy 289.258393 -311.88648)
			(xy 289.281264 -311.930057) (xy 289.296848 -311.976738) (xy 289.304743 -312.025315) (xy 289.305238 -312.049922)
			(xy 290.594046 -312.049922) (xy 290.598006 -312.000868) (xy 290.609783 -311.953084) (xy 290.629074 -311.907808)
			(xy 290.655377 -311.866212) (xy 290.688012 -311.829375) (xy 290.726133 -311.79825) (xy 290.768754 -311.773643)
			(xy 290.81477 -311.756191) (xy 290.862989 -311.746347) (xy 290.912164 -311.744366) (xy 290.961019 -311.750298)
			(xy 291.00829 -311.76399) (xy 291.052752 -311.785088) (xy 291.093255 -311.813044) (xy 291.128748 -311.847136)
			(xy 291.158313 -311.88648) (xy 291.181184 -311.930057) (xy 291.196768 -311.976738) (xy 291.204663 -312.025315)
			(xy 291.205158 -312.049922) (xy 292.493966 -312.049922) (xy 292.497926 -312.000868) (xy 292.509703 -311.953084)
			(xy 292.528994 -311.907808) (xy 292.555297 -311.866212) (xy 292.587932 -311.829375) (xy 292.626053 -311.79825)
			(xy 292.668674 -311.773643) (xy 292.71469 -311.756191) (xy 292.762909 -311.746347) (xy 292.812084 -311.744366)
			(xy 292.860939 -311.750298) (xy 292.90821 -311.76399) (xy 292.952672 -311.785088) (xy 292.993175 -311.813044)
			(xy 293.028668 -311.847136) (xy 293.058233 -311.88648) (xy 293.081104 -311.930057) (xy 293.096688 -311.976738)
			(xy 293.104583 -312.025315) (xy 293.105078 -312.049922) (xy 294.393886 -312.049922) (xy 294.397846 -312.000868)
			(xy 294.409623 -311.953084) (xy 294.428914 -311.907808) (xy 294.455217 -311.866212) (xy 294.487852 -311.829375)
			(xy 294.525973 -311.79825) (xy 294.568594 -311.773643) (xy 294.61461 -311.756191) (xy 294.662829 -311.746347)
			(xy 294.712004 -311.744366) (xy 294.760859 -311.750298) (xy 294.80813 -311.76399) (xy 294.852592 -311.785088)
			(xy 294.893095 -311.813044) (xy 294.928588 -311.847136) (xy 294.958153 -311.88648) (xy 294.981024 -311.930057)
			(xy 294.996608 -311.976738) (xy 295.004503 -312.025315) (xy 295.004998 -312.049922) (xy 296.29406 -312.049922)
			(xy 296.29802 -312.000868) (xy 296.309797 -311.953084) (xy 296.329088 -311.907808) (xy 296.355391 -311.866212)
			(xy 296.388026 -311.829375) (xy 296.426147 -311.79825) (xy 296.468768 -311.773643) (xy 296.514784 -311.756191)
			(xy 296.563003 -311.746347) (xy 296.612178 -311.744366) (xy 296.661033 -311.750298) (xy 296.708304 -311.76399)
			(xy 296.752766 -311.785088) (xy 296.793269 -311.813044) (xy 296.828762 -311.847136) (xy 296.858327 -311.88648)
			(xy 296.881198 -311.930057) (xy 296.896782 -311.976738) (xy 296.904677 -312.025315) (xy 296.905172 -312.049922)
			(xy 298.19398 -312.049922) (xy 298.19794 -312.000868) (xy 298.209717 -311.953084) (xy 298.229008 -311.907808)
			(xy 298.255311 -311.866212) (xy 298.287946 -311.829375) (xy 298.326067 -311.79825) (xy 298.368688 -311.773643)
			(xy 298.414704 -311.756191) (xy 298.462923 -311.746347) (xy 298.512098 -311.744366) (xy 298.560953 -311.750298)
			(xy 298.608224 -311.76399) (xy 298.652686 -311.785088) (xy 298.693189 -311.813044) (xy 298.728682 -311.847136)
			(xy 298.758247 -311.88648) (xy 298.781118 -311.930057) (xy 298.796702 -311.976738) (xy 298.804597 -312.025315)
			(xy 298.805092 -312.049922) (xy 300.0939 -312.049922) (xy 300.09786 -312.000868) (xy 300.109637 -311.953084)
			(xy 300.128928 -311.907808) (xy 300.155231 -311.866212) (xy 300.187866 -311.829375) (xy 300.225987 -311.79825)
			(xy 300.268608 -311.773643) (xy 300.314624 -311.756191) (xy 300.362843 -311.746347) (xy 300.412018 -311.744366)
			(xy 300.460873 -311.750298) (xy 300.508144 -311.76399) (xy 300.552606 -311.785088) (xy 300.593109 -311.813044)
			(xy 300.628602 -311.847136) (xy 300.658167 -311.88648) (xy 300.681038 -311.930057) (xy 300.696622 -311.976738)
			(xy 300.704517 -312.025315) (xy 300.705012 -312.049922) (xy 301.994074 -312.049922) (xy 301.998034 -312.000868)
			(xy 302.009811 -311.953084) (xy 302.029102 -311.907808) (xy 302.055405 -311.866212) (xy 302.08804 -311.829375)
			(xy 302.126161 -311.79825) (xy 302.168782 -311.773643) (xy 302.214798 -311.756191) (xy 302.263017 -311.746347)
			(xy 302.312192 -311.744366) (xy 302.361047 -311.750298) (xy 302.408318 -311.76399) (xy 302.45278 -311.785088)
			(xy 302.493283 -311.813044) (xy 302.528776 -311.847136) (xy 302.558341 -311.88648) (xy 302.581212 -311.930057)
			(xy 302.596796 -311.976738) (xy 302.604691 -312.025315) (xy 302.605186 -312.049922) (xy 303.893994 -312.049922)
			(xy 303.897954 -312.000868) (xy 303.909731 -311.953084) (xy 303.929022 -311.907808) (xy 303.955325 -311.866212)
			(xy 303.98796 -311.829375) (xy 304.026081 -311.79825) (xy 304.068702 -311.773643) (xy 304.114718 -311.756191)
			(xy 304.162937 -311.746347) (xy 304.212112 -311.744366) (xy 304.260967 -311.750298) (xy 304.308238 -311.76399)
			(xy 304.3527 -311.785088) (xy 304.393203 -311.813044) (xy 304.428696 -311.847136) (xy 304.458261 -311.88648)
			(xy 304.481132 -311.930057) (xy 304.496716 -311.976738) (xy 304.504611 -312.025315) (xy 304.505106 -312.049922)
			(xy 305.793914 -312.049922) (xy 305.797874 -312.000868) (xy 305.809651 -311.953084) (xy 305.828942 -311.907808)
			(xy 305.855245 -311.866212) (xy 305.88788 -311.829375) (xy 305.926001 -311.79825) (xy 305.968622 -311.773643)
			(xy 306.014638 -311.756191) (xy 306.062857 -311.746347) (xy 306.112032 -311.744366) (xy 306.160887 -311.750298)
			(xy 306.208158 -311.76399) (xy 306.25262 -311.785088) (xy 306.293123 -311.813044) (xy 306.328616 -311.847136)
			(xy 306.358181 -311.88648) (xy 306.381052 -311.930057) (xy 306.396636 -311.976738) (xy 306.404531 -312.025315)
			(xy 306.405026 -312.049922) (xy 307.694088 -312.049922) (xy 307.698048 -312.000868) (xy 307.709825 -311.953084)
			(xy 307.729116 -311.907808) (xy 307.755419 -311.866212) (xy 307.788054 -311.829375) (xy 307.826175 -311.79825)
			(xy 307.868796 -311.773643) (xy 307.914812 -311.756191) (xy 307.963031 -311.746347) (xy 308.012206 -311.744366)
			(xy 308.061061 -311.750298) (xy 308.108332 -311.76399) (xy 308.152794 -311.785088) (xy 308.193297 -311.813044)
			(xy 308.22879 -311.847136) (xy 308.258355 -311.88648) (xy 308.281226 -311.930057) (xy 308.29681 -311.976738)
			(xy 308.304705 -312.025315) (xy 308.3052 -312.049922) (xy 309.594008 -312.049922) (xy 309.597968 -312.000868)
			(xy 309.609745 -311.953084) (xy 309.629036 -311.907808) (xy 309.655339 -311.866212) (xy 309.687974 -311.829375)
			(xy 309.726095 -311.79825) (xy 309.768716 -311.773643) (xy 309.814732 -311.756191) (xy 309.862951 -311.746347)
			(xy 309.912126 -311.744366) (xy 309.960981 -311.750298) (xy 310.008252 -311.76399) (xy 310.052714 -311.785088)
			(xy 310.093217 -311.813044) (xy 310.12871 -311.847136) (xy 310.158275 -311.88648) (xy 310.181146 -311.930057)
			(xy 310.19673 -311.976738) (xy 310.204625 -312.025315) (xy 310.20512 -312.049922) (xy 311.493928 -312.049922)
			(xy 311.497888 -312.000868) (xy 311.509665 -311.953084) (xy 311.528956 -311.907808) (xy 311.555259 -311.866212)
			(xy 311.587894 -311.829375) (xy 311.626015 -311.79825) (xy 311.668636 -311.773643) (xy 311.714652 -311.756191)
			(xy 311.762871 -311.746347) (xy 311.812046 -311.744366) (xy 311.860901 -311.750298) (xy 311.908172 -311.76399)
			(xy 311.952634 -311.785088) (xy 311.993137 -311.813044) (xy 312.02863 -311.847136) (xy 312.058195 -311.88648)
			(xy 312.081066 -311.930057) (xy 312.09665 -311.976738) (xy 312.104545 -312.025315) (xy 312.10504 -312.049922)
			(xy 313.394102 -312.049922) (xy 313.398062 -312.000868) (xy 313.409839 -311.953084) (xy 313.42913 -311.907808)
			(xy 313.455433 -311.866212) (xy 313.488068 -311.829375) (xy 313.526189 -311.79825) (xy 313.56881 -311.773643)
			(xy 313.614826 -311.756191) (xy 313.663045 -311.746347) (xy 313.71222 -311.744366) (xy 313.761075 -311.750298)
			(xy 313.808346 -311.76399) (xy 313.852808 -311.785088) (xy 313.893311 -311.813044) (xy 313.928804 -311.847136)
			(xy 313.958369 -311.88648) (xy 313.98124 -311.930057) (xy 313.996824 -311.976738) (xy 314.004719 -312.025315)
			(xy 314.005214 -312.049922) (xy 314.344062 -312.049922) (xy 314.348022 -312.000868) (xy 314.359799 -311.953084)
			(xy 314.37909 -311.907808) (xy 314.405393 -311.866212) (xy 314.438028 -311.829375) (xy 314.476149 -311.79825)
			(xy 314.51877 -311.773643) (xy 314.564786 -311.756191) (xy 314.613005 -311.746347) (xy 314.66218 -311.744366)
			(xy 314.711035 -311.750298) (xy 314.758306 -311.76399) (xy 314.802768 -311.785088) (xy 314.843271 -311.813044)
			(xy 314.878764 -311.847136) (xy 314.908329 -311.88648) (xy 314.9312 -311.930057) (xy 314.946784 -311.976738)
			(xy 314.954679 -312.025315) (xy 314.955174 -312.049922) (xy 384.844048 -312.049922) (xy 384.848008 -312.000868)
			(xy 384.859785 -311.953084) (xy 384.879076 -311.907808) (xy 384.905379 -311.866212) (xy 384.938014 -311.829375)
			(xy 384.976135 -311.79825) (xy 385.018756 -311.773643) (xy 385.064772 -311.756191) (xy 385.112991 -311.746347)
			(xy 385.162166 -311.744366) (xy 385.211021 -311.750298) (xy 385.258292 -311.76399) (xy 385.302754 -311.785088)
			(xy 385.343257 -311.813044) (xy 385.37875 -311.847136) (xy 385.408315 -311.88648) (xy 385.431186 -311.930057)
			(xy 385.44677 -311.976738) (xy 385.454665 -312.025315) (xy 385.45516 -312.049922) (xy 385.794008 -312.049922)
			(xy 385.797968 -312.000868) (xy 385.809745 -311.953084) (xy 385.829036 -311.907808) (xy 385.855339 -311.866212)
			(xy 385.887974 -311.829375) (xy 385.926095 -311.79825) (xy 385.968716 -311.773643) (xy 386.014732 -311.756191)
			(xy 386.062951 -311.746347) (xy 386.112126 -311.744366) (xy 386.160981 -311.750298) (xy 386.208252 -311.76399)
			(xy 386.252714 -311.785088) (xy 386.293217 -311.813044) (xy 386.32871 -311.847136) (xy 386.358275 -311.88648)
			(xy 386.381146 -311.930057) (xy 386.39673 -311.976738) (xy 386.404625 -312.025315) (xy 386.40512 -312.049922)
			(xy 387.694182 -312.049922) (xy 387.698142 -312.000868) (xy 387.709919 -311.953084) (xy 387.72921 -311.907808)
			(xy 387.755513 -311.866212) (xy 387.788148 -311.829375) (xy 387.826269 -311.79825) (xy 387.86889 -311.773643)
			(xy 387.914906 -311.756191) (xy 387.963125 -311.746347) (xy 388.0123 -311.744366) (xy 388.061155 -311.750298)
			(xy 388.108426 -311.76399) (xy 388.152888 -311.785088) (xy 388.193391 -311.813044) (xy 388.228884 -311.847136)
			(xy 388.258449 -311.88648) (xy 388.28132 -311.930057) (xy 388.296904 -311.976738) (xy 388.304799 -312.025315)
			(xy 388.305294 -312.049922) (xy 389.594102 -312.049922) (xy 389.598062 -312.000868) (xy 389.609839 -311.953084)
			(xy 389.62913 -311.907808) (xy 389.655433 -311.866212) (xy 389.688068 -311.829375) (xy 389.726189 -311.79825)
			(xy 389.76881 -311.773643) (xy 389.814826 -311.756191) (xy 389.863045 -311.746347) (xy 389.91222 -311.744366)
			(xy 389.961075 -311.750298) (xy 390.008346 -311.76399) (xy 390.052808 -311.785088) (xy 390.093311 -311.813044)
			(xy 390.128804 -311.847136) (xy 390.158369 -311.88648) (xy 390.18124 -311.930057) (xy 390.196824 -311.976738)
			(xy 390.204719 -312.025315) (xy 390.205214 -312.049922) (xy 391.494022 -312.049922) (xy 391.497982 -312.000868)
			(xy 391.509759 -311.953084) (xy 391.52905 -311.907808) (xy 391.555353 -311.866212) (xy 391.587988 -311.829375)
			(xy 391.626109 -311.79825) (xy 391.66873 -311.773643) (xy 391.714746 -311.756191) (xy 391.762965 -311.746347)
			(xy 391.81214 -311.744366) (xy 391.860995 -311.750298) (xy 391.908266 -311.76399) (xy 391.952728 -311.785088)
			(xy 391.993231 -311.813044) (xy 392.028724 -311.847136) (xy 392.058289 -311.88648) (xy 392.08116 -311.930057)
			(xy 392.096744 -311.976738) (xy 392.104639 -312.025315) (xy 392.105134 -312.049922) (xy 393.394196 -312.049922)
			(xy 393.398156 -312.000868) (xy 393.409933 -311.953084) (xy 393.429224 -311.907808) (xy 393.455527 -311.866212)
			(xy 393.488162 -311.829375) (xy 393.526283 -311.79825) (xy 393.568904 -311.773643) (xy 393.61492 -311.756191)
			(xy 393.663139 -311.746347) (xy 393.712314 -311.744366) (xy 393.761169 -311.750298) (xy 393.80844 -311.76399)
			(xy 393.852902 -311.785088) (xy 393.893405 -311.813044) (xy 393.928898 -311.847136) (xy 393.958463 -311.88648)
			(xy 393.981334 -311.930057) (xy 393.996918 -311.976738) (xy 394.004813 -312.025315) (xy 394.005308 -312.049922)
			(xy 395.294116 -312.049922) (xy 395.298076 -312.000868) (xy 395.309853 -311.953084) (xy 395.329144 -311.907808)
			(xy 395.355447 -311.866212) (xy 395.388082 -311.829375) (xy 395.426203 -311.79825) (xy 395.468824 -311.773643)
			(xy 395.51484 -311.756191) (xy 395.563059 -311.746347) (xy 395.612234 -311.744366) (xy 395.661089 -311.750298)
			(xy 395.70836 -311.76399) (xy 395.752822 -311.785088) (xy 395.793325 -311.813044) (xy 395.828818 -311.847136)
			(xy 395.858383 -311.88648) (xy 395.881254 -311.930057) (xy 395.896838 -311.976738) (xy 395.904733 -312.025315)
			(xy 395.905228 -312.049922) (xy 397.194036 -312.049922) (xy 397.197996 -312.000868) (xy 397.209773 -311.953084)
			(xy 397.229064 -311.907808) (xy 397.255367 -311.866212) (xy 397.288002 -311.829375) (xy 397.326123 -311.79825)
			(xy 397.368744 -311.773643) (xy 397.41476 -311.756191) (xy 397.462979 -311.746347) (xy 397.512154 -311.744366)
			(xy 397.561009 -311.750298) (xy 397.60828 -311.76399) (xy 397.652742 -311.785088) (xy 397.693245 -311.813044)
			(xy 397.728738 -311.847136) (xy 397.758303 -311.88648) (xy 397.781174 -311.930057) (xy 397.796758 -311.976738)
			(xy 397.804653 -312.025315) (xy 397.805148 -312.049922) (xy 399.09421 -312.049922) (xy 399.09817 -312.000868)
			(xy 399.109947 -311.953084) (xy 399.129238 -311.907808) (xy 399.155541 -311.866212) (xy 399.188176 -311.829375)
			(xy 399.226297 -311.79825) (xy 399.268918 -311.773643) (xy 399.314934 -311.756191) (xy 399.363153 -311.746347)
			(xy 399.412328 -311.744366) (xy 399.461183 -311.750298) (xy 399.508454 -311.76399) (xy 399.552916 -311.785088)
			(xy 399.593419 -311.813044) (xy 399.628912 -311.847136) (xy 399.658477 -311.88648) (xy 399.681348 -311.930057)
			(xy 399.696932 -311.976738) (xy 399.704827 -312.025315) (xy 399.705322 -312.049922) (xy 400.99413 -312.049922)
			(xy 400.99809 -312.000868) (xy 401.009867 -311.953084) (xy 401.029158 -311.907808) (xy 401.055461 -311.866212)
			(xy 401.088096 -311.829375) (xy 401.126217 -311.79825) (xy 401.168838 -311.773643) (xy 401.214854 -311.756191)
			(xy 401.263073 -311.746347) (xy 401.312248 -311.744366) (xy 401.361103 -311.750298) (xy 401.408374 -311.76399)
			(xy 401.452836 -311.785088) (xy 401.493339 -311.813044) (xy 401.528832 -311.847136) (xy 401.558397 -311.88648)
			(xy 401.581268 -311.930057) (xy 401.596852 -311.976738) (xy 401.604747 -312.025315) (xy 401.605242 -312.049922)
			(xy 402.89405 -312.049922) (xy 402.89801 -312.000868) (xy 402.909787 -311.953084) (xy 402.929078 -311.907808)
			(xy 402.955381 -311.866212) (xy 402.988016 -311.829375) (xy 403.026137 -311.79825) (xy 403.068758 -311.773643)
			(xy 403.114774 -311.756191) (xy 403.162993 -311.746347) (xy 403.212168 -311.744366) (xy 403.261023 -311.750298)
			(xy 403.308294 -311.76399) (xy 403.352756 -311.785088) (xy 403.393259 -311.813044) (xy 403.428752 -311.847136)
			(xy 403.458317 -311.88648) (xy 403.481188 -311.930057) (xy 403.496772 -311.976738) (xy 403.504667 -312.025315)
			(xy 403.505162 -312.049922) (xy 404.794224 -312.049922) (xy 404.798184 -312.000868) (xy 404.809961 -311.953084)
			(xy 404.829252 -311.907808) (xy 404.855555 -311.866212) (xy 404.88819 -311.829375) (xy 404.926311 -311.79825)
			(xy 404.968932 -311.773643) (xy 405.014948 -311.756191) (xy 405.063167 -311.746347) (xy 405.112342 -311.744366)
			(xy 405.161197 -311.750298) (xy 405.208468 -311.76399) (xy 405.25293 -311.785088) (xy 405.293433 -311.813044)
			(xy 405.328926 -311.847136) (xy 405.358491 -311.88648) (xy 405.381362 -311.930057) (xy 405.396946 -311.976738)
			(xy 405.404841 -312.025315) (xy 405.405336 -312.049922) (xy 406.694144 -312.049922) (xy 406.698104 -312.000868)
			(xy 406.709881 -311.953084) (xy 406.729172 -311.907808) (xy 406.755475 -311.866212) (xy 406.78811 -311.829375)
			(xy 406.826231 -311.79825) (xy 406.868852 -311.773643) (xy 406.914868 -311.756191) (xy 406.963087 -311.746347)
			(xy 407.012262 -311.744366) (xy 407.061117 -311.750298) (xy 407.108388 -311.76399) (xy 407.15285 -311.785088)
			(xy 407.193353 -311.813044) (xy 407.228846 -311.847136) (xy 407.258411 -311.88648) (xy 407.281282 -311.930057)
			(xy 407.296866 -311.976738) (xy 407.304761 -312.025315) (xy 407.305256 -312.049922) (xy 408.594064 -312.049922)
			(xy 408.598024 -312.000868) (xy 408.609801 -311.953084) (xy 408.629092 -311.907808) (xy 408.655395 -311.866212)
			(xy 408.68803 -311.829375) (xy 408.726151 -311.79825) (xy 408.768772 -311.773643) (xy 408.814788 -311.756191)
			(xy 408.863007 -311.746347) (xy 408.912182 -311.744366) (xy 408.961037 -311.750298) (xy 409.008308 -311.76399)
			(xy 409.05277 -311.785088) (xy 409.093273 -311.813044) (xy 409.128766 -311.847136) (xy 409.158331 -311.88648)
			(xy 409.181202 -311.930057) (xy 409.196786 -311.976738) (xy 409.204681 -312.025315) (xy 409.205176 -312.049922)
			(xy 410.493984 -312.049922) (xy 410.497944 -312.000868) (xy 410.509721 -311.953084) (xy 410.529012 -311.907808)
			(xy 410.555315 -311.866212) (xy 410.58795 -311.829375) (xy 410.626071 -311.79825) (xy 410.668692 -311.773643)
			(xy 410.714708 -311.756191) (xy 410.762927 -311.746347) (xy 410.812102 -311.744366) (xy 410.860957 -311.750298)
			(xy 410.908228 -311.76399) (xy 410.95269 -311.785088) (xy 410.993193 -311.813044) (xy 411.028686 -311.847136)
			(xy 411.058251 -311.88648) (xy 411.081122 -311.930057) (xy 411.096706 -311.976738) (xy 411.104601 -312.025315)
			(xy 411.105096 -312.049922) (xy 412.394158 -312.049922) (xy 412.398118 -312.000868) (xy 412.409895 -311.953084)
			(xy 412.429186 -311.907808) (xy 412.455489 -311.866212) (xy 412.488124 -311.829375) (xy 412.526245 -311.79825)
			(xy 412.568866 -311.773643) (xy 412.614882 -311.756191) (xy 412.663101 -311.746347) (xy 412.712276 -311.744366)
			(xy 412.761131 -311.750298) (xy 412.808402 -311.76399) (xy 412.852864 -311.785088) (xy 412.893367 -311.813044)
			(xy 412.92886 -311.847136) (xy 412.958425 -311.88648) (xy 412.981296 -311.930057) (xy 412.99688 -311.976738)
			(xy 413.004775 -312.025315) (xy 413.00527 -312.049922) (xy 414.294078 -312.049922) (xy 414.298038 -312.000868)
			(xy 414.309815 -311.953084) (xy 414.329106 -311.907808) (xy 414.355409 -311.866212) (xy 414.388044 -311.829375)
			(xy 414.426165 -311.79825) (xy 414.468786 -311.773643) (xy 414.514802 -311.756191) (xy 414.563021 -311.746347)
			(xy 414.612196 -311.744366) (xy 414.661051 -311.750298) (xy 414.708322 -311.76399) (xy 414.752784 -311.785088)
			(xy 414.793287 -311.813044) (xy 414.82878 -311.847136) (xy 414.858345 -311.88648) (xy 414.881216 -311.930057)
			(xy 414.8968 -311.976738) (xy 414.904695 -312.025315) (xy 414.90519 -312.049922) (xy 416.193998 -312.049922)
			(xy 416.197958 -312.000868) (xy 416.209735 -311.953084) (xy 416.229026 -311.907808) (xy 416.255329 -311.866212)
			(xy 416.287964 -311.829375) (xy 416.326085 -311.79825) (xy 416.368706 -311.773643) (xy 416.414722 -311.756191)
			(xy 416.462941 -311.746347) (xy 416.512116 -311.744366) (xy 416.560971 -311.750298) (xy 416.608242 -311.76399)
			(xy 416.652704 -311.785088) (xy 416.693207 -311.813044) (xy 416.7287 -311.847136) (xy 416.758265 -311.88648)
			(xy 416.781136 -311.930057) (xy 416.79672 -311.976738) (xy 416.804615 -312.025315) (xy 416.80511 -312.049922)
			(xy 418.094172 -312.049922) (xy 418.098132 -312.000868) (xy 418.109909 -311.953084) (xy 418.1292 -311.907808)
			(xy 418.155503 -311.866212) (xy 418.188138 -311.829375) (xy 418.226259 -311.79825) (xy 418.26888 -311.773643)
			(xy 418.314896 -311.756191) (xy 418.363115 -311.746347) (xy 418.41229 -311.744366) (xy 418.461145 -311.750298)
			(xy 418.508416 -311.76399) (xy 418.552878 -311.785088) (xy 418.593381 -311.813044) (xy 418.628874 -311.847136)
			(xy 418.658439 -311.88648) (xy 418.68131 -311.930057) (xy 418.696894 -311.976738) (xy 418.704789 -312.025315)
			(xy 418.705284 -312.049922) (xy 419.994092 -312.049922) (xy 419.998052 -312.000868) (xy 420.009829 -311.953084)
			(xy 420.02912 -311.907808) (xy 420.055423 -311.866212) (xy 420.088058 -311.829375) (xy 420.126179 -311.79825)
			(xy 420.1688 -311.773643) (xy 420.214816 -311.756191) (xy 420.263035 -311.746347) (xy 420.31221 -311.744366)
			(xy 420.361065 -311.750298) (xy 420.408336 -311.76399) (xy 420.452798 -311.785088) (xy 420.493301 -311.813044)
			(xy 420.528794 -311.847136) (xy 420.558359 -311.88648) (xy 420.58123 -311.930057) (xy 420.596814 -311.976738)
			(xy 420.604709 -312.025315) (xy 420.605204 -312.049922) (xy 421.894012 -312.049922) (xy 421.897972 -312.000868)
			(xy 421.909749 -311.953084) (xy 421.92904 -311.907808) (xy 421.955343 -311.866212) (xy 421.987978 -311.829375)
			(xy 422.026099 -311.79825) (xy 422.06872 -311.773643) (xy 422.114736 -311.756191) (xy 422.162955 -311.746347)
			(xy 422.21213 -311.744366) (xy 422.260985 -311.750298) (xy 422.308256 -311.76399) (xy 422.352718 -311.785088)
			(xy 422.393221 -311.813044) (xy 422.428714 -311.847136) (xy 422.458279 -311.88648) (xy 422.48115 -311.930057)
			(xy 422.496734 -311.976738) (xy 422.504629 -312.025315) (xy 422.505124 -312.049922) (xy 423.794186 -312.049922)
			(xy 423.798146 -312.000868) (xy 423.809923 -311.953084) (xy 423.829214 -311.907808) (xy 423.855517 -311.866212)
			(xy 423.888152 -311.829375) (xy 423.926273 -311.79825) (xy 423.968894 -311.773643) (xy 424.01491 -311.756191)
			(xy 424.063129 -311.746347) (xy 424.112304 -311.744366) (xy 424.161159 -311.750298) (xy 424.20843 -311.76399)
			(xy 424.252892 -311.785088) (xy 424.293395 -311.813044) (xy 424.328888 -311.847136) (xy 424.358453 -311.88648)
			(xy 424.381324 -311.930057) (xy 424.396908 -311.976738) (xy 424.404803 -312.025315) (xy 424.405298 -312.049922)
			(xy 425.694106 -312.049922) (xy 425.698066 -312.000868) (xy 425.709843 -311.953084) (xy 425.729134 -311.907808)
			(xy 425.755437 -311.866212) (xy 425.788072 -311.829375) (xy 425.826193 -311.79825) (xy 425.868814 -311.773643)
			(xy 425.91483 -311.756191) (xy 425.963049 -311.746347) (xy 426.012224 -311.744366) (xy 426.061079 -311.750298)
			(xy 426.10835 -311.76399) (xy 426.152812 -311.785088) (xy 426.193315 -311.813044) (xy 426.228808 -311.847136)
			(xy 426.258373 -311.88648) (xy 426.281244 -311.930057) (xy 426.296828 -311.976738) (xy 426.304723 -312.025315)
			(xy 426.305218 -312.049922) (xy 427.594026 -312.049922) (xy 427.597986 -312.000868) (xy 427.609763 -311.953084)
			(xy 427.629054 -311.907808) (xy 427.655357 -311.866212) (xy 427.687992 -311.829375) (xy 427.726113 -311.79825)
			(xy 427.768734 -311.773643) (xy 427.81475 -311.756191) (xy 427.862969 -311.746347) (xy 427.912144 -311.744366)
			(xy 427.960999 -311.750298) (xy 428.00827 -311.76399) (xy 428.052732 -311.785088) (xy 428.093235 -311.813044)
			(xy 428.128728 -311.847136) (xy 428.158293 -311.88648) (xy 428.181164 -311.930057) (xy 428.196748 -311.976738)
			(xy 428.204643 -312.025315) (xy 428.205138 -312.049922) (xy 429.4942 -312.049922) (xy 429.49816 -312.000868)
			(xy 429.509937 -311.953084) (xy 429.529228 -311.907808) (xy 429.555531 -311.866212) (xy 429.588166 -311.829375)
			(xy 429.626287 -311.79825) (xy 429.668908 -311.773643) (xy 429.714924 -311.756191) (xy 429.763143 -311.746347)
			(xy 429.812318 -311.744366) (xy 429.861173 -311.750298) (xy 429.908444 -311.76399) (xy 429.952906 -311.785088)
			(xy 429.993409 -311.813044) (xy 430.028902 -311.847136) (xy 430.058467 -311.88648) (xy 430.081338 -311.930057)
			(xy 430.096922 -311.976738) (xy 430.104817 -312.025315) (xy 430.105312 -312.049922) (xy 430.44416 -312.049922)
			(xy 430.44812 -312.000868) (xy 430.459897 -311.953084) (xy 430.479188 -311.907808) (xy 430.505491 -311.866212)
			(xy 430.538126 -311.829375) (xy 430.576247 -311.79825) (xy 430.618868 -311.773643) (xy 430.664884 -311.756191)
			(xy 430.713103 -311.746347) (xy 430.762278 -311.744366) (xy 430.811133 -311.750298) (xy 430.858404 -311.76399)
			(xy 430.902866 -311.785088) (xy 430.943369 -311.813044) (xy 430.978862 -311.847136) (xy 431.008427 -311.88648)
			(xy 431.031298 -311.930057) (xy 431.046882 -311.976738) (xy 431.054777 -312.025315) (xy 431.055272 -312.049922)
			(xy 431.054777 -312.074529) (xy 431.046882 -312.123106) (xy 431.031298 -312.169787) (xy 431.008427 -312.213364)
			(xy 430.978862 -312.252708) (xy 430.943369 -312.2868) (xy 430.902866 -312.314756) (xy 430.858404 -312.335854)
			(xy 430.811133 -312.349546) (xy 430.762278 -312.355478) (xy 430.713103 -312.353497) (xy 430.664884 -312.343653)
			(xy 430.618868 -312.326201) (xy 430.576247 -312.301594) (xy 430.538126 -312.270469) (xy 430.505491 -312.233632)
			(xy 430.479188 -312.192036) (xy 430.459897 -312.14676) (xy 430.44812 -312.098976) (xy 430.44416 -312.049922)
			(xy 430.105312 -312.049922) (xy 430.104817 -312.074529) (xy 430.096922 -312.123106) (xy 430.081338 -312.169787)
			(xy 430.058467 -312.213364) (xy 430.028902 -312.252708) (xy 429.993409 -312.2868) (xy 429.952906 -312.314756)
			(xy 429.908444 -312.335854) (xy 429.861173 -312.349546) (xy 429.812318 -312.355478) (xy 429.763143 -312.353497)
			(xy 429.714924 -312.343653) (xy 429.668908 -312.326201) (xy 429.626287 -312.301594) (xy 429.588166 -312.270469)
			(xy 429.555531 -312.233632) (xy 429.529228 -312.192036) (xy 429.509937 -312.14676) (xy 429.49816 -312.098976)
			(xy 429.4942 -312.049922) (xy 428.205138 -312.049922) (xy 428.204643 -312.074529) (xy 428.196748 -312.123106)
			(xy 428.181164 -312.169787) (xy 428.158293 -312.213364) (xy 428.128728 -312.252708) (xy 428.093235 -312.2868)
			(xy 428.052732 -312.314756) (xy 428.00827 -312.335854) (xy 427.960999 -312.349546) (xy 427.912144 -312.355478)
			(xy 427.862969 -312.353497) (xy 427.81475 -312.343653) (xy 427.768734 -312.326201) (xy 427.726113 -312.301594)
			(xy 427.687992 -312.270469) (xy 427.655357 -312.233632) (xy 427.629054 -312.192036) (xy 427.609763 -312.14676)
			(xy 427.597986 -312.098976) (xy 427.594026 -312.049922) (xy 426.305218 -312.049922) (xy 426.304723 -312.074529)
			(xy 426.296828 -312.123106) (xy 426.281244 -312.169787) (xy 426.258373 -312.213364) (xy 426.228808 -312.252708)
			(xy 426.193315 -312.2868) (xy 426.152812 -312.314756) (xy 426.10835 -312.335854) (xy 426.061079 -312.349546)
			(xy 426.012224 -312.355478) (xy 425.963049 -312.353497) (xy 425.91483 -312.343653) (xy 425.868814 -312.326201)
			(xy 425.826193 -312.301594) (xy 425.788072 -312.270469) (xy 425.755437 -312.233632) (xy 425.729134 -312.192036)
			(xy 425.709843 -312.14676) (xy 425.698066 -312.098976) (xy 425.694106 -312.049922) (xy 424.405298 -312.049922)
			(xy 424.404803 -312.074529) (xy 424.396908 -312.123106) (xy 424.381324 -312.169787) (xy 424.358453 -312.213364)
			(xy 424.328888 -312.252708) (xy 424.293395 -312.2868) (xy 424.252892 -312.314756) (xy 424.20843 -312.335854)
			(xy 424.161159 -312.349546) (xy 424.112304 -312.355478) (xy 424.063129 -312.353497) (xy 424.01491 -312.343653)
			(xy 423.968894 -312.326201) (xy 423.926273 -312.301594) (xy 423.888152 -312.270469) (xy 423.855517 -312.233632)
			(xy 423.829214 -312.192036) (xy 423.809923 -312.14676) (xy 423.798146 -312.098976) (xy 423.794186 -312.049922)
			(xy 422.505124 -312.049922) (xy 422.504629 -312.074529) (xy 422.496734 -312.123106) (xy 422.48115 -312.169787)
			(xy 422.458279 -312.213364) (xy 422.428714 -312.252708) (xy 422.393221 -312.2868) (xy 422.352718 -312.314756)
			(xy 422.308256 -312.335854) (xy 422.260985 -312.349546) (xy 422.21213 -312.355478) (xy 422.162955 -312.353497)
			(xy 422.114736 -312.343653) (xy 422.06872 -312.326201) (xy 422.026099 -312.301594) (xy 421.987978 -312.270469)
			(xy 421.955343 -312.233632) (xy 421.92904 -312.192036) (xy 421.909749 -312.14676) (xy 421.897972 -312.098976)
			(xy 421.894012 -312.049922) (xy 420.605204 -312.049922) (xy 420.604709 -312.074529) (xy 420.596814 -312.123106)
			(xy 420.58123 -312.169787) (xy 420.558359 -312.213364) (xy 420.528794 -312.252708) (xy 420.493301 -312.2868)
			(xy 420.452798 -312.314756) (xy 420.408336 -312.335854) (xy 420.361065 -312.349546) (xy 420.31221 -312.355478)
			(xy 420.263035 -312.353497) (xy 420.214816 -312.343653) (xy 420.1688 -312.326201) (xy 420.126179 -312.301594)
			(xy 420.088058 -312.270469) (xy 420.055423 -312.233632) (xy 420.02912 -312.192036) (xy 420.009829 -312.14676)
			(xy 419.998052 -312.098976) (xy 419.994092 -312.049922) (xy 418.705284 -312.049922) (xy 418.704789 -312.074529)
			(xy 418.696894 -312.123106) (xy 418.68131 -312.169787) (xy 418.658439 -312.213364) (xy 418.628874 -312.252708)
			(xy 418.593381 -312.2868) (xy 418.552878 -312.314756) (xy 418.508416 -312.335854) (xy 418.461145 -312.349546)
			(xy 418.41229 -312.355478) (xy 418.363115 -312.353497) (xy 418.314896 -312.343653) (xy 418.26888 -312.326201)
			(xy 418.226259 -312.301594) (xy 418.188138 -312.270469) (xy 418.155503 -312.233632) (xy 418.1292 -312.192036)
			(xy 418.109909 -312.14676) (xy 418.098132 -312.098976) (xy 418.094172 -312.049922) (xy 416.80511 -312.049922)
			(xy 416.804615 -312.074529) (xy 416.79672 -312.123106) (xy 416.781136 -312.169787) (xy 416.758265 -312.213364)
			(xy 416.7287 -312.252708) (xy 416.693207 -312.2868) (xy 416.652704 -312.314756) (xy 416.608242 -312.335854)
			(xy 416.560971 -312.349546) (xy 416.512116 -312.355478) (xy 416.462941 -312.353497) (xy 416.414722 -312.343653)
			(xy 416.368706 -312.326201) (xy 416.326085 -312.301594) (xy 416.287964 -312.270469) (xy 416.255329 -312.233632)
			(xy 416.229026 -312.192036) (xy 416.209735 -312.14676) (xy 416.197958 -312.098976) (xy 416.193998 -312.049922)
			(xy 414.90519 -312.049922) (xy 414.904695 -312.074529) (xy 414.8968 -312.123106) (xy 414.881216 -312.169787)
			(xy 414.858345 -312.213364) (xy 414.82878 -312.252708) (xy 414.793287 -312.2868) (xy 414.752784 -312.314756)
			(xy 414.708322 -312.335854) (xy 414.661051 -312.349546) (xy 414.612196 -312.355478) (xy 414.563021 -312.353497)
			(xy 414.514802 -312.343653) (xy 414.468786 -312.326201) (xy 414.426165 -312.301594) (xy 414.388044 -312.270469)
			(xy 414.355409 -312.233632) (xy 414.329106 -312.192036) (xy 414.309815 -312.14676) (xy 414.298038 -312.098976)
			(xy 414.294078 -312.049922) (xy 413.00527 -312.049922) (xy 413.004775 -312.074529) (xy 412.99688 -312.123106)
			(xy 412.981296 -312.169787) (xy 412.958425 -312.213364) (xy 412.92886 -312.252708) (xy 412.893367 -312.2868)
			(xy 412.852864 -312.314756) (xy 412.808402 -312.335854) (xy 412.761131 -312.349546) (xy 412.712276 -312.355478)
			(xy 412.663101 -312.353497) (xy 412.614882 -312.343653) (xy 412.568866 -312.326201) (xy 412.526245 -312.301594)
			(xy 412.488124 -312.270469) (xy 412.455489 -312.233632) (xy 412.429186 -312.192036) (xy 412.409895 -312.14676)
			(xy 412.398118 -312.098976) (xy 412.394158 -312.049922) (xy 411.105096 -312.049922) (xy 411.104601 -312.074529)
			(xy 411.096706 -312.123106) (xy 411.081122 -312.169787) (xy 411.058251 -312.213364) (xy 411.028686 -312.252708)
			(xy 410.993193 -312.2868) (xy 410.95269 -312.314756) (xy 410.908228 -312.335854) (xy 410.860957 -312.349546)
			(xy 410.812102 -312.355478) (xy 410.762927 -312.353497) (xy 410.714708 -312.343653) (xy 410.668692 -312.326201)
			(xy 410.626071 -312.301594) (xy 410.58795 -312.270469) (xy 410.555315 -312.233632) (xy 410.529012 -312.192036)
			(xy 410.509721 -312.14676) (xy 410.497944 -312.098976) (xy 410.493984 -312.049922) (xy 409.205176 -312.049922)
			(xy 409.204681 -312.074529) (xy 409.196786 -312.123106) (xy 409.181202 -312.169787) (xy 409.158331 -312.213364)
			(xy 409.128766 -312.252708) (xy 409.093273 -312.2868) (xy 409.05277 -312.314756) (xy 409.008308 -312.335854)
			(xy 408.961037 -312.349546) (xy 408.912182 -312.355478) (xy 408.863007 -312.353497) (xy 408.814788 -312.343653)
			(xy 408.768772 -312.326201) (xy 408.726151 -312.301594) (xy 408.68803 -312.270469) (xy 408.655395 -312.233632)
			(xy 408.629092 -312.192036) (xy 408.609801 -312.14676) (xy 408.598024 -312.098976) (xy 408.594064 -312.049922)
			(xy 407.305256 -312.049922) (xy 407.304761 -312.074529) (xy 407.296866 -312.123106) (xy 407.281282 -312.169787)
			(xy 407.258411 -312.213364) (xy 407.228846 -312.252708) (xy 407.193353 -312.2868) (xy 407.15285 -312.314756)
			(xy 407.108388 -312.335854) (xy 407.061117 -312.349546) (xy 407.012262 -312.355478) (xy 406.963087 -312.353497)
			(xy 406.914868 -312.343653) (xy 406.868852 -312.326201) (xy 406.826231 -312.301594) (xy 406.78811 -312.270469)
			(xy 406.755475 -312.233632) (xy 406.729172 -312.192036) (xy 406.709881 -312.14676) (xy 406.698104 -312.098976)
			(xy 406.694144 -312.049922) (xy 405.405336 -312.049922) (xy 405.404841 -312.074529) (xy 405.396946 -312.123106)
			(xy 405.381362 -312.169787) (xy 405.358491 -312.213364) (xy 405.328926 -312.252708) (xy 405.293433 -312.2868)
			(xy 405.25293 -312.314756) (xy 405.208468 -312.335854) (xy 405.161197 -312.349546) (xy 405.112342 -312.355478)
			(xy 405.063167 -312.353497) (xy 405.014948 -312.343653) (xy 404.968932 -312.326201) (xy 404.926311 -312.301594)
			(xy 404.88819 -312.270469) (xy 404.855555 -312.233632) (xy 404.829252 -312.192036) (xy 404.809961 -312.14676)
			(xy 404.798184 -312.098976) (xy 404.794224 -312.049922) (xy 403.505162 -312.049922) (xy 403.504667 -312.074529)
			(xy 403.496772 -312.123106) (xy 403.481188 -312.169787) (xy 403.458317 -312.213364) (xy 403.428752 -312.252708)
			(xy 403.393259 -312.2868) (xy 403.352756 -312.314756) (xy 403.308294 -312.335854) (xy 403.261023 -312.349546)
			(xy 403.212168 -312.355478) (xy 403.162993 -312.353497) (xy 403.114774 -312.343653) (xy 403.068758 -312.326201)
			(xy 403.026137 -312.301594) (xy 402.988016 -312.270469) (xy 402.955381 -312.233632) (xy 402.929078 -312.192036)
			(xy 402.909787 -312.14676) (xy 402.89801 -312.098976) (xy 402.89405 -312.049922) (xy 401.605242 -312.049922)
			(xy 401.604747 -312.074529) (xy 401.596852 -312.123106) (xy 401.581268 -312.169787) (xy 401.558397 -312.213364)
			(xy 401.528832 -312.252708) (xy 401.493339 -312.2868) (xy 401.452836 -312.314756) (xy 401.408374 -312.335854)
			(xy 401.361103 -312.349546) (xy 401.312248 -312.355478) (xy 401.263073 -312.353497) (xy 401.214854 -312.343653)
			(xy 401.168838 -312.326201) (xy 401.126217 -312.301594) (xy 401.088096 -312.270469) (xy 401.055461 -312.233632)
			(xy 401.029158 -312.192036) (xy 401.009867 -312.14676) (xy 400.99809 -312.098976) (xy 400.99413 -312.049922)
			(xy 399.705322 -312.049922) (xy 399.704827 -312.074529) (xy 399.696932 -312.123106) (xy 399.681348 -312.169787)
			(xy 399.658477 -312.213364) (xy 399.628912 -312.252708) (xy 399.593419 -312.2868) (xy 399.552916 -312.314756)
			(xy 399.508454 -312.335854) (xy 399.461183 -312.349546) (xy 399.412328 -312.355478) (xy 399.363153 -312.353497)
			(xy 399.314934 -312.343653) (xy 399.268918 -312.326201) (xy 399.226297 -312.301594) (xy 399.188176 -312.270469)
			(xy 399.155541 -312.233632) (xy 399.129238 -312.192036) (xy 399.109947 -312.14676) (xy 399.09817 -312.098976)
			(xy 399.09421 -312.049922) (xy 397.805148 -312.049922) (xy 397.804653 -312.074529) (xy 397.796758 -312.123106)
			(xy 397.781174 -312.169787) (xy 397.758303 -312.213364) (xy 397.728738 -312.252708) (xy 397.693245 -312.2868)
			(xy 397.652742 -312.314756) (xy 397.60828 -312.335854) (xy 397.561009 -312.349546) (xy 397.512154 -312.355478)
			(xy 397.462979 -312.353497) (xy 397.41476 -312.343653) (xy 397.368744 -312.326201) (xy 397.326123 -312.301594)
			(xy 397.288002 -312.270469) (xy 397.255367 -312.233632) (xy 397.229064 -312.192036) (xy 397.209773 -312.14676)
			(xy 397.197996 -312.098976) (xy 397.194036 -312.049922) (xy 395.905228 -312.049922) (xy 395.904733 -312.074529)
			(xy 395.896838 -312.123106) (xy 395.881254 -312.169787) (xy 395.858383 -312.213364) (xy 395.828818 -312.252708)
			(xy 395.793325 -312.2868) (xy 395.752822 -312.314756) (xy 395.70836 -312.335854) (xy 395.661089 -312.349546)
			(xy 395.612234 -312.355478) (xy 395.563059 -312.353497) (xy 395.51484 -312.343653) (xy 395.468824 -312.326201)
			(xy 395.426203 -312.301594) (xy 395.388082 -312.270469) (xy 395.355447 -312.233632) (xy 395.329144 -312.192036)
			(xy 395.309853 -312.14676) (xy 395.298076 -312.098976) (xy 395.294116 -312.049922) (xy 394.005308 -312.049922)
			(xy 394.004813 -312.074529) (xy 393.996918 -312.123106) (xy 393.981334 -312.169787) (xy 393.958463 -312.213364)
			(xy 393.928898 -312.252708) (xy 393.893405 -312.2868) (xy 393.852902 -312.314756) (xy 393.80844 -312.335854)
			(xy 393.761169 -312.349546) (xy 393.712314 -312.355478) (xy 393.663139 -312.353497) (xy 393.61492 -312.343653)
			(xy 393.568904 -312.326201) (xy 393.526283 -312.301594) (xy 393.488162 -312.270469) (xy 393.455527 -312.233632)
			(xy 393.429224 -312.192036) (xy 393.409933 -312.14676) (xy 393.398156 -312.098976) (xy 393.394196 -312.049922)
			(xy 392.105134 -312.049922) (xy 392.104639 -312.074529) (xy 392.096744 -312.123106) (xy 392.08116 -312.169787)
			(xy 392.058289 -312.213364) (xy 392.028724 -312.252708) (xy 391.993231 -312.2868) (xy 391.952728 -312.314756)
			(xy 391.908266 -312.335854) (xy 391.860995 -312.349546) (xy 391.81214 -312.355478) (xy 391.762965 -312.353497)
			(xy 391.714746 -312.343653) (xy 391.66873 -312.326201) (xy 391.626109 -312.301594) (xy 391.587988 -312.270469)
			(xy 391.555353 -312.233632) (xy 391.52905 -312.192036) (xy 391.509759 -312.14676) (xy 391.497982 -312.098976)
			(xy 391.494022 -312.049922) (xy 390.205214 -312.049922) (xy 390.204719 -312.074529) (xy 390.196824 -312.123106)
			(xy 390.18124 -312.169787) (xy 390.158369 -312.213364) (xy 390.128804 -312.252708) (xy 390.093311 -312.2868)
			(xy 390.052808 -312.314756) (xy 390.008346 -312.335854) (xy 389.961075 -312.349546) (xy 389.91222 -312.355478)
			(xy 389.863045 -312.353497) (xy 389.814826 -312.343653) (xy 389.76881 -312.326201) (xy 389.726189 -312.301594)
			(xy 389.688068 -312.270469) (xy 389.655433 -312.233632) (xy 389.62913 -312.192036) (xy 389.609839 -312.14676)
			(xy 389.598062 -312.098976) (xy 389.594102 -312.049922) (xy 388.305294 -312.049922) (xy 388.304799 -312.074529)
			(xy 388.296904 -312.123106) (xy 388.28132 -312.169787) (xy 388.258449 -312.213364) (xy 388.228884 -312.252708)
			(xy 388.193391 -312.2868) (xy 388.152888 -312.314756) (xy 388.108426 -312.335854) (xy 388.061155 -312.349546)
			(xy 388.0123 -312.355478) (xy 387.963125 -312.353497) (xy 387.914906 -312.343653) (xy 387.86889 -312.326201)
			(xy 387.826269 -312.301594) (xy 387.788148 -312.270469) (xy 387.755513 -312.233632) (xy 387.72921 -312.192036)
			(xy 387.709919 -312.14676) (xy 387.698142 -312.098976) (xy 387.694182 -312.049922) (xy 386.40512 -312.049922)
			(xy 386.404625 -312.074529) (xy 386.39673 -312.123106) (xy 386.381146 -312.169787) (xy 386.358275 -312.213364)
			(xy 386.32871 -312.252708) (xy 386.293217 -312.2868) (xy 386.252714 -312.314756) (xy 386.208252 -312.335854)
			(xy 386.160981 -312.349546) (xy 386.112126 -312.355478) (xy 386.062951 -312.353497) (xy 386.014732 -312.343653)
			(xy 385.968716 -312.326201) (xy 385.926095 -312.301594) (xy 385.887974 -312.270469) (xy 385.855339 -312.233632)
			(xy 385.829036 -312.192036) (xy 385.809745 -312.14676) (xy 385.797968 -312.098976) (xy 385.794008 -312.049922)
			(xy 385.45516 -312.049922) (xy 385.454665 -312.074529) (xy 385.44677 -312.123106) (xy 385.431186 -312.169787)
			(xy 385.408315 -312.213364) (xy 385.37875 -312.252708) (xy 385.343257 -312.2868) (xy 385.302754 -312.314756)
			(xy 385.258292 -312.335854) (xy 385.211021 -312.349546) (xy 385.162166 -312.355478) (xy 385.112991 -312.353497)
			(xy 385.064772 -312.343653) (xy 385.018756 -312.326201) (xy 384.976135 -312.301594) (xy 384.938014 -312.270469)
			(xy 384.905379 -312.233632) (xy 384.879076 -312.192036) (xy 384.859785 -312.14676) (xy 384.848008 -312.098976)
			(xy 384.844048 -312.049922) (xy 314.955174 -312.049922) (xy 314.954679 -312.074529) (xy 314.946784 -312.123106)
			(xy 314.9312 -312.169787) (xy 314.908329 -312.213364) (xy 314.878764 -312.252708) (xy 314.843271 -312.2868)
			(xy 314.802768 -312.314756) (xy 314.758306 -312.335854) (xy 314.711035 -312.349546) (xy 314.66218 -312.355478)
			(xy 314.613005 -312.353497) (xy 314.564786 -312.343653) (xy 314.51877 -312.326201) (xy 314.476149 -312.301594)
			(xy 314.438028 -312.270469) (xy 314.405393 -312.233632) (xy 314.37909 -312.192036) (xy 314.359799 -312.14676)
			(xy 314.348022 -312.098976) (xy 314.344062 -312.049922) (xy 314.005214 -312.049922) (xy 314.004719 -312.074529)
			(xy 313.996824 -312.123106) (xy 313.98124 -312.169787) (xy 313.958369 -312.213364) (xy 313.928804 -312.252708)
			(xy 313.893311 -312.2868) (xy 313.852808 -312.314756) (xy 313.808346 -312.335854) (xy 313.761075 -312.349546)
			(xy 313.71222 -312.355478) (xy 313.663045 -312.353497) (xy 313.614826 -312.343653) (xy 313.56881 -312.326201)
			(xy 313.526189 -312.301594) (xy 313.488068 -312.270469) (xy 313.455433 -312.233632) (xy 313.42913 -312.192036)
			(xy 313.409839 -312.14676) (xy 313.398062 -312.098976) (xy 313.394102 -312.049922) (xy 312.10504 -312.049922)
			(xy 312.104545 -312.074529) (xy 312.09665 -312.123106) (xy 312.081066 -312.169787) (xy 312.058195 -312.213364)
			(xy 312.02863 -312.252708) (xy 311.993137 -312.2868) (xy 311.952634 -312.314756) (xy 311.908172 -312.335854)
			(xy 311.860901 -312.349546) (xy 311.812046 -312.355478) (xy 311.762871 -312.353497) (xy 311.714652 -312.343653)
			(xy 311.668636 -312.326201) (xy 311.626015 -312.301594) (xy 311.587894 -312.270469) (xy 311.555259 -312.233632)
			(xy 311.528956 -312.192036) (xy 311.509665 -312.14676) (xy 311.497888 -312.098976) (xy 311.493928 -312.049922)
			(xy 310.20512 -312.049922) (xy 310.204625 -312.074529) (xy 310.19673 -312.123106) (xy 310.181146 -312.169787)
			(xy 310.158275 -312.213364) (xy 310.12871 -312.252708) (xy 310.093217 -312.2868) (xy 310.052714 -312.314756)
			(xy 310.008252 -312.335854) (xy 309.960981 -312.349546) (xy 309.912126 -312.355478) (xy 309.862951 -312.353497)
			(xy 309.814732 -312.343653) (xy 309.768716 -312.326201) (xy 309.726095 -312.301594) (xy 309.687974 -312.270469)
			(xy 309.655339 -312.233632) (xy 309.629036 -312.192036) (xy 309.609745 -312.14676) (xy 309.597968 -312.098976)
			(xy 309.594008 -312.049922) (xy 308.3052 -312.049922) (xy 308.304705 -312.074529) (xy 308.29681 -312.123106)
			(xy 308.281226 -312.169787) (xy 308.258355 -312.213364) (xy 308.22879 -312.252708) (xy 308.193297 -312.2868)
			(xy 308.152794 -312.314756) (xy 308.108332 -312.335854) (xy 308.061061 -312.349546) (xy 308.012206 -312.355478)
			(xy 307.963031 -312.353497) (xy 307.914812 -312.343653) (xy 307.868796 -312.326201) (xy 307.826175 -312.301594)
			(xy 307.788054 -312.270469) (xy 307.755419 -312.233632) (xy 307.729116 -312.192036) (xy 307.709825 -312.14676)
			(xy 307.698048 -312.098976) (xy 307.694088 -312.049922) (xy 306.405026 -312.049922) (xy 306.404531 -312.074529)
			(xy 306.396636 -312.123106) (xy 306.381052 -312.169787) (xy 306.358181 -312.213364) (xy 306.328616 -312.252708)
			(xy 306.293123 -312.2868) (xy 306.25262 -312.314756) (xy 306.208158 -312.335854) (xy 306.160887 -312.349546)
			(xy 306.112032 -312.355478) (xy 306.062857 -312.353497) (xy 306.014638 -312.343653) (xy 305.968622 -312.326201)
			(xy 305.926001 -312.301594) (xy 305.88788 -312.270469) (xy 305.855245 -312.233632) (xy 305.828942 -312.192036)
			(xy 305.809651 -312.14676) (xy 305.797874 -312.098976) (xy 305.793914 -312.049922) (xy 304.505106 -312.049922)
			(xy 304.504611 -312.074529) (xy 304.496716 -312.123106) (xy 304.481132 -312.169787) (xy 304.458261 -312.213364)
			(xy 304.428696 -312.252708) (xy 304.393203 -312.2868) (xy 304.3527 -312.314756) (xy 304.308238 -312.335854)
			(xy 304.260967 -312.349546) (xy 304.212112 -312.355478) (xy 304.162937 -312.353497) (xy 304.114718 -312.343653)
			(xy 304.068702 -312.326201) (xy 304.026081 -312.301594) (xy 303.98796 -312.270469) (xy 303.955325 -312.233632)
			(xy 303.929022 -312.192036) (xy 303.909731 -312.14676) (xy 303.897954 -312.098976) (xy 303.893994 -312.049922)
			(xy 302.605186 -312.049922) (xy 302.604691 -312.074529) (xy 302.596796 -312.123106) (xy 302.581212 -312.169787)
			(xy 302.558341 -312.213364) (xy 302.528776 -312.252708) (xy 302.493283 -312.2868) (xy 302.45278 -312.314756)
			(xy 302.408318 -312.335854) (xy 302.361047 -312.349546) (xy 302.312192 -312.355478) (xy 302.263017 -312.353497)
			(xy 302.214798 -312.343653) (xy 302.168782 -312.326201) (xy 302.126161 -312.301594) (xy 302.08804 -312.270469)
			(xy 302.055405 -312.233632) (xy 302.029102 -312.192036) (xy 302.009811 -312.14676) (xy 301.998034 -312.098976)
			(xy 301.994074 -312.049922) (xy 300.705012 -312.049922) (xy 300.704517 -312.074529) (xy 300.696622 -312.123106)
			(xy 300.681038 -312.169787) (xy 300.658167 -312.213364) (xy 300.628602 -312.252708) (xy 300.593109 -312.2868)
			(xy 300.552606 -312.314756) (xy 300.508144 -312.335854) (xy 300.460873 -312.349546) (xy 300.412018 -312.355478)
			(xy 300.362843 -312.353497) (xy 300.314624 -312.343653) (xy 300.268608 -312.326201) (xy 300.225987 -312.301594)
			(xy 300.187866 -312.270469) (xy 300.155231 -312.233632) (xy 300.128928 -312.192036) (xy 300.109637 -312.14676)
			(xy 300.09786 -312.098976) (xy 300.0939 -312.049922) (xy 298.805092 -312.049922) (xy 298.804597 -312.074529)
			(xy 298.796702 -312.123106) (xy 298.781118 -312.169787) (xy 298.758247 -312.213364) (xy 298.728682 -312.252708)
			(xy 298.693189 -312.2868) (xy 298.652686 -312.314756) (xy 298.608224 -312.335854) (xy 298.560953 -312.349546)
			(xy 298.512098 -312.355478) (xy 298.462923 -312.353497) (xy 298.414704 -312.343653) (xy 298.368688 -312.326201)
			(xy 298.326067 -312.301594) (xy 298.287946 -312.270469) (xy 298.255311 -312.233632) (xy 298.229008 -312.192036)
			(xy 298.209717 -312.14676) (xy 298.19794 -312.098976) (xy 298.19398 -312.049922) (xy 296.905172 -312.049922)
			(xy 296.904677 -312.074529) (xy 296.896782 -312.123106) (xy 296.881198 -312.169787) (xy 296.858327 -312.213364)
			(xy 296.828762 -312.252708) (xy 296.793269 -312.2868) (xy 296.752766 -312.314756) (xy 296.708304 -312.335854)
			(xy 296.661033 -312.349546) (xy 296.612178 -312.355478) (xy 296.563003 -312.353497) (xy 296.514784 -312.343653)
			(xy 296.468768 -312.326201) (xy 296.426147 -312.301594) (xy 296.388026 -312.270469) (xy 296.355391 -312.233632)
			(xy 296.329088 -312.192036) (xy 296.309797 -312.14676) (xy 296.29802 -312.098976) (xy 296.29406 -312.049922)
			(xy 295.004998 -312.049922) (xy 295.004503 -312.074529) (xy 294.996608 -312.123106) (xy 294.981024 -312.169787)
			(xy 294.958153 -312.213364) (xy 294.928588 -312.252708) (xy 294.893095 -312.2868) (xy 294.852592 -312.314756)
			(xy 294.80813 -312.335854) (xy 294.760859 -312.349546) (xy 294.712004 -312.355478) (xy 294.662829 -312.353497)
			(xy 294.61461 -312.343653) (xy 294.568594 -312.326201) (xy 294.525973 -312.301594) (xy 294.487852 -312.270469)
			(xy 294.455217 -312.233632) (xy 294.428914 -312.192036) (xy 294.409623 -312.14676) (xy 294.397846 -312.098976)
			(xy 294.393886 -312.049922) (xy 293.105078 -312.049922) (xy 293.104583 -312.074529) (xy 293.096688 -312.123106)
			(xy 293.081104 -312.169787) (xy 293.058233 -312.213364) (xy 293.028668 -312.252708) (xy 292.993175 -312.2868)
			(xy 292.952672 -312.314756) (xy 292.90821 -312.335854) (xy 292.860939 -312.349546) (xy 292.812084 -312.355478)
			(xy 292.762909 -312.353497) (xy 292.71469 -312.343653) (xy 292.668674 -312.326201) (xy 292.626053 -312.301594)
			(xy 292.587932 -312.270469) (xy 292.555297 -312.233632) (xy 292.528994 -312.192036) (xy 292.509703 -312.14676)
			(xy 292.497926 -312.098976) (xy 292.493966 -312.049922) (xy 291.205158 -312.049922) (xy 291.204663 -312.074529)
			(xy 291.196768 -312.123106) (xy 291.181184 -312.169787) (xy 291.158313 -312.213364) (xy 291.128748 -312.252708)
			(xy 291.093255 -312.2868) (xy 291.052752 -312.314756) (xy 291.00829 -312.335854) (xy 290.961019 -312.349546)
			(xy 290.912164 -312.355478) (xy 290.862989 -312.353497) (xy 290.81477 -312.343653) (xy 290.768754 -312.326201)
			(xy 290.726133 -312.301594) (xy 290.688012 -312.270469) (xy 290.655377 -312.233632) (xy 290.629074 -312.192036)
			(xy 290.609783 -312.14676) (xy 290.598006 -312.098976) (xy 290.594046 -312.049922) (xy 289.305238 -312.049922)
			(xy 289.304743 -312.074529) (xy 289.296848 -312.123106) (xy 289.281264 -312.169787) (xy 289.258393 -312.213364)
			(xy 289.228828 -312.252708) (xy 289.193335 -312.2868) (xy 289.152832 -312.314756) (xy 289.10837 -312.335854)
			(xy 289.061099 -312.349546) (xy 289.012244 -312.355478) (xy 288.963069 -312.353497) (xy 288.91485 -312.343653)
			(xy 288.868834 -312.326201) (xy 288.826213 -312.301594) (xy 288.788092 -312.270469) (xy 288.755457 -312.233632)
			(xy 288.729154 -312.192036) (xy 288.709863 -312.14676) (xy 288.698086 -312.098976) (xy 288.694126 -312.049922)
			(xy 287.405064 -312.049922) (xy 287.404569 -312.074529) (xy 287.396674 -312.123106) (xy 287.38109 -312.169787)
			(xy 287.358219 -312.213364) (xy 287.328654 -312.252708) (xy 287.293161 -312.2868) (xy 287.252658 -312.314756)
			(xy 287.208196 -312.335854) (xy 287.160925 -312.349546) (xy 287.11207 -312.355478) (xy 287.062895 -312.353497)
			(xy 287.014676 -312.343653) (xy 286.96866 -312.326201) (xy 286.926039 -312.301594) (xy 286.887918 -312.270469)
			(xy 286.855283 -312.233632) (xy 286.82898 -312.192036) (xy 286.809689 -312.14676) (xy 286.797912 -312.098976)
			(xy 286.793952 -312.049922) (xy 285.505144 -312.049922) (xy 285.504649 -312.074529) (xy 285.496754 -312.123106)
			(xy 285.48117 -312.169787) (xy 285.458299 -312.213364) (xy 285.428734 -312.252708) (xy 285.393241 -312.2868)
			(xy 285.352738 -312.314756) (xy 285.308276 -312.335854) (xy 285.261005 -312.349546) (xy 285.21215 -312.355478)
			(xy 285.162975 -312.353497) (xy 285.114756 -312.343653) (xy 285.06874 -312.326201) (xy 285.026119 -312.301594)
			(xy 284.987998 -312.270469) (xy 284.955363 -312.233632) (xy 284.92906 -312.192036) (xy 284.909769 -312.14676)
			(xy 284.897992 -312.098976) (xy 284.894032 -312.049922) (xy 283.605224 -312.049922) (xy 283.604729 -312.074529)
			(xy 283.596834 -312.123106) (xy 283.58125 -312.169787) (xy 283.558379 -312.213364) (xy 283.528814 -312.252708)
			(xy 283.493321 -312.2868) (xy 283.452818 -312.314756) (xy 283.408356 -312.335854) (xy 283.361085 -312.349546)
			(xy 283.31223 -312.355478) (xy 283.263055 -312.353497) (xy 283.214836 -312.343653) (xy 283.16882 -312.326201)
			(xy 283.126199 -312.301594) (xy 283.088078 -312.270469) (xy 283.055443 -312.233632) (xy 283.02914 -312.192036)
			(xy 283.009849 -312.14676) (xy 282.998072 -312.098976) (xy 282.994112 -312.049922) (xy 281.70505 -312.049922)
			(xy 281.704555 -312.074529) (xy 281.69666 -312.123106) (xy 281.681076 -312.169787) (xy 281.658205 -312.213364)
			(xy 281.62864 -312.252708) (xy 281.593147 -312.2868) (xy 281.552644 -312.314756) (xy 281.508182 -312.335854)
			(xy 281.460911 -312.349546) (xy 281.412056 -312.355478) (xy 281.362881 -312.353497) (xy 281.314662 -312.343653)
			(xy 281.268646 -312.326201) (xy 281.226025 -312.301594) (xy 281.187904 -312.270469) (xy 281.155269 -312.233632)
			(xy 281.128966 -312.192036) (xy 281.109675 -312.14676) (xy 281.097898 -312.098976) (xy 281.093938 -312.049922)
			(xy 279.80513 -312.049922) (xy 279.804635 -312.074529) (xy 279.79674 -312.123106) (xy 279.781156 -312.169787)
			(xy 279.758285 -312.213364) (xy 279.72872 -312.252708) (xy 279.693227 -312.2868) (xy 279.652724 -312.314756)
			(xy 279.608262 -312.335854) (xy 279.560991 -312.349546) (xy 279.512136 -312.355478) (xy 279.462961 -312.353497)
			(xy 279.414742 -312.343653) (xy 279.368726 -312.326201) (xy 279.326105 -312.301594) (xy 279.287984 -312.270469)
			(xy 279.255349 -312.233632) (xy 279.229046 -312.192036) (xy 279.209755 -312.14676) (xy 279.197978 -312.098976)
			(xy 279.194018 -312.049922) (xy 277.90521 -312.049922) (xy 277.904715 -312.074529) (xy 277.89682 -312.123106)
			(xy 277.881236 -312.169787) (xy 277.858365 -312.213364) (xy 277.8288 -312.252708) (xy 277.793307 -312.2868)
			(xy 277.752804 -312.314756) (xy 277.708342 -312.335854) (xy 277.661071 -312.349546) (xy 277.612216 -312.355478)
			(xy 277.563041 -312.353497) (xy 277.514822 -312.343653) (xy 277.468806 -312.326201) (xy 277.426185 -312.301594)
			(xy 277.388064 -312.270469) (xy 277.355429 -312.233632) (xy 277.329126 -312.192036) (xy 277.309835 -312.14676)
			(xy 277.298058 -312.098976) (xy 277.294098 -312.049922) (xy 276.005036 -312.049922) (xy 276.004541 -312.074529)
			(xy 275.996646 -312.123106) (xy 275.981062 -312.169787) (xy 275.958191 -312.213364) (xy 275.928626 -312.252708)
			(xy 275.893133 -312.2868) (xy 275.85263 -312.314756) (xy 275.808168 -312.335854) (xy 275.760897 -312.349546)
			(xy 275.712042 -312.355478) (xy 275.662867 -312.353497) (xy 275.614648 -312.343653) (xy 275.568632 -312.326201)
			(xy 275.526011 -312.301594) (xy 275.48789 -312.270469) (xy 275.455255 -312.233632) (xy 275.428952 -312.192036)
			(xy 275.409661 -312.14676) (xy 275.397884 -312.098976) (xy 275.393924 -312.049922) (xy 274.105116 -312.049922)
			(xy 274.104621 -312.074529) (xy 274.096726 -312.123106) (xy 274.081142 -312.169787) (xy 274.058271 -312.213364)
			(xy 274.028706 -312.252708) (xy 273.993213 -312.2868) (xy 273.95271 -312.314756) (xy 273.908248 -312.335854)
			(xy 273.860977 -312.349546) (xy 273.812122 -312.355478) (xy 273.762947 -312.353497) (xy 273.714728 -312.343653)
			(xy 273.668712 -312.326201) (xy 273.626091 -312.301594) (xy 273.58797 -312.270469) (xy 273.555335 -312.233632)
			(xy 273.529032 -312.192036) (xy 273.509741 -312.14676) (xy 273.497964 -312.098976) (xy 273.494004 -312.049922)
			(xy 272.205196 -312.049922) (xy 272.204701 -312.074529) (xy 272.196806 -312.123106) (xy 272.181222 -312.169787)
			(xy 272.158351 -312.213364) (xy 272.128786 -312.252708) (xy 272.093293 -312.2868) (xy 272.05279 -312.314756)
			(xy 272.008328 -312.335854) (xy 271.961057 -312.349546) (xy 271.912202 -312.355478) (xy 271.863027 -312.353497)
			(xy 271.814808 -312.343653) (xy 271.768792 -312.326201) (xy 271.726171 -312.301594) (xy 271.68805 -312.270469)
			(xy 271.655415 -312.233632) (xy 271.629112 -312.192036) (xy 271.609821 -312.14676) (xy 271.598044 -312.098976)
			(xy 271.594084 -312.049922) (xy 270.305022 -312.049922) (xy 270.304527 -312.074529) (xy 270.296632 -312.123106)
			(xy 270.281048 -312.169787) (xy 270.258177 -312.213364) (xy 270.228612 -312.252708) (xy 270.193119 -312.2868)
			(xy 270.152616 -312.314756) (xy 270.108154 -312.335854) (xy 270.060883 -312.349546) (xy 270.012028 -312.355478)
			(xy 269.962853 -312.353497) (xy 269.914634 -312.343653) (xy 269.868618 -312.326201) (xy 269.825997 -312.301594)
			(xy 269.787876 -312.270469) (xy 269.755241 -312.233632) (xy 269.728938 -312.192036) (xy 269.709647 -312.14676)
			(xy 269.69787 -312.098976) (xy 269.69391 -312.049922) (xy 269.355062 -312.049922) (xy 269.354567 -312.074529)
			(xy 269.346672 -312.123106) (xy 269.331088 -312.169787) (xy 269.308217 -312.213364) (xy 269.278652 -312.252708)
			(xy 269.243159 -312.2868) (xy 269.202656 -312.314756) (xy 269.158194 -312.335854) (xy 269.110923 -312.349546)
			(xy 269.062068 -312.355478) (xy 269.012893 -312.353497) (xy 268.964674 -312.343653) (xy 268.918658 -312.326201)
			(xy 268.876037 -312.301594) (xy 268.837916 -312.270469) (xy 268.805281 -312.233632) (xy 268.778978 -312.192036)
			(xy 268.759687 -312.14676) (xy 268.74791 -312.098976) (xy 268.74395 -312.049922) (xy 198.85533 -312.049922)
			(xy 198.854835 -312.074529) (xy 198.84694 -312.123106) (xy 198.831356 -312.169787) (xy 198.808485 -312.213364)
			(xy 198.77892 -312.252708) (xy 198.743427 -312.2868) (xy 198.702924 -312.314756) (xy 198.658462 -312.335854)
			(xy 198.611191 -312.349546) (xy 198.562336 -312.355478) (xy 198.513161 -312.353497) (xy 198.464942 -312.343653)
			(xy 198.418926 -312.326201) (xy 198.376305 -312.301594) (xy 198.338184 -312.270469) (xy 198.305549 -312.233632)
			(xy 198.279246 -312.192036) (xy 198.259955 -312.14676) (xy 198.248178 -312.098976) (xy 198.244218 -312.049922)
			(xy 197.90537 -312.049922) (xy 197.904875 -312.074529) (xy 197.89698 -312.123106) (xy 197.881396 -312.169787)
			(xy 197.858525 -312.213364) (xy 197.82896 -312.252708) (xy 197.793467 -312.2868) (xy 197.752964 -312.314756)
			(xy 197.708502 -312.335854) (xy 197.661231 -312.349546) (xy 197.612376 -312.355478) (xy 197.563201 -312.353497)
			(xy 197.514982 -312.343653) (xy 197.468966 -312.326201) (xy 197.426345 -312.301594) (xy 197.388224 -312.270469)
			(xy 197.355589 -312.233632) (xy 197.329286 -312.192036) (xy 197.309995 -312.14676) (xy 197.298218 -312.098976)
			(xy 197.294258 -312.049922) (xy 196.005196 -312.049922) (xy 196.004701 -312.074529) (xy 195.996806 -312.123106)
			(xy 195.981222 -312.169787) (xy 195.958351 -312.213364) (xy 195.928786 -312.252708) (xy 195.893293 -312.2868)
			(xy 195.85279 -312.314756) (xy 195.808328 -312.335854) (xy 195.761057 -312.349546) (xy 195.712202 -312.355478)
			(xy 195.663027 -312.353497) (xy 195.614808 -312.343653) (xy 195.568792 -312.326201) (xy 195.526171 -312.301594)
			(xy 195.48805 -312.270469) (xy 195.455415 -312.233632) (xy 195.429112 -312.192036) (xy 195.409821 -312.14676)
			(xy 195.398044 -312.098976) (xy 195.394084 -312.049922) (xy 194.105276 -312.049922) (xy 194.104781 -312.074529)
			(xy 194.096886 -312.123106) (xy 194.081302 -312.169787) (xy 194.058431 -312.213364) (xy 194.028866 -312.252708)
			(xy 193.993373 -312.2868) (xy 193.95287 -312.314756) (xy 193.908408 -312.335854) (xy 193.861137 -312.349546)
			(xy 193.812282 -312.355478) (xy 193.763107 -312.353497) (xy 193.714888 -312.343653) (xy 193.668872 -312.326201)
			(xy 193.626251 -312.301594) (xy 193.58813 -312.270469) (xy 193.555495 -312.233632) (xy 193.529192 -312.192036)
			(xy 193.509901 -312.14676) (xy 193.498124 -312.098976) (xy 193.494164 -312.049922) (xy 192.205356 -312.049922)
			(xy 192.204861 -312.074529) (xy 192.196966 -312.123106) (xy 192.181382 -312.169787) (xy 192.158511 -312.213364)
			(xy 192.128946 -312.252708) (xy 192.093453 -312.2868) (xy 192.05295 -312.314756) (xy 192.008488 -312.335854)
			(xy 191.961217 -312.349546) (xy 191.912362 -312.355478) (xy 191.863187 -312.353497) (xy 191.814968 -312.343653)
			(xy 191.768952 -312.326201) (xy 191.726331 -312.301594) (xy 191.68821 -312.270469) (xy 191.655575 -312.233632)
			(xy 191.629272 -312.192036) (xy 191.609981 -312.14676) (xy 191.598204 -312.098976) (xy 191.594244 -312.049922)
			(xy 190.305182 -312.049922) (xy 190.304687 -312.074529) (xy 190.296792 -312.123106) (xy 190.281208 -312.169787)
			(xy 190.258337 -312.213364) (xy 190.228772 -312.252708) (xy 190.193279 -312.2868) (xy 190.152776 -312.314756)
			(xy 190.108314 -312.335854) (xy 190.061043 -312.349546) (xy 190.012188 -312.355478) (xy 189.963013 -312.353497)
			(xy 189.914794 -312.343653) (xy 189.868778 -312.326201) (xy 189.826157 -312.301594) (xy 189.788036 -312.270469)
			(xy 189.755401 -312.233632) (xy 189.729098 -312.192036) (xy 189.709807 -312.14676) (xy 189.69803 -312.098976)
			(xy 189.69407 -312.049922) (xy 188.405262 -312.049922) (xy 188.404767 -312.074529) (xy 188.396872 -312.123106)
			(xy 188.381288 -312.169787) (xy 188.358417 -312.213364) (xy 188.328852 -312.252708) (xy 188.293359 -312.2868)
			(xy 188.252856 -312.314756) (xy 188.208394 -312.335854) (xy 188.161123 -312.349546) (xy 188.112268 -312.355478)
			(xy 188.063093 -312.353497) (xy 188.014874 -312.343653) (xy 187.968858 -312.326201) (xy 187.926237 -312.301594)
			(xy 187.888116 -312.270469) (xy 187.855481 -312.233632) (xy 187.829178 -312.192036) (xy 187.809887 -312.14676)
			(xy 187.79811 -312.098976) (xy 187.79415 -312.049922) (xy 186.505342 -312.049922) (xy 186.504847 -312.074529)
			(xy 186.496952 -312.123106) (xy 186.481368 -312.169787) (xy 186.458497 -312.213364) (xy 186.428932 -312.252708)
			(xy 186.393439 -312.2868) (xy 186.352936 -312.314756) (xy 186.308474 -312.335854) (xy 186.261203 -312.349546)
			(xy 186.212348 -312.355478) (xy 186.163173 -312.353497) (xy 186.114954 -312.343653) (xy 186.068938 -312.326201)
			(xy 186.026317 -312.301594) (xy 185.988196 -312.270469) (xy 185.955561 -312.233632) (xy 185.929258 -312.192036)
			(xy 185.909967 -312.14676) (xy 185.89819 -312.098976) (xy 185.89423 -312.049922) (xy 184.605168 -312.049922)
			(xy 184.604673 -312.074529) (xy 184.596778 -312.123106) (xy 184.581194 -312.169787) (xy 184.558323 -312.213364)
			(xy 184.528758 -312.252708) (xy 184.493265 -312.2868) (xy 184.452762 -312.314756) (xy 184.4083 -312.335854)
			(xy 184.361029 -312.349546) (xy 184.312174 -312.355478) (xy 184.262999 -312.353497) (xy 184.21478 -312.343653)
			(xy 184.168764 -312.326201) (xy 184.126143 -312.301594) (xy 184.088022 -312.270469) (xy 184.055387 -312.233632)
			(xy 184.029084 -312.192036) (xy 184.009793 -312.14676) (xy 183.998016 -312.098976) (xy 183.994056 -312.049922)
			(xy 182.705248 -312.049922) (xy 182.704753 -312.074529) (xy 182.696858 -312.123106) (xy 182.681274 -312.169787)
			(xy 182.658403 -312.213364) (xy 182.628838 -312.252708) (xy 182.593345 -312.2868) (xy 182.552842 -312.314756)
			(xy 182.50838 -312.335854) (xy 182.461109 -312.349546) (xy 182.412254 -312.355478) (xy 182.363079 -312.353497)
			(xy 182.31486 -312.343653) (xy 182.268844 -312.326201) (xy 182.226223 -312.301594) (xy 182.188102 -312.270469)
			(xy 182.155467 -312.233632) (xy 182.129164 -312.192036) (xy 182.109873 -312.14676) (xy 182.098096 -312.098976)
			(xy 182.094136 -312.049922) (xy 180.805328 -312.049922) (xy 180.804833 -312.074529) (xy 180.796938 -312.123106)
			(xy 180.781354 -312.169787) (xy 180.758483 -312.213364) (xy 180.728918 -312.252708) (xy 180.693425 -312.2868)
			(xy 180.652922 -312.314756) (xy 180.60846 -312.335854) (xy 180.561189 -312.349546) (xy 180.512334 -312.355478)
			(xy 180.463159 -312.353497) (xy 180.41494 -312.343653) (xy 180.368924 -312.326201) (xy 180.326303 -312.301594)
			(xy 180.288182 -312.270469) (xy 180.255547 -312.233632) (xy 180.229244 -312.192036) (xy 180.209953 -312.14676)
			(xy 180.198176 -312.098976) (xy 180.194216 -312.049922) (xy 178.905154 -312.049922) (xy 178.904659 -312.074529)
			(xy 178.896764 -312.123106) (xy 178.88118 -312.169787) (xy 178.858309 -312.213364) (xy 178.828744 -312.252708)
			(xy 178.793251 -312.2868) (xy 178.752748 -312.314756) (xy 178.708286 -312.335854) (xy 178.661015 -312.349546)
			(xy 178.61216 -312.355478) (xy 178.562985 -312.353497) (xy 178.514766 -312.343653) (xy 178.46875 -312.326201)
			(xy 178.426129 -312.301594) (xy 178.388008 -312.270469) (xy 178.355373 -312.233632) (xy 178.32907 -312.192036)
			(xy 178.309779 -312.14676) (xy 178.298002 -312.098976) (xy 178.294042 -312.049922) (xy 177.005234 -312.049922)
			(xy 177.004739 -312.074529) (xy 176.996844 -312.123106) (xy 176.98126 -312.169787) (xy 176.958389 -312.213364)
			(xy 176.928824 -312.252708) (xy 176.893331 -312.2868) (xy 176.852828 -312.314756) (xy 176.808366 -312.335854)
			(xy 176.761095 -312.349546) (xy 176.71224 -312.355478) (xy 176.663065 -312.353497) (xy 176.614846 -312.343653)
			(xy 176.56883 -312.326201) (xy 176.526209 -312.301594) (xy 176.488088 -312.270469) (xy 176.455453 -312.233632)
			(xy 176.42915 -312.192036) (xy 176.409859 -312.14676) (xy 176.398082 -312.098976) (xy 176.394122 -312.049922)
			(xy 175.105314 -312.049922) (xy 175.104819 -312.074529) (xy 175.096924 -312.123106) (xy 175.08134 -312.169787)
			(xy 175.058469 -312.213364) (xy 175.028904 -312.252708) (xy 174.993411 -312.2868) (xy 174.952908 -312.314756)
			(xy 174.908446 -312.335854) (xy 174.861175 -312.349546) (xy 174.81232 -312.355478) (xy 174.763145 -312.353497)
			(xy 174.714926 -312.343653) (xy 174.66891 -312.326201) (xy 174.626289 -312.301594) (xy 174.588168 -312.270469)
			(xy 174.555533 -312.233632) (xy 174.52923 -312.192036) (xy 174.509939 -312.14676) (xy 174.498162 -312.098976)
			(xy 174.494202 -312.049922) (xy 173.205394 -312.049922) (xy 173.204899 -312.074529) (xy 173.197004 -312.123106)
			(xy 173.18142 -312.169787) (xy 173.158549 -312.213364) (xy 173.128984 -312.252708) (xy 173.093491 -312.2868)
			(xy 173.052988 -312.314756) (xy 173.008526 -312.335854) (xy 172.961255 -312.349546) (xy 172.9124 -312.355478)
			(xy 172.863225 -312.353497) (xy 172.815006 -312.343653) (xy 172.76899 -312.326201) (xy 172.726369 -312.301594)
			(xy 172.688248 -312.270469) (xy 172.655613 -312.233632) (xy 172.62931 -312.192036) (xy 172.610019 -312.14676)
			(xy 172.598242 -312.098976) (xy 172.594282 -312.049922) (xy 171.30522 -312.049922) (xy 171.304725 -312.074529)
			(xy 171.29683 -312.123106) (xy 171.281246 -312.169787) (xy 171.258375 -312.213364) (xy 171.22881 -312.252708)
			(xy 171.193317 -312.2868) (xy 171.152814 -312.314756) (xy 171.108352 -312.335854) (xy 171.061081 -312.349546)
			(xy 171.012226 -312.355478) (xy 170.963051 -312.353497) (xy 170.914832 -312.343653) (xy 170.868816 -312.326201)
			(xy 170.826195 -312.301594) (xy 170.788074 -312.270469) (xy 170.755439 -312.233632) (xy 170.729136 -312.192036)
			(xy 170.709845 -312.14676) (xy 170.698068 -312.098976) (xy 170.694108 -312.049922) (xy 169.4053 -312.049922)
			(xy 169.404805 -312.074529) (xy 169.39691 -312.123106) (xy 169.381326 -312.169787) (xy 169.358455 -312.213364)
			(xy 169.32889 -312.252708) (xy 169.293397 -312.2868) (xy 169.252894 -312.314756) (xy 169.208432 -312.335854)
			(xy 169.161161 -312.349546) (xy 169.112306 -312.355478) (xy 169.063131 -312.353497) (xy 169.014912 -312.343653)
			(xy 168.968896 -312.326201) (xy 168.926275 -312.301594) (xy 168.888154 -312.270469) (xy 168.855519 -312.233632)
			(xy 168.829216 -312.192036) (xy 168.809925 -312.14676) (xy 168.798148 -312.098976) (xy 168.794188 -312.049922)
			(xy 167.50538 -312.049922) (xy 167.504885 -312.074529) (xy 167.49699 -312.123106) (xy 167.481406 -312.169787)
			(xy 167.458535 -312.213364) (xy 167.42897 -312.252708) (xy 167.393477 -312.2868) (xy 167.352974 -312.314756)
			(xy 167.308512 -312.335854) (xy 167.261241 -312.349546) (xy 167.212386 -312.355478) (xy 167.163211 -312.353497)
			(xy 167.114992 -312.343653) (xy 167.068976 -312.326201) (xy 167.026355 -312.301594) (xy 166.988234 -312.270469)
			(xy 166.955599 -312.233632) (xy 166.929296 -312.192036) (xy 166.910005 -312.14676) (xy 166.898228 -312.098976)
			(xy 166.894268 -312.049922) (xy 165.605206 -312.049922) (xy 165.604711 -312.074529) (xy 165.596816 -312.123106)
			(xy 165.581232 -312.169787) (xy 165.558361 -312.213364) (xy 165.528796 -312.252708) (xy 165.493303 -312.2868)
			(xy 165.4528 -312.314756) (xy 165.408338 -312.335854) (xy 165.361067 -312.349546) (xy 165.312212 -312.355478)
			(xy 165.263037 -312.353497) (xy 165.214818 -312.343653) (xy 165.168802 -312.326201) (xy 165.126181 -312.301594)
			(xy 165.08806 -312.270469) (xy 165.055425 -312.233632) (xy 165.029122 -312.192036) (xy 165.009831 -312.14676)
			(xy 164.998054 -312.098976) (xy 164.994094 -312.049922) (xy 163.705286 -312.049922) (xy 163.704791 -312.074529)
			(xy 163.696896 -312.123106) (xy 163.681312 -312.169787) (xy 163.658441 -312.213364) (xy 163.628876 -312.252708)
			(xy 163.593383 -312.2868) (xy 163.55288 -312.314756) (xy 163.508418 -312.335854) (xy 163.461147 -312.349546)
			(xy 163.412292 -312.355478) (xy 163.363117 -312.353497) (xy 163.314898 -312.343653) (xy 163.268882 -312.326201)
			(xy 163.226261 -312.301594) (xy 163.18814 -312.270469) (xy 163.155505 -312.233632) (xy 163.129202 -312.192036)
			(xy 163.109911 -312.14676) (xy 163.098134 -312.098976) (xy 163.094174 -312.049922) (xy 161.805366 -312.049922)
			(xy 161.804871 -312.074529) (xy 161.796976 -312.123106) (xy 161.781392 -312.169787) (xy 161.758521 -312.213364)
			(xy 161.728956 -312.252708) (xy 161.693463 -312.2868) (xy 161.65296 -312.314756) (xy 161.608498 -312.335854)
			(xy 161.561227 -312.349546) (xy 161.512372 -312.355478) (xy 161.463197 -312.353497) (xy 161.414978 -312.343653)
			(xy 161.368962 -312.326201) (xy 161.326341 -312.301594) (xy 161.28822 -312.270469) (xy 161.255585 -312.233632)
			(xy 161.229282 -312.192036) (xy 161.209991 -312.14676) (xy 161.198214 -312.098976) (xy 161.194254 -312.049922)
			(xy 159.905192 -312.049922) (xy 159.904697 -312.074529) (xy 159.896802 -312.123106) (xy 159.881218 -312.169787)
			(xy 159.858347 -312.213364) (xy 159.828782 -312.252708) (xy 159.793289 -312.2868) (xy 159.752786 -312.314756)
			(xy 159.708324 -312.335854) (xy 159.661053 -312.349546) (xy 159.612198 -312.355478) (xy 159.563023 -312.353497)
			(xy 159.514804 -312.343653) (xy 159.468788 -312.326201) (xy 159.426167 -312.301594) (xy 159.388046 -312.270469)
			(xy 159.355411 -312.233632) (xy 159.329108 -312.192036) (xy 159.309817 -312.14676) (xy 159.29804 -312.098976)
			(xy 159.29408 -312.049922) (xy 158.005272 -312.049922) (xy 158.004777 -312.074529) (xy 157.996882 -312.123106)
			(xy 157.981298 -312.169787) (xy 157.958427 -312.213364) (xy 157.928862 -312.252708) (xy 157.893369 -312.2868)
			(xy 157.852866 -312.314756) (xy 157.808404 -312.335854) (xy 157.761133 -312.349546) (xy 157.712278 -312.355478)
			(xy 157.663103 -312.353497) (xy 157.614884 -312.343653) (xy 157.568868 -312.326201) (xy 157.526247 -312.301594)
			(xy 157.488126 -312.270469) (xy 157.455491 -312.233632) (xy 157.429188 -312.192036) (xy 157.409897 -312.14676)
			(xy 157.39812 -312.098976) (xy 157.39416 -312.049922) (xy 156.105352 -312.049922) (xy 156.104857 -312.074529)
			(xy 156.096962 -312.123106) (xy 156.081378 -312.169787) (xy 156.058507 -312.213364) (xy 156.028942 -312.252708)
			(xy 155.993449 -312.2868) (xy 155.952946 -312.314756) (xy 155.908484 -312.335854) (xy 155.861213 -312.349546)
			(xy 155.812358 -312.355478) (xy 155.763183 -312.353497) (xy 155.714964 -312.343653) (xy 155.668948 -312.326201)
			(xy 155.626327 -312.301594) (xy 155.588206 -312.270469) (xy 155.555571 -312.233632) (xy 155.529268 -312.192036)
			(xy 155.509977 -312.14676) (xy 155.4982 -312.098976) (xy 155.49424 -312.049922) (xy 154.205178 -312.049922)
			(xy 154.204683 -312.074529) (xy 154.196788 -312.123106) (xy 154.181204 -312.169787) (xy 154.158333 -312.213364)
			(xy 154.128768 -312.252708) (xy 154.093275 -312.2868) (xy 154.052772 -312.314756) (xy 154.00831 -312.335854)
			(xy 153.961039 -312.349546) (xy 153.912184 -312.355478) (xy 153.863009 -312.353497) (xy 153.81479 -312.343653)
			(xy 153.768774 -312.326201) (xy 153.726153 -312.301594) (xy 153.688032 -312.270469) (xy 153.655397 -312.233632)
			(xy 153.629094 -312.192036) (xy 153.609803 -312.14676) (xy 153.598026 -312.098976) (xy 153.594066 -312.049922)
			(xy 153.255218 -312.049922) (xy 153.254723 -312.074529) (xy 153.246828 -312.123106) (xy 153.231244 -312.169787)
			(xy 153.208373 -312.213364) (xy 153.178808 -312.252708) (xy 153.143315 -312.2868) (xy 153.102812 -312.314756)
			(xy 153.05835 -312.335854) (xy 153.011079 -312.349546) (xy 152.962224 -312.355478) (xy 152.913049 -312.353497)
			(xy 152.86483 -312.343653) (xy 152.818814 -312.326201) (xy 152.776193 -312.301594) (xy 152.738072 -312.270469)
			(xy 152.705437 -312.233632) (xy 152.679134 -312.192036) (xy 152.659843 -312.14676) (xy 152.648066 -312.098976)
			(xy 152.644106 -312.049922) (xy 82.755232 -312.049922) (xy 82.754737 -312.074529) (xy 82.746842 -312.123106)
			(xy 82.731258 -312.169787) (xy 82.708387 -312.213364) (xy 82.678822 -312.252708) (xy 82.643329 -312.2868)
			(xy 82.602826 -312.314756) (xy 82.558364 -312.335854) (xy 82.511093 -312.349546) (xy 82.462238 -312.355478)
			(xy 82.413063 -312.353497) (xy 82.364844 -312.343653) (xy 82.318828 -312.326201) (xy 82.276207 -312.301594)
			(xy 82.238086 -312.270469) (xy 82.205451 -312.233632) (xy 82.179148 -312.192036) (xy 82.159857 -312.14676)
			(xy 82.14808 -312.098976) (xy 82.14412 -312.049922) (xy 81.805272 -312.049922) (xy 81.804777 -312.074529)
			(xy 81.796882 -312.123106) (xy 81.781298 -312.169787) (xy 81.758427 -312.213364) (xy 81.728862 -312.252708)
			(xy 81.693369 -312.2868) (xy 81.652866 -312.314756) (xy 81.608404 -312.335854) (xy 81.561133 -312.349546)
			(xy 81.512278 -312.355478) (xy 81.463103 -312.353497) (xy 81.414884 -312.343653) (xy 81.368868 -312.326201)
			(xy 81.326247 -312.301594) (xy 81.288126 -312.270469) (xy 81.255491 -312.233632) (xy 81.229188 -312.192036)
			(xy 81.209897 -312.14676) (xy 81.19812 -312.098976) (xy 81.19416 -312.049922) (xy 79.905098 -312.049922)
			(xy 79.904603 -312.074529) (xy 79.896708 -312.123106) (xy 79.881124 -312.169787) (xy 79.858253 -312.213364)
			(xy 79.828688 -312.252708) (xy 79.793195 -312.2868) (xy 79.752692 -312.314756) (xy 79.70823 -312.335854)
			(xy 79.660959 -312.349546) (xy 79.612104 -312.355478) (xy 79.562929 -312.353497) (xy 79.51471 -312.343653)
			(xy 79.468694 -312.326201) (xy 79.426073 -312.301594) (xy 79.387952 -312.270469) (xy 79.355317 -312.233632)
			(xy 79.329014 -312.192036) (xy 79.309723 -312.14676) (xy 79.297946 -312.098976) (xy 79.293986 -312.049922)
			(xy 78.005178 -312.049922) (xy 78.004683 -312.074529) (xy 77.996788 -312.123106) (xy 77.981204 -312.169787)
			(xy 77.958333 -312.213364) (xy 77.928768 -312.252708) (xy 77.893275 -312.2868) (xy 77.852772 -312.314756)
			(xy 77.80831 -312.335854) (xy 77.761039 -312.349546) (xy 77.712184 -312.355478) (xy 77.663009 -312.353497)
			(xy 77.61479 -312.343653) (xy 77.568774 -312.326201) (xy 77.526153 -312.301594) (xy 77.488032 -312.270469)
			(xy 77.455397 -312.233632) (xy 77.429094 -312.192036) (xy 77.409803 -312.14676) (xy 77.398026 -312.098976)
			(xy 77.394066 -312.049922) (xy 76.105258 -312.049922) (xy 76.104763 -312.074529) (xy 76.096868 -312.123106)
			(xy 76.081284 -312.169787) (xy 76.058413 -312.213364) (xy 76.028848 -312.252708) (xy 75.993355 -312.2868)
			(xy 75.952852 -312.314756) (xy 75.90839 -312.335854) (xy 75.861119 -312.349546) (xy 75.812264 -312.355478)
			(xy 75.763089 -312.353497) (xy 75.71487 -312.343653) (xy 75.668854 -312.326201) (xy 75.626233 -312.301594)
			(xy 75.588112 -312.270469) (xy 75.555477 -312.233632) (xy 75.529174 -312.192036) (xy 75.509883 -312.14676)
			(xy 75.498106 -312.098976) (xy 75.494146 -312.049922) (xy 74.205084 -312.049922) (xy 74.204589 -312.074529)
			(xy 74.196694 -312.123106) (xy 74.18111 -312.169787) (xy 74.158239 -312.213364) (xy 74.128674 -312.252708)
			(xy 74.093181 -312.2868) (xy 74.052678 -312.314756) (xy 74.008216 -312.335854) (xy 73.960945 -312.349546)
			(xy 73.91209 -312.355478) (xy 73.862915 -312.353497) (xy 73.814696 -312.343653) (xy 73.76868 -312.326201)
			(xy 73.726059 -312.301594) (xy 73.687938 -312.270469) (xy 73.655303 -312.233632) (xy 73.629 -312.192036)
			(xy 73.609709 -312.14676) (xy 73.597932 -312.098976) (xy 73.593972 -312.049922) (xy 72.305164 -312.049922)
			(xy 72.304669 -312.074529) (xy 72.296774 -312.123106) (xy 72.28119 -312.169787) (xy 72.258319 -312.213364)
			(xy 72.228754 -312.252708) (xy 72.193261 -312.2868) (xy 72.152758 -312.314756) (xy 72.108296 -312.335854)
			(xy 72.061025 -312.349546) (xy 72.01217 -312.355478) (xy 71.962995 -312.353497) (xy 71.914776 -312.343653)
			(xy 71.86876 -312.326201) (xy 71.826139 -312.301594) (xy 71.788018 -312.270469) (xy 71.755383 -312.233632)
			(xy 71.72908 -312.192036) (xy 71.709789 -312.14676) (xy 71.698012 -312.098976) (xy 71.694052 -312.049922)
			(xy 70.405244 -312.049922) (xy 70.404749 -312.074529) (xy 70.396854 -312.123106) (xy 70.38127 -312.169787)
			(xy 70.358399 -312.213364) (xy 70.328834 -312.252708) (xy 70.293341 -312.2868) (xy 70.252838 -312.314756)
			(xy 70.208376 -312.335854) (xy 70.161105 -312.349546) (xy 70.11225 -312.355478) (xy 70.063075 -312.353497)
			(xy 70.014856 -312.343653) (xy 69.96884 -312.326201) (xy 69.926219 -312.301594) (xy 69.888098 -312.270469)
			(xy 69.855463 -312.233632) (xy 69.82916 -312.192036) (xy 69.809869 -312.14676) (xy 69.798092 -312.098976)
			(xy 69.794132 -312.049922) (xy 68.50507 -312.049922) (xy 68.504575 -312.074529) (xy 68.49668 -312.123106)
			(xy 68.481096 -312.169787) (xy 68.458225 -312.213364) (xy 68.42866 -312.252708) (xy 68.393167 -312.2868)
			(xy 68.352664 -312.314756) (xy 68.308202 -312.335854) (xy 68.260931 -312.349546) (xy 68.212076 -312.355478)
			(xy 68.162901 -312.353497) (xy 68.114682 -312.343653) (xy 68.068666 -312.326201) (xy 68.026045 -312.301594)
			(xy 67.987924 -312.270469) (xy 67.955289 -312.233632) (xy 67.928986 -312.192036) (xy 67.909695 -312.14676)
			(xy 67.897918 -312.098976) (xy 67.893958 -312.049922) (xy 66.60515 -312.049922) (xy 66.604655 -312.074529)
			(xy 66.59676 -312.123106) (xy 66.581176 -312.169787) (xy 66.558305 -312.213364) (xy 66.52874 -312.252708)
			(xy 66.493247 -312.2868) (xy 66.452744 -312.314756) (xy 66.408282 -312.335854) (xy 66.361011 -312.349546)
			(xy 66.312156 -312.355478) (xy 66.262981 -312.353497) (xy 66.214762 -312.343653) (xy 66.168746 -312.326201)
			(xy 66.126125 -312.301594) (xy 66.088004 -312.270469) (xy 66.055369 -312.233632) (xy 66.029066 -312.192036)
			(xy 66.009775 -312.14676) (xy 65.997998 -312.098976) (xy 65.994038 -312.049922) (xy 64.70523 -312.049922)
			(xy 64.704735 -312.074529) (xy 64.69684 -312.123106) (xy 64.681256 -312.169787) (xy 64.658385 -312.213364)
			(xy 64.62882 -312.252708) (xy 64.593327 -312.2868) (xy 64.552824 -312.314756) (xy 64.508362 -312.335854)
			(xy 64.461091 -312.349546) (xy 64.412236 -312.355478) (xy 64.363061 -312.353497) (xy 64.314842 -312.343653)
			(xy 64.268826 -312.326201) (xy 64.226205 -312.301594) (xy 64.188084 -312.270469) (xy 64.155449 -312.233632)
			(xy 64.129146 -312.192036) (xy 64.109855 -312.14676) (xy 64.098078 -312.098976) (xy 64.094118 -312.049922)
			(xy 62.805056 -312.049922) (xy 62.804561 -312.074529) (xy 62.796666 -312.123106) (xy 62.781082 -312.169787)
			(xy 62.758211 -312.213364) (xy 62.728646 -312.252708) (xy 62.693153 -312.2868) (xy 62.65265 -312.314756)
			(xy 62.608188 -312.335854) (xy 62.560917 -312.349546) (xy 62.512062 -312.355478) (xy 62.462887 -312.353497)
			(xy 62.414668 -312.343653) (xy 62.368652 -312.326201) (xy 62.326031 -312.301594) (xy 62.28791 -312.270469)
			(xy 62.255275 -312.233632) (xy 62.228972 -312.192036) (xy 62.209681 -312.14676) (xy 62.197904 -312.098976)
			(xy 62.193944 -312.049922) (xy 60.905136 -312.049922) (xy 60.904641 -312.074529) (xy 60.896746 -312.123106)
			(xy 60.881162 -312.169787) (xy 60.858291 -312.213364) (xy 60.828726 -312.252708) (xy 60.793233 -312.2868)
			(xy 60.75273 -312.314756) (xy 60.708268 -312.335854) (xy 60.660997 -312.349546) (xy 60.612142 -312.355478)
			(xy 60.562967 -312.353497) (xy 60.514748 -312.343653) (xy 60.468732 -312.326201) (xy 60.426111 -312.301594)
			(xy 60.38799 -312.270469) (xy 60.355355 -312.233632) (xy 60.329052 -312.192036) (xy 60.309761 -312.14676)
			(xy 60.297984 -312.098976) (xy 60.294024 -312.049922) (xy 59.005216 -312.049922) (xy 59.004721 -312.074529)
			(xy 58.996826 -312.123106) (xy 58.981242 -312.169787) (xy 58.958371 -312.213364) (xy 58.928806 -312.252708)
			(xy 58.893313 -312.2868) (xy 58.85281 -312.314756) (xy 58.808348 -312.335854) (xy 58.761077 -312.349546)
			(xy 58.712222 -312.355478) (xy 58.663047 -312.353497) (xy 58.614828 -312.343653) (xy 58.568812 -312.326201)
			(xy 58.526191 -312.301594) (xy 58.48807 -312.270469) (xy 58.455435 -312.233632) (xy 58.429132 -312.192036)
			(xy 58.409841 -312.14676) (xy 58.398064 -312.098976) (xy 58.394104 -312.049922) (xy 57.105296 -312.049922)
			(xy 57.104801 -312.074529) (xy 57.096906 -312.123106) (xy 57.081322 -312.169787) (xy 57.058451 -312.213364)
			(xy 57.028886 -312.252708) (xy 56.993393 -312.2868) (xy 56.95289 -312.314756) (xy 56.908428 -312.335854)
			(xy 56.861157 -312.349546) (xy 56.812302 -312.355478) (xy 56.763127 -312.353497) (xy 56.714908 -312.343653)
			(xy 56.668892 -312.326201) (xy 56.626271 -312.301594) (xy 56.58815 -312.270469) (xy 56.555515 -312.233632)
			(xy 56.529212 -312.192036) (xy 56.509921 -312.14676) (xy 56.498144 -312.098976) (xy 56.494184 -312.049922)
			(xy 55.205122 -312.049922) (xy 55.204627 -312.074529) (xy 55.196732 -312.123106) (xy 55.181148 -312.169787)
			(xy 55.158277 -312.213364) (xy 55.128712 -312.252708) (xy 55.093219 -312.2868) (xy 55.052716 -312.314756)
			(xy 55.008254 -312.335854) (xy 54.960983 -312.349546) (xy 54.912128 -312.355478) (xy 54.862953 -312.353497)
			(xy 54.814734 -312.343653) (xy 54.768718 -312.326201) (xy 54.726097 -312.301594) (xy 54.687976 -312.270469)
			(xy 54.655341 -312.233632) (xy 54.629038 -312.192036) (xy 54.609747 -312.14676) (xy 54.59797 -312.098976)
			(xy 54.59401 -312.049922) (xy 53.305202 -312.049922) (xy 53.304707 -312.074529) (xy 53.296812 -312.123106)
			(xy 53.281228 -312.169787) (xy 53.258357 -312.213364) (xy 53.228792 -312.252708) (xy 53.193299 -312.2868)
			(xy 53.152796 -312.314756) (xy 53.108334 -312.335854) (xy 53.061063 -312.349546) (xy 53.012208 -312.355478)
			(xy 52.963033 -312.353497) (xy 52.914814 -312.343653) (xy 52.868798 -312.326201) (xy 52.826177 -312.301594)
			(xy 52.788056 -312.270469) (xy 52.755421 -312.233632) (xy 52.729118 -312.192036) (xy 52.709827 -312.14676)
			(xy 52.69805 -312.098976) (xy 52.69409 -312.049922) (xy 51.405282 -312.049922) (xy 51.404787 -312.074529)
			(xy 51.396892 -312.123106) (xy 51.381308 -312.169787) (xy 51.358437 -312.213364) (xy 51.328872 -312.252708)
			(xy 51.293379 -312.2868) (xy 51.252876 -312.314756) (xy 51.208414 -312.335854) (xy 51.161143 -312.349546)
			(xy 51.112288 -312.355478) (xy 51.063113 -312.353497) (xy 51.014894 -312.343653) (xy 50.968878 -312.326201)
			(xy 50.926257 -312.301594) (xy 50.888136 -312.270469) (xy 50.855501 -312.233632) (xy 50.829198 -312.192036)
			(xy 50.809907 -312.14676) (xy 50.79813 -312.098976) (xy 50.79417 -312.049922) (xy 49.505108 -312.049922)
			(xy 49.504613 -312.074529) (xy 49.496718 -312.123106) (xy 49.481134 -312.169787) (xy 49.458263 -312.213364)
			(xy 49.428698 -312.252708) (xy 49.393205 -312.2868) (xy 49.352702 -312.314756) (xy 49.30824 -312.335854)
			(xy 49.260969 -312.349546) (xy 49.212114 -312.355478) (xy 49.162939 -312.353497) (xy 49.11472 -312.343653)
			(xy 49.068704 -312.326201) (xy 49.026083 -312.301594) (xy 48.987962 -312.270469) (xy 48.955327 -312.233632)
			(xy 48.929024 -312.192036) (xy 48.909733 -312.14676) (xy 48.897956 -312.098976) (xy 48.893996 -312.049922)
			(xy 47.605188 -312.049922) (xy 47.604693 -312.074529) (xy 47.596798 -312.123106) (xy 47.581214 -312.169787)
			(xy 47.558343 -312.213364) (xy 47.528778 -312.252708) (xy 47.493285 -312.2868) (xy 47.452782 -312.314756)
			(xy 47.40832 -312.335854) (xy 47.361049 -312.349546) (xy 47.312194 -312.355478) (xy 47.263019 -312.353497)
			(xy 47.2148 -312.343653) (xy 47.168784 -312.326201) (xy 47.126163 -312.301594) (xy 47.088042 -312.270469)
			(xy 47.055407 -312.233632) (xy 47.029104 -312.192036) (xy 47.009813 -312.14676) (xy 46.998036 -312.098976)
			(xy 46.994076 -312.049922) (xy 45.705268 -312.049922) (xy 45.704773 -312.074529) (xy 45.696878 -312.123106)
			(xy 45.681294 -312.169787) (xy 45.658423 -312.213364) (xy 45.628858 -312.252708) (xy 45.593365 -312.2868)
			(xy 45.552862 -312.314756) (xy 45.5084 -312.335854) (xy 45.461129 -312.349546) (xy 45.412274 -312.355478)
			(xy 45.363099 -312.353497) (xy 45.31488 -312.343653) (xy 45.268864 -312.326201) (xy 45.226243 -312.301594)
			(xy 45.188122 -312.270469) (xy 45.155487 -312.233632) (xy 45.129184 -312.192036) (xy 45.109893 -312.14676)
			(xy 45.098116 -312.098976) (xy 45.094156 -312.049922) (xy 43.805094 -312.049922) (xy 43.804599 -312.074529)
			(xy 43.796704 -312.123106) (xy 43.78112 -312.169787) (xy 43.758249 -312.213364) (xy 43.728684 -312.252708)
			(xy 43.693191 -312.2868) (xy 43.652688 -312.314756) (xy 43.608226 -312.335854) (xy 43.560955 -312.349546)
			(xy 43.5121 -312.355478) (xy 43.462925 -312.353497) (xy 43.414706 -312.343653) (xy 43.36869 -312.326201)
			(xy 43.326069 -312.301594) (xy 43.287948 -312.270469) (xy 43.255313 -312.233632) (xy 43.22901 -312.192036)
			(xy 43.209719 -312.14676) (xy 43.197942 -312.098976) (xy 43.193982 -312.049922) (xy 41.905174 -312.049922)
			(xy 41.904679 -312.074529) (xy 41.896784 -312.123106) (xy 41.8812 -312.169787) (xy 41.858329 -312.213364)
			(xy 41.828764 -312.252708) (xy 41.793271 -312.2868) (xy 41.752768 -312.314756) (xy 41.708306 -312.335854)
			(xy 41.661035 -312.349546) (xy 41.61218 -312.355478) (xy 41.563005 -312.353497) (xy 41.514786 -312.343653)
			(xy 41.46877 -312.326201) (xy 41.426149 -312.301594) (xy 41.388028 -312.270469) (xy 41.355393 -312.233632)
			(xy 41.32909 -312.192036) (xy 41.309799 -312.14676) (xy 41.298022 -312.098976) (xy 41.294062 -312.049922)
			(xy 40.005254 -312.049922) (xy 40.004759 -312.074529) (xy 39.996864 -312.123106) (xy 39.98128 -312.169787)
			(xy 39.958409 -312.213364) (xy 39.928844 -312.252708) (xy 39.893351 -312.2868) (xy 39.852848 -312.314756)
			(xy 39.808386 -312.335854) (xy 39.761115 -312.349546) (xy 39.71226 -312.355478) (xy 39.663085 -312.353497)
			(xy 39.614866 -312.343653) (xy 39.56885 -312.326201) (xy 39.526229 -312.301594) (xy 39.488108 -312.270469)
			(xy 39.455473 -312.233632) (xy 39.42917 -312.192036) (xy 39.409879 -312.14676) (xy 39.398102 -312.098976)
			(xy 39.394142 -312.049922) (xy 38.10508 -312.049922) (xy 38.104585 -312.074529) (xy 38.09669 -312.123106)
			(xy 38.081106 -312.169787) (xy 38.058235 -312.213364) (xy 38.02867 -312.252708) (xy 37.993177 -312.2868)
			(xy 37.952674 -312.314756) (xy 37.908212 -312.335854) (xy 37.860941 -312.349546) (xy 37.812086 -312.355478)
			(xy 37.762911 -312.353497) (xy 37.714692 -312.343653) (xy 37.668676 -312.326201) (xy 37.626055 -312.301594)
			(xy 37.587934 -312.270469) (xy 37.555299 -312.233632) (xy 37.528996 -312.192036) (xy 37.509705 -312.14676)
			(xy 37.497928 -312.098976) (xy 37.493968 -312.049922) (xy 37.15512 -312.049922) (xy 37.154625 -312.074529)
			(xy 37.14673 -312.123106) (xy 37.131146 -312.169787) (xy 37.108275 -312.213364) (xy 37.07871 -312.252708)
			(xy 37.043217 -312.2868) (xy 37.002714 -312.314756) (xy 36.958252 -312.335854) (xy 36.910981 -312.349546)
			(xy 36.862126 -312.355478) (xy 36.812951 -312.353497) (xy 36.764732 -312.343653) (xy 36.718716 -312.326201)
			(xy 36.676095 -312.301594) (xy 36.637974 -312.270469) (xy 36.605339 -312.233632) (xy 36.579036 -312.192036)
			(xy 36.559745 -312.14676) (xy 36.547968 -312.098976) (xy 36.544008 -312.049922) (xy 0.508 -312.049922)
			(xy 0.508 -312.999882) (xy 38.444182 -312.999882) (xy 38.448142 -312.950828) (xy 38.459919 -312.903044)
			(xy 38.47921 -312.857768) (xy 38.505513 -312.816172) (xy 38.538148 -312.779335) (xy 38.576269 -312.74821)
			(xy 38.61889 -312.723603) (xy 38.664906 -312.706151) (xy 38.713125 -312.696307) (xy 38.7623 -312.694326)
			(xy 38.811155 -312.700258) (xy 38.858426 -312.71395) (xy 38.902888 -312.735048) (xy 38.943391 -312.763004)
			(xy 38.978884 -312.797096) (xy 39.008449 -312.83644) (xy 39.03132 -312.880017) (xy 39.046904 -312.926698)
			(xy 39.054799 -312.975275) (xy 39.055294 -312.999882) (xy 40.344102 -312.999882) (xy 40.348062 -312.950828)
			(xy 40.359839 -312.903044) (xy 40.37913 -312.857768) (xy 40.405433 -312.816172) (xy 40.438068 -312.779335)
			(xy 40.476189 -312.74821) (xy 40.51881 -312.723603) (xy 40.564826 -312.706151) (xy 40.613045 -312.696307)
			(xy 40.66222 -312.694326) (xy 40.711075 -312.700258) (xy 40.758346 -312.71395) (xy 40.802808 -312.735048)
			(xy 40.843311 -312.763004) (xy 40.878804 -312.797096) (xy 40.908369 -312.83644) (xy 40.93124 -312.880017)
			(xy 40.946824 -312.926698) (xy 40.954719 -312.975275) (xy 40.955214 -312.999882) (xy 42.244022 -312.999882)
			(xy 42.247982 -312.950828) (xy 42.259759 -312.903044) (xy 42.27905 -312.857768) (xy 42.305353 -312.816172)
			(xy 42.337988 -312.779335) (xy 42.376109 -312.74821) (xy 42.41873 -312.723603) (xy 42.464746 -312.706151)
			(xy 42.512965 -312.696307) (xy 42.56214 -312.694326) (xy 42.610995 -312.700258) (xy 42.658266 -312.71395)
			(xy 42.702728 -312.735048) (xy 42.743231 -312.763004) (xy 42.778724 -312.797096) (xy 42.808289 -312.83644)
			(xy 42.83116 -312.880017) (xy 42.846744 -312.926698) (xy 42.854639 -312.975275) (xy 42.855134 -312.999882)
			(xy 44.143942 -312.999882) (xy 44.147902 -312.950828) (xy 44.159679 -312.903044) (xy 44.17897 -312.857768)
			(xy 44.205273 -312.816172) (xy 44.237908 -312.779335) (xy 44.276029 -312.74821) (xy 44.31865 -312.723603)
			(xy 44.364666 -312.706151) (xy 44.412885 -312.696307) (xy 44.46206 -312.694326) (xy 44.510915 -312.700258)
			(xy 44.558186 -312.71395) (xy 44.602648 -312.735048) (xy 44.643151 -312.763004) (xy 44.678644 -312.797096)
			(xy 44.708209 -312.83644) (xy 44.73108 -312.880017) (xy 44.746664 -312.926698) (xy 44.754559 -312.975275)
			(xy 44.755054 -312.999882) (xy 46.044116 -312.999882) (xy 46.048076 -312.950828) (xy 46.059853 -312.903044)
			(xy 46.079144 -312.857768) (xy 46.105447 -312.816172) (xy 46.138082 -312.779335) (xy 46.176203 -312.74821)
			(xy 46.218824 -312.723603) (xy 46.26484 -312.706151) (xy 46.313059 -312.696307) (xy 46.362234 -312.694326)
			(xy 46.411089 -312.700258) (xy 46.45836 -312.71395) (xy 46.502822 -312.735048) (xy 46.543325 -312.763004)
			(xy 46.578818 -312.797096) (xy 46.608383 -312.83644) (xy 46.631254 -312.880017) (xy 46.646838 -312.926698)
			(xy 46.654733 -312.975275) (xy 46.655228 -312.999882) (xy 47.944036 -312.999882) (xy 47.947996 -312.950828)
			(xy 47.959773 -312.903044) (xy 47.979064 -312.857768) (xy 48.005367 -312.816172) (xy 48.038002 -312.779335)
			(xy 48.076123 -312.74821) (xy 48.118744 -312.723603) (xy 48.16476 -312.706151) (xy 48.212979 -312.696307)
			(xy 48.262154 -312.694326) (xy 48.311009 -312.700258) (xy 48.35828 -312.71395) (xy 48.402742 -312.735048)
			(xy 48.443245 -312.763004) (xy 48.478738 -312.797096) (xy 48.508303 -312.83644) (xy 48.531174 -312.880017)
			(xy 48.546758 -312.926698) (xy 48.554653 -312.975275) (xy 48.555148 -312.999882) (xy 49.843956 -312.999882)
			(xy 49.847916 -312.950828) (xy 49.859693 -312.903044) (xy 49.878984 -312.857768) (xy 49.905287 -312.816172)
			(xy 49.937922 -312.779335) (xy 49.976043 -312.74821) (xy 50.018664 -312.723603) (xy 50.06468 -312.706151)
			(xy 50.112899 -312.696307) (xy 50.162074 -312.694326) (xy 50.210929 -312.700258) (xy 50.2582 -312.71395)
			(xy 50.302662 -312.735048) (xy 50.343165 -312.763004) (xy 50.378658 -312.797096) (xy 50.408223 -312.83644)
			(xy 50.431094 -312.880017) (xy 50.446678 -312.926698) (xy 50.454573 -312.975275) (xy 50.455068 -312.999882)
			(xy 51.74413 -312.999882) (xy 51.74809 -312.950828) (xy 51.759867 -312.903044) (xy 51.779158 -312.857768)
			(xy 51.805461 -312.816172) (xy 51.838096 -312.779335) (xy 51.876217 -312.74821) (xy 51.918838 -312.723603)
			(xy 51.964854 -312.706151) (xy 52.013073 -312.696307) (xy 52.062248 -312.694326) (xy 52.111103 -312.700258)
			(xy 52.158374 -312.71395) (xy 52.202836 -312.735048) (xy 52.243339 -312.763004) (xy 52.278832 -312.797096)
			(xy 52.308397 -312.83644) (xy 52.331268 -312.880017) (xy 52.346852 -312.926698) (xy 52.354747 -312.975275)
			(xy 52.355242 -312.999882) (xy 53.64405 -312.999882) (xy 53.64801 -312.950828) (xy 53.659787 -312.903044)
			(xy 53.679078 -312.857768) (xy 53.705381 -312.816172) (xy 53.738016 -312.779335) (xy 53.776137 -312.74821)
			(xy 53.818758 -312.723603) (xy 53.864774 -312.706151) (xy 53.912993 -312.696307) (xy 53.962168 -312.694326)
			(xy 54.011023 -312.700258) (xy 54.058294 -312.71395) (xy 54.102756 -312.735048) (xy 54.143259 -312.763004)
			(xy 54.178752 -312.797096) (xy 54.208317 -312.83644) (xy 54.231188 -312.880017) (xy 54.246772 -312.926698)
			(xy 54.254667 -312.975275) (xy 54.255162 -312.999882) (xy 55.54397 -312.999882) (xy 55.54793 -312.950828)
			(xy 55.559707 -312.903044) (xy 55.578998 -312.857768) (xy 55.605301 -312.816172) (xy 55.637936 -312.779335)
			(xy 55.676057 -312.74821) (xy 55.718678 -312.723603) (xy 55.764694 -312.706151) (xy 55.812913 -312.696307)
			(xy 55.862088 -312.694326) (xy 55.910943 -312.700258) (xy 55.958214 -312.71395) (xy 56.002676 -312.735048)
			(xy 56.043179 -312.763004) (xy 56.078672 -312.797096) (xy 56.108237 -312.83644) (xy 56.131108 -312.880017)
			(xy 56.146692 -312.926698) (xy 56.154587 -312.975275) (xy 56.155082 -312.999882) (xy 57.444144 -312.999882)
			(xy 57.448104 -312.950828) (xy 57.459881 -312.903044) (xy 57.479172 -312.857768) (xy 57.505475 -312.816172)
			(xy 57.53811 -312.779335) (xy 57.576231 -312.74821) (xy 57.618852 -312.723603) (xy 57.664868 -312.706151)
			(xy 57.713087 -312.696307) (xy 57.762262 -312.694326) (xy 57.811117 -312.700258) (xy 57.858388 -312.71395)
			(xy 57.90285 -312.735048) (xy 57.943353 -312.763004) (xy 57.978846 -312.797096) (xy 58.008411 -312.83644)
			(xy 58.031282 -312.880017) (xy 58.046866 -312.926698) (xy 58.054761 -312.975275) (xy 58.055256 -312.999882)
			(xy 59.344064 -312.999882) (xy 59.348024 -312.950828) (xy 59.359801 -312.903044) (xy 59.379092 -312.857768)
			(xy 59.405395 -312.816172) (xy 59.43803 -312.779335) (xy 59.476151 -312.74821) (xy 59.518772 -312.723603)
			(xy 59.564788 -312.706151) (xy 59.613007 -312.696307) (xy 59.662182 -312.694326) (xy 59.711037 -312.700258)
			(xy 59.758308 -312.71395) (xy 59.80277 -312.735048) (xy 59.843273 -312.763004) (xy 59.878766 -312.797096)
			(xy 59.908331 -312.83644) (xy 59.931202 -312.880017) (xy 59.946786 -312.926698) (xy 59.954681 -312.975275)
			(xy 59.955176 -312.999882) (xy 61.243984 -312.999882) (xy 61.247944 -312.950828) (xy 61.259721 -312.903044)
			(xy 61.279012 -312.857768) (xy 61.305315 -312.816172) (xy 61.33795 -312.779335) (xy 61.376071 -312.74821)
			(xy 61.418692 -312.723603) (xy 61.464708 -312.706151) (xy 61.512927 -312.696307) (xy 61.562102 -312.694326)
			(xy 61.610957 -312.700258) (xy 61.658228 -312.71395) (xy 61.70269 -312.735048) (xy 61.743193 -312.763004)
			(xy 61.778686 -312.797096) (xy 61.808251 -312.83644) (xy 61.831122 -312.880017) (xy 61.846706 -312.926698)
			(xy 61.854601 -312.975275) (xy 61.855096 -312.999882) (xy 63.144158 -312.999882) (xy 63.148118 -312.950828)
			(xy 63.159895 -312.903044) (xy 63.179186 -312.857768) (xy 63.205489 -312.816172) (xy 63.238124 -312.779335)
			(xy 63.276245 -312.74821) (xy 63.318866 -312.723603) (xy 63.364882 -312.706151) (xy 63.413101 -312.696307)
			(xy 63.462276 -312.694326) (xy 63.511131 -312.700258) (xy 63.558402 -312.71395) (xy 63.602864 -312.735048)
			(xy 63.643367 -312.763004) (xy 63.67886 -312.797096) (xy 63.708425 -312.83644) (xy 63.731296 -312.880017)
			(xy 63.74688 -312.926698) (xy 63.754775 -312.975275) (xy 63.75527 -312.999882) (xy 65.044078 -312.999882)
			(xy 65.048038 -312.950828) (xy 65.059815 -312.903044) (xy 65.079106 -312.857768) (xy 65.105409 -312.816172)
			(xy 65.138044 -312.779335) (xy 65.176165 -312.74821) (xy 65.218786 -312.723603) (xy 65.264802 -312.706151)
			(xy 65.313021 -312.696307) (xy 65.362196 -312.694326) (xy 65.411051 -312.700258) (xy 65.458322 -312.71395)
			(xy 65.502784 -312.735048) (xy 65.543287 -312.763004) (xy 65.57878 -312.797096) (xy 65.608345 -312.83644)
			(xy 65.631216 -312.880017) (xy 65.6468 -312.926698) (xy 65.654695 -312.975275) (xy 65.65519 -312.999882)
			(xy 66.943998 -312.999882) (xy 66.947958 -312.950828) (xy 66.959735 -312.903044) (xy 66.979026 -312.857768)
			(xy 67.005329 -312.816172) (xy 67.037964 -312.779335) (xy 67.076085 -312.74821) (xy 67.118706 -312.723603)
			(xy 67.164722 -312.706151) (xy 67.212941 -312.696307) (xy 67.262116 -312.694326) (xy 67.310971 -312.700258)
			(xy 67.358242 -312.71395) (xy 67.402704 -312.735048) (xy 67.443207 -312.763004) (xy 67.4787 -312.797096)
			(xy 67.508265 -312.83644) (xy 67.531136 -312.880017) (xy 67.54672 -312.926698) (xy 67.554615 -312.975275)
			(xy 67.55511 -312.999882) (xy 68.844172 -312.999882) (xy 68.848132 -312.950828) (xy 68.859909 -312.903044)
			(xy 68.8792 -312.857768) (xy 68.905503 -312.816172) (xy 68.938138 -312.779335) (xy 68.976259 -312.74821)
			(xy 69.01888 -312.723603) (xy 69.064896 -312.706151) (xy 69.113115 -312.696307) (xy 69.16229 -312.694326)
			(xy 69.211145 -312.700258) (xy 69.258416 -312.71395) (xy 69.302878 -312.735048) (xy 69.343381 -312.763004)
			(xy 69.378874 -312.797096) (xy 69.408439 -312.83644) (xy 69.43131 -312.880017) (xy 69.446894 -312.926698)
			(xy 69.454789 -312.975275) (xy 69.455284 -312.999882) (xy 70.744092 -312.999882) (xy 70.748052 -312.950828)
			(xy 70.759829 -312.903044) (xy 70.77912 -312.857768) (xy 70.805423 -312.816172) (xy 70.838058 -312.779335)
			(xy 70.876179 -312.74821) (xy 70.9188 -312.723603) (xy 70.964816 -312.706151) (xy 71.013035 -312.696307)
			(xy 71.06221 -312.694326) (xy 71.111065 -312.700258) (xy 71.158336 -312.71395) (xy 71.202798 -312.735048)
			(xy 71.243301 -312.763004) (xy 71.278794 -312.797096) (xy 71.308359 -312.83644) (xy 71.33123 -312.880017)
			(xy 71.346814 -312.926698) (xy 71.354709 -312.975275) (xy 71.355204 -312.999882) (xy 72.644012 -312.999882)
			(xy 72.647972 -312.950828) (xy 72.659749 -312.903044) (xy 72.67904 -312.857768) (xy 72.705343 -312.816172)
			(xy 72.737978 -312.779335) (xy 72.776099 -312.74821) (xy 72.81872 -312.723603) (xy 72.864736 -312.706151)
			(xy 72.912955 -312.696307) (xy 72.96213 -312.694326) (xy 73.010985 -312.700258) (xy 73.058256 -312.71395)
			(xy 73.102718 -312.735048) (xy 73.143221 -312.763004) (xy 73.178714 -312.797096) (xy 73.208279 -312.83644)
			(xy 73.23115 -312.880017) (xy 73.246734 -312.926698) (xy 73.254629 -312.975275) (xy 73.255124 -312.999882)
			(xy 74.544186 -312.999882) (xy 74.548146 -312.950828) (xy 74.559923 -312.903044) (xy 74.579214 -312.857768)
			(xy 74.605517 -312.816172) (xy 74.638152 -312.779335) (xy 74.676273 -312.74821) (xy 74.718894 -312.723603)
			(xy 74.76491 -312.706151) (xy 74.813129 -312.696307) (xy 74.862304 -312.694326) (xy 74.911159 -312.700258)
			(xy 74.95843 -312.71395) (xy 75.002892 -312.735048) (xy 75.043395 -312.763004) (xy 75.078888 -312.797096)
			(xy 75.108453 -312.83644) (xy 75.131324 -312.880017) (xy 75.146908 -312.926698) (xy 75.154803 -312.975275)
			(xy 75.155298 -312.999882) (xy 76.444106 -312.999882) (xy 76.448066 -312.950828) (xy 76.459843 -312.903044)
			(xy 76.479134 -312.857768) (xy 76.505437 -312.816172) (xy 76.538072 -312.779335) (xy 76.576193 -312.74821)
			(xy 76.618814 -312.723603) (xy 76.66483 -312.706151) (xy 76.713049 -312.696307) (xy 76.762224 -312.694326)
			(xy 76.811079 -312.700258) (xy 76.85835 -312.71395) (xy 76.902812 -312.735048) (xy 76.943315 -312.763004)
			(xy 76.978808 -312.797096) (xy 77.008373 -312.83644) (xy 77.031244 -312.880017) (xy 77.046828 -312.926698)
			(xy 77.054723 -312.975275) (xy 77.055218 -312.999882) (xy 78.344026 -312.999882) (xy 78.347986 -312.950828)
			(xy 78.359763 -312.903044) (xy 78.379054 -312.857768) (xy 78.405357 -312.816172) (xy 78.437992 -312.779335)
			(xy 78.476113 -312.74821) (xy 78.518734 -312.723603) (xy 78.56475 -312.706151) (xy 78.612969 -312.696307)
			(xy 78.662144 -312.694326) (xy 78.710999 -312.700258) (xy 78.75827 -312.71395) (xy 78.802732 -312.735048)
			(xy 78.843235 -312.763004) (xy 78.878728 -312.797096) (xy 78.908293 -312.83644) (xy 78.931164 -312.880017)
			(xy 78.946748 -312.926698) (xy 78.954643 -312.975275) (xy 78.955138 -312.999882) (xy 80.243946 -312.999882)
			(xy 80.247906 -312.950828) (xy 80.259683 -312.903044) (xy 80.278974 -312.857768) (xy 80.305277 -312.816172)
			(xy 80.337912 -312.779335) (xy 80.376033 -312.74821) (xy 80.418654 -312.723603) (xy 80.46467 -312.706151)
			(xy 80.512889 -312.696307) (xy 80.562064 -312.694326) (xy 80.610919 -312.700258) (xy 80.65819 -312.71395)
			(xy 80.702652 -312.735048) (xy 80.743155 -312.763004) (xy 80.778648 -312.797096) (xy 80.808213 -312.83644)
			(xy 80.831084 -312.880017) (xy 80.846668 -312.926698) (xy 80.854563 -312.975275) (xy 80.855058 -312.999882)
			(xy 154.54428 -312.999882) (xy 154.54824 -312.950828) (xy 154.560017 -312.903044) (xy 154.579308 -312.857768)
			(xy 154.605611 -312.816172) (xy 154.638246 -312.779335) (xy 154.676367 -312.74821) (xy 154.718988 -312.723603)
			(xy 154.765004 -312.706151) (xy 154.813223 -312.696307) (xy 154.862398 -312.694326) (xy 154.911253 -312.700258)
			(xy 154.958524 -312.71395) (xy 155.002986 -312.735048) (xy 155.043489 -312.763004) (xy 155.078982 -312.797096)
			(xy 155.108547 -312.83644) (xy 155.131418 -312.880017) (xy 155.147002 -312.926698) (xy 155.154897 -312.975275)
			(xy 155.155392 -312.999882) (xy 156.4442 -312.999882) (xy 156.44816 -312.950828) (xy 156.459937 -312.903044)
			(xy 156.479228 -312.857768) (xy 156.505531 -312.816172) (xy 156.538166 -312.779335) (xy 156.576287 -312.74821)
			(xy 156.618908 -312.723603) (xy 156.664924 -312.706151) (xy 156.713143 -312.696307) (xy 156.762318 -312.694326)
			(xy 156.811173 -312.700258) (xy 156.858444 -312.71395) (xy 156.902906 -312.735048) (xy 156.943409 -312.763004)
			(xy 156.978902 -312.797096) (xy 157.008467 -312.83644) (xy 157.031338 -312.880017) (xy 157.046922 -312.926698)
			(xy 157.054817 -312.975275) (xy 157.055312 -312.999882) (xy 158.34412 -312.999882) (xy 158.34808 -312.950828)
			(xy 158.359857 -312.903044) (xy 158.379148 -312.857768) (xy 158.405451 -312.816172) (xy 158.438086 -312.779335)
			(xy 158.476207 -312.74821) (xy 158.518828 -312.723603) (xy 158.564844 -312.706151) (xy 158.613063 -312.696307)
			(xy 158.662238 -312.694326) (xy 158.711093 -312.700258) (xy 158.758364 -312.71395) (xy 158.802826 -312.735048)
			(xy 158.843329 -312.763004) (xy 158.878822 -312.797096) (xy 158.908387 -312.83644) (xy 158.931258 -312.880017)
			(xy 158.946842 -312.926698) (xy 158.954737 -312.975275) (xy 158.955232 -312.999882) (xy 160.24404 -312.999882)
			(xy 160.248 -312.950828) (xy 160.259777 -312.903044) (xy 160.279068 -312.857768) (xy 160.305371 -312.816172)
			(xy 160.338006 -312.779335) (xy 160.376127 -312.74821) (xy 160.418748 -312.723603) (xy 160.464764 -312.706151)
			(xy 160.512983 -312.696307) (xy 160.562158 -312.694326) (xy 160.611013 -312.700258) (xy 160.658284 -312.71395)
			(xy 160.702746 -312.735048) (xy 160.743249 -312.763004) (xy 160.778742 -312.797096) (xy 160.808307 -312.83644)
			(xy 160.831178 -312.880017) (xy 160.846762 -312.926698) (xy 160.854657 -312.975275) (xy 160.855152 -312.999882)
			(xy 162.144214 -312.999882) (xy 162.148174 -312.950828) (xy 162.159951 -312.903044) (xy 162.179242 -312.857768)
			(xy 162.205545 -312.816172) (xy 162.23818 -312.779335) (xy 162.276301 -312.74821) (xy 162.318922 -312.723603)
			(xy 162.364938 -312.706151) (xy 162.413157 -312.696307) (xy 162.462332 -312.694326) (xy 162.511187 -312.700258)
			(xy 162.558458 -312.71395) (xy 162.60292 -312.735048) (xy 162.643423 -312.763004) (xy 162.678916 -312.797096)
			(xy 162.708481 -312.83644) (xy 162.731352 -312.880017) (xy 162.746936 -312.926698) (xy 162.754831 -312.975275)
			(xy 162.755326 -312.999882) (xy 164.044134 -312.999882) (xy 164.048094 -312.950828) (xy 164.059871 -312.903044)
			(xy 164.079162 -312.857768) (xy 164.105465 -312.816172) (xy 164.1381 -312.779335) (xy 164.176221 -312.74821)
			(xy 164.218842 -312.723603) (xy 164.264858 -312.706151) (xy 164.313077 -312.696307) (xy 164.362252 -312.694326)
			(xy 164.411107 -312.700258) (xy 164.458378 -312.71395) (xy 164.50284 -312.735048) (xy 164.543343 -312.763004)
			(xy 164.578836 -312.797096) (xy 164.608401 -312.83644) (xy 164.631272 -312.880017) (xy 164.646856 -312.926698)
			(xy 164.654751 -312.975275) (xy 164.655246 -312.999882) (xy 165.944054 -312.999882) (xy 165.948014 -312.950828)
			(xy 165.959791 -312.903044) (xy 165.979082 -312.857768) (xy 166.005385 -312.816172) (xy 166.03802 -312.779335)
			(xy 166.076141 -312.74821) (xy 166.118762 -312.723603) (xy 166.164778 -312.706151) (xy 166.212997 -312.696307)
			(xy 166.262172 -312.694326) (xy 166.311027 -312.700258) (xy 166.358298 -312.71395) (xy 166.40276 -312.735048)
			(xy 166.443263 -312.763004) (xy 166.478756 -312.797096) (xy 166.508321 -312.83644) (xy 166.531192 -312.880017)
			(xy 166.546776 -312.926698) (xy 166.554671 -312.975275) (xy 166.555166 -312.999882) (xy 167.844228 -312.999882)
			(xy 167.848188 -312.950828) (xy 167.859965 -312.903044) (xy 167.879256 -312.857768) (xy 167.905559 -312.816172)
			(xy 167.938194 -312.779335) (xy 167.976315 -312.74821) (xy 168.018936 -312.723603) (xy 168.064952 -312.706151)
			(xy 168.113171 -312.696307) (xy 168.162346 -312.694326) (xy 168.211201 -312.700258) (xy 168.258472 -312.71395)
			(xy 168.302934 -312.735048) (xy 168.343437 -312.763004) (xy 168.37893 -312.797096) (xy 168.408495 -312.83644)
			(xy 168.431366 -312.880017) (xy 168.44695 -312.926698) (xy 168.454845 -312.975275) (xy 168.45534 -312.999882)
			(xy 169.744148 -312.999882) (xy 169.748108 -312.950828) (xy 169.759885 -312.903044) (xy 169.779176 -312.857768)
			(xy 169.805479 -312.816172) (xy 169.838114 -312.779335) (xy 169.876235 -312.74821) (xy 169.918856 -312.723603)
			(xy 169.964872 -312.706151) (xy 170.013091 -312.696307) (xy 170.062266 -312.694326) (xy 170.111121 -312.700258)
			(xy 170.158392 -312.71395) (xy 170.202854 -312.735048) (xy 170.243357 -312.763004) (xy 170.27885 -312.797096)
			(xy 170.308415 -312.83644) (xy 170.331286 -312.880017) (xy 170.34687 -312.926698) (xy 170.354765 -312.975275)
			(xy 170.35526 -312.999882) (xy 171.644068 -312.999882) (xy 171.648028 -312.950828) (xy 171.659805 -312.903044)
			(xy 171.679096 -312.857768) (xy 171.705399 -312.816172) (xy 171.738034 -312.779335) (xy 171.776155 -312.74821)
			(xy 171.818776 -312.723603) (xy 171.864792 -312.706151) (xy 171.913011 -312.696307) (xy 171.962186 -312.694326)
			(xy 172.011041 -312.700258) (xy 172.058312 -312.71395) (xy 172.102774 -312.735048) (xy 172.143277 -312.763004)
			(xy 172.17877 -312.797096) (xy 172.208335 -312.83644) (xy 172.231206 -312.880017) (xy 172.24679 -312.926698)
			(xy 172.254685 -312.975275) (xy 172.25518 -312.999882) (xy 173.544242 -312.999882) (xy 173.548202 -312.950828)
			(xy 173.559979 -312.903044) (xy 173.57927 -312.857768) (xy 173.605573 -312.816172) (xy 173.638208 -312.779335)
			(xy 173.676329 -312.74821) (xy 173.71895 -312.723603) (xy 173.764966 -312.706151) (xy 173.813185 -312.696307)
			(xy 173.86236 -312.694326) (xy 173.911215 -312.700258) (xy 173.958486 -312.71395) (xy 174.002948 -312.735048)
			(xy 174.043451 -312.763004) (xy 174.078944 -312.797096) (xy 174.108509 -312.83644) (xy 174.13138 -312.880017)
			(xy 174.146964 -312.926698) (xy 174.154859 -312.975275) (xy 174.155354 -312.999882) (xy 175.444162 -312.999882)
			(xy 175.448122 -312.950828) (xy 175.459899 -312.903044) (xy 175.47919 -312.857768) (xy 175.505493 -312.816172)
			(xy 175.538128 -312.779335) (xy 175.576249 -312.74821) (xy 175.61887 -312.723603) (xy 175.664886 -312.706151)
			(xy 175.713105 -312.696307) (xy 175.76228 -312.694326) (xy 175.811135 -312.700258) (xy 175.858406 -312.71395)
			(xy 175.902868 -312.735048) (xy 175.943371 -312.763004) (xy 175.978864 -312.797096) (xy 176.008429 -312.83644)
			(xy 176.0313 -312.880017) (xy 176.046884 -312.926698) (xy 176.054779 -312.975275) (xy 176.055274 -312.999882)
			(xy 177.344082 -312.999882) (xy 177.348042 -312.950828) (xy 177.359819 -312.903044) (xy 177.37911 -312.857768)
			(xy 177.405413 -312.816172) (xy 177.438048 -312.779335) (xy 177.476169 -312.74821) (xy 177.51879 -312.723603)
			(xy 177.564806 -312.706151) (xy 177.613025 -312.696307) (xy 177.6622 -312.694326) (xy 177.711055 -312.700258)
			(xy 177.758326 -312.71395) (xy 177.802788 -312.735048) (xy 177.843291 -312.763004) (xy 177.878784 -312.797096)
			(xy 177.908349 -312.83644) (xy 177.93122 -312.880017) (xy 177.946804 -312.926698) (xy 177.954699 -312.975275)
			(xy 177.955194 -312.999882) (xy 179.244256 -312.999882) (xy 179.248216 -312.950828) (xy 179.259993 -312.903044)
			(xy 179.279284 -312.857768) (xy 179.305587 -312.816172) (xy 179.338222 -312.779335) (xy 179.376343 -312.74821)
			(xy 179.418964 -312.723603) (xy 179.46498 -312.706151) (xy 179.513199 -312.696307) (xy 179.562374 -312.694326)
			(xy 179.611229 -312.700258) (xy 179.6585 -312.71395) (xy 179.702962 -312.735048) (xy 179.743465 -312.763004)
			(xy 179.778958 -312.797096) (xy 179.808523 -312.83644) (xy 179.831394 -312.880017) (xy 179.846978 -312.926698)
			(xy 179.854873 -312.975275) (xy 179.855368 -312.999882) (xy 181.144176 -312.999882) (xy 181.148136 -312.950828)
			(xy 181.159913 -312.903044) (xy 181.179204 -312.857768) (xy 181.205507 -312.816172) (xy 181.238142 -312.779335)
			(xy 181.276263 -312.74821) (xy 181.318884 -312.723603) (xy 181.3649 -312.706151) (xy 181.413119 -312.696307)
			(xy 181.462294 -312.694326) (xy 181.511149 -312.700258) (xy 181.55842 -312.71395) (xy 181.602882 -312.735048)
			(xy 181.643385 -312.763004) (xy 181.678878 -312.797096) (xy 181.708443 -312.83644) (xy 181.731314 -312.880017)
			(xy 181.746898 -312.926698) (xy 181.754793 -312.975275) (xy 181.755288 -312.999882) (xy 183.044096 -312.999882)
			(xy 183.048056 -312.950828) (xy 183.059833 -312.903044) (xy 183.079124 -312.857768) (xy 183.105427 -312.816172)
			(xy 183.138062 -312.779335) (xy 183.176183 -312.74821) (xy 183.218804 -312.723603) (xy 183.26482 -312.706151)
			(xy 183.313039 -312.696307) (xy 183.362214 -312.694326) (xy 183.411069 -312.700258) (xy 183.45834 -312.71395)
			(xy 183.502802 -312.735048) (xy 183.543305 -312.763004) (xy 183.578798 -312.797096) (xy 183.608363 -312.83644)
			(xy 183.631234 -312.880017) (xy 183.646818 -312.926698) (xy 183.654713 -312.975275) (xy 183.655208 -312.999882)
			(xy 184.94427 -312.999882) (xy 184.94823 -312.950828) (xy 184.960007 -312.903044) (xy 184.979298 -312.857768)
			(xy 185.005601 -312.816172) (xy 185.038236 -312.779335) (xy 185.076357 -312.74821) (xy 185.118978 -312.723603)
			(xy 185.164994 -312.706151) (xy 185.213213 -312.696307) (xy 185.262388 -312.694326) (xy 185.311243 -312.700258)
			(xy 185.358514 -312.71395) (xy 185.402976 -312.735048) (xy 185.443479 -312.763004) (xy 185.478972 -312.797096)
			(xy 185.508537 -312.83644) (xy 185.531408 -312.880017) (xy 185.546992 -312.926698) (xy 185.554887 -312.975275)
			(xy 185.555382 -312.999882) (xy 186.84419 -312.999882) (xy 186.84815 -312.950828) (xy 186.859927 -312.903044)
			(xy 186.879218 -312.857768) (xy 186.905521 -312.816172) (xy 186.938156 -312.779335) (xy 186.976277 -312.74821)
			(xy 187.018898 -312.723603) (xy 187.064914 -312.706151) (xy 187.113133 -312.696307) (xy 187.162308 -312.694326)
			(xy 187.211163 -312.700258) (xy 187.258434 -312.71395) (xy 187.302896 -312.735048) (xy 187.343399 -312.763004)
			(xy 187.378892 -312.797096) (xy 187.408457 -312.83644) (xy 187.431328 -312.880017) (xy 187.446912 -312.926698)
			(xy 187.454807 -312.975275) (xy 187.455302 -312.999882) (xy 188.74411 -312.999882) (xy 188.74807 -312.950828)
			(xy 188.759847 -312.903044) (xy 188.779138 -312.857768) (xy 188.805441 -312.816172) (xy 188.838076 -312.779335)
			(xy 188.876197 -312.74821) (xy 188.918818 -312.723603) (xy 188.964834 -312.706151) (xy 189.013053 -312.696307)
			(xy 189.062228 -312.694326) (xy 189.111083 -312.700258) (xy 189.158354 -312.71395) (xy 189.202816 -312.735048)
			(xy 189.243319 -312.763004) (xy 189.278812 -312.797096) (xy 189.308377 -312.83644) (xy 189.331248 -312.880017)
			(xy 189.346832 -312.926698) (xy 189.354727 -312.975275) (xy 189.355222 -312.999882) (xy 190.644284 -312.999882)
			(xy 190.648244 -312.950828) (xy 190.660021 -312.903044) (xy 190.679312 -312.857768) (xy 190.705615 -312.816172)
			(xy 190.73825 -312.779335) (xy 190.776371 -312.74821) (xy 190.818992 -312.723603) (xy 190.865008 -312.706151)
			(xy 190.913227 -312.696307) (xy 190.962402 -312.694326) (xy 191.011257 -312.700258) (xy 191.058528 -312.71395)
			(xy 191.10299 -312.735048) (xy 191.143493 -312.763004) (xy 191.178986 -312.797096) (xy 191.208551 -312.83644)
			(xy 191.231422 -312.880017) (xy 191.247006 -312.926698) (xy 191.254901 -312.975275) (xy 191.255396 -312.999882)
			(xy 192.544204 -312.999882) (xy 192.548164 -312.950828) (xy 192.559941 -312.903044) (xy 192.579232 -312.857768)
			(xy 192.605535 -312.816172) (xy 192.63817 -312.779335) (xy 192.676291 -312.74821) (xy 192.718912 -312.723603)
			(xy 192.764928 -312.706151) (xy 192.813147 -312.696307) (xy 192.862322 -312.694326) (xy 192.911177 -312.700258)
			(xy 192.958448 -312.71395) (xy 193.00291 -312.735048) (xy 193.043413 -312.763004) (xy 193.078906 -312.797096)
			(xy 193.108471 -312.83644) (xy 193.131342 -312.880017) (xy 193.146926 -312.926698) (xy 193.154821 -312.975275)
			(xy 193.155316 -312.999882) (xy 194.444124 -312.999882) (xy 194.448084 -312.950828) (xy 194.459861 -312.903044)
			(xy 194.479152 -312.857768) (xy 194.505455 -312.816172) (xy 194.53809 -312.779335) (xy 194.576211 -312.74821)
			(xy 194.618832 -312.723603) (xy 194.664848 -312.706151) (xy 194.713067 -312.696307) (xy 194.762242 -312.694326)
			(xy 194.811097 -312.700258) (xy 194.858368 -312.71395) (xy 194.90283 -312.735048) (xy 194.943333 -312.763004)
			(xy 194.978826 -312.797096) (xy 195.008391 -312.83644) (xy 195.031262 -312.880017) (xy 195.046846 -312.926698)
			(xy 195.054741 -312.975275) (xy 195.055236 -312.999882) (xy 196.344044 -312.999882) (xy 196.348004 -312.950828)
			(xy 196.359781 -312.903044) (xy 196.379072 -312.857768) (xy 196.405375 -312.816172) (xy 196.43801 -312.779335)
			(xy 196.476131 -312.74821) (xy 196.518752 -312.723603) (xy 196.564768 -312.706151) (xy 196.612987 -312.696307)
			(xy 196.662162 -312.694326) (xy 196.711017 -312.700258) (xy 196.758288 -312.71395) (xy 196.80275 -312.735048)
			(xy 196.843253 -312.763004) (xy 196.878746 -312.797096) (xy 196.908311 -312.83644) (xy 196.931182 -312.880017)
			(xy 196.946766 -312.926698) (xy 196.954661 -312.975275) (xy 196.955156 -312.999882) (xy 270.644124 -312.999882)
			(xy 270.648084 -312.950828) (xy 270.659861 -312.903044) (xy 270.679152 -312.857768) (xy 270.705455 -312.816172)
			(xy 270.73809 -312.779335) (xy 270.776211 -312.74821) (xy 270.818832 -312.723603) (xy 270.864848 -312.706151)
			(xy 270.913067 -312.696307) (xy 270.962242 -312.694326) (xy 271.011097 -312.700258) (xy 271.058368 -312.71395)
			(xy 271.10283 -312.735048) (xy 271.143333 -312.763004) (xy 271.178826 -312.797096) (xy 271.208391 -312.83644)
			(xy 271.231262 -312.880017) (xy 271.246846 -312.926698) (xy 271.254741 -312.975275) (xy 271.255236 -312.999882)
			(xy 272.544044 -312.999882) (xy 272.548004 -312.950828) (xy 272.559781 -312.903044) (xy 272.579072 -312.857768)
			(xy 272.605375 -312.816172) (xy 272.63801 -312.779335) (xy 272.676131 -312.74821) (xy 272.718752 -312.723603)
			(xy 272.764768 -312.706151) (xy 272.812987 -312.696307) (xy 272.862162 -312.694326) (xy 272.911017 -312.700258)
			(xy 272.958288 -312.71395) (xy 273.00275 -312.735048) (xy 273.043253 -312.763004) (xy 273.078746 -312.797096)
			(xy 273.108311 -312.83644) (xy 273.131182 -312.880017) (xy 273.146766 -312.926698) (xy 273.154661 -312.975275)
			(xy 273.155156 -312.999882) (xy 274.443964 -312.999882) (xy 274.447924 -312.950828) (xy 274.459701 -312.903044)
			(xy 274.478992 -312.857768) (xy 274.505295 -312.816172) (xy 274.53793 -312.779335) (xy 274.576051 -312.74821)
			(xy 274.618672 -312.723603) (xy 274.664688 -312.706151) (xy 274.712907 -312.696307) (xy 274.762082 -312.694326)
			(xy 274.810937 -312.700258) (xy 274.858208 -312.71395) (xy 274.90267 -312.735048) (xy 274.943173 -312.763004)
			(xy 274.978666 -312.797096) (xy 275.008231 -312.83644) (xy 275.031102 -312.880017) (xy 275.046686 -312.926698)
			(xy 275.054581 -312.975275) (xy 275.055076 -312.999882) (xy 276.343884 -312.999882) (xy 276.347844 -312.950828)
			(xy 276.359621 -312.903044) (xy 276.378912 -312.857768) (xy 276.405215 -312.816172) (xy 276.43785 -312.779335)
			(xy 276.475971 -312.74821) (xy 276.518592 -312.723603) (xy 276.564608 -312.706151) (xy 276.612827 -312.696307)
			(xy 276.662002 -312.694326) (xy 276.710857 -312.700258) (xy 276.758128 -312.71395) (xy 276.80259 -312.735048)
			(xy 276.843093 -312.763004) (xy 276.878586 -312.797096) (xy 276.908151 -312.83644) (xy 276.931022 -312.880017)
			(xy 276.946606 -312.926698) (xy 276.954501 -312.975275) (xy 276.954996 -312.999882) (xy 278.244058 -312.999882)
			(xy 278.248018 -312.950828) (xy 278.259795 -312.903044) (xy 278.279086 -312.857768) (xy 278.305389 -312.816172)
			(xy 278.338024 -312.779335) (xy 278.376145 -312.74821) (xy 278.418766 -312.723603) (xy 278.464782 -312.706151)
			(xy 278.513001 -312.696307) (xy 278.562176 -312.694326) (xy 278.611031 -312.700258) (xy 278.658302 -312.71395)
			(xy 278.702764 -312.735048) (xy 278.743267 -312.763004) (xy 278.77876 -312.797096) (xy 278.808325 -312.83644)
			(xy 278.831196 -312.880017) (xy 278.84678 -312.926698) (xy 278.854675 -312.975275) (xy 278.85517 -312.999882)
			(xy 280.143978 -312.999882) (xy 280.147938 -312.950828) (xy 280.159715 -312.903044) (xy 280.179006 -312.857768)
			(xy 280.205309 -312.816172) (xy 280.237944 -312.779335) (xy 280.276065 -312.74821) (xy 280.318686 -312.723603)
			(xy 280.364702 -312.706151) (xy 280.412921 -312.696307) (xy 280.462096 -312.694326) (xy 280.510951 -312.700258)
			(xy 280.558222 -312.71395) (xy 280.602684 -312.735048) (xy 280.643187 -312.763004) (xy 280.67868 -312.797096)
			(xy 280.708245 -312.83644) (xy 280.731116 -312.880017) (xy 280.7467 -312.926698) (xy 280.754595 -312.975275)
			(xy 280.75509 -312.999882) (xy 282.043898 -312.999882) (xy 282.047858 -312.950828) (xy 282.059635 -312.903044)
			(xy 282.078926 -312.857768) (xy 282.105229 -312.816172) (xy 282.137864 -312.779335) (xy 282.175985 -312.74821)
			(xy 282.218606 -312.723603) (xy 282.264622 -312.706151) (xy 282.312841 -312.696307) (xy 282.362016 -312.694326)
			(xy 282.410871 -312.700258) (xy 282.458142 -312.71395) (xy 282.502604 -312.735048) (xy 282.543107 -312.763004)
			(xy 282.5786 -312.797096) (xy 282.608165 -312.83644) (xy 282.631036 -312.880017) (xy 282.64662 -312.926698)
			(xy 282.654515 -312.975275) (xy 282.65501 -312.999882) (xy 283.944072 -312.999882) (xy 283.948032 -312.950828)
			(xy 283.959809 -312.903044) (xy 283.9791 -312.857768) (xy 284.005403 -312.816172) (xy 284.038038 -312.779335)
			(xy 284.076159 -312.74821) (xy 284.11878 -312.723603) (xy 284.164796 -312.706151) (xy 284.213015 -312.696307)
			(xy 284.26219 -312.694326) (xy 284.311045 -312.700258) (xy 284.358316 -312.71395) (xy 284.402778 -312.735048)
			(xy 284.443281 -312.763004) (xy 284.478774 -312.797096) (xy 284.508339 -312.83644) (xy 284.53121 -312.880017)
			(xy 284.546794 -312.926698) (xy 284.554689 -312.975275) (xy 284.555184 -312.999882) (xy 285.843992 -312.999882)
			(xy 285.847952 -312.950828) (xy 285.859729 -312.903044) (xy 285.87902 -312.857768) (xy 285.905323 -312.816172)
			(xy 285.937958 -312.779335) (xy 285.976079 -312.74821) (xy 286.0187 -312.723603) (xy 286.064716 -312.706151)
			(xy 286.112935 -312.696307) (xy 286.16211 -312.694326) (xy 286.210965 -312.700258) (xy 286.258236 -312.71395)
			(xy 286.302698 -312.735048) (xy 286.343201 -312.763004) (xy 286.378694 -312.797096) (xy 286.408259 -312.83644)
			(xy 286.43113 -312.880017) (xy 286.446714 -312.926698) (xy 286.454609 -312.975275) (xy 286.455104 -312.999882)
			(xy 287.743912 -312.999882) (xy 287.747872 -312.950828) (xy 287.759649 -312.903044) (xy 287.77894 -312.857768)
			(xy 287.805243 -312.816172) (xy 287.837878 -312.779335) (xy 287.875999 -312.74821) (xy 287.91862 -312.723603)
			(xy 287.964636 -312.706151) (xy 288.012855 -312.696307) (xy 288.06203 -312.694326) (xy 288.110885 -312.700258)
			(xy 288.158156 -312.71395) (xy 288.202618 -312.735048) (xy 288.243121 -312.763004) (xy 288.278614 -312.797096)
			(xy 288.308179 -312.83644) (xy 288.33105 -312.880017) (xy 288.346634 -312.926698) (xy 288.354529 -312.975275)
			(xy 288.355024 -312.999882) (xy 289.644086 -312.999882) (xy 289.648046 -312.950828) (xy 289.659823 -312.903044)
			(xy 289.679114 -312.857768) (xy 289.705417 -312.816172) (xy 289.738052 -312.779335) (xy 289.776173 -312.74821)
			(xy 289.818794 -312.723603) (xy 289.86481 -312.706151) (xy 289.913029 -312.696307) (xy 289.962204 -312.694326)
			(xy 290.011059 -312.700258) (xy 290.05833 -312.71395) (xy 290.102792 -312.735048) (xy 290.143295 -312.763004)
			(xy 290.178788 -312.797096) (xy 290.208353 -312.83644) (xy 290.231224 -312.880017) (xy 290.246808 -312.926698)
			(xy 290.254703 -312.975275) (xy 290.255198 -312.999882) (xy 291.544006 -312.999882) (xy 291.547966 -312.950828)
			(xy 291.559743 -312.903044) (xy 291.579034 -312.857768) (xy 291.605337 -312.816172) (xy 291.637972 -312.779335)
			(xy 291.676093 -312.74821) (xy 291.718714 -312.723603) (xy 291.76473 -312.706151) (xy 291.812949 -312.696307)
			(xy 291.862124 -312.694326) (xy 291.910979 -312.700258) (xy 291.95825 -312.71395) (xy 292.002712 -312.735048)
			(xy 292.043215 -312.763004) (xy 292.078708 -312.797096) (xy 292.108273 -312.83644) (xy 292.131144 -312.880017)
			(xy 292.146728 -312.926698) (xy 292.154623 -312.975275) (xy 292.155118 -312.999882) (xy 293.443926 -312.999882)
			(xy 293.447886 -312.950828) (xy 293.459663 -312.903044) (xy 293.478954 -312.857768) (xy 293.505257 -312.816172)
			(xy 293.537892 -312.779335) (xy 293.576013 -312.74821) (xy 293.618634 -312.723603) (xy 293.66465 -312.706151)
			(xy 293.712869 -312.696307) (xy 293.762044 -312.694326) (xy 293.810899 -312.700258) (xy 293.85817 -312.71395)
			(xy 293.902632 -312.735048) (xy 293.943135 -312.763004) (xy 293.978628 -312.797096) (xy 294.008193 -312.83644)
			(xy 294.031064 -312.880017) (xy 294.046648 -312.926698) (xy 294.054543 -312.975275) (xy 294.055038 -312.999882)
			(xy 295.3441 -312.999882) (xy 295.34806 -312.950828) (xy 295.359837 -312.903044) (xy 295.379128 -312.857768)
			(xy 295.405431 -312.816172) (xy 295.438066 -312.779335) (xy 295.476187 -312.74821) (xy 295.518808 -312.723603)
			(xy 295.564824 -312.706151) (xy 295.613043 -312.696307) (xy 295.662218 -312.694326) (xy 295.711073 -312.700258)
			(xy 295.758344 -312.71395) (xy 295.802806 -312.735048) (xy 295.843309 -312.763004) (xy 295.878802 -312.797096)
			(xy 295.908367 -312.83644) (xy 295.931238 -312.880017) (xy 295.946822 -312.926698) (xy 295.954717 -312.975275)
			(xy 295.955212 -312.999882) (xy 297.24402 -312.999882) (xy 297.24798 -312.950828) (xy 297.259757 -312.903044)
			(xy 297.279048 -312.857768) (xy 297.305351 -312.816172) (xy 297.337986 -312.779335) (xy 297.376107 -312.74821)
			(xy 297.418728 -312.723603) (xy 297.464744 -312.706151) (xy 297.512963 -312.696307) (xy 297.562138 -312.694326)
			(xy 297.610993 -312.700258) (xy 297.658264 -312.71395) (xy 297.702726 -312.735048) (xy 297.743229 -312.763004)
			(xy 297.778722 -312.797096) (xy 297.808287 -312.83644) (xy 297.831158 -312.880017) (xy 297.846742 -312.926698)
			(xy 297.854637 -312.975275) (xy 297.855132 -312.999882) (xy 299.14394 -312.999882) (xy 299.1479 -312.950828)
			(xy 299.159677 -312.903044) (xy 299.178968 -312.857768) (xy 299.205271 -312.816172) (xy 299.237906 -312.779335)
			(xy 299.276027 -312.74821) (xy 299.318648 -312.723603) (xy 299.364664 -312.706151) (xy 299.412883 -312.696307)
			(xy 299.462058 -312.694326) (xy 299.510913 -312.700258) (xy 299.558184 -312.71395) (xy 299.602646 -312.735048)
			(xy 299.643149 -312.763004) (xy 299.678642 -312.797096) (xy 299.708207 -312.83644) (xy 299.731078 -312.880017)
			(xy 299.746662 -312.926698) (xy 299.754557 -312.975275) (xy 299.755052 -312.999882) (xy 301.044114 -312.999882)
			(xy 301.048074 -312.950828) (xy 301.059851 -312.903044) (xy 301.079142 -312.857768) (xy 301.105445 -312.816172)
			(xy 301.13808 -312.779335) (xy 301.176201 -312.74821) (xy 301.218822 -312.723603) (xy 301.264838 -312.706151)
			(xy 301.313057 -312.696307) (xy 301.362232 -312.694326) (xy 301.411087 -312.700258) (xy 301.458358 -312.71395)
			(xy 301.50282 -312.735048) (xy 301.543323 -312.763004) (xy 301.578816 -312.797096) (xy 301.608381 -312.83644)
			(xy 301.631252 -312.880017) (xy 301.646836 -312.926698) (xy 301.654731 -312.975275) (xy 301.655226 -312.999882)
			(xy 302.944034 -312.999882) (xy 302.947994 -312.950828) (xy 302.959771 -312.903044) (xy 302.979062 -312.857768)
			(xy 303.005365 -312.816172) (xy 303.038 -312.779335) (xy 303.076121 -312.74821) (xy 303.118742 -312.723603)
			(xy 303.164758 -312.706151) (xy 303.212977 -312.696307) (xy 303.262152 -312.694326) (xy 303.311007 -312.700258)
			(xy 303.358278 -312.71395) (xy 303.40274 -312.735048) (xy 303.443243 -312.763004) (xy 303.478736 -312.797096)
			(xy 303.508301 -312.83644) (xy 303.531172 -312.880017) (xy 303.546756 -312.926698) (xy 303.554651 -312.975275)
			(xy 303.555146 -312.999882) (xy 304.843954 -312.999882) (xy 304.847914 -312.950828) (xy 304.859691 -312.903044)
			(xy 304.878982 -312.857768) (xy 304.905285 -312.816172) (xy 304.93792 -312.779335) (xy 304.976041 -312.74821)
			(xy 305.018662 -312.723603) (xy 305.064678 -312.706151) (xy 305.112897 -312.696307) (xy 305.162072 -312.694326)
			(xy 305.210927 -312.700258) (xy 305.258198 -312.71395) (xy 305.30266 -312.735048) (xy 305.343163 -312.763004)
			(xy 305.378656 -312.797096) (xy 305.408221 -312.83644) (xy 305.431092 -312.880017) (xy 305.446676 -312.926698)
			(xy 305.454571 -312.975275) (xy 305.455066 -312.999882) (xy 306.744128 -312.999882) (xy 306.748088 -312.950828)
			(xy 306.759865 -312.903044) (xy 306.779156 -312.857768) (xy 306.805459 -312.816172) (xy 306.838094 -312.779335)
			(xy 306.876215 -312.74821) (xy 306.918836 -312.723603) (xy 306.964852 -312.706151) (xy 307.013071 -312.696307)
			(xy 307.062246 -312.694326) (xy 307.111101 -312.700258) (xy 307.158372 -312.71395) (xy 307.202834 -312.735048)
			(xy 307.243337 -312.763004) (xy 307.27883 -312.797096) (xy 307.308395 -312.83644) (xy 307.331266 -312.880017)
			(xy 307.34685 -312.926698) (xy 307.354745 -312.975275) (xy 307.35524 -312.999882) (xy 308.644048 -312.999882)
			(xy 308.648008 -312.950828) (xy 308.659785 -312.903044) (xy 308.679076 -312.857768) (xy 308.705379 -312.816172)
			(xy 308.738014 -312.779335) (xy 308.776135 -312.74821) (xy 308.818756 -312.723603) (xy 308.864772 -312.706151)
			(xy 308.912991 -312.696307) (xy 308.962166 -312.694326) (xy 309.011021 -312.700258) (xy 309.058292 -312.71395)
			(xy 309.102754 -312.735048) (xy 309.143257 -312.763004) (xy 309.17875 -312.797096) (xy 309.208315 -312.83644)
			(xy 309.231186 -312.880017) (xy 309.24677 -312.926698) (xy 309.254665 -312.975275) (xy 309.25516 -312.999882)
			(xy 310.543968 -312.999882) (xy 310.547928 -312.950828) (xy 310.559705 -312.903044) (xy 310.578996 -312.857768)
			(xy 310.605299 -312.816172) (xy 310.637934 -312.779335) (xy 310.676055 -312.74821) (xy 310.718676 -312.723603)
			(xy 310.764692 -312.706151) (xy 310.812911 -312.696307) (xy 310.862086 -312.694326) (xy 310.910941 -312.700258)
			(xy 310.958212 -312.71395) (xy 311.002674 -312.735048) (xy 311.043177 -312.763004) (xy 311.07867 -312.797096)
			(xy 311.108235 -312.83644) (xy 311.131106 -312.880017) (xy 311.14669 -312.926698) (xy 311.154585 -312.975275)
			(xy 311.15508 -312.999882) (xy 312.443888 -312.999882) (xy 312.447848 -312.950828) (xy 312.459625 -312.903044)
			(xy 312.478916 -312.857768) (xy 312.505219 -312.816172) (xy 312.537854 -312.779335) (xy 312.575975 -312.74821)
			(xy 312.618596 -312.723603) (xy 312.664612 -312.706151) (xy 312.712831 -312.696307) (xy 312.762006 -312.694326)
			(xy 312.810861 -312.700258) (xy 312.858132 -312.71395) (xy 312.902594 -312.735048) (xy 312.943097 -312.763004)
			(xy 312.97859 -312.797096) (xy 313.008155 -312.83644) (xy 313.031026 -312.880017) (xy 313.04661 -312.926698)
			(xy 313.054505 -312.975275) (xy 313.055 -312.999882) (xy 386.744222 -312.999882) (xy 386.748182 -312.950828)
			(xy 386.759959 -312.903044) (xy 386.77925 -312.857768) (xy 386.805553 -312.816172) (xy 386.838188 -312.779335)
			(xy 386.876309 -312.74821) (xy 386.91893 -312.723603) (xy 386.964946 -312.706151) (xy 387.013165 -312.696307)
			(xy 387.06234 -312.694326) (xy 387.111195 -312.700258) (xy 387.158466 -312.71395) (xy 387.202928 -312.735048)
			(xy 387.243431 -312.763004) (xy 387.278924 -312.797096) (xy 387.308489 -312.83644) (xy 387.33136 -312.880017)
			(xy 387.346944 -312.926698) (xy 387.354839 -312.975275) (xy 387.355334 -312.999882) (xy 388.644142 -312.999882)
			(xy 388.648102 -312.950828) (xy 388.659879 -312.903044) (xy 388.67917 -312.857768) (xy 388.705473 -312.816172)
			(xy 388.738108 -312.779335) (xy 388.776229 -312.74821) (xy 388.81885 -312.723603) (xy 388.864866 -312.706151)
			(xy 388.913085 -312.696307) (xy 388.96226 -312.694326) (xy 389.011115 -312.700258) (xy 389.058386 -312.71395)
			(xy 389.102848 -312.735048) (xy 389.143351 -312.763004) (xy 389.178844 -312.797096) (xy 389.208409 -312.83644)
			(xy 389.23128 -312.880017) (xy 389.246864 -312.926698) (xy 389.254759 -312.975275) (xy 389.255254 -312.999882)
			(xy 390.544062 -312.999882) (xy 390.548022 -312.950828) (xy 390.559799 -312.903044) (xy 390.57909 -312.857768)
			(xy 390.605393 -312.816172) (xy 390.638028 -312.779335) (xy 390.676149 -312.74821) (xy 390.71877 -312.723603)
			(xy 390.764786 -312.706151) (xy 390.813005 -312.696307) (xy 390.86218 -312.694326) (xy 390.911035 -312.700258)
			(xy 390.958306 -312.71395) (xy 391.002768 -312.735048) (xy 391.043271 -312.763004) (xy 391.078764 -312.797096)
			(xy 391.108329 -312.83644) (xy 391.1312 -312.880017) (xy 391.146784 -312.926698) (xy 391.154679 -312.975275)
			(xy 391.155174 -312.999882) (xy 392.443982 -312.999882) (xy 392.447942 -312.950828) (xy 392.459719 -312.903044)
			(xy 392.47901 -312.857768) (xy 392.505313 -312.816172) (xy 392.537948 -312.779335) (xy 392.576069 -312.74821)
			(xy 392.61869 -312.723603) (xy 392.664706 -312.706151) (xy 392.712925 -312.696307) (xy 392.7621 -312.694326)
			(xy 392.810955 -312.700258) (xy 392.858226 -312.71395) (xy 392.902688 -312.735048) (xy 392.943191 -312.763004)
			(xy 392.978684 -312.797096) (xy 393.008249 -312.83644) (xy 393.03112 -312.880017) (xy 393.046704 -312.926698)
			(xy 393.054599 -312.975275) (xy 393.055094 -312.999882) (xy 394.344156 -312.999882) (xy 394.348116 -312.950828)
			(xy 394.359893 -312.903044) (xy 394.379184 -312.857768) (xy 394.405487 -312.816172) (xy 394.438122 -312.779335)
			(xy 394.476243 -312.74821) (xy 394.518864 -312.723603) (xy 394.56488 -312.706151) (xy 394.613099 -312.696307)
			(xy 394.662274 -312.694326) (xy 394.711129 -312.700258) (xy 394.7584 -312.71395) (xy 394.802862 -312.735048)
			(xy 394.843365 -312.763004) (xy 394.878858 -312.797096) (xy 394.908423 -312.83644) (xy 394.931294 -312.880017)
			(xy 394.946878 -312.926698) (xy 394.954773 -312.975275) (xy 394.955268 -312.999882) (xy 396.244076 -312.999882)
			(xy 396.248036 -312.950828) (xy 396.259813 -312.903044) (xy 396.279104 -312.857768) (xy 396.305407 -312.816172)
			(xy 396.338042 -312.779335) (xy 396.376163 -312.74821) (xy 396.418784 -312.723603) (xy 396.4648 -312.706151)
			(xy 396.513019 -312.696307) (xy 396.562194 -312.694326) (xy 396.611049 -312.700258) (xy 396.65832 -312.71395)
			(xy 396.702782 -312.735048) (xy 396.743285 -312.763004) (xy 396.778778 -312.797096) (xy 396.808343 -312.83644)
			(xy 396.831214 -312.880017) (xy 396.846798 -312.926698) (xy 396.854693 -312.975275) (xy 396.855188 -312.999882)
			(xy 398.143996 -312.999882) (xy 398.147956 -312.950828) (xy 398.159733 -312.903044) (xy 398.179024 -312.857768)
			(xy 398.205327 -312.816172) (xy 398.237962 -312.779335) (xy 398.276083 -312.74821) (xy 398.318704 -312.723603)
			(xy 398.36472 -312.706151) (xy 398.412939 -312.696307) (xy 398.462114 -312.694326) (xy 398.510969 -312.700258)
			(xy 398.55824 -312.71395) (xy 398.602702 -312.735048) (xy 398.643205 -312.763004) (xy 398.678698 -312.797096)
			(xy 398.708263 -312.83644) (xy 398.731134 -312.880017) (xy 398.746718 -312.926698) (xy 398.754613 -312.975275)
			(xy 398.755108 -312.999882) (xy 400.04417 -312.999882) (xy 400.04813 -312.950828) (xy 400.059907 -312.903044)
			(xy 400.079198 -312.857768) (xy 400.105501 -312.816172) (xy 400.138136 -312.779335) (xy 400.176257 -312.74821)
			(xy 400.218878 -312.723603) (xy 400.264894 -312.706151) (xy 400.313113 -312.696307) (xy 400.362288 -312.694326)
			(xy 400.411143 -312.700258) (xy 400.458414 -312.71395) (xy 400.502876 -312.735048) (xy 400.543379 -312.763004)
			(xy 400.578872 -312.797096) (xy 400.608437 -312.83644) (xy 400.631308 -312.880017) (xy 400.646892 -312.926698)
			(xy 400.654787 -312.975275) (xy 400.655282 -312.999882) (xy 401.94409 -312.999882) (xy 401.94805 -312.950828)
			(xy 401.959827 -312.903044) (xy 401.979118 -312.857768) (xy 402.005421 -312.816172) (xy 402.038056 -312.779335)
			(xy 402.076177 -312.74821) (xy 402.118798 -312.723603) (xy 402.164814 -312.706151) (xy 402.213033 -312.696307)
			(xy 402.262208 -312.694326) (xy 402.311063 -312.700258) (xy 402.358334 -312.71395) (xy 402.402796 -312.735048)
			(xy 402.443299 -312.763004) (xy 402.478792 -312.797096) (xy 402.508357 -312.83644) (xy 402.531228 -312.880017)
			(xy 402.546812 -312.926698) (xy 402.554707 -312.975275) (xy 402.555202 -312.999882) (xy 403.84401 -312.999882)
			(xy 403.84797 -312.950828) (xy 403.859747 -312.903044) (xy 403.879038 -312.857768) (xy 403.905341 -312.816172)
			(xy 403.937976 -312.779335) (xy 403.976097 -312.74821) (xy 404.018718 -312.723603) (xy 404.064734 -312.706151)
			(xy 404.112953 -312.696307) (xy 404.162128 -312.694326) (xy 404.210983 -312.700258) (xy 404.258254 -312.71395)
			(xy 404.302716 -312.735048) (xy 404.343219 -312.763004) (xy 404.378712 -312.797096) (xy 404.408277 -312.83644)
			(xy 404.431148 -312.880017) (xy 404.446732 -312.926698) (xy 404.454627 -312.975275) (xy 404.455122 -312.999882)
			(xy 405.744184 -312.999882) (xy 405.748144 -312.950828) (xy 405.759921 -312.903044) (xy 405.779212 -312.857768)
			(xy 405.805515 -312.816172) (xy 405.83815 -312.779335) (xy 405.876271 -312.74821) (xy 405.918892 -312.723603)
			(xy 405.964908 -312.706151) (xy 406.013127 -312.696307) (xy 406.062302 -312.694326) (xy 406.111157 -312.700258)
			(xy 406.158428 -312.71395) (xy 406.20289 -312.735048) (xy 406.243393 -312.763004) (xy 406.278886 -312.797096)
			(xy 406.308451 -312.83644) (xy 406.331322 -312.880017) (xy 406.346906 -312.926698) (xy 406.354801 -312.975275)
			(xy 406.355296 -312.999882) (xy 407.644104 -312.999882) (xy 407.648064 -312.950828) (xy 407.659841 -312.903044)
			(xy 407.679132 -312.857768) (xy 407.705435 -312.816172) (xy 407.73807 -312.779335) (xy 407.776191 -312.74821)
			(xy 407.818812 -312.723603) (xy 407.864828 -312.706151) (xy 407.913047 -312.696307) (xy 407.962222 -312.694326)
			(xy 408.011077 -312.700258) (xy 408.058348 -312.71395) (xy 408.10281 -312.735048) (xy 408.143313 -312.763004)
			(xy 408.178806 -312.797096) (xy 408.208371 -312.83644) (xy 408.231242 -312.880017) (xy 408.246826 -312.926698)
			(xy 408.254721 -312.975275) (xy 408.255216 -312.999882) (xy 409.544024 -312.999882) (xy 409.547984 -312.950828)
			(xy 409.559761 -312.903044) (xy 409.579052 -312.857768) (xy 409.605355 -312.816172) (xy 409.63799 -312.779335)
			(xy 409.676111 -312.74821) (xy 409.718732 -312.723603) (xy 409.764748 -312.706151) (xy 409.812967 -312.696307)
			(xy 409.862142 -312.694326) (xy 409.910997 -312.700258) (xy 409.958268 -312.71395) (xy 410.00273 -312.735048)
			(xy 410.043233 -312.763004) (xy 410.078726 -312.797096) (xy 410.108291 -312.83644) (xy 410.131162 -312.880017)
			(xy 410.146746 -312.926698) (xy 410.154641 -312.975275) (xy 410.155136 -312.999882) (xy 411.444198 -312.999882)
			(xy 411.448158 -312.950828) (xy 411.459935 -312.903044) (xy 411.479226 -312.857768) (xy 411.505529 -312.816172)
			(xy 411.538164 -312.779335) (xy 411.576285 -312.74821) (xy 411.618906 -312.723603) (xy 411.664922 -312.706151)
			(xy 411.713141 -312.696307) (xy 411.762316 -312.694326) (xy 411.811171 -312.700258) (xy 411.858442 -312.71395)
			(xy 411.902904 -312.735048) (xy 411.943407 -312.763004) (xy 411.9789 -312.797096) (xy 412.008465 -312.83644)
			(xy 412.031336 -312.880017) (xy 412.04692 -312.926698) (xy 412.054815 -312.975275) (xy 412.05531 -312.999882)
			(xy 413.344118 -312.999882) (xy 413.348078 -312.950828) (xy 413.359855 -312.903044) (xy 413.379146 -312.857768)
			(xy 413.405449 -312.816172) (xy 413.438084 -312.779335) (xy 413.476205 -312.74821) (xy 413.518826 -312.723603)
			(xy 413.564842 -312.706151) (xy 413.613061 -312.696307) (xy 413.662236 -312.694326) (xy 413.711091 -312.700258)
			(xy 413.758362 -312.71395) (xy 413.802824 -312.735048) (xy 413.843327 -312.763004) (xy 413.87882 -312.797096)
			(xy 413.908385 -312.83644) (xy 413.931256 -312.880017) (xy 413.94684 -312.926698) (xy 413.954735 -312.975275)
			(xy 413.95523 -312.999882) (xy 415.244038 -312.999882) (xy 415.247998 -312.950828) (xy 415.259775 -312.903044)
			(xy 415.279066 -312.857768) (xy 415.305369 -312.816172) (xy 415.338004 -312.779335) (xy 415.376125 -312.74821)
			(xy 415.418746 -312.723603) (xy 415.464762 -312.706151) (xy 415.512981 -312.696307) (xy 415.562156 -312.694326)
			(xy 415.611011 -312.700258) (xy 415.658282 -312.71395) (xy 415.702744 -312.735048) (xy 415.743247 -312.763004)
			(xy 415.77874 -312.797096) (xy 415.808305 -312.83644) (xy 415.831176 -312.880017) (xy 415.84676 -312.926698)
			(xy 415.854655 -312.975275) (xy 415.85515 -312.999882) (xy 417.144212 -312.999882) (xy 417.148172 -312.950828)
			(xy 417.159949 -312.903044) (xy 417.17924 -312.857768) (xy 417.205543 -312.816172) (xy 417.238178 -312.779335)
			(xy 417.276299 -312.74821) (xy 417.31892 -312.723603) (xy 417.364936 -312.706151) (xy 417.413155 -312.696307)
			(xy 417.46233 -312.694326) (xy 417.511185 -312.700258) (xy 417.558456 -312.71395) (xy 417.602918 -312.735048)
			(xy 417.643421 -312.763004) (xy 417.678914 -312.797096) (xy 417.708479 -312.83644) (xy 417.73135 -312.880017)
			(xy 417.746934 -312.926698) (xy 417.754829 -312.975275) (xy 417.755324 -312.999882) (xy 419.044132 -312.999882)
			(xy 419.048092 -312.950828) (xy 419.059869 -312.903044) (xy 419.07916 -312.857768) (xy 419.105463 -312.816172)
			(xy 419.138098 -312.779335) (xy 419.176219 -312.74821) (xy 419.21884 -312.723603) (xy 419.264856 -312.706151)
			(xy 419.313075 -312.696307) (xy 419.36225 -312.694326) (xy 419.411105 -312.700258) (xy 419.458376 -312.71395)
			(xy 419.502838 -312.735048) (xy 419.543341 -312.763004) (xy 419.578834 -312.797096) (xy 419.608399 -312.83644)
			(xy 419.63127 -312.880017) (xy 419.646854 -312.926698) (xy 419.654749 -312.975275) (xy 419.655244 -312.999882)
			(xy 420.944052 -312.999882) (xy 420.948012 -312.950828) (xy 420.959789 -312.903044) (xy 420.97908 -312.857768)
			(xy 421.005383 -312.816172) (xy 421.038018 -312.779335) (xy 421.076139 -312.74821) (xy 421.11876 -312.723603)
			(xy 421.164776 -312.706151) (xy 421.212995 -312.696307) (xy 421.26217 -312.694326) (xy 421.311025 -312.700258)
			(xy 421.358296 -312.71395) (xy 421.402758 -312.735048) (xy 421.443261 -312.763004) (xy 421.478754 -312.797096)
			(xy 421.508319 -312.83644) (xy 421.53119 -312.880017) (xy 421.546774 -312.926698) (xy 421.554669 -312.975275)
			(xy 421.555164 -312.999882) (xy 422.844226 -312.999882) (xy 422.848186 -312.950828) (xy 422.859963 -312.903044)
			(xy 422.879254 -312.857768) (xy 422.905557 -312.816172) (xy 422.938192 -312.779335) (xy 422.976313 -312.74821)
			(xy 423.018934 -312.723603) (xy 423.06495 -312.706151) (xy 423.113169 -312.696307) (xy 423.162344 -312.694326)
			(xy 423.211199 -312.700258) (xy 423.25847 -312.71395) (xy 423.302932 -312.735048) (xy 423.343435 -312.763004)
			(xy 423.378928 -312.797096) (xy 423.408493 -312.83644) (xy 423.431364 -312.880017) (xy 423.446948 -312.926698)
			(xy 423.454843 -312.975275) (xy 423.455338 -312.999882) (xy 424.744146 -312.999882) (xy 424.748106 -312.950828)
			(xy 424.759883 -312.903044) (xy 424.779174 -312.857768) (xy 424.805477 -312.816172) (xy 424.838112 -312.779335)
			(xy 424.876233 -312.74821) (xy 424.918854 -312.723603) (xy 424.96487 -312.706151) (xy 425.013089 -312.696307)
			(xy 425.062264 -312.694326) (xy 425.111119 -312.700258) (xy 425.15839 -312.71395) (xy 425.202852 -312.735048)
			(xy 425.243355 -312.763004) (xy 425.278848 -312.797096) (xy 425.308413 -312.83644) (xy 425.331284 -312.880017)
			(xy 425.346868 -312.926698) (xy 425.354763 -312.975275) (xy 425.355258 -312.999882) (xy 426.644066 -312.999882)
			(xy 426.648026 -312.950828) (xy 426.659803 -312.903044) (xy 426.679094 -312.857768) (xy 426.705397 -312.816172)
			(xy 426.738032 -312.779335) (xy 426.776153 -312.74821) (xy 426.818774 -312.723603) (xy 426.86479 -312.706151)
			(xy 426.913009 -312.696307) (xy 426.962184 -312.694326) (xy 427.011039 -312.700258) (xy 427.05831 -312.71395)
			(xy 427.102772 -312.735048) (xy 427.143275 -312.763004) (xy 427.178768 -312.797096) (xy 427.208333 -312.83644)
			(xy 427.231204 -312.880017) (xy 427.246788 -312.926698) (xy 427.254683 -312.975275) (xy 427.255178 -312.999882)
			(xy 428.543986 -312.999882) (xy 428.547946 -312.950828) (xy 428.559723 -312.903044) (xy 428.579014 -312.857768)
			(xy 428.605317 -312.816172) (xy 428.637952 -312.779335) (xy 428.676073 -312.74821) (xy 428.718694 -312.723603)
			(xy 428.76471 -312.706151) (xy 428.812929 -312.696307) (xy 428.862104 -312.694326) (xy 428.910959 -312.700258)
			(xy 428.95823 -312.71395) (xy 429.002692 -312.735048) (xy 429.043195 -312.763004) (xy 429.078688 -312.797096)
			(xy 429.108253 -312.83644) (xy 429.131124 -312.880017) (xy 429.146708 -312.926698) (xy 429.154603 -312.975275)
			(xy 429.155098 -312.999882) (xy 429.154603 -313.024489) (xy 429.146708 -313.073066) (xy 429.131124 -313.119747)
			(xy 429.108253 -313.163324) (xy 429.078688 -313.202668) (xy 429.043195 -313.23676) (xy 429.002692 -313.264716)
			(xy 428.95823 -313.285814) (xy 428.910959 -313.299506) (xy 428.862104 -313.305438) (xy 428.812929 -313.303457)
			(xy 428.76471 -313.293613) (xy 428.718694 -313.276161) (xy 428.676073 -313.251554) (xy 428.637952 -313.220429)
			(xy 428.605317 -313.183592) (xy 428.579014 -313.141996) (xy 428.559723 -313.09672) (xy 428.547946 -313.048936)
			(xy 428.543986 -312.999882) (xy 427.255178 -312.999882) (xy 427.254683 -313.024489) (xy 427.246788 -313.073066)
			(xy 427.231204 -313.119747) (xy 427.208333 -313.163324) (xy 427.178768 -313.202668) (xy 427.143275 -313.23676)
			(xy 427.102772 -313.264716) (xy 427.05831 -313.285814) (xy 427.011039 -313.299506) (xy 426.962184 -313.305438)
			(xy 426.913009 -313.303457) (xy 426.86479 -313.293613) (xy 426.818774 -313.276161) (xy 426.776153 -313.251554)
			(xy 426.738032 -313.220429) (xy 426.705397 -313.183592) (xy 426.679094 -313.141996) (xy 426.659803 -313.09672)
			(xy 426.648026 -313.048936) (xy 426.644066 -312.999882) (xy 425.355258 -312.999882) (xy 425.354763 -313.024489)
			(xy 425.346868 -313.073066) (xy 425.331284 -313.119747) (xy 425.308413 -313.163324) (xy 425.278848 -313.202668)
			(xy 425.243355 -313.23676) (xy 425.202852 -313.264716) (xy 425.15839 -313.285814) (xy 425.111119 -313.299506)
			(xy 425.062264 -313.305438) (xy 425.013089 -313.303457) (xy 424.96487 -313.293613) (xy 424.918854 -313.276161)
			(xy 424.876233 -313.251554) (xy 424.838112 -313.220429) (xy 424.805477 -313.183592) (xy 424.779174 -313.141996)
			(xy 424.759883 -313.09672) (xy 424.748106 -313.048936) (xy 424.744146 -312.999882) (xy 423.455338 -312.999882)
			(xy 423.454843 -313.024489) (xy 423.446948 -313.073066) (xy 423.431364 -313.119747) (xy 423.408493 -313.163324)
			(xy 423.378928 -313.202668) (xy 423.343435 -313.23676) (xy 423.302932 -313.264716) (xy 423.25847 -313.285814)
			(xy 423.211199 -313.299506) (xy 423.162344 -313.305438) (xy 423.113169 -313.303457) (xy 423.06495 -313.293613)
			(xy 423.018934 -313.276161) (xy 422.976313 -313.251554) (xy 422.938192 -313.220429) (xy 422.905557 -313.183592)
			(xy 422.879254 -313.141996) (xy 422.859963 -313.09672) (xy 422.848186 -313.048936) (xy 422.844226 -312.999882)
			(xy 421.555164 -312.999882) (xy 421.554669 -313.024489) (xy 421.546774 -313.073066) (xy 421.53119 -313.119747)
			(xy 421.508319 -313.163324) (xy 421.478754 -313.202668) (xy 421.443261 -313.23676) (xy 421.402758 -313.264716)
			(xy 421.358296 -313.285814) (xy 421.311025 -313.299506) (xy 421.26217 -313.305438) (xy 421.212995 -313.303457)
			(xy 421.164776 -313.293613) (xy 421.11876 -313.276161) (xy 421.076139 -313.251554) (xy 421.038018 -313.220429)
			(xy 421.005383 -313.183592) (xy 420.97908 -313.141996) (xy 420.959789 -313.09672) (xy 420.948012 -313.048936)
			(xy 420.944052 -312.999882) (xy 419.655244 -312.999882) (xy 419.654749 -313.024489) (xy 419.646854 -313.073066)
			(xy 419.63127 -313.119747) (xy 419.608399 -313.163324) (xy 419.578834 -313.202668) (xy 419.543341 -313.23676)
			(xy 419.502838 -313.264716) (xy 419.458376 -313.285814) (xy 419.411105 -313.299506) (xy 419.36225 -313.305438)
			(xy 419.313075 -313.303457) (xy 419.264856 -313.293613) (xy 419.21884 -313.276161) (xy 419.176219 -313.251554)
			(xy 419.138098 -313.220429) (xy 419.105463 -313.183592) (xy 419.07916 -313.141996) (xy 419.059869 -313.09672)
			(xy 419.048092 -313.048936) (xy 419.044132 -312.999882) (xy 417.755324 -312.999882) (xy 417.754829 -313.024489)
			(xy 417.746934 -313.073066) (xy 417.73135 -313.119747) (xy 417.708479 -313.163324) (xy 417.678914 -313.202668)
			(xy 417.643421 -313.23676) (xy 417.602918 -313.264716) (xy 417.558456 -313.285814) (xy 417.511185 -313.299506)
			(xy 417.46233 -313.305438) (xy 417.413155 -313.303457) (xy 417.364936 -313.293613) (xy 417.31892 -313.276161)
			(xy 417.276299 -313.251554) (xy 417.238178 -313.220429) (xy 417.205543 -313.183592) (xy 417.17924 -313.141996)
			(xy 417.159949 -313.09672) (xy 417.148172 -313.048936) (xy 417.144212 -312.999882) (xy 415.85515 -312.999882)
			(xy 415.854655 -313.024489) (xy 415.84676 -313.073066) (xy 415.831176 -313.119747) (xy 415.808305 -313.163324)
			(xy 415.77874 -313.202668) (xy 415.743247 -313.23676) (xy 415.702744 -313.264716) (xy 415.658282 -313.285814)
			(xy 415.611011 -313.299506) (xy 415.562156 -313.305438) (xy 415.512981 -313.303457) (xy 415.464762 -313.293613)
			(xy 415.418746 -313.276161) (xy 415.376125 -313.251554) (xy 415.338004 -313.220429) (xy 415.305369 -313.183592)
			(xy 415.279066 -313.141996) (xy 415.259775 -313.09672) (xy 415.247998 -313.048936) (xy 415.244038 -312.999882)
			(xy 413.95523 -312.999882) (xy 413.954735 -313.024489) (xy 413.94684 -313.073066) (xy 413.931256 -313.119747)
			(xy 413.908385 -313.163324) (xy 413.87882 -313.202668) (xy 413.843327 -313.23676) (xy 413.802824 -313.264716)
			(xy 413.758362 -313.285814) (xy 413.711091 -313.299506) (xy 413.662236 -313.305438) (xy 413.613061 -313.303457)
			(xy 413.564842 -313.293613) (xy 413.518826 -313.276161) (xy 413.476205 -313.251554) (xy 413.438084 -313.220429)
			(xy 413.405449 -313.183592) (xy 413.379146 -313.141996) (xy 413.359855 -313.09672) (xy 413.348078 -313.048936)
			(xy 413.344118 -312.999882) (xy 412.05531 -312.999882) (xy 412.054815 -313.024489) (xy 412.04692 -313.073066)
			(xy 412.031336 -313.119747) (xy 412.008465 -313.163324) (xy 411.9789 -313.202668) (xy 411.943407 -313.23676)
			(xy 411.902904 -313.264716) (xy 411.858442 -313.285814) (xy 411.811171 -313.299506) (xy 411.762316 -313.305438)
			(xy 411.713141 -313.303457) (xy 411.664922 -313.293613) (xy 411.618906 -313.276161) (xy 411.576285 -313.251554)
			(xy 411.538164 -313.220429) (xy 411.505529 -313.183592) (xy 411.479226 -313.141996) (xy 411.459935 -313.09672)
			(xy 411.448158 -313.048936) (xy 411.444198 -312.999882) (xy 410.155136 -312.999882) (xy 410.154641 -313.024489)
			(xy 410.146746 -313.073066) (xy 410.131162 -313.119747) (xy 410.108291 -313.163324) (xy 410.078726 -313.202668)
			(xy 410.043233 -313.23676) (xy 410.00273 -313.264716) (xy 409.958268 -313.285814) (xy 409.910997 -313.299506)
			(xy 409.862142 -313.305438) (xy 409.812967 -313.303457) (xy 409.764748 -313.293613) (xy 409.718732 -313.276161)
			(xy 409.676111 -313.251554) (xy 409.63799 -313.220429) (xy 409.605355 -313.183592) (xy 409.579052 -313.141996)
			(xy 409.559761 -313.09672) (xy 409.547984 -313.048936) (xy 409.544024 -312.999882) (xy 408.255216 -312.999882)
			(xy 408.254721 -313.024489) (xy 408.246826 -313.073066) (xy 408.231242 -313.119747) (xy 408.208371 -313.163324)
			(xy 408.178806 -313.202668) (xy 408.143313 -313.23676) (xy 408.10281 -313.264716) (xy 408.058348 -313.285814)
			(xy 408.011077 -313.299506) (xy 407.962222 -313.305438) (xy 407.913047 -313.303457) (xy 407.864828 -313.293613)
			(xy 407.818812 -313.276161) (xy 407.776191 -313.251554) (xy 407.73807 -313.220429) (xy 407.705435 -313.183592)
			(xy 407.679132 -313.141996) (xy 407.659841 -313.09672) (xy 407.648064 -313.048936) (xy 407.644104 -312.999882)
			(xy 406.355296 -312.999882) (xy 406.354801 -313.024489) (xy 406.346906 -313.073066) (xy 406.331322 -313.119747)
			(xy 406.308451 -313.163324) (xy 406.278886 -313.202668) (xy 406.243393 -313.23676) (xy 406.20289 -313.264716)
			(xy 406.158428 -313.285814) (xy 406.111157 -313.299506) (xy 406.062302 -313.305438) (xy 406.013127 -313.303457)
			(xy 405.964908 -313.293613) (xy 405.918892 -313.276161) (xy 405.876271 -313.251554) (xy 405.83815 -313.220429)
			(xy 405.805515 -313.183592) (xy 405.779212 -313.141996) (xy 405.759921 -313.09672) (xy 405.748144 -313.048936)
			(xy 405.744184 -312.999882) (xy 404.455122 -312.999882) (xy 404.454627 -313.024489) (xy 404.446732 -313.073066)
			(xy 404.431148 -313.119747) (xy 404.408277 -313.163324) (xy 404.378712 -313.202668) (xy 404.343219 -313.23676)
			(xy 404.302716 -313.264716) (xy 404.258254 -313.285814) (xy 404.210983 -313.299506) (xy 404.162128 -313.305438)
			(xy 404.112953 -313.303457) (xy 404.064734 -313.293613) (xy 404.018718 -313.276161) (xy 403.976097 -313.251554)
			(xy 403.937976 -313.220429) (xy 403.905341 -313.183592) (xy 403.879038 -313.141996) (xy 403.859747 -313.09672)
			(xy 403.84797 -313.048936) (xy 403.84401 -312.999882) (xy 402.555202 -312.999882) (xy 402.554707 -313.024489)
			(xy 402.546812 -313.073066) (xy 402.531228 -313.119747) (xy 402.508357 -313.163324) (xy 402.478792 -313.202668)
			(xy 402.443299 -313.23676) (xy 402.402796 -313.264716) (xy 402.358334 -313.285814) (xy 402.311063 -313.299506)
			(xy 402.262208 -313.305438) (xy 402.213033 -313.303457) (xy 402.164814 -313.293613) (xy 402.118798 -313.276161)
			(xy 402.076177 -313.251554) (xy 402.038056 -313.220429) (xy 402.005421 -313.183592) (xy 401.979118 -313.141996)
			(xy 401.959827 -313.09672) (xy 401.94805 -313.048936) (xy 401.94409 -312.999882) (xy 400.655282 -312.999882)
			(xy 400.654787 -313.024489) (xy 400.646892 -313.073066) (xy 400.631308 -313.119747) (xy 400.608437 -313.163324)
			(xy 400.578872 -313.202668) (xy 400.543379 -313.23676) (xy 400.502876 -313.264716) (xy 400.458414 -313.285814)
			(xy 400.411143 -313.299506) (xy 400.362288 -313.305438) (xy 400.313113 -313.303457) (xy 400.264894 -313.293613)
			(xy 400.218878 -313.276161) (xy 400.176257 -313.251554) (xy 400.138136 -313.220429) (xy 400.105501 -313.183592)
			(xy 400.079198 -313.141996) (xy 400.059907 -313.09672) (xy 400.04813 -313.048936) (xy 400.04417 -312.999882)
			(xy 398.755108 -312.999882) (xy 398.754613 -313.024489) (xy 398.746718 -313.073066) (xy 398.731134 -313.119747)
			(xy 398.708263 -313.163324) (xy 398.678698 -313.202668) (xy 398.643205 -313.23676) (xy 398.602702 -313.264716)
			(xy 398.55824 -313.285814) (xy 398.510969 -313.299506) (xy 398.462114 -313.305438) (xy 398.412939 -313.303457)
			(xy 398.36472 -313.293613) (xy 398.318704 -313.276161) (xy 398.276083 -313.251554) (xy 398.237962 -313.220429)
			(xy 398.205327 -313.183592) (xy 398.179024 -313.141996) (xy 398.159733 -313.09672) (xy 398.147956 -313.048936)
			(xy 398.143996 -312.999882) (xy 396.855188 -312.999882) (xy 396.854693 -313.024489) (xy 396.846798 -313.073066)
			(xy 396.831214 -313.119747) (xy 396.808343 -313.163324) (xy 396.778778 -313.202668) (xy 396.743285 -313.23676)
			(xy 396.702782 -313.264716) (xy 396.65832 -313.285814) (xy 396.611049 -313.299506) (xy 396.562194 -313.305438)
			(xy 396.513019 -313.303457) (xy 396.4648 -313.293613) (xy 396.418784 -313.276161) (xy 396.376163 -313.251554)
			(xy 396.338042 -313.220429) (xy 396.305407 -313.183592) (xy 396.279104 -313.141996) (xy 396.259813 -313.09672)
			(xy 396.248036 -313.048936) (xy 396.244076 -312.999882) (xy 394.955268 -312.999882) (xy 394.954773 -313.024489)
			(xy 394.946878 -313.073066) (xy 394.931294 -313.119747) (xy 394.908423 -313.163324) (xy 394.878858 -313.202668)
			(xy 394.843365 -313.23676) (xy 394.802862 -313.264716) (xy 394.7584 -313.285814) (xy 394.711129 -313.299506)
			(xy 394.662274 -313.305438) (xy 394.613099 -313.303457) (xy 394.56488 -313.293613) (xy 394.518864 -313.276161)
			(xy 394.476243 -313.251554) (xy 394.438122 -313.220429) (xy 394.405487 -313.183592) (xy 394.379184 -313.141996)
			(xy 394.359893 -313.09672) (xy 394.348116 -313.048936) (xy 394.344156 -312.999882) (xy 393.055094 -312.999882)
			(xy 393.054599 -313.024489) (xy 393.046704 -313.073066) (xy 393.03112 -313.119747) (xy 393.008249 -313.163324)
			(xy 392.978684 -313.202668) (xy 392.943191 -313.23676) (xy 392.902688 -313.264716) (xy 392.858226 -313.285814)
			(xy 392.810955 -313.299506) (xy 392.7621 -313.305438) (xy 392.712925 -313.303457) (xy 392.664706 -313.293613)
			(xy 392.61869 -313.276161) (xy 392.576069 -313.251554) (xy 392.537948 -313.220429) (xy 392.505313 -313.183592)
			(xy 392.47901 -313.141996) (xy 392.459719 -313.09672) (xy 392.447942 -313.048936) (xy 392.443982 -312.999882)
			(xy 391.155174 -312.999882) (xy 391.154679 -313.024489) (xy 391.146784 -313.073066) (xy 391.1312 -313.119747)
			(xy 391.108329 -313.163324) (xy 391.078764 -313.202668) (xy 391.043271 -313.23676) (xy 391.002768 -313.264716)
			(xy 390.958306 -313.285814) (xy 390.911035 -313.299506) (xy 390.86218 -313.305438) (xy 390.813005 -313.303457)
			(xy 390.764786 -313.293613) (xy 390.71877 -313.276161) (xy 390.676149 -313.251554) (xy 390.638028 -313.220429)
			(xy 390.605393 -313.183592) (xy 390.57909 -313.141996) (xy 390.559799 -313.09672) (xy 390.548022 -313.048936)
			(xy 390.544062 -312.999882) (xy 389.255254 -312.999882) (xy 389.254759 -313.024489) (xy 389.246864 -313.073066)
			(xy 389.23128 -313.119747) (xy 389.208409 -313.163324) (xy 389.178844 -313.202668) (xy 389.143351 -313.23676)
			(xy 389.102848 -313.264716) (xy 389.058386 -313.285814) (xy 389.011115 -313.299506) (xy 388.96226 -313.305438)
			(xy 388.913085 -313.303457) (xy 388.864866 -313.293613) (xy 388.81885 -313.276161) (xy 388.776229 -313.251554)
			(xy 388.738108 -313.220429) (xy 388.705473 -313.183592) (xy 388.67917 -313.141996) (xy 388.659879 -313.09672)
			(xy 388.648102 -313.048936) (xy 388.644142 -312.999882) (xy 387.355334 -312.999882) (xy 387.354839 -313.024489)
			(xy 387.346944 -313.073066) (xy 387.33136 -313.119747) (xy 387.308489 -313.163324) (xy 387.278924 -313.202668)
			(xy 387.243431 -313.23676) (xy 387.202928 -313.264716) (xy 387.158466 -313.285814) (xy 387.111195 -313.299506)
			(xy 387.06234 -313.305438) (xy 387.013165 -313.303457) (xy 386.964946 -313.293613) (xy 386.91893 -313.276161)
			(xy 386.876309 -313.251554) (xy 386.838188 -313.220429) (xy 386.805553 -313.183592) (xy 386.77925 -313.141996)
			(xy 386.759959 -313.09672) (xy 386.748182 -313.048936) (xy 386.744222 -312.999882) (xy 313.055 -312.999882)
			(xy 313.054505 -313.024489) (xy 313.04661 -313.073066) (xy 313.031026 -313.119747) (xy 313.008155 -313.163324)
			(xy 312.97859 -313.202668) (xy 312.943097 -313.23676) (xy 312.902594 -313.264716) (xy 312.858132 -313.285814)
			(xy 312.810861 -313.299506) (xy 312.762006 -313.305438) (xy 312.712831 -313.303457) (xy 312.664612 -313.293613)
			(xy 312.618596 -313.276161) (xy 312.575975 -313.251554) (xy 312.537854 -313.220429) (xy 312.505219 -313.183592)
			(xy 312.478916 -313.141996) (xy 312.459625 -313.09672) (xy 312.447848 -313.048936) (xy 312.443888 -312.999882)
			(xy 311.15508 -312.999882) (xy 311.154585 -313.024489) (xy 311.14669 -313.073066) (xy 311.131106 -313.119747)
			(xy 311.108235 -313.163324) (xy 311.07867 -313.202668) (xy 311.043177 -313.23676) (xy 311.002674 -313.264716)
			(xy 310.958212 -313.285814) (xy 310.910941 -313.299506) (xy 310.862086 -313.305438) (xy 310.812911 -313.303457)
			(xy 310.764692 -313.293613) (xy 310.718676 -313.276161) (xy 310.676055 -313.251554) (xy 310.637934 -313.220429)
			(xy 310.605299 -313.183592) (xy 310.578996 -313.141996) (xy 310.559705 -313.09672) (xy 310.547928 -313.048936)
			(xy 310.543968 -312.999882) (xy 309.25516 -312.999882) (xy 309.254665 -313.024489) (xy 309.24677 -313.073066)
			(xy 309.231186 -313.119747) (xy 309.208315 -313.163324) (xy 309.17875 -313.202668) (xy 309.143257 -313.23676)
			(xy 309.102754 -313.264716) (xy 309.058292 -313.285814) (xy 309.011021 -313.299506) (xy 308.962166 -313.305438)
			(xy 308.912991 -313.303457) (xy 308.864772 -313.293613) (xy 308.818756 -313.276161) (xy 308.776135 -313.251554)
			(xy 308.738014 -313.220429) (xy 308.705379 -313.183592) (xy 308.679076 -313.141996) (xy 308.659785 -313.09672)
			(xy 308.648008 -313.048936) (xy 308.644048 -312.999882) (xy 307.35524 -312.999882) (xy 307.354745 -313.024489)
			(xy 307.34685 -313.073066) (xy 307.331266 -313.119747) (xy 307.308395 -313.163324) (xy 307.27883 -313.202668)
			(xy 307.243337 -313.23676) (xy 307.202834 -313.264716) (xy 307.158372 -313.285814) (xy 307.111101 -313.299506)
			(xy 307.062246 -313.305438) (xy 307.013071 -313.303457) (xy 306.964852 -313.293613) (xy 306.918836 -313.276161)
			(xy 306.876215 -313.251554) (xy 306.838094 -313.220429) (xy 306.805459 -313.183592) (xy 306.779156 -313.141996)
			(xy 306.759865 -313.09672) (xy 306.748088 -313.048936) (xy 306.744128 -312.999882) (xy 305.455066 -312.999882)
			(xy 305.454571 -313.024489) (xy 305.446676 -313.073066) (xy 305.431092 -313.119747) (xy 305.408221 -313.163324)
			(xy 305.378656 -313.202668) (xy 305.343163 -313.23676) (xy 305.30266 -313.264716) (xy 305.258198 -313.285814)
			(xy 305.210927 -313.299506) (xy 305.162072 -313.305438) (xy 305.112897 -313.303457) (xy 305.064678 -313.293613)
			(xy 305.018662 -313.276161) (xy 304.976041 -313.251554) (xy 304.93792 -313.220429) (xy 304.905285 -313.183592)
			(xy 304.878982 -313.141996) (xy 304.859691 -313.09672) (xy 304.847914 -313.048936) (xy 304.843954 -312.999882)
			(xy 303.555146 -312.999882) (xy 303.554651 -313.024489) (xy 303.546756 -313.073066) (xy 303.531172 -313.119747)
			(xy 303.508301 -313.163324) (xy 303.478736 -313.202668) (xy 303.443243 -313.23676) (xy 303.40274 -313.264716)
			(xy 303.358278 -313.285814) (xy 303.311007 -313.299506) (xy 303.262152 -313.305438) (xy 303.212977 -313.303457)
			(xy 303.164758 -313.293613) (xy 303.118742 -313.276161) (xy 303.076121 -313.251554) (xy 303.038 -313.220429)
			(xy 303.005365 -313.183592) (xy 302.979062 -313.141996) (xy 302.959771 -313.09672) (xy 302.947994 -313.048936)
			(xy 302.944034 -312.999882) (xy 301.655226 -312.999882) (xy 301.654731 -313.024489) (xy 301.646836 -313.073066)
			(xy 301.631252 -313.119747) (xy 301.608381 -313.163324) (xy 301.578816 -313.202668) (xy 301.543323 -313.23676)
			(xy 301.50282 -313.264716) (xy 301.458358 -313.285814) (xy 301.411087 -313.299506) (xy 301.362232 -313.305438)
			(xy 301.313057 -313.303457) (xy 301.264838 -313.293613) (xy 301.218822 -313.276161) (xy 301.176201 -313.251554)
			(xy 301.13808 -313.220429) (xy 301.105445 -313.183592) (xy 301.079142 -313.141996) (xy 301.059851 -313.09672)
			(xy 301.048074 -313.048936) (xy 301.044114 -312.999882) (xy 299.755052 -312.999882) (xy 299.754557 -313.024489)
			(xy 299.746662 -313.073066) (xy 299.731078 -313.119747) (xy 299.708207 -313.163324) (xy 299.678642 -313.202668)
			(xy 299.643149 -313.23676) (xy 299.602646 -313.264716) (xy 299.558184 -313.285814) (xy 299.510913 -313.299506)
			(xy 299.462058 -313.305438) (xy 299.412883 -313.303457) (xy 299.364664 -313.293613) (xy 299.318648 -313.276161)
			(xy 299.276027 -313.251554) (xy 299.237906 -313.220429) (xy 299.205271 -313.183592) (xy 299.178968 -313.141996)
			(xy 299.159677 -313.09672) (xy 299.1479 -313.048936) (xy 299.14394 -312.999882) (xy 297.855132 -312.999882)
			(xy 297.854637 -313.024489) (xy 297.846742 -313.073066) (xy 297.831158 -313.119747) (xy 297.808287 -313.163324)
			(xy 297.778722 -313.202668) (xy 297.743229 -313.23676) (xy 297.702726 -313.264716) (xy 297.658264 -313.285814)
			(xy 297.610993 -313.299506) (xy 297.562138 -313.305438) (xy 297.512963 -313.303457) (xy 297.464744 -313.293613)
			(xy 297.418728 -313.276161) (xy 297.376107 -313.251554) (xy 297.337986 -313.220429) (xy 297.305351 -313.183592)
			(xy 297.279048 -313.141996) (xy 297.259757 -313.09672) (xy 297.24798 -313.048936) (xy 297.24402 -312.999882)
			(xy 295.955212 -312.999882) (xy 295.954717 -313.024489) (xy 295.946822 -313.073066) (xy 295.931238 -313.119747)
			(xy 295.908367 -313.163324) (xy 295.878802 -313.202668) (xy 295.843309 -313.23676) (xy 295.802806 -313.264716)
			(xy 295.758344 -313.285814) (xy 295.711073 -313.299506) (xy 295.662218 -313.305438) (xy 295.613043 -313.303457)
			(xy 295.564824 -313.293613) (xy 295.518808 -313.276161) (xy 295.476187 -313.251554) (xy 295.438066 -313.220429)
			(xy 295.405431 -313.183592) (xy 295.379128 -313.141996) (xy 295.359837 -313.09672) (xy 295.34806 -313.048936)
			(xy 295.3441 -312.999882) (xy 294.055038 -312.999882) (xy 294.054543 -313.024489) (xy 294.046648 -313.073066)
			(xy 294.031064 -313.119747) (xy 294.008193 -313.163324) (xy 293.978628 -313.202668) (xy 293.943135 -313.23676)
			(xy 293.902632 -313.264716) (xy 293.85817 -313.285814) (xy 293.810899 -313.299506) (xy 293.762044 -313.305438)
			(xy 293.712869 -313.303457) (xy 293.66465 -313.293613) (xy 293.618634 -313.276161) (xy 293.576013 -313.251554)
			(xy 293.537892 -313.220429) (xy 293.505257 -313.183592) (xy 293.478954 -313.141996) (xy 293.459663 -313.09672)
			(xy 293.447886 -313.048936) (xy 293.443926 -312.999882) (xy 292.155118 -312.999882) (xy 292.154623 -313.024489)
			(xy 292.146728 -313.073066) (xy 292.131144 -313.119747) (xy 292.108273 -313.163324) (xy 292.078708 -313.202668)
			(xy 292.043215 -313.23676) (xy 292.002712 -313.264716) (xy 291.95825 -313.285814) (xy 291.910979 -313.299506)
			(xy 291.862124 -313.305438) (xy 291.812949 -313.303457) (xy 291.76473 -313.293613) (xy 291.718714 -313.276161)
			(xy 291.676093 -313.251554) (xy 291.637972 -313.220429) (xy 291.605337 -313.183592) (xy 291.579034 -313.141996)
			(xy 291.559743 -313.09672) (xy 291.547966 -313.048936) (xy 291.544006 -312.999882) (xy 290.255198 -312.999882)
			(xy 290.254703 -313.024489) (xy 290.246808 -313.073066) (xy 290.231224 -313.119747) (xy 290.208353 -313.163324)
			(xy 290.178788 -313.202668) (xy 290.143295 -313.23676) (xy 290.102792 -313.264716) (xy 290.05833 -313.285814)
			(xy 290.011059 -313.299506) (xy 289.962204 -313.305438) (xy 289.913029 -313.303457) (xy 289.86481 -313.293613)
			(xy 289.818794 -313.276161) (xy 289.776173 -313.251554) (xy 289.738052 -313.220429) (xy 289.705417 -313.183592)
			(xy 289.679114 -313.141996) (xy 289.659823 -313.09672) (xy 289.648046 -313.048936) (xy 289.644086 -312.999882)
			(xy 288.355024 -312.999882) (xy 288.354529 -313.024489) (xy 288.346634 -313.073066) (xy 288.33105 -313.119747)
			(xy 288.308179 -313.163324) (xy 288.278614 -313.202668) (xy 288.243121 -313.23676) (xy 288.202618 -313.264716)
			(xy 288.158156 -313.285814) (xy 288.110885 -313.299506) (xy 288.06203 -313.305438) (xy 288.012855 -313.303457)
			(xy 287.964636 -313.293613) (xy 287.91862 -313.276161) (xy 287.875999 -313.251554) (xy 287.837878 -313.220429)
			(xy 287.805243 -313.183592) (xy 287.77894 -313.141996) (xy 287.759649 -313.09672) (xy 287.747872 -313.048936)
			(xy 287.743912 -312.999882) (xy 286.455104 -312.999882) (xy 286.454609 -313.024489) (xy 286.446714 -313.073066)
			(xy 286.43113 -313.119747) (xy 286.408259 -313.163324) (xy 286.378694 -313.202668) (xy 286.343201 -313.23676)
			(xy 286.302698 -313.264716) (xy 286.258236 -313.285814) (xy 286.210965 -313.299506) (xy 286.16211 -313.305438)
			(xy 286.112935 -313.303457) (xy 286.064716 -313.293613) (xy 286.0187 -313.276161) (xy 285.976079 -313.251554)
			(xy 285.937958 -313.220429) (xy 285.905323 -313.183592) (xy 285.87902 -313.141996) (xy 285.859729 -313.09672)
			(xy 285.847952 -313.048936) (xy 285.843992 -312.999882) (xy 284.555184 -312.999882) (xy 284.554689 -313.024489)
			(xy 284.546794 -313.073066) (xy 284.53121 -313.119747) (xy 284.508339 -313.163324) (xy 284.478774 -313.202668)
			(xy 284.443281 -313.23676) (xy 284.402778 -313.264716) (xy 284.358316 -313.285814) (xy 284.311045 -313.299506)
			(xy 284.26219 -313.305438) (xy 284.213015 -313.303457) (xy 284.164796 -313.293613) (xy 284.11878 -313.276161)
			(xy 284.076159 -313.251554) (xy 284.038038 -313.220429) (xy 284.005403 -313.183592) (xy 283.9791 -313.141996)
			(xy 283.959809 -313.09672) (xy 283.948032 -313.048936) (xy 283.944072 -312.999882) (xy 282.65501 -312.999882)
			(xy 282.654515 -313.024489) (xy 282.64662 -313.073066) (xy 282.631036 -313.119747) (xy 282.608165 -313.163324)
			(xy 282.5786 -313.202668) (xy 282.543107 -313.23676) (xy 282.502604 -313.264716) (xy 282.458142 -313.285814)
			(xy 282.410871 -313.299506) (xy 282.362016 -313.305438) (xy 282.312841 -313.303457) (xy 282.264622 -313.293613)
			(xy 282.218606 -313.276161) (xy 282.175985 -313.251554) (xy 282.137864 -313.220429) (xy 282.105229 -313.183592)
			(xy 282.078926 -313.141996) (xy 282.059635 -313.09672) (xy 282.047858 -313.048936) (xy 282.043898 -312.999882)
			(xy 280.75509 -312.999882) (xy 280.754595 -313.024489) (xy 280.7467 -313.073066) (xy 280.731116 -313.119747)
			(xy 280.708245 -313.163324) (xy 280.67868 -313.202668) (xy 280.643187 -313.23676) (xy 280.602684 -313.264716)
			(xy 280.558222 -313.285814) (xy 280.510951 -313.299506) (xy 280.462096 -313.305438) (xy 280.412921 -313.303457)
			(xy 280.364702 -313.293613) (xy 280.318686 -313.276161) (xy 280.276065 -313.251554) (xy 280.237944 -313.220429)
			(xy 280.205309 -313.183592) (xy 280.179006 -313.141996) (xy 280.159715 -313.09672) (xy 280.147938 -313.048936)
			(xy 280.143978 -312.999882) (xy 278.85517 -312.999882) (xy 278.854675 -313.024489) (xy 278.84678 -313.073066)
			(xy 278.831196 -313.119747) (xy 278.808325 -313.163324) (xy 278.77876 -313.202668) (xy 278.743267 -313.23676)
			(xy 278.702764 -313.264716) (xy 278.658302 -313.285814) (xy 278.611031 -313.299506) (xy 278.562176 -313.305438)
			(xy 278.513001 -313.303457) (xy 278.464782 -313.293613) (xy 278.418766 -313.276161) (xy 278.376145 -313.251554)
			(xy 278.338024 -313.220429) (xy 278.305389 -313.183592) (xy 278.279086 -313.141996) (xy 278.259795 -313.09672)
			(xy 278.248018 -313.048936) (xy 278.244058 -312.999882) (xy 276.954996 -312.999882) (xy 276.954501 -313.024489)
			(xy 276.946606 -313.073066) (xy 276.931022 -313.119747) (xy 276.908151 -313.163324) (xy 276.878586 -313.202668)
			(xy 276.843093 -313.23676) (xy 276.80259 -313.264716) (xy 276.758128 -313.285814) (xy 276.710857 -313.299506)
			(xy 276.662002 -313.305438) (xy 276.612827 -313.303457) (xy 276.564608 -313.293613) (xy 276.518592 -313.276161)
			(xy 276.475971 -313.251554) (xy 276.43785 -313.220429) (xy 276.405215 -313.183592) (xy 276.378912 -313.141996)
			(xy 276.359621 -313.09672) (xy 276.347844 -313.048936) (xy 276.343884 -312.999882) (xy 275.055076 -312.999882)
			(xy 275.054581 -313.024489) (xy 275.046686 -313.073066) (xy 275.031102 -313.119747) (xy 275.008231 -313.163324)
			(xy 274.978666 -313.202668) (xy 274.943173 -313.23676) (xy 274.90267 -313.264716) (xy 274.858208 -313.285814)
			(xy 274.810937 -313.299506) (xy 274.762082 -313.305438) (xy 274.712907 -313.303457) (xy 274.664688 -313.293613)
			(xy 274.618672 -313.276161) (xy 274.576051 -313.251554) (xy 274.53793 -313.220429) (xy 274.505295 -313.183592)
			(xy 274.478992 -313.141996) (xy 274.459701 -313.09672) (xy 274.447924 -313.048936) (xy 274.443964 -312.999882)
			(xy 273.155156 -312.999882) (xy 273.154661 -313.024489) (xy 273.146766 -313.073066) (xy 273.131182 -313.119747)
			(xy 273.108311 -313.163324) (xy 273.078746 -313.202668) (xy 273.043253 -313.23676) (xy 273.00275 -313.264716)
			(xy 272.958288 -313.285814) (xy 272.911017 -313.299506) (xy 272.862162 -313.305438) (xy 272.812987 -313.303457)
			(xy 272.764768 -313.293613) (xy 272.718752 -313.276161) (xy 272.676131 -313.251554) (xy 272.63801 -313.220429)
			(xy 272.605375 -313.183592) (xy 272.579072 -313.141996) (xy 272.559781 -313.09672) (xy 272.548004 -313.048936)
			(xy 272.544044 -312.999882) (xy 271.255236 -312.999882) (xy 271.254741 -313.024489) (xy 271.246846 -313.073066)
			(xy 271.231262 -313.119747) (xy 271.208391 -313.163324) (xy 271.178826 -313.202668) (xy 271.143333 -313.23676)
			(xy 271.10283 -313.264716) (xy 271.058368 -313.285814) (xy 271.011097 -313.299506) (xy 270.962242 -313.305438)
			(xy 270.913067 -313.303457) (xy 270.864848 -313.293613) (xy 270.818832 -313.276161) (xy 270.776211 -313.251554)
			(xy 270.73809 -313.220429) (xy 270.705455 -313.183592) (xy 270.679152 -313.141996) (xy 270.659861 -313.09672)
			(xy 270.648084 -313.048936) (xy 270.644124 -312.999882) (xy 196.955156 -312.999882) (xy 196.954661 -313.024489)
			(xy 196.946766 -313.073066) (xy 196.931182 -313.119747) (xy 196.908311 -313.163324) (xy 196.878746 -313.202668)
			(xy 196.843253 -313.23676) (xy 196.80275 -313.264716) (xy 196.758288 -313.285814) (xy 196.711017 -313.299506)
			(xy 196.662162 -313.305438) (xy 196.612987 -313.303457) (xy 196.564768 -313.293613) (xy 196.518752 -313.276161)
			(xy 196.476131 -313.251554) (xy 196.43801 -313.220429) (xy 196.405375 -313.183592) (xy 196.379072 -313.141996)
			(xy 196.359781 -313.09672) (xy 196.348004 -313.048936) (xy 196.344044 -312.999882) (xy 195.055236 -312.999882)
			(xy 195.054741 -313.024489) (xy 195.046846 -313.073066) (xy 195.031262 -313.119747) (xy 195.008391 -313.163324)
			(xy 194.978826 -313.202668) (xy 194.943333 -313.23676) (xy 194.90283 -313.264716) (xy 194.858368 -313.285814)
			(xy 194.811097 -313.299506) (xy 194.762242 -313.305438) (xy 194.713067 -313.303457) (xy 194.664848 -313.293613)
			(xy 194.618832 -313.276161) (xy 194.576211 -313.251554) (xy 194.53809 -313.220429) (xy 194.505455 -313.183592)
			(xy 194.479152 -313.141996) (xy 194.459861 -313.09672) (xy 194.448084 -313.048936) (xy 194.444124 -312.999882)
			(xy 193.155316 -312.999882) (xy 193.154821 -313.024489) (xy 193.146926 -313.073066) (xy 193.131342 -313.119747)
			(xy 193.108471 -313.163324) (xy 193.078906 -313.202668) (xy 193.043413 -313.23676) (xy 193.00291 -313.264716)
			(xy 192.958448 -313.285814) (xy 192.911177 -313.299506) (xy 192.862322 -313.305438) (xy 192.813147 -313.303457)
			(xy 192.764928 -313.293613) (xy 192.718912 -313.276161) (xy 192.676291 -313.251554) (xy 192.63817 -313.220429)
			(xy 192.605535 -313.183592) (xy 192.579232 -313.141996) (xy 192.559941 -313.09672) (xy 192.548164 -313.048936)
			(xy 192.544204 -312.999882) (xy 191.255396 -312.999882) (xy 191.254901 -313.024489) (xy 191.247006 -313.073066)
			(xy 191.231422 -313.119747) (xy 191.208551 -313.163324) (xy 191.178986 -313.202668) (xy 191.143493 -313.23676)
			(xy 191.10299 -313.264716) (xy 191.058528 -313.285814) (xy 191.011257 -313.299506) (xy 190.962402 -313.305438)
			(xy 190.913227 -313.303457) (xy 190.865008 -313.293613) (xy 190.818992 -313.276161) (xy 190.776371 -313.251554)
			(xy 190.73825 -313.220429) (xy 190.705615 -313.183592) (xy 190.679312 -313.141996) (xy 190.660021 -313.09672)
			(xy 190.648244 -313.048936) (xy 190.644284 -312.999882) (xy 189.355222 -312.999882) (xy 189.354727 -313.024489)
			(xy 189.346832 -313.073066) (xy 189.331248 -313.119747) (xy 189.308377 -313.163324) (xy 189.278812 -313.202668)
			(xy 189.243319 -313.23676) (xy 189.202816 -313.264716) (xy 189.158354 -313.285814) (xy 189.111083 -313.299506)
			(xy 189.062228 -313.305438) (xy 189.013053 -313.303457) (xy 188.964834 -313.293613) (xy 188.918818 -313.276161)
			(xy 188.876197 -313.251554) (xy 188.838076 -313.220429) (xy 188.805441 -313.183592) (xy 188.779138 -313.141996)
			(xy 188.759847 -313.09672) (xy 188.74807 -313.048936) (xy 188.74411 -312.999882) (xy 187.455302 -312.999882)
			(xy 187.454807 -313.024489) (xy 187.446912 -313.073066) (xy 187.431328 -313.119747) (xy 187.408457 -313.163324)
			(xy 187.378892 -313.202668) (xy 187.343399 -313.23676) (xy 187.302896 -313.264716) (xy 187.258434 -313.285814)
			(xy 187.211163 -313.299506) (xy 187.162308 -313.305438) (xy 187.113133 -313.303457) (xy 187.064914 -313.293613)
			(xy 187.018898 -313.276161) (xy 186.976277 -313.251554) (xy 186.938156 -313.220429) (xy 186.905521 -313.183592)
			(xy 186.879218 -313.141996) (xy 186.859927 -313.09672) (xy 186.84815 -313.048936) (xy 186.84419 -312.999882)
			(xy 185.555382 -312.999882) (xy 185.554887 -313.024489) (xy 185.546992 -313.073066) (xy 185.531408 -313.119747)
			(xy 185.508537 -313.163324) (xy 185.478972 -313.202668) (xy 185.443479 -313.23676) (xy 185.402976 -313.264716)
			(xy 185.358514 -313.285814) (xy 185.311243 -313.299506) (xy 185.262388 -313.305438) (xy 185.213213 -313.303457)
			(xy 185.164994 -313.293613) (xy 185.118978 -313.276161) (xy 185.076357 -313.251554) (xy 185.038236 -313.220429)
			(xy 185.005601 -313.183592) (xy 184.979298 -313.141996) (xy 184.960007 -313.09672) (xy 184.94823 -313.048936)
			(xy 184.94427 -312.999882) (xy 183.655208 -312.999882) (xy 183.654713 -313.024489) (xy 183.646818 -313.073066)
			(xy 183.631234 -313.119747) (xy 183.608363 -313.163324) (xy 183.578798 -313.202668) (xy 183.543305 -313.23676)
			(xy 183.502802 -313.264716) (xy 183.45834 -313.285814) (xy 183.411069 -313.299506) (xy 183.362214 -313.305438)
			(xy 183.313039 -313.303457) (xy 183.26482 -313.293613) (xy 183.218804 -313.276161) (xy 183.176183 -313.251554)
			(xy 183.138062 -313.220429) (xy 183.105427 -313.183592) (xy 183.079124 -313.141996) (xy 183.059833 -313.09672)
			(xy 183.048056 -313.048936) (xy 183.044096 -312.999882) (xy 181.755288 -312.999882) (xy 181.754793 -313.024489)
			(xy 181.746898 -313.073066) (xy 181.731314 -313.119747) (xy 181.708443 -313.163324) (xy 181.678878 -313.202668)
			(xy 181.643385 -313.23676) (xy 181.602882 -313.264716) (xy 181.55842 -313.285814) (xy 181.511149 -313.299506)
			(xy 181.462294 -313.305438) (xy 181.413119 -313.303457) (xy 181.3649 -313.293613) (xy 181.318884 -313.276161)
			(xy 181.276263 -313.251554) (xy 181.238142 -313.220429) (xy 181.205507 -313.183592) (xy 181.179204 -313.141996)
			(xy 181.159913 -313.09672) (xy 181.148136 -313.048936) (xy 181.144176 -312.999882) (xy 179.855368 -312.999882)
			(xy 179.854873 -313.024489) (xy 179.846978 -313.073066) (xy 179.831394 -313.119747) (xy 179.808523 -313.163324)
			(xy 179.778958 -313.202668) (xy 179.743465 -313.23676) (xy 179.702962 -313.264716) (xy 179.6585 -313.285814)
			(xy 179.611229 -313.299506) (xy 179.562374 -313.305438) (xy 179.513199 -313.303457) (xy 179.46498 -313.293613)
			(xy 179.418964 -313.276161) (xy 179.376343 -313.251554) (xy 179.338222 -313.220429) (xy 179.305587 -313.183592)
			(xy 179.279284 -313.141996) (xy 179.259993 -313.09672) (xy 179.248216 -313.048936) (xy 179.244256 -312.999882)
			(xy 177.955194 -312.999882) (xy 177.954699 -313.024489) (xy 177.946804 -313.073066) (xy 177.93122 -313.119747)
			(xy 177.908349 -313.163324) (xy 177.878784 -313.202668) (xy 177.843291 -313.23676) (xy 177.802788 -313.264716)
			(xy 177.758326 -313.285814) (xy 177.711055 -313.299506) (xy 177.6622 -313.305438) (xy 177.613025 -313.303457)
			(xy 177.564806 -313.293613) (xy 177.51879 -313.276161) (xy 177.476169 -313.251554) (xy 177.438048 -313.220429)
			(xy 177.405413 -313.183592) (xy 177.37911 -313.141996) (xy 177.359819 -313.09672) (xy 177.348042 -313.048936)
			(xy 177.344082 -312.999882) (xy 176.055274 -312.999882) (xy 176.054779 -313.024489) (xy 176.046884 -313.073066)
			(xy 176.0313 -313.119747) (xy 176.008429 -313.163324) (xy 175.978864 -313.202668) (xy 175.943371 -313.23676)
			(xy 175.902868 -313.264716) (xy 175.858406 -313.285814) (xy 175.811135 -313.299506) (xy 175.76228 -313.305438)
			(xy 175.713105 -313.303457) (xy 175.664886 -313.293613) (xy 175.61887 -313.276161) (xy 175.576249 -313.251554)
			(xy 175.538128 -313.220429) (xy 175.505493 -313.183592) (xy 175.47919 -313.141996) (xy 175.459899 -313.09672)
			(xy 175.448122 -313.048936) (xy 175.444162 -312.999882) (xy 174.155354 -312.999882) (xy 174.154859 -313.024489)
			(xy 174.146964 -313.073066) (xy 174.13138 -313.119747) (xy 174.108509 -313.163324) (xy 174.078944 -313.202668)
			(xy 174.043451 -313.23676) (xy 174.002948 -313.264716) (xy 173.958486 -313.285814) (xy 173.911215 -313.299506)
			(xy 173.86236 -313.305438) (xy 173.813185 -313.303457) (xy 173.764966 -313.293613) (xy 173.71895 -313.276161)
			(xy 173.676329 -313.251554) (xy 173.638208 -313.220429) (xy 173.605573 -313.183592) (xy 173.57927 -313.141996)
			(xy 173.559979 -313.09672) (xy 173.548202 -313.048936) (xy 173.544242 -312.999882) (xy 172.25518 -312.999882)
			(xy 172.254685 -313.024489) (xy 172.24679 -313.073066) (xy 172.231206 -313.119747) (xy 172.208335 -313.163324)
			(xy 172.17877 -313.202668) (xy 172.143277 -313.23676) (xy 172.102774 -313.264716) (xy 172.058312 -313.285814)
			(xy 172.011041 -313.299506) (xy 171.962186 -313.305438) (xy 171.913011 -313.303457) (xy 171.864792 -313.293613)
			(xy 171.818776 -313.276161) (xy 171.776155 -313.251554) (xy 171.738034 -313.220429) (xy 171.705399 -313.183592)
			(xy 171.679096 -313.141996) (xy 171.659805 -313.09672) (xy 171.648028 -313.048936) (xy 171.644068 -312.999882)
			(xy 170.35526 -312.999882) (xy 170.354765 -313.024489) (xy 170.34687 -313.073066) (xy 170.331286 -313.119747)
			(xy 170.308415 -313.163324) (xy 170.27885 -313.202668) (xy 170.243357 -313.23676) (xy 170.202854 -313.264716)
			(xy 170.158392 -313.285814) (xy 170.111121 -313.299506) (xy 170.062266 -313.305438) (xy 170.013091 -313.303457)
			(xy 169.964872 -313.293613) (xy 169.918856 -313.276161) (xy 169.876235 -313.251554) (xy 169.838114 -313.220429)
			(xy 169.805479 -313.183592) (xy 169.779176 -313.141996) (xy 169.759885 -313.09672) (xy 169.748108 -313.048936)
			(xy 169.744148 -312.999882) (xy 168.45534 -312.999882) (xy 168.454845 -313.024489) (xy 168.44695 -313.073066)
			(xy 168.431366 -313.119747) (xy 168.408495 -313.163324) (xy 168.37893 -313.202668) (xy 168.343437 -313.23676)
			(xy 168.302934 -313.264716) (xy 168.258472 -313.285814) (xy 168.211201 -313.299506) (xy 168.162346 -313.305438)
			(xy 168.113171 -313.303457) (xy 168.064952 -313.293613) (xy 168.018936 -313.276161) (xy 167.976315 -313.251554)
			(xy 167.938194 -313.220429) (xy 167.905559 -313.183592) (xy 167.879256 -313.141996) (xy 167.859965 -313.09672)
			(xy 167.848188 -313.048936) (xy 167.844228 -312.999882) (xy 166.555166 -312.999882) (xy 166.554671 -313.024489)
			(xy 166.546776 -313.073066) (xy 166.531192 -313.119747) (xy 166.508321 -313.163324) (xy 166.478756 -313.202668)
			(xy 166.443263 -313.23676) (xy 166.40276 -313.264716) (xy 166.358298 -313.285814) (xy 166.311027 -313.299506)
			(xy 166.262172 -313.305438) (xy 166.212997 -313.303457) (xy 166.164778 -313.293613) (xy 166.118762 -313.276161)
			(xy 166.076141 -313.251554) (xy 166.03802 -313.220429) (xy 166.005385 -313.183592) (xy 165.979082 -313.141996)
			(xy 165.959791 -313.09672) (xy 165.948014 -313.048936) (xy 165.944054 -312.999882) (xy 164.655246 -312.999882)
			(xy 164.654751 -313.024489) (xy 164.646856 -313.073066) (xy 164.631272 -313.119747) (xy 164.608401 -313.163324)
			(xy 164.578836 -313.202668) (xy 164.543343 -313.23676) (xy 164.50284 -313.264716) (xy 164.458378 -313.285814)
			(xy 164.411107 -313.299506) (xy 164.362252 -313.305438) (xy 164.313077 -313.303457) (xy 164.264858 -313.293613)
			(xy 164.218842 -313.276161) (xy 164.176221 -313.251554) (xy 164.1381 -313.220429) (xy 164.105465 -313.183592)
			(xy 164.079162 -313.141996) (xy 164.059871 -313.09672) (xy 164.048094 -313.048936) (xy 164.044134 -312.999882)
			(xy 162.755326 -312.999882) (xy 162.754831 -313.024489) (xy 162.746936 -313.073066) (xy 162.731352 -313.119747)
			(xy 162.708481 -313.163324) (xy 162.678916 -313.202668) (xy 162.643423 -313.23676) (xy 162.60292 -313.264716)
			(xy 162.558458 -313.285814) (xy 162.511187 -313.299506) (xy 162.462332 -313.305438) (xy 162.413157 -313.303457)
			(xy 162.364938 -313.293613) (xy 162.318922 -313.276161) (xy 162.276301 -313.251554) (xy 162.23818 -313.220429)
			(xy 162.205545 -313.183592) (xy 162.179242 -313.141996) (xy 162.159951 -313.09672) (xy 162.148174 -313.048936)
			(xy 162.144214 -312.999882) (xy 160.855152 -312.999882) (xy 160.854657 -313.024489) (xy 160.846762 -313.073066)
			(xy 160.831178 -313.119747) (xy 160.808307 -313.163324) (xy 160.778742 -313.202668) (xy 160.743249 -313.23676)
			(xy 160.702746 -313.264716) (xy 160.658284 -313.285814) (xy 160.611013 -313.299506) (xy 160.562158 -313.305438)
			(xy 160.512983 -313.303457) (xy 160.464764 -313.293613) (xy 160.418748 -313.276161) (xy 160.376127 -313.251554)
			(xy 160.338006 -313.220429) (xy 160.305371 -313.183592) (xy 160.279068 -313.141996) (xy 160.259777 -313.09672)
			(xy 160.248 -313.048936) (xy 160.24404 -312.999882) (xy 158.955232 -312.999882) (xy 158.954737 -313.024489)
			(xy 158.946842 -313.073066) (xy 158.931258 -313.119747) (xy 158.908387 -313.163324) (xy 158.878822 -313.202668)
			(xy 158.843329 -313.23676) (xy 158.802826 -313.264716) (xy 158.758364 -313.285814) (xy 158.711093 -313.299506)
			(xy 158.662238 -313.305438) (xy 158.613063 -313.303457) (xy 158.564844 -313.293613) (xy 158.518828 -313.276161)
			(xy 158.476207 -313.251554) (xy 158.438086 -313.220429) (xy 158.405451 -313.183592) (xy 158.379148 -313.141996)
			(xy 158.359857 -313.09672) (xy 158.34808 -313.048936) (xy 158.34412 -312.999882) (xy 157.055312 -312.999882)
			(xy 157.054817 -313.024489) (xy 157.046922 -313.073066) (xy 157.031338 -313.119747) (xy 157.008467 -313.163324)
			(xy 156.978902 -313.202668) (xy 156.943409 -313.23676) (xy 156.902906 -313.264716) (xy 156.858444 -313.285814)
			(xy 156.811173 -313.299506) (xy 156.762318 -313.305438) (xy 156.713143 -313.303457) (xy 156.664924 -313.293613)
			(xy 156.618908 -313.276161) (xy 156.576287 -313.251554) (xy 156.538166 -313.220429) (xy 156.505531 -313.183592)
			(xy 156.479228 -313.141996) (xy 156.459937 -313.09672) (xy 156.44816 -313.048936) (xy 156.4442 -312.999882)
			(xy 155.155392 -312.999882) (xy 155.154897 -313.024489) (xy 155.147002 -313.073066) (xy 155.131418 -313.119747)
			(xy 155.108547 -313.163324) (xy 155.078982 -313.202668) (xy 155.043489 -313.23676) (xy 155.002986 -313.264716)
			(xy 154.958524 -313.285814) (xy 154.911253 -313.299506) (xy 154.862398 -313.305438) (xy 154.813223 -313.303457)
			(xy 154.765004 -313.293613) (xy 154.718988 -313.276161) (xy 154.676367 -313.251554) (xy 154.638246 -313.220429)
			(xy 154.605611 -313.183592) (xy 154.579308 -313.141996) (xy 154.560017 -313.09672) (xy 154.54824 -313.048936)
			(xy 154.54428 -312.999882) (xy 80.855058 -312.999882) (xy 80.854563 -313.024489) (xy 80.846668 -313.073066)
			(xy 80.831084 -313.119747) (xy 80.808213 -313.163324) (xy 80.778648 -313.202668) (xy 80.743155 -313.23676)
			(xy 80.702652 -313.264716) (xy 80.65819 -313.285814) (xy 80.610919 -313.299506) (xy 80.562064 -313.305438)
			(xy 80.512889 -313.303457) (xy 80.46467 -313.293613) (xy 80.418654 -313.276161) (xy 80.376033 -313.251554)
			(xy 80.337912 -313.220429) (xy 80.305277 -313.183592) (xy 80.278974 -313.141996) (xy 80.259683 -313.09672)
			(xy 80.247906 -313.048936) (xy 80.243946 -312.999882) (xy 78.955138 -312.999882) (xy 78.954643 -313.024489)
			(xy 78.946748 -313.073066) (xy 78.931164 -313.119747) (xy 78.908293 -313.163324) (xy 78.878728 -313.202668)
			(xy 78.843235 -313.23676) (xy 78.802732 -313.264716) (xy 78.75827 -313.285814) (xy 78.710999 -313.299506)
			(xy 78.662144 -313.305438) (xy 78.612969 -313.303457) (xy 78.56475 -313.293613) (xy 78.518734 -313.276161)
			(xy 78.476113 -313.251554) (xy 78.437992 -313.220429) (xy 78.405357 -313.183592) (xy 78.379054 -313.141996)
			(xy 78.359763 -313.09672) (xy 78.347986 -313.048936) (xy 78.344026 -312.999882) (xy 77.055218 -312.999882)
			(xy 77.054723 -313.024489) (xy 77.046828 -313.073066) (xy 77.031244 -313.119747) (xy 77.008373 -313.163324)
			(xy 76.978808 -313.202668) (xy 76.943315 -313.23676) (xy 76.902812 -313.264716) (xy 76.85835 -313.285814)
			(xy 76.811079 -313.299506) (xy 76.762224 -313.305438) (xy 76.713049 -313.303457) (xy 76.66483 -313.293613)
			(xy 76.618814 -313.276161) (xy 76.576193 -313.251554) (xy 76.538072 -313.220429) (xy 76.505437 -313.183592)
			(xy 76.479134 -313.141996) (xy 76.459843 -313.09672) (xy 76.448066 -313.048936) (xy 76.444106 -312.999882)
			(xy 75.155298 -312.999882) (xy 75.154803 -313.024489) (xy 75.146908 -313.073066) (xy 75.131324 -313.119747)
			(xy 75.108453 -313.163324) (xy 75.078888 -313.202668) (xy 75.043395 -313.23676) (xy 75.002892 -313.264716)
			(xy 74.95843 -313.285814) (xy 74.911159 -313.299506) (xy 74.862304 -313.305438) (xy 74.813129 -313.303457)
			(xy 74.76491 -313.293613) (xy 74.718894 -313.276161) (xy 74.676273 -313.251554) (xy 74.638152 -313.220429)
			(xy 74.605517 -313.183592) (xy 74.579214 -313.141996) (xy 74.559923 -313.09672) (xy 74.548146 -313.048936)
			(xy 74.544186 -312.999882) (xy 73.255124 -312.999882) (xy 73.254629 -313.024489) (xy 73.246734 -313.073066)
			(xy 73.23115 -313.119747) (xy 73.208279 -313.163324) (xy 73.178714 -313.202668) (xy 73.143221 -313.23676)
			(xy 73.102718 -313.264716) (xy 73.058256 -313.285814) (xy 73.010985 -313.299506) (xy 72.96213 -313.305438)
			(xy 72.912955 -313.303457) (xy 72.864736 -313.293613) (xy 72.81872 -313.276161) (xy 72.776099 -313.251554)
			(xy 72.737978 -313.220429) (xy 72.705343 -313.183592) (xy 72.67904 -313.141996) (xy 72.659749 -313.09672)
			(xy 72.647972 -313.048936) (xy 72.644012 -312.999882) (xy 71.355204 -312.999882) (xy 71.354709 -313.024489)
			(xy 71.346814 -313.073066) (xy 71.33123 -313.119747) (xy 71.308359 -313.163324) (xy 71.278794 -313.202668)
			(xy 71.243301 -313.23676) (xy 71.202798 -313.264716) (xy 71.158336 -313.285814) (xy 71.111065 -313.299506)
			(xy 71.06221 -313.305438) (xy 71.013035 -313.303457) (xy 70.964816 -313.293613) (xy 70.9188 -313.276161)
			(xy 70.876179 -313.251554) (xy 70.838058 -313.220429) (xy 70.805423 -313.183592) (xy 70.77912 -313.141996)
			(xy 70.759829 -313.09672) (xy 70.748052 -313.048936) (xy 70.744092 -312.999882) (xy 69.455284 -312.999882)
			(xy 69.454789 -313.024489) (xy 69.446894 -313.073066) (xy 69.43131 -313.119747) (xy 69.408439 -313.163324)
			(xy 69.378874 -313.202668) (xy 69.343381 -313.23676) (xy 69.302878 -313.264716) (xy 69.258416 -313.285814)
			(xy 69.211145 -313.299506) (xy 69.16229 -313.305438) (xy 69.113115 -313.303457) (xy 69.064896 -313.293613)
			(xy 69.01888 -313.276161) (xy 68.976259 -313.251554) (xy 68.938138 -313.220429) (xy 68.905503 -313.183592)
			(xy 68.8792 -313.141996) (xy 68.859909 -313.09672) (xy 68.848132 -313.048936) (xy 68.844172 -312.999882)
			(xy 67.55511 -312.999882) (xy 67.554615 -313.024489) (xy 67.54672 -313.073066) (xy 67.531136 -313.119747)
			(xy 67.508265 -313.163324) (xy 67.4787 -313.202668) (xy 67.443207 -313.23676) (xy 67.402704 -313.264716)
			(xy 67.358242 -313.285814) (xy 67.310971 -313.299506) (xy 67.262116 -313.305438) (xy 67.212941 -313.303457)
			(xy 67.164722 -313.293613) (xy 67.118706 -313.276161) (xy 67.076085 -313.251554) (xy 67.037964 -313.220429)
			(xy 67.005329 -313.183592) (xy 66.979026 -313.141996) (xy 66.959735 -313.09672) (xy 66.947958 -313.048936)
			(xy 66.943998 -312.999882) (xy 65.65519 -312.999882) (xy 65.654695 -313.024489) (xy 65.6468 -313.073066)
			(xy 65.631216 -313.119747) (xy 65.608345 -313.163324) (xy 65.57878 -313.202668) (xy 65.543287 -313.23676)
			(xy 65.502784 -313.264716) (xy 65.458322 -313.285814) (xy 65.411051 -313.299506) (xy 65.362196 -313.305438)
			(xy 65.313021 -313.303457) (xy 65.264802 -313.293613) (xy 65.218786 -313.276161) (xy 65.176165 -313.251554)
			(xy 65.138044 -313.220429) (xy 65.105409 -313.183592) (xy 65.079106 -313.141996) (xy 65.059815 -313.09672)
			(xy 65.048038 -313.048936) (xy 65.044078 -312.999882) (xy 63.75527 -312.999882) (xy 63.754775 -313.024489)
			(xy 63.74688 -313.073066) (xy 63.731296 -313.119747) (xy 63.708425 -313.163324) (xy 63.67886 -313.202668)
			(xy 63.643367 -313.23676) (xy 63.602864 -313.264716) (xy 63.558402 -313.285814) (xy 63.511131 -313.299506)
			(xy 63.462276 -313.305438) (xy 63.413101 -313.303457) (xy 63.364882 -313.293613) (xy 63.318866 -313.276161)
			(xy 63.276245 -313.251554) (xy 63.238124 -313.220429) (xy 63.205489 -313.183592) (xy 63.179186 -313.141996)
			(xy 63.159895 -313.09672) (xy 63.148118 -313.048936) (xy 63.144158 -312.999882) (xy 61.855096 -312.999882)
			(xy 61.854601 -313.024489) (xy 61.846706 -313.073066) (xy 61.831122 -313.119747) (xy 61.808251 -313.163324)
			(xy 61.778686 -313.202668) (xy 61.743193 -313.23676) (xy 61.70269 -313.264716) (xy 61.658228 -313.285814)
			(xy 61.610957 -313.299506) (xy 61.562102 -313.305438) (xy 61.512927 -313.303457) (xy 61.464708 -313.293613)
			(xy 61.418692 -313.276161) (xy 61.376071 -313.251554) (xy 61.33795 -313.220429) (xy 61.305315 -313.183592)
			(xy 61.279012 -313.141996) (xy 61.259721 -313.09672) (xy 61.247944 -313.048936) (xy 61.243984 -312.999882)
			(xy 59.955176 -312.999882) (xy 59.954681 -313.024489) (xy 59.946786 -313.073066) (xy 59.931202 -313.119747)
			(xy 59.908331 -313.163324) (xy 59.878766 -313.202668) (xy 59.843273 -313.23676) (xy 59.80277 -313.264716)
			(xy 59.758308 -313.285814) (xy 59.711037 -313.299506) (xy 59.662182 -313.305438) (xy 59.613007 -313.303457)
			(xy 59.564788 -313.293613) (xy 59.518772 -313.276161) (xy 59.476151 -313.251554) (xy 59.43803 -313.220429)
			(xy 59.405395 -313.183592) (xy 59.379092 -313.141996) (xy 59.359801 -313.09672) (xy 59.348024 -313.048936)
			(xy 59.344064 -312.999882) (xy 58.055256 -312.999882) (xy 58.054761 -313.024489) (xy 58.046866 -313.073066)
			(xy 58.031282 -313.119747) (xy 58.008411 -313.163324) (xy 57.978846 -313.202668) (xy 57.943353 -313.23676)
			(xy 57.90285 -313.264716) (xy 57.858388 -313.285814) (xy 57.811117 -313.299506) (xy 57.762262 -313.305438)
			(xy 57.713087 -313.303457) (xy 57.664868 -313.293613) (xy 57.618852 -313.276161) (xy 57.576231 -313.251554)
			(xy 57.53811 -313.220429) (xy 57.505475 -313.183592) (xy 57.479172 -313.141996) (xy 57.459881 -313.09672)
			(xy 57.448104 -313.048936) (xy 57.444144 -312.999882) (xy 56.155082 -312.999882) (xy 56.154587 -313.024489)
			(xy 56.146692 -313.073066) (xy 56.131108 -313.119747) (xy 56.108237 -313.163324) (xy 56.078672 -313.202668)
			(xy 56.043179 -313.23676) (xy 56.002676 -313.264716) (xy 55.958214 -313.285814) (xy 55.910943 -313.299506)
			(xy 55.862088 -313.305438) (xy 55.812913 -313.303457) (xy 55.764694 -313.293613) (xy 55.718678 -313.276161)
			(xy 55.676057 -313.251554) (xy 55.637936 -313.220429) (xy 55.605301 -313.183592) (xy 55.578998 -313.141996)
			(xy 55.559707 -313.09672) (xy 55.54793 -313.048936) (xy 55.54397 -312.999882) (xy 54.255162 -312.999882)
			(xy 54.254667 -313.024489) (xy 54.246772 -313.073066) (xy 54.231188 -313.119747) (xy 54.208317 -313.163324)
			(xy 54.178752 -313.202668) (xy 54.143259 -313.23676) (xy 54.102756 -313.264716) (xy 54.058294 -313.285814)
			(xy 54.011023 -313.299506) (xy 53.962168 -313.305438) (xy 53.912993 -313.303457) (xy 53.864774 -313.293613)
			(xy 53.818758 -313.276161) (xy 53.776137 -313.251554) (xy 53.738016 -313.220429) (xy 53.705381 -313.183592)
			(xy 53.679078 -313.141996) (xy 53.659787 -313.09672) (xy 53.64801 -313.048936) (xy 53.64405 -312.999882)
			(xy 52.355242 -312.999882) (xy 52.354747 -313.024489) (xy 52.346852 -313.073066) (xy 52.331268 -313.119747)
			(xy 52.308397 -313.163324) (xy 52.278832 -313.202668) (xy 52.243339 -313.23676) (xy 52.202836 -313.264716)
			(xy 52.158374 -313.285814) (xy 52.111103 -313.299506) (xy 52.062248 -313.305438) (xy 52.013073 -313.303457)
			(xy 51.964854 -313.293613) (xy 51.918838 -313.276161) (xy 51.876217 -313.251554) (xy 51.838096 -313.220429)
			(xy 51.805461 -313.183592) (xy 51.779158 -313.141996) (xy 51.759867 -313.09672) (xy 51.74809 -313.048936)
			(xy 51.74413 -312.999882) (xy 50.455068 -312.999882) (xy 50.454573 -313.024489) (xy 50.446678 -313.073066)
			(xy 50.431094 -313.119747) (xy 50.408223 -313.163324) (xy 50.378658 -313.202668) (xy 50.343165 -313.23676)
			(xy 50.302662 -313.264716) (xy 50.2582 -313.285814) (xy 50.210929 -313.299506) (xy 50.162074 -313.305438)
			(xy 50.112899 -313.303457) (xy 50.06468 -313.293613) (xy 50.018664 -313.276161) (xy 49.976043 -313.251554)
			(xy 49.937922 -313.220429) (xy 49.905287 -313.183592) (xy 49.878984 -313.141996) (xy 49.859693 -313.09672)
			(xy 49.847916 -313.048936) (xy 49.843956 -312.999882) (xy 48.555148 -312.999882) (xy 48.554653 -313.024489)
			(xy 48.546758 -313.073066) (xy 48.531174 -313.119747) (xy 48.508303 -313.163324) (xy 48.478738 -313.202668)
			(xy 48.443245 -313.23676) (xy 48.402742 -313.264716) (xy 48.35828 -313.285814) (xy 48.311009 -313.299506)
			(xy 48.262154 -313.305438) (xy 48.212979 -313.303457) (xy 48.16476 -313.293613) (xy 48.118744 -313.276161)
			(xy 48.076123 -313.251554) (xy 48.038002 -313.220429) (xy 48.005367 -313.183592) (xy 47.979064 -313.141996)
			(xy 47.959773 -313.09672) (xy 47.947996 -313.048936) (xy 47.944036 -312.999882) (xy 46.655228 -312.999882)
			(xy 46.654733 -313.024489) (xy 46.646838 -313.073066) (xy 46.631254 -313.119747) (xy 46.608383 -313.163324)
			(xy 46.578818 -313.202668) (xy 46.543325 -313.23676) (xy 46.502822 -313.264716) (xy 46.45836 -313.285814)
			(xy 46.411089 -313.299506) (xy 46.362234 -313.305438) (xy 46.313059 -313.303457) (xy 46.26484 -313.293613)
			(xy 46.218824 -313.276161) (xy 46.176203 -313.251554) (xy 46.138082 -313.220429) (xy 46.105447 -313.183592)
			(xy 46.079144 -313.141996) (xy 46.059853 -313.09672) (xy 46.048076 -313.048936) (xy 46.044116 -312.999882)
			(xy 44.755054 -312.999882) (xy 44.754559 -313.024489) (xy 44.746664 -313.073066) (xy 44.73108 -313.119747)
			(xy 44.708209 -313.163324) (xy 44.678644 -313.202668) (xy 44.643151 -313.23676) (xy 44.602648 -313.264716)
			(xy 44.558186 -313.285814) (xy 44.510915 -313.299506) (xy 44.46206 -313.305438) (xy 44.412885 -313.303457)
			(xy 44.364666 -313.293613) (xy 44.31865 -313.276161) (xy 44.276029 -313.251554) (xy 44.237908 -313.220429)
			(xy 44.205273 -313.183592) (xy 44.17897 -313.141996) (xy 44.159679 -313.09672) (xy 44.147902 -313.048936)
			(xy 44.143942 -312.999882) (xy 42.855134 -312.999882) (xy 42.854639 -313.024489) (xy 42.846744 -313.073066)
			(xy 42.83116 -313.119747) (xy 42.808289 -313.163324) (xy 42.778724 -313.202668) (xy 42.743231 -313.23676)
			(xy 42.702728 -313.264716) (xy 42.658266 -313.285814) (xy 42.610995 -313.299506) (xy 42.56214 -313.305438)
			(xy 42.512965 -313.303457) (xy 42.464746 -313.293613) (xy 42.41873 -313.276161) (xy 42.376109 -313.251554)
			(xy 42.337988 -313.220429) (xy 42.305353 -313.183592) (xy 42.27905 -313.141996) (xy 42.259759 -313.09672)
			(xy 42.247982 -313.048936) (xy 42.244022 -312.999882) (xy 40.955214 -312.999882) (xy 40.954719 -313.024489)
			(xy 40.946824 -313.073066) (xy 40.93124 -313.119747) (xy 40.908369 -313.163324) (xy 40.878804 -313.202668)
			(xy 40.843311 -313.23676) (xy 40.802808 -313.264716) (xy 40.758346 -313.285814) (xy 40.711075 -313.299506)
			(xy 40.66222 -313.305438) (xy 40.613045 -313.303457) (xy 40.564826 -313.293613) (xy 40.51881 -313.276161)
			(xy 40.476189 -313.251554) (xy 40.438068 -313.220429) (xy 40.405433 -313.183592) (xy 40.37913 -313.141996)
			(xy 40.359839 -313.09672) (xy 40.348062 -313.048936) (xy 40.344102 -312.999882) (xy 39.055294 -312.999882)
			(xy 39.054799 -313.024489) (xy 39.046904 -313.073066) (xy 39.03132 -313.119747) (xy 39.008449 -313.163324)
			(xy 38.978884 -313.202668) (xy 38.943391 -313.23676) (xy 38.902888 -313.264716) (xy 38.858426 -313.285814)
			(xy 38.811155 -313.299506) (xy 38.7623 -313.305438) (xy 38.713125 -313.303457) (xy 38.664906 -313.293613)
			(xy 38.61889 -313.276161) (xy 38.576269 -313.251554) (xy 38.538148 -313.220429) (xy 38.505513 -313.183592)
			(xy 38.47921 -313.141996) (xy 38.459919 -313.09672) (xy 38.448142 -313.048936) (xy 38.444182 -312.999882)
			(xy 0.508 -312.999882) (xy 0.508 -313.949842) (xy 38.444182 -313.949842) (xy 38.448142 -313.900788)
			(xy 38.459919 -313.853004) (xy 38.47921 -313.807728) (xy 38.505513 -313.766132) (xy 38.538148 -313.729295)
			(xy 38.576269 -313.69817) (xy 38.61889 -313.673563) (xy 38.664906 -313.656111) (xy 38.713125 -313.646267)
			(xy 38.7623 -313.644286) (xy 38.811155 -313.650218) (xy 38.858426 -313.66391) (xy 38.902888 -313.685008)
			(xy 38.943391 -313.712964) (xy 38.978884 -313.747056) (xy 39.008449 -313.7864) (xy 39.03132 -313.829977)
			(xy 39.046904 -313.876658) (xy 39.054799 -313.925235) (xy 39.055294 -313.949842) (xy 40.344102 -313.949842)
			(xy 40.348062 -313.900788) (xy 40.359839 -313.853004) (xy 40.37913 -313.807728) (xy 40.405433 -313.766132)
			(xy 40.438068 -313.729295) (xy 40.476189 -313.69817) (xy 40.51881 -313.673563) (xy 40.564826 -313.656111)
			(xy 40.613045 -313.646267) (xy 40.66222 -313.644286) (xy 40.711075 -313.650218) (xy 40.758346 -313.66391)
			(xy 40.802808 -313.685008) (xy 40.843311 -313.712964) (xy 40.878804 -313.747056) (xy 40.908369 -313.7864)
			(xy 40.93124 -313.829977) (xy 40.946824 -313.876658) (xy 40.954719 -313.925235) (xy 40.955214 -313.949842)
			(xy 42.244022 -313.949842) (xy 42.247982 -313.900788) (xy 42.259759 -313.853004) (xy 42.27905 -313.807728)
			(xy 42.305353 -313.766132) (xy 42.337988 -313.729295) (xy 42.376109 -313.69817) (xy 42.41873 -313.673563)
			(xy 42.464746 -313.656111) (xy 42.512965 -313.646267) (xy 42.56214 -313.644286) (xy 42.610995 -313.650218)
			(xy 42.658266 -313.66391) (xy 42.702728 -313.685008) (xy 42.743231 -313.712964) (xy 42.778724 -313.747056)
			(xy 42.808289 -313.7864) (xy 42.83116 -313.829977) (xy 42.846744 -313.876658) (xy 42.854639 -313.925235)
			(xy 42.855134 -313.949842) (xy 44.143942 -313.949842) (xy 44.147902 -313.900788) (xy 44.159679 -313.853004)
			(xy 44.17897 -313.807728) (xy 44.205273 -313.766132) (xy 44.237908 -313.729295) (xy 44.276029 -313.69817)
			(xy 44.31865 -313.673563) (xy 44.364666 -313.656111) (xy 44.412885 -313.646267) (xy 44.46206 -313.644286)
			(xy 44.510915 -313.650218) (xy 44.558186 -313.66391) (xy 44.602648 -313.685008) (xy 44.643151 -313.712964)
			(xy 44.678644 -313.747056) (xy 44.708209 -313.7864) (xy 44.73108 -313.829977) (xy 44.746664 -313.876658)
			(xy 44.754559 -313.925235) (xy 44.755054 -313.949842) (xy 46.044116 -313.949842) (xy 46.048076 -313.900788)
			(xy 46.059853 -313.853004) (xy 46.079144 -313.807728) (xy 46.105447 -313.766132) (xy 46.138082 -313.729295)
			(xy 46.176203 -313.69817) (xy 46.218824 -313.673563) (xy 46.26484 -313.656111) (xy 46.313059 -313.646267)
			(xy 46.362234 -313.644286) (xy 46.411089 -313.650218) (xy 46.45836 -313.66391) (xy 46.502822 -313.685008)
			(xy 46.543325 -313.712964) (xy 46.578818 -313.747056) (xy 46.608383 -313.7864) (xy 46.631254 -313.829977)
			(xy 46.646838 -313.876658) (xy 46.654733 -313.925235) (xy 46.655228 -313.949842) (xy 47.944036 -313.949842)
			(xy 47.947996 -313.900788) (xy 47.959773 -313.853004) (xy 47.979064 -313.807728) (xy 48.005367 -313.766132)
			(xy 48.038002 -313.729295) (xy 48.076123 -313.69817) (xy 48.118744 -313.673563) (xy 48.16476 -313.656111)
			(xy 48.212979 -313.646267) (xy 48.262154 -313.644286) (xy 48.311009 -313.650218) (xy 48.35828 -313.66391)
			(xy 48.402742 -313.685008) (xy 48.443245 -313.712964) (xy 48.478738 -313.747056) (xy 48.508303 -313.7864)
			(xy 48.531174 -313.829977) (xy 48.546758 -313.876658) (xy 48.554653 -313.925235) (xy 48.555148 -313.949842)
			(xy 49.843956 -313.949842) (xy 49.847916 -313.900788) (xy 49.859693 -313.853004) (xy 49.878984 -313.807728)
			(xy 49.905287 -313.766132) (xy 49.937922 -313.729295) (xy 49.976043 -313.69817) (xy 50.018664 -313.673563)
			(xy 50.06468 -313.656111) (xy 50.112899 -313.646267) (xy 50.162074 -313.644286) (xy 50.210929 -313.650218)
			(xy 50.2582 -313.66391) (xy 50.302662 -313.685008) (xy 50.343165 -313.712964) (xy 50.378658 -313.747056)
			(xy 50.408223 -313.7864) (xy 50.431094 -313.829977) (xy 50.446678 -313.876658) (xy 50.454573 -313.925235)
			(xy 50.455068 -313.949842) (xy 51.74413 -313.949842) (xy 51.74809 -313.900788) (xy 51.759867 -313.853004)
			(xy 51.779158 -313.807728) (xy 51.805461 -313.766132) (xy 51.838096 -313.729295) (xy 51.876217 -313.69817)
			(xy 51.918838 -313.673563) (xy 51.964854 -313.656111) (xy 52.013073 -313.646267) (xy 52.062248 -313.644286)
			(xy 52.111103 -313.650218) (xy 52.158374 -313.66391) (xy 52.202836 -313.685008) (xy 52.243339 -313.712964)
			(xy 52.278832 -313.747056) (xy 52.308397 -313.7864) (xy 52.331268 -313.829977) (xy 52.346852 -313.876658)
			(xy 52.354747 -313.925235) (xy 52.355242 -313.949842) (xy 53.64405 -313.949842) (xy 53.64801 -313.900788)
			(xy 53.659787 -313.853004) (xy 53.679078 -313.807728) (xy 53.705381 -313.766132) (xy 53.738016 -313.729295)
			(xy 53.776137 -313.69817) (xy 53.818758 -313.673563) (xy 53.864774 -313.656111) (xy 53.912993 -313.646267)
			(xy 53.962168 -313.644286) (xy 54.011023 -313.650218) (xy 54.058294 -313.66391) (xy 54.102756 -313.685008)
			(xy 54.143259 -313.712964) (xy 54.178752 -313.747056) (xy 54.208317 -313.7864) (xy 54.231188 -313.829977)
			(xy 54.246772 -313.876658) (xy 54.254667 -313.925235) (xy 54.255162 -313.949842) (xy 55.54397 -313.949842)
			(xy 55.54793 -313.900788) (xy 55.559707 -313.853004) (xy 55.578998 -313.807728) (xy 55.605301 -313.766132)
			(xy 55.637936 -313.729295) (xy 55.676057 -313.69817) (xy 55.718678 -313.673563) (xy 55.764694 -313.656111)
			(xy 55.812913 -313.646267) (xy 55.862088 -313.644286) (xy 55.910943 -313.650218) (xy 55.958214 -313.66391)
			(xy 56.002676 -313.685008) (xy 56.043179 -313.712964) (xy 56.078672 -313.747056) (xy 56.108237 -313.7864)
			(xy 56.131108 -313.829977) (xy 56.146692 -313.876658) (xy 56.154587 -313.925235) (xy 56.155082 -313.949842)
			(xy 57.444144 -313.949842) (xy 57.448104 -313.900788) (xy 57.459881 -313.853004) (xy 57.479172 -313.807728)
			(xy 57.505475 -313.766132) (xy 57.53811 -313.729295) (xy 57.576231 -313.69817) (xy 57.618852 -313.673563)
			(xy 57.664868 -313.656111) (xy 57.713087 -313.646267) (xy 57.762262 -313.644286) (xy 57.811117 -313.650218)
			(xy 57.858388 -313.66391) (xy 57.90285 -313.685008) (xy 57.943353 -313.712964) (xy 57.978846 -313.747056)
			(xy 58.008411 -313.7864) (xy 58.031282 -313.829977) (xy 58.046866 -313.876658) (xy 58.054761 -313.925235)
			(xy 58.055256 -313.949842) (xy 59.344064 -313.949842) (xy 59.348024 -313.900788) (xy 59.359801 -313.853004)
			(xy 59.379092 -313.807728) (xy 59.405395 -313.766132) (xy 59.43803 -313.729295) (xy 59.476151 -313.69817)
			(xy 59.518772 -313.673563) (xy 59.564788 -313.656111) (xy 59.613007 -313.646267) (xy 59.662182 -313.644286)
			(xy 59.711037 -313.650218) (xy 59.758308 -313.66391) (xy 59.80277 -313.685008) (xy 59.843273 -313.712964)
			(xy 59.878766 -313.747056) (xy 59.908331 -313.7864) (xy 59.931202 -313.829977) (xy 59.946786 -313.876658)
			(xy 59.954681 -313.925235) (xy 59.955176 -313.949842) (xy 61.243984 -313.949842) (xy 61.247944 -313.900788)
			(xy 61.259721 -313.853004) (xy 61.279012 -313.807728) (xy 61.305315 -313.766132) (xy 61.33795 -313.729295)
			(xy 61.376071 -313.69817) (xy 61.418692 -313.673563) (xy 61.464708 -313.656111) (xy 61.512927 -313.646267)
			(xy 61.562102 -313.644286) (xy 61.610957 -313.650218) (xy 61.658228 -313.66391) (xy 61.70269 -313.685008)
			(xy 61.743193 -313.712964) (xy 61.778686 -313.747056) (xy 61.808251 -313.7864) (xy 61.831122 -313.829977)
			(xy 61.846706 -313.876658) (xy 61.854601 -313.925235) (xy 61.855096 -313.949842) (xy 63.144158 -313.949842)
			(xy 63.148118 -313.900788) (xy 63.159895 -313.853004) (xy 63.179186 -313.807728) (xy 63.205489 -313.766132)
			(xy 63.238124 -313.729295) (xy 63.276245 -313.69817) (xy 63.318866 -313.673563) (xy 63.364882 -313.656111)
			(xy 63.413101 -313.646267) (xy 63.462276 -313.644286) (xy 63.511131 -313.650218) (xy 63.558402 -313.66391)
			(xy 63.602864 -313.685008) (xy 63.643367 -313.712964) (xy 63.67886 -313.747056) (xy 63.708425 -313.7864)
			(xy 63.731296 -313.829977) (xy 63.74688 -313.876658) (xy 63.754775 -313.925235) (xy 63.75527 -313.949842)
			(xy 65.044078 -313.949842) (xy 65.048038 -313.900788) (xy 65.059815 -313.853004) (xy 65.079106 -313.807728)
			(xy 65.105409 -313.766132) (xy 65.138044 -313.729295) (xy 65.176165 -313.69817) (xy 65.218786 -313.673563)
			(xy 65.264802 -313.656111) (xy 65.313021 -313.646267) (xy 65.362196 -313.644286) (xy 65.411051 -313.650218)
			(xy 65.458322 -313.66391) (xy 65.502784 -313.685008) (xy 65.543287 -313.712964) (xy 65.57878 -313.747056)
			(xy 65.608345 -313.7864) (xy 65.631216 -313.829977) (xy 65.6468 -313.876658) (xy 65.654695 -313.925235)
			(xy 65.65519 -313.949842) (xy 66.943998 -313.949842) (xy 66.947958 -313.900788) (xy 66.959735 -313.853004)
			(xy 66.979026 -313.807728) (xy 67.005329 -313.766132) (xy 67.037964 -313.729295) (xy 67.076085 -313.69817)
			(xy 67.118706 -313.673563) (xy 67.164722 -313.656111) (xy 67.212941 -313.646267) (xy 67.262116 -313.644286)
			(xy 67.310971 -313.650218) (xy 67.358242 -313.66391) (xy 67.402704 -313.685008) (xy 67.443207 -313.712964)
			(xy 67.4787 -313.747056) (xy 67.508265 -313.7864) (xy 67.531136 -313.829977) (xy 67.54672 -313.876658)
			(xy 67.554615 -313.925235) (xy 67.55511 -313.949842) (xy 68.844172 -313.949842) (xy 68.848132 -313.900788)
			(xy 68.859909 -313.853004) (xy 68.8792 -313.807728) (xy 68.905503 -313.766132) (xy 68.938138 -313.729295)
			(xy 68.976259 -313.69817) (xy 69.01888 -313.673563) (xy 69.064896 -313.656111) (xy 69.113115 -313.646267)
			(xy 69.16229 -313.644286) (xy 69.211145 -313.650218) (xy 69.258416 -313.66391) (xy 69.302878 -313.685008)
			(xy 69.343381 -313.712964) (xy 69.378874 -313.747056) (xy 69.408439 -313.7864) (xy 69.43131 -313.829977)
			(xy 69.446894 -313.876658) (xy 69.454789 -313.925235) (xy 69.455284 -313.949842) (xy 70.744092 -313.949842)
			(xy 70.748052 -313.900788) (xy 70.759829 -313.853004) (xy 70.77912 -313.807728) (xy 70.805423 -313.766132)
			(xy 70.838058 -313.729295) (xy 70.876179 -313.69817) (xy 70.9188 -313.673563) (xy 70.964816 -313.656111)
			(xy 71.013035 -313.646267) (xy 71.06221 -313.644286) (xy 71.111065 -313.650218) (xy 71.158336 -313.66391)
			(xy 71.202798 -313.685008) (xy 71.243301 -313.712964) (xy 71.278794 -313.747056) (xy 71.308359 -313.7864)
			(xy 71.33123 -313.829977) (xy 71.346814 -313.876658) (xy 71.354709 -313.925235) (xy 71.355204 -313.949842)
			(xy 72.644012 -313.949842) (xy 72.647972 -313.900788) (xy 72.659749 -313.853004) (xy 72.67904 -313.807728)
			(xy 72.705343 -313.766132) (xy 72.737978 -313.729295) (xy 72.776099 -313.69817) (xy 72.81872 -313.673563)
			(xy 72.864736 -313.656111) (xy 72.912955 -313.646267) (xy 72.96213 -313.644286) (xy 73.010985 -313.650218)
			(xy 73.058256 -313.66391) (xy 73.102718 -313.685008) (xy 73.143221 -313.712964) (xy 73.178714 -313.747056)
			(xy 73.208279 -313.7864) (xy 73.23115 -313.829977) (xy 73.246734 -313.876658) (xy 73.254629 -313.925235)
			(xy 73.255124 -313.949842) (xy 74.544186 -313.949842) (xy 74.548146 -313.900788) (xy 74.559923 -313.853004)
			(xy 74.579214 -313.807728) (xy 74.605517 -313.766132) (xy 74.638152 -313.729295) (xy 74.676273 -313.69817)
			(xy 74.718894 -313.673563) (xy 74.76491 -313.656111) (xy 74.813129 -313.646267) (xy 74.862304 -313.644286)
			(xy 74.911159 -313.650218) (xy 74.95843 -313.66391) (xy 75.002892 -313.685008) (xy 75.043395 -313.712964)
			(xy 75.078888 -313.747056) (xy 75.108453 -313.7864) (xy 75.131324 -313.829977) (xy 75.146908 -313.876658)
			(xy 75.154803 -313.925235) (xy 75.155298 -313.949842) (xy 76.444106 -313.949842) (xy 76.448066 -313.900788)
			(xy 76.459843 -313.853004) (xy 76.479134 -313.807728) (xy 76.505437 -313.766132) (xy 76.538072 -313.729295)
			(xy 76.576193 -313.69817) (xy 76.618814 -313.673563) (xy 76.66483 -313.656111) (xy 76.713049 -313.646267)
			(xy 76.762224 -313.644286) (xy 76.811079 -313.650218) (xy 76.85835 -313.66391) (xy 76.902812 -313.685008)
			(xy 76.943315 -313.712964) (xy 76.978808 -313.747056) (xy 77.008373 -313.7864) (xy 77.031244 -313.829977)
			(xy 77.046828 -313.876658) (xy 77.054723 -313.925235) (xy 77.055218 -313.949842) (xy 78.344026 -313.949842)
			(xy 78.347986 -313.900788) (xy 78.359763 -313.853004) (xy 78.379054 -313.807728) (xy 78.405357 -313.766132)
			(xy 78.437992 -313.729295) (xy 78.476113 -313.69817) (xy 78.518734 -313.673563) (xy 78.56475 -313.656111)
			(xy 78.612969 -313.646267) (xy 78.662144 -313.644286) (xy 78.710999 -313.650218) (xy 78.75827 -313.66391)
			(xy 78.802732 -313.685008) (xy 78.843235 -313.712964) (xy 78.878728 -313.747056) (xy 78.908293 -313.7864)
			(xy 78.931164 -313.829977) (xy 78.946748 -313.876658) (xy 78.954643 -313.925235) (xy 78.955138 -313.949842)
			(xy 80.243946 -313.949842) (xy 80.247906 -313.900788) (xy 80.259683 -313.853004) (xy 80.278974 -313.807728)
			(xy 80.305277 -313.766132) (xy 80.337912 -313.729295) (xy 80.376033 -313.69817) (xy 80.418654 -313.673563)
			(xy 80.46467 -313.656111) (xy 80.512889 -313.646267) (xy 80.562064 -313.644286) (xy 80.610919 -313.650218)
			(xy 80.65819 -313.66391) (xy 80.702652 -313.685008) (xy 80.743155 -313.712964) (xy 80.778648 -313.747056)
			(xy 80.808213 -313.7864) (xy 80.831084 -313.829977) (xy 80.846668 -313.876658) (xy 80.854563 -313.925235)
			(xy 80.855058 -313.949842) (xy 154.54428 -313.949842) (xy 154.54824 -313.900788) (xy 154.560017 -313.853004)
			(xy 154.579308 -313.807728) (xy 154.605611 -313.766132) (xy 154.638246 -313.729295) (xy 154.676367 -313.69817)
			(xy 154.718988 -313.673563) (xy 154.765004 -313.656111) (xy 154.813223 -313.646267) (xy 154.862398 -313.644286)
			(xy 154.911253 -313.650218) (xy 154.958524 -313.66391) (xy 155.002986 -313.685008) (xy 155.043489 -313.712964)
			(xy 155.078982 -313.747056) (xy 155.108547 -313.7864) (xy 155.131418 -313.829977) (xy 155.147002 -313.876658)
			(xy 155.154897 -313.925235) (xy 155.155392 -313.949842) (xy 156.4442 -313.949842) (xy 156.44816 -313.900788)
			(xy 156.459937 -313.853004) (xy 156.479228 -313.807728) (xy 156.505531 -313.766132) (xy 156.538166 -313.729295)
			(xy 156.576287 -313.69817) (xy 156.618908 -313.673563) (xy 156.664924 -313.656111) (xy 156.713143 -313.646267)
			(xy 156.762318 -313.644286) (xy 156.811173 -313.650218) (xy 156.858444 -313.66391) (xy 156.902906 -313.685008)
			(xy 156.943409 -313.712964) (xy 156.978902 -313.747056) (xy 157.008467 -313.7864) (xy 157.031338 -313.829977)
			(xy 157.046922 -313.876658) (xy 157.054817 -313.925235) (xy 157.055312 -313.949842) (xy 158.34412 -313.949842)
			(xy 158.34808 -313.900788) (xy 158.359857 -313.853004) (xy 158.379148 -313.807728) (xy 158.405451 -313.766132)
			(xy 158.438086 -313.729295) (xy 158.476207 -313.69817) (xy 158.518828 -313.673563) (xy 158.564844 -313.656111)
			(xy 158.613063 -313.646267) (xy 158.662238 -313.644286) (xy 158.711093 -313.650218) (xy 158.758364 -313.66391)
			(xy 158.802826 -313.685008) (xy 158.843329 -313.712964) (xy 158.878822 -313.747056) (xy 158.908387 -313.7864)
			(xy 158.931258 -313.829977) (xy 158.946842 -313.876658) (xy 158.954737 -313.925235) (xy 158.955232 -313.949842)
			(xy 160.24404 -313.949842) (xy 160.248 -313.900788) (xy 160.259777 -313.853004) (xy 160.279068 -313.807728)
			(xy 160.305371 -313.766132) (xy 160.338006 -313.729295) (xy 160.376127 -313.69817) (xy 160.418748 -313.673563)
			(xy 160.464764 -313.656111) (xy 160.512983 -313.646267) (xy 160.562158 -313.644286) (xy 160.611013 -313.650218)
			(xy 160.658284 -313.66391) (xy 160.702746 -313.685008) (xy 160.743249 -313.712964) (xy 160.778742 -313.747056)
			(xy 160.808307 -313.7864) (xy 160.831178 -313.829977) (xy 160.846762 -313.876658) (xy 160.854657 -313.925235)
			(xy 160.855152 -313.949842) (xy 162.144214 -313.949842) (xy 162.148174 -313.900788) (xy 162.159951 -313.853004)
			(xy 162.179242 -313.807728) (xy 162.205545 -313.766132) (xy 162.23818 -313.729295) (xy 162.276301 -313.69817)
			(xy 162.318922 -313.673563) (xy 162.364938 -313.656111) (xy 162.413157 -313.646267) (xy 162.462332 -313.644286)
			(xy 162.511187 -313.650218) (xy 162.558458 -313.66391) (xy 162.60292 -313.685008) (xy 162.643423 -313.712964)
			(xy 162.678916 -313.747056) (xy 162.708481 -313.7864) (xy 162.731352 -313.829977) (xy 162.746936 -313.876658)
			(xy 162.754831 -313.925235) (xy 162.755326 -313.949842) (xy 164.044134 -313.949842) (xy 164.048094 -313.900788)
			(xy 164.059871 -313.853004) (xy 164.079162 -313.807728) (xy 164.105465 -313.766132) (xy 164.1381 -313.729295)
			(xy 164.176221 -313.69817) (xy 164.218842 -313.673563) (xy 164.264858 -313.656111) (xy 164.313077 -313.646267)
			(xy 164.362252 -313.644286) (xy 164.411107 -313.650218) (xy 164.458378 -313.66391) (xy 164.50284 -313.685008)
			(xy 164.543343 -313.712964) (xy 164.578836 -313.747056) (xy 164.608401 -313.7864) (xy 164.631272 -313.829977)
			(xy 164.646856 -313.876658) (xy 164.654751 -313.925235) (xy 164.655246 -313.949842) (xy 165.944054 -313.949842)
			(xy 165.948014 -313.900788) (xy 165.959791 -313.853004) (xy 165.979082 -313.807728) (xy 166.005385 -313.766132)
			(xy 166.03802 -313.729295) (xy 166.076141 -313.69817) (xy 166.118762 -313.673563) (xy 166.164778 -313.656111)
			(xy 166.212997 -313.646267) (xy 166.262172 -313.644286) (xy 166.311027 -313.650218) (xy 166.358298 -313.66391)
			(xy 166.40276 -313.685008) (xy 166.443263 -313.712964) (xy 166.478756 -313.747056) (xy 166.508321 -313.7864)
			(xy 166.531192 -313.829977) (xy 166.546776 -313.876658) (xy 166.554671 -313.925235) (xy 166.555166 -313.949842)
			(xy 167.844228 -313.949842) (xy 167.848188 -313.900788) (xy 167.859965 -313.853004) (xy 167.879256 -313.807728)
			(xy 167.905559 -313.766132) (xy 167.938194 -313.729295) (xy 167.976315 -313.69817) (xy 168.018936 -313.673563)
			(xy 168.064952 -313.656111) (xy 168.113171 -313.646267) (xy 168.162346 -313.644286) (xy 168.211201 -313.650218)
			(xy 168.258472 -313.66391) (xy 168.302934 -313.685008) (xy 168.343437 -313.712964) (xy 168.37893 -313.747056)
			(xy 168.408495 -313.7864) (xy 168.431366 -313.829977) (xy 168.44695 -313.876658) (xy 168.454845 -313.925235)
			(xy 168.45534 -313.949842) (xy 169.744148 -313.949842) (xy 169.748108 -313.900788) (xy 169.759885 -313.853004)
			(xy 169.779176 -313.807728) (xy 169.805479 -313.766132) (xy 169.838114 -313.729295) (xy 169.876235 -313.69817)
			(xy 169.918856 -313.673563) (xy 169.964872 -313.656111) (xy 170.013091 -313.646267) (xy 170.062266 -313.644286)
			(xy 170.111121 -313.650218) (xy 170.158392 -313.66391) (xy 170.202854 -313.685008) (xy 170.243357 -313.712964)
			(xy 170.27885 -313.747056) (xy 170.308415 -313.7864) (xy 170.331286 -313.829977) (xy 170.34687 -313.876658)
			(xy 170.354765 -313.925235) (xy 170.35526 -313.949842) (xy 171.644068 -313.949842) (xy 171.648028 -313.900788)
			(xy 171.659805 -313.853004) (xy 171.679096 -313.807728) (xy 171.705399 -313.766132) (xy 171.738034 -313.729295)
			(xy 171.776155 -313.69817) (xy 171.818776 -313.673563) (xy 171.864792 -313.656111) (xy 171.913011 -313.646267)
			(xy 171.962186 -313.644286) (xy 172.011041 -313.650218) (xy 172.058312 -313.66391) (xy 172.102774 -313.685008)
			(xy 172.143277 -313.712964) (xy 172.17877 -313.747056) (xy 172.208335 -313.7864) (xy 172.231206 -313.829977)
			(xy 172.24679 -313.876658) (xy 172.254685 -313.925235) (xy 172.25518 -313.949842) (xy 173.544242 -313.949842)
			(xy 173.548202 -313.900788) (xy 173.559979 -313.853004) (xy 173.57927 -313.807728) (xy 173.605573 -313.766132)
			(xy 173.638208 -313.729295) (xy 173.676329 -313.69817) (xy 173.71895 -313.673563) (xy 173.764966 -313.656111)
			(xy 173.813185 -313.646267) (xy 173.86236 -313.644286) (xy 173.911215 -313.650218) (xy 173.958486 -313.66391)
			(xy 174.002948 -313.685008) (xy 174.043451 -313.712964) (xy 174.078944 -313.747056) (xy 174.108509 -313.7864)
			(xy 174.13138 -313.829977) (xy 174.146964 -313.876658) (xy 174.154859 -313.925235) (xy 174.155354 -313.949842)
			(xy 175.444162 -313.949842) (xy 175.448122 -313.900788) (xy 175.459899 -313.853004) (xy 175.47919 -313.807728)
			(xy 175.505493 -313.766132) (xy 175.538128 -313.729295) (xy 175.576249 -313.69817) (xy 175.61887 -313.673563)
			(xy 175.664886 -313.656111) (xy 175.713105 -313.646267) (xy 175.76228 -313.644286) (xy 175.811135 -313.650218)
			(xy 175.858406 -313.66391) (xy 175.902868 -313.685008) (xy 175.943371 -313.712964) (xy 175.978864 -313.747056)
			(xy 176.008429 -313.7864) (xy 176.0313 -313.829977) (xy 176.046884 -313.876658) (xy 176.054779 -313.925235)
			(xy 176.055274 -313.949842) (xy 177.344082 -313.949842) (xy 177.348042 -313.900788) (xy 177.359819 -313.853004)
			(xy 177.37911 -313.807728) (xy 177.405413 -313.766132) (xy 177.438048 -313.729295) (xy 177.476169 -313.69817)
			(xy 177.51879 -313.673563) (xy 177.564806 -313.656111) (xy 177.613025 -313.646267) (xy 177.6622 -313.644286)
			(xy 177.711055 -313.650218) (xy 177.758326 -313.66391) (xy 177.802788 -313.685008) (xy 177.843291 -313.712964)
			(xy 177.878784 -313.747056) (xy 177.908349 -313.7864) (xy 177.93122 -313.829977) (xy 177.946804 -313.876658)
			(xy 177.954699 -313.925235) (xy 177.955194 -313.949842) (xy 179.244256 -313.949842) (xy 179.248216 -313.900788)
			(xy 179.259993 -313.853004) (xy 179.279284 -313.807728) (xy 179.305587 -313.766132) (xy 179.338222 -313.729295)
			(xy 179.376343 -313.69817) (xy 179.418964 -313.673563) (xy 179.46498 -313.656111) (xy 179.513199 -313.646267)
			(xy 179.562374 -313.644286) (xy 179.611229 -313.650218) (xy 179.6585 -313.66391) (xy 179.702962 -313.685008)
			(xy 179.743465 -313.712964) (xy 179.778958 -313.747056) (xy 179.808523 -313.7864) (xy 179.831394 -313.829977)
			(xy 179.846978 -313.876658) (xy 179.854873 -313.925235) (xy 179.855368 -313.949842) (xy 181.144176 -313.949842)
			(xy 181.148136 -313.900788) (xy 181.159913 -313.853004) (xy 181.179204 -313.807728) (xy 181.205507 -313.766132)
			(xy 181.238142 -313.729295) (xy 181.276263 -313.69817) (xy 181.318884 -313.673563) (xy 181.3649 -313.656111)
			(xy 181.413119 -313.646267) (xy 181.462294 -313.644286) (xy 181.511149 -313.650218) (xy 181.55842 -313.66391)
			(xy 181.602882 -313.685008) (xy 181.643385 -313.712964) (xy 181.678878 -313.747056) (xy 181.708443 -313.7864)
			(xy 181.731314 -313.829977) (xy 181.746898 -313.876658) (xy 181.754793 -313.925235) (xy 181.755288 -313.949842)
			(xy 183.044096 -313.949842) (xy 183.048056 -313.900788) (xy 183.059833 -313.853004) (xy 183.079124 -313.807728)
			(xy 183.105427 -313.766132) (xy 183.138062 -313.729295) (xy 183.176183 -313.69817) (xy 183.218804 -313.673563)
			(xy 183.26482 -313.656111) (xy 183.313039 -313.646267) (xy 183.362214 -313.644286) (xy 183.411069 -313.650218)
			(xy 183.45834 -313.66391) (xy 183.502802 -313.685008) (xy 183.543305 -313.712964) (xy 183.578798 -313.747056)
			(xy 183.608363 -313.7864) (xy 183.631234 -313.829977) (xy 183.646818 -313.876658) (xy 183.654713 -313.925235)
			(xy 183.655208 -313.949842) (xy 184.94427 -313.949842) (xy 184.94823 -313.900788) (xy 184.960007 -313.853004)
			(xy 184.979298 -313.807728) (xy 185.005601 -313.766132) (xy 185.038236 -313.729295) (xy 185.076357 -313.69817)
			(xy 185.118978 -313.673563) (xy 185.164994 -313.656111) (xy 185.213213 -313.646267) (xy 185.262388 -313.644286)
			(xy 185.311243 -313.650218) (xy 185.358514 -313.66391) (xy 185.402976 -313.685008) (xy 185.443479 -313.712964)
			(xy 185.478972 -313.747056) (xy 185.508537 -313.7864) (xy 185.531408 -313.829977) (xy 185.546992 -313.876658)
			(xy 185.554887 -313.925235) (xy 185.555382 -313.949842) (xy 186.84419 -313.949842) (xy 186.84815 -313.900788)
			(xy 186.859927 -313.853004) (xy 186.879218 -313.807728) (xy 186.905521 -313.766132) (xy 186.938156 -313.729295)
			(xy 186.976277 -313.69817) (xy 187.018898 -313.673563) (xy 187.064914 -313.656111) (xy 187.113133 -313.646267)
			(xy 187.162308 -313.644286) (xy 187.211163 -313.650218) (xy 187.258434 -313.66391) (xy 187.302896 -313.685008)
			(xy 187.343399 -313.712964) (xy 187.378892 -313.747056) (xy 187.408457 -313.7864) (xy 187.431328 -313.829977)
			(xy 187.446912 -313.876658) (xy 187.454807 -313.925235) (xy 187.455302 -313.949842) (xy 188.74411 -313.949842)
			(xy 188.74807 -313.900788) (xy 188.759847 -313.853004) (xy 188.779138 -313.807728) (xy 188.805441 -313.766132)
			(xy 188.838076 -313.729295) (xy 188.876197 -313.69817) (xy 188.918818 -313.673563) (xy 188.964834 -313.656111)
			(xy 189.013053 -313.646267) (xy 189.062228 -313.644286) (xy 189.111083 -313.650218) (xy 189.158354 -313.66391)
			(xy 189.202816 -313.685008) (xy 189.243319 -313.712964) (xy 189.278812 -313.747056) (xy 189.308377 -313.7864)
			(xy 189.331248 -313.829977) (xy 189.346832 -313.876658) (xy 189.354727 -313.925235) (xy 189.355222 -313.949842)
			(xy 190.644284 -313.949842) (xy 190.648244 -313.900788) (xy 190.660021 -313.853004) (xy 190.679312 -313.807728)
			(xy 190.705615 -313.766132) (xy 190.73825 -313.729295) (xy 190.776371 -313.69817) (xy 190.818992 -313.673563)
			(xy 190.865008 -313.656111) (xy 190.913227 -313.646267) (xy 190.962402 -313.644286) (xy 191.011257 -313.650218)
			(xy 191.058528 -313.66391) (xy 191.10299 -313.685008) (xy 191.143493 -313.712964) (xy 191.178986 -313.747056)
			(xy 191.208551 -313.7864) (xy 191.231422 -313.829977) (xy 191.247006 -313.876658) (xy 191.254901 -313.925235)
			(xy 191.255396 -313.949842) (xy 192.544204 -313.949842) (xy 192.548164 -313.900788) (xy 192.559941 -313.853004)
			(xy 192.579232 -313.807728) (xy 192.605535 -313.766132) (xy 192.63817 -313.729295) (xy 192.676291 -313.69817)
			(xy 192.718912 -313.673563) (xy 192.764928 -313.656111) (xy 192.813147 -313.646267) (xy 192.862322 -313.644286)
			(xy 192.911177 -313.650218) (xy 192.958448 -313.66391) (xy 193.00291 -313.685008) (xy 193.043413 -313.712964)
			(xy 193.078906 -313.747056) (xy 193.108471 -313.7864) (xy 193.131342 -313.829977) (xy 193.146926 -313.876658)
			(xy 193.154821 -313.925235) (xy 193.155316 -313.949842) (xy 194.444124 -313.949842) (xy 194.448084 -313.900788)
			(xy 194.459861 -313.853004) (xy 194.479152 -313.807728) (xy 194.505455 -313.766132) (xy 194.53809 -313.729295)
			(xy 194.576211 -313.69817) (xy 194.618832 -313.673563) (xy 194.664848 -313.656111) (xy 194.713067 -313.646267)
			(xy 194.762242 -313.644286) (xy 194.811097 -313.650218) (xy 194.858368 -313.66391) (xy 194.90283 -313.685008)
			(xy 194.943333 -313.712964) (xy 194.978826 -313.747056) (xy 195.008391 -313.7864) (xy 195.031262 -313.829977)
			(xy 195.046846 -313.876658) (xy 195.054741 -313.925235) (xy 195.055236 -313.949842) (xy 196.344044 -313.949842)
			(xy 196.348004 -313.900788) (xy 196.359781 -313.853004) (xy 196.379072 -313.807728) (xy 196.405375 -313.766132)
			(xy 196.43801 -313.729295) (xy 196.476131 -313.69817) (xy 196.518752 -313.673563) (xy 196.564768 -313.656111)
			(xy 196.612987 -313.646267) (xy 196.662162 -313.644286) (xy 196.711017 -313.650218) (xy 196.758288 -313.66391)
			(xy 196.80275 -313.685008) (xy 196.843253 -313.712964) (xy 196.878746 -313.747056) (xy 196.908311 -313.7864)
			(xy 196.931182 -313.829977) (xy 196.946766 -313.876658) (xy 196.954661 -313.925235) (xy 196.955156 -313.949842)
			(xy 270.644124 -313.949842) (xy 270.648084 -313.900788) (xy 270.659861 -313.853004) (xy 270.679152 -313.807728)
			(xy 270.705455 -313.766132) (xy 270.73809 -313.729295) (xy 270.776211 -313.69817) (xy 270.818832 -313.673563)
			(xy 270.864848 -313.656111) (xy 270.913067 -313.646267) (xy 270.962242 -313.644286) (xy 271.011097 -313.650218)
			(xy 271.058368 -313.66391) (xy 271.10283 -313.685008) (xy 271.143333 -313.712964) (xy 271.178826 -313.747056)
			(xy 271.208391 -313.7864) (xy 271.231262 -313.829977) (xy 271.246846 -313.876658) (xy 271.254741 -313.925235)
			(xy 271.255236 -313.949842) (xy 272.544044 -313.949842) (xy 272.548004 -313.900788) (xy 272.559781 -313.853004)
			(xy 272.579072 -313.807728) (xy 272.605375 -313.766132) (xy 272.63801 -313.729295) (xy 272.676131 -313.69817)
			(xy 272.718752 -313.673563) (xy 272.764768 -313.656111) (xy 272.812987 -313.646267) (xy 272.862162 -313.644286)
			(xy 272.911017 -313.650218) (xy 272.958288 -313.66391) (xy 273.00275 -313.685008) (xy 273.043253 -313.712964)
			(xy 273.078746 -313.747056) (xy 273.108311 -313.7864) (xy 273.131182 -313.829977) (xy 273.146766 -313.876658)
			(xy 273.154661 -313.925235) (xy 273.155156 -313.949842) (xy 274.443964 -313.949842) (xy 274.447924 -313.900788)
			(xy 274.459701 -313.853004) (xy 274.478992 -313.807728) (xy 274.505295 -313.766132) (xy 274.53793 -313.729295)
			(xy 274.576051 -313.69817) (xy 274.618672 -313.673563) (xy 274.664688 -313.656111) (xy 274.712907 -313.646267)
			(xy 274.762082 -313.644286) (xy 274.810937 -313.650218) (xy 274.858208 -313.66391) (xy 274.90267 -313.685008)
			(xy 274.943173 -313.712964) (xy 274.978666 -313.747056) (xy 275.008231 -313.7864) (xy 275.031102 -313.829977)
			(xy 275.046686 -313.876658) (xy 275.054581 -313.925235) (xy 275.055076 -313.949842) (xy 276.343884 -313.949842)
			(xy 276.347844 -313.900788) (xy 276.359621 -313.853004) (xy 276.378912 -313.807728) (xy 276.405215 -313.766132)
			(xy 276.43785 -313.729295) (xy 276.475971 -313.69817) (xy 276.518592 -313.673563) (xy 276.564608 -313.656111)
			(xy 276.612827 -313.646267) (xy 276.662002 -313.644286) (xy 276.710857 -313.650218) (xy 276.758128 -313.66391)
			(xy 276.80259 -313.685008) (xy 276.843093 -313.712964) (xy 276.878586 -313.747056) (xy 276.908151 -313.7864)
			(xy 276.931022 -313.829977) (xy 276.946606 -313.876658) (xy 276.954501 -313.925235) (xy 276.954996 -313.949842)
			(xy 278.244058 -313.949842) (xy 278.248018 -313.900788) (xy 278.259795 -313.853004) (xy 278.279086 -313.807728)
			(xy 278.305389 -313.766132) (xy 278.338024 -313.729295) (xy 278.376145 -313.69817) (xy 278.418766 -313.673563)
			(xy 278.464782 -313.656111) (xy 278.513001 -313.646267) (xy 278.562176 -313.644286) (xy 278.611031 -313.650218)
			(xy 278.658302 -313.66391) (xy 278.702764 -313.685008) (xy 278.743267 -313.712964) (xy 278.77876 -313.747056)
			(xy 278.808325 -313.7864) (xy 278.831196 -313.829977) (xy 278.84678 -313.876658) (xy 278.854675 -313.925235)
			(xy 278.85517 -313.949842) (xy 280.143978 -313.949842) (xy 280.147938 -313.900788) (xy 280.159715 -313.853004)
			(xy 280.179006 -313.807728) (xy 280.205309 -313.766132) (xy 280.237944 -313.729295) (xy 280.276065 -313.69817)
			(xy 280.318686 -313.673563) (xy 280.364702 -313.656111) (xy 280.412921 -313.646267) (xy 280.462096 -313.644286)
			(xy 280.510951 -313.650218) (xy 280.558222 -313.66391) (xy 280.602684 -313.685008) (xy 280.643187 -313.712964)
			(xy 280.67868 -313.747056) (xy 280.708245 -313.7864) (xy 280.731116 -313.829977) (xy 280.7467 -313.876658)
			(xy 280.754595 -313.925235) (xy 280.75509 -313.949842) (xy 282.043898 -313.949842) (xy 282.047858 -313.900788)
			(xy 282.059635 -313.853004) (xy 282.078926 -313.807728) (xy 282.105229 -313.766132) (xy 282.137864 -313.729295)
			(xy 282.175985 -313.69817) (xy 282.218606 -313.673563) (xy 282.264622 -313.656111) (xy 282.312841 -313.646267)
			(xy 282.362016 -313.644286) (xy 282.410871 -313.650218) (xy 282.458142 -313.66391) (xy 282.502604 -313.685008)
			(xy 282.543107 -313.712964) (xy 282.5786 -313.747056) (xy 282.608165 -313.7864) (xy 282.631036 -313.829977)
			(xy 282.64662 -313.876658) (xy 282.654515 -313.925235) (xy 282.65501 -313.949842) (xy 283.944072 -313.949842)
			(xy 283.948032 -313.900788) (xy 283.959809 -313.853004) (xy 283.9791 -313.807728) (xy 284.005403 -313.766132)
			(xy 284.038038 -313.729295) (xy 284.076159 -313.69817) (xy 284.11878 -313.673563) (xy 284.164796 -313.656111)
			(xy 284.213015 -313.646267) (xy 284.26219 -313.644286) (xy 284.311045 -313.650218) (xy 284.358316 -313.66391)
			(xy 284.402778 -313.685008) (xy 284.443281 -313.712964) (xy 284.478774 -313.747056) (xy 284.508339 -313.7864)
			(xy 284.53121 -313.829977) (xy 284.546794 -313.876658) (xy 284.554689 -313.925235) (xy 284.555184 -313.949842)
			(xy 285.843992 -313.949842) (xy 285.847952 -313.900788) (xy 285.859729 -313.853004) (xy 285.87902 -313.807728)
			(xy 285.905323 -313.766132) (xy 285.937958 -313.729295) (xy 285.976079 -313.69817) (xy 286.0187 -313.673563)
			(xy 286.064716 -313.656111) (xy 286.112935 -313.646267) (xy 286.16211 -313.644286) (xy 286.210965 -313.650218)
			(xy 286.258236 -313.66391) (xy 286.302698 -313.685008) (xy 286.343201 -313.712964) (xy 286.378694 -313.747056)
			(xy 286.408259 -313.7864) (xy 286.43113 -313.829977) (xy 286.446714 -313.876658) (xy 286.454609 -313.925235)
			(xy 286.455104 -313.949842) (xy 287.743912 -313.949842) (xy 287.747872 -313.900788) (xy 287.759649 -313.853004)
			(xy 287.77894 -313.807728) (xy 287.805243 -313.766132) (xy 287.837878 -313.729295) (xy 287.875999 -313.69817)
			(xy 287.91862 -313.673563) (xy 287.964636 -313.656111) (xy 288.012855 -313.646267) (xy 288.06203 -313.644286)
			(xy 288.110885 -313.650218) (xy 288.158156 -313.66391) (xy 288.202618 -313.685008) (xy 288.243121 -313.712964)
			(xy 288.278614 -313.747056) (xy 288.308179 -313.7864) (xy 288.33105 -313.829977) (xy 288.346634 -313.876658)
			(xy 288.354529 -313.925235) (xy 288.355024 -313.949842) (xy 289.644086 -313.949842) (xy 289.648046 -313.900788)
			(xy 289.659823 -313.853004) (xy 289.679114 -313.807728) (xy 289.705417 -313.766132) (xy 289.738052 -313.729295)
			(xy 289.776173 -313.69817) (xy 289.818794 -313.673563) (xy 289.86481 -313.656111) (xy 289.913029 -313.646267)
			(xy 289.962204 -313.644286) (xy 290.011059 -313.650218) (xy 290.05833 -313.66391) (xy 290.102792 -313.685008)
			(xy 290.143295 -313.712964) (xy 290.178788 -313.747056) (xy 290.208353 -313.7864) (xy 290.231224 -313.829977)
			(xy 290.246808 -313.876658) (xy 290.254703 -313.925235) (xy 290.255198 -313.949842) (xy 291.544006 -313.949842)
			(xy 291.547966 -313.900788) (xy 291.559743 -313.853004) (xy 291.579034 -313.807728) (xy 291.605337 -313.766132)
			(xy 291.637972 -313.729295) (xy 291.676093 -313.69817) (xy 291.718714 -313.673563) (xy 291.76473 -313.656111)
			(xy 291.812949 -313.646267) (xy 291.862124 -313.644286) (xy 291.910979 -313.650218) (xy 291.95825 -313.66391)
			(xy 292.002712 -313.685008) (xy 292.043215 -313.712964) (xy 292.078708 -313.747056) (xy 292.108273 -313.7864)
			(xy 292.131144 -313.829977) (xy 292.146728 -313.876658) (xy 292.154623 -313.925235) (xy 292.155118 -313.949842)
			(xy 293.443926 -313.949842) (xy 293.447886 -313.900788) (xy 293.459663 -313.853004) (xy 293.478954 -313.807728)
			(xy 293.505257 -313.766132) (xy 293.537892 -313.729295) (xy 293.576013 -313.69817) (xy 293.618634 -313.673563)
			(xy 293.66465 -313.656111) (xy 293.712869 -313.646267) (xy 293.762044 -313.644286) (xy 293.810899 -313.650218)
			(xy 293.85817 -313.66391) (xy 293.902632 -313.685008) (xy 293.943135 -313.712964) (xy 293.978628 -313.747056)
			(xy 294.008193 -313.7864) (xy 294.031064 -313.829977) (xy 294.046648 -313.876658) (xy 294.054543 -313.925235)
			(xy 294.055038 -313.949842) (xy 295.3441 -313.949842) (xy 295.34806 -313.900788) (xy 295.359837 -313.853004)
			(xy 295.379128 -313.807728) (xy 295.405431 -313.766132) (xy 295.438066 -313.729295) (xy 295.476187 -313.69817)
			(xy 295.518808 -313.673563) (xy 295.564824 -313.656111) (xy 295.613043 -313.646267) (xy 295.662218 -313.644286)
			(xy 295.711073 -313.650218) (xy 295.758344 -313.66391) (xy 295.802806 -313.685008) (xy 295.843309 -313.712964)
			(xy 295.878802 -313.747056) (xy 295.908367 -313.7864) (xy 295.931238 -313.829977) (xy 295.946822 -313.876658)
			(xy 295.954717 -313.925235) (xy 295.955212 -313.949842) (xy 297.24402 -313.949842) (xy 297.24798 -313.900788)
			(xy 297.259757 -313.853004) (xy 297.279048 -313.807728) (xy 297.305351 -313.766132) (xy 297.337986 -313.729295)
			(xy 297.376107 -313.69817) (xy 297.418728 -313.673563) (xy 297.464744 -313.656111) (xy 297.512963 -313.646267)
			(xy 297.562138 -313.644286) (xy 297.610993 -313.650218) (xy 297.658264 -313.66391) (xy 297.702726 -313.685008)
			(xy 297.743229 -313.712964) (xy 297.778722 -313.747056) (xy 297.808287 -313.7864) (xy 297.831158 -313.829977)
			(xy 297.846742 -313.876658) (xy 297.854637 -313.925235) (xy 297.855132 -313.949842) (xy 299.14394 -313.949842)
			(xy 299.1479 -313.900788) (xy 299.159677 -313.853004) (xy 299.178968 -313.807728) (xy 299.205271 -313.766132)
			(xy 299.237906 -313.729295) (xy 299.276027 -313.69817) (xy 299.318648 -313.673563) (xy 299.364664 -313.656111)
			(xy 299.412883 -313.646267) (xy 299.462058 -313.644286) (xy 299.510913 -313.650218) (xy 299.558184 -313.66391)
			(xy 299.602646 -313.685008) (xy 299.643149 -313.712964) (xy 299.678642 -313.747056) (xy 299.708207 -313.7864)
			(xy 299.731078 -313.829977) (xy 299.746662 -313.876658) (xy 299.754557 -313.925235) (xy 299.755052 -313.949842)
			(xy 301.044114 -313.949842) (xy 301.048074 -313.900788) (xy 301.059851 -313.853004) (xy 301.079142 -313.807728)
			(xy 301.105445 -313.766132) (xy 301.13808 -313.729295) (xy 301.176201 -313.69817) (xy 301.218822 -313.673563)
			(xy 301.264838 -313.656111) (xy 301.313057 -313.646267) (xy 301.362232 -313.644286) (xy 301.411087 -313.650218)
			(xy 301.458358 -313.66391) (xy 301.50282 -313.685008) (xy 301.543323 -313.712964) (xy 301.578816 -313.747056)
			(xy 301.608381 -313.7864) (xy 301.631252 -313.829977) (xy 301.646836 -313.876658) (xy 301.654731 -313.925235)
			(xy 301.655226 -313.949842) (xy 302.944034 -313.949842) (xy 302.947994 -313.900788) (xy 302.959771 -313.853004)
			(xy 302.979062 -313.807728) (xy 303.005365 -313.766132) (xy 303.038 -313.729295) (xy 303.076121 -313.69817)
			(xy 303.118742 -313.673563) (xy 303.164758 -313.656111) (xy 303.212977 -313.646267) (xy 303.262152 -313.644286)
			(xy 303.311007 -313.650218) (xy 303.358278 -313.66391) (xy 303.40274 -313.685008) (xy 303.443243 -313.712964)
			(xy 303.478736 -313.747056) (xy 303.508301 -313.7864) (xy 303.531172 -313.829977) (xy 303.546756 -313.876658)
			(xy 303.554651 -313.925235) (xy 303.555146 -313.949842) (xy 304.843954 -313.949842) (xy 304.847914 -313.900788)
			(xy 304.859691 -313.853004) (xy 304.878982 -313.807728) (xy 304.905285 -313.766132) (xy 304.93792 -313.729295)
			(xy 304.976041 -313.69817) (xy 305.018662 -313.673563) (xy 305.064678 -313.656111) (xy 305.112897 -313.646267)
			(xy 305.162072 -313.644286) (xy 305.210927 -313.650218) (xy 305.258198 -313.66391) (xy 305.30266 -313.685008)
			(xy 305.343163 -313.712964) (xy 305.378656 -313.747056) (xy 305.408221 -313.7864) (xy 305.431092 -313.829977)
			(xy 305.446676 -313.876658) (xy 305.454571 -313.925235) (xy 305.455066 -313.949842) (xy 306.744128 -313.949842)
			(xy 306.748088 -313.900788) (xy 306.759865 -313.853004) (xy 306.779156 -313.807728) (xy 306.805459 -313.766132)
			(xy 306.838094 -313.729295) (xy 306.876215 -313.69817) (xy 306.918836 -313.673563) (xy 306.964852 -313.656111)
			(xy 307.013071 -313.646267) (xy 307.062246 -313.644286) (xy 307.111101 -313.650218) (xy 307.158372 -313.66391)
			(xy 307.202834 -313.685008) (xy 307.243337 -313.712964) (xy 307.27883 -313.747056) (xy 307.308395 -313.7864)
			(xy 307.331266 -313.829977) (xy 307.34685 -313.876658) (xy 307.354745 -313.925235) (xy 307.35524 -313.949842)
			(xy 308.644048 -313.949842) (xy 308.648008 -313.900788) (xy 308.659785 -313.853004) (xy 308.679076 -313.807728)
			(xy 308.705379 -313.766132) (xy 308.738014 -313.729295) (xy 308.776135 -313.69817) (xy 308.818756 -313.673563)
			(xy 308.864772 -313.656111) (xy 308.912991 -313.646267) (xy 308.962166 -313.644286) (xy 309.011021 -313.650218)
			(xy 309.058292 -313.66391) (xy 309.102754 -313.685008) (xy 309.143257 -313.712964) (xy 309.17875 -313.747056)
			(xy 309.208315 -313.7864) (xy 309.231186 -313.829977) (xy 309.24677 -313.876658) (xy 309.254665 -313.925235)
			(xy 309.25516 -313.949842) (xy 310.543968 -313.949842) (xy 310.547928 -313.900788) (xy 310.559705 -313.853004)
			(xy 310.578996 -313.807728) (xy 310.605299 -313.766132) (xy 310.637934 -313.729295) (xy 310.676055 -313.69817)
			(xy 310.718676 -313.673563) (xy 310.764692 -313.656111) (xy 310.812911 -313.646267) (xy 310.862086 -313.644286)
			(xy 310.910941 -313.650218) (xy 310.958212 -313.66391) (xy 311.002674 -313.685008) (xy 311.043177 -313.712964)
			(xy 311.07867 -313.747056) (xy 311.108235 -313.7864) (xy 311.131106 -313.829977) (xy 311.14669 -313.876658)
			(xy 311.154585 -313.925235) (xy 311.15508 -313.949842) (xy 312.443888 -313.949842) (xy 312.447848 -313.900788)
			(xy 312.459625 -313.853004) (xy 312.478916 -313.807728) (xy 312.505219 -313.766132) (xy 312.537854 -313.729295)
			(xy 312.575975 -313.69817) (xy 312.618596 -313.673563) (xy 312.664612 -313.656111) (xy 312.712831 -313.646267)
			(xy 312.762006 -313.644286) (xy 312.810861 -313.650218) (xy 312.858132 -313.66391) (xy 312.902594 -313.685008)
			(xy 312.943097 -313.712964) (xy 312.97859 -313.747056) (xy 313.008155 -313.7864) (xy 313.031026 -313.829977)
			(xy 313.04661 -313.876658) (xy 313.054505 -313.925235) (xy 313.055 -313.949842) (xy 386.744222 -313.949842)
			(xy 386.748182 -313.900788) (xy 386.759959 -313.853004) (xy 386.77925 -313.807728) (xy 386.805553 -313.766132)
			(xy 386.838188 -313.729295) (xy 386.876309 -313.69817) (xy 386.91893 -313.673563) (xy 386.964946 -313.656111)
			(xy 387.013165 -313.646267) (xy 387.06234 -313.644286) (xy 387.111195 -313.650218) (xy 387.158466 -313.66391)
			(xy 387.202928 -313.685008) (xy 387.243431 -313.712964) (xy 387.278924 -313.747056) (xy 387.308489 -313.7864)
			(xy 387.33136 -313.829977) (xy 387.346944 -313.876658) (xy 387.354839 -313.925235) (xy 387.355334 -313.949842)
			(xy 388.644142 -313.949842) (xy 388.648102 -313.900788) (xy 388.659879 -313.853004) (xy 388.67917 -313.807728)
			(xy 388.705473 -313.766132) (xy 388.738108 -313.729295) (xy 388.776229 -313.69817) (xy 388.81885 -313.673563)
			(xy 388.864866 -313.656111) (xy 388.913085 -313.646267) (xy 388.96226 -313.644286) (xy 389.011115 -313.650218)
			(xy 389.058386 -313.66391) (xy 389.102848 -313.685008) (xy 389.143351 -313.712964) (xy 389.178844 -313.747056)
			(xy 389.208409 -313.7864) (xy 389.23128 -313.829977) (xy 389.246864 -313.876658) (xy 389.254759 -313.925235)
			(xy 389.255254 -313.949842) (xy 390.544062 -313.949842) (xy 390.548022 -313.900788) (xy 390.559799 -313.853004)
			(xy 390.57909 -313.807728) (xy 390.605393 -313.766132) (xy 390.638028 -313.729295) (xy 390.676149 -313.69817)
			(xy 390.71877 -313.673563) (xy 390.764786 -313.656111) (xy 390.813005 -313.646267) (xy 390.86218 -313.644286)
			(xy 390.911035 -313.650218) (xy 390.958306 -313.66391) (xy 391.002768 -313.685008) (xy 391.043271 -313.712964)
			(xy 391.078764 -313.747056) (xy 391.108329 -313.7864) (xy 391.1312 -313.829977) (xy 391.146784 -313.876658)
			(xy 391.154679 -313.925235) (xy 391.155174 -313.949842) (xy 392.443982 -313.949842) (xy 392.447942 -313.900788)
			(xy 392.459719 -313.853004) (xy 392.47901 -313.807728) (xy 392.505313 -313.766132) (xy 392.537948 -313.729295)
			(xy 392.576069 -313.69817) (xy 392.61869 -313.673563) (xy 392.664706 -313.656111) (xy 392.712925 -313.646267)
			(xy 392.7621 -313.644286) (xy 392.810955 -313.650218) (xy 392.858226 -313.66391) (xy 392.902688 -313.685008)
			(xy 392.943191 -313.712964) (xy 392.978684 -313.747056) (xy 393.008249 -313.7864) (xy 393.03112 -313.829977)
			(xy 393.046704 -313.876658) (xy 393.054599 -313.925235) (xy 393.055094 -313.949842) (xy 394.344156 -313.949842)
			(xy 394.348116 -313.900788) (xy 394.359893 -313.853004) (xy 394.379184 -313.807728) (xy 394.405487 -313.766132)
			(xy 394.438122 -313.729295) (xy 394.476243 -313.69817) (xy 394.518864 -313.673563) (xy 394.56488 -313.656111)
			(xy 394.613099 -313.646267) (xy 394.662274 -313.644286) (xy 394.711129 -313.650218) (xy 394.7584 -313.66391)
			(xy 394.802862 -313.685008) (xy 394.843365 -313.712964) (xy 394.878858 -313.747056) (xy 394.908423 -313.7864)
			(xy 394.931294 -313.829977) (xy 394.946878 -313.876658) (xy 394.954773 -313.925235) (xy 394.955268 -313.949842)
			(xy 396.244076 -313.949842) (xy 396.248036 -313.900788) (xy 396.259813 -313.853004) (xy 396.279104 -313.807728)
			(xy 396.305407 -313.766132) (xy 396.338042 -313.729295) (xy 396.376163 -313.69817) (xy 396.418784 -313.673563)
			(xy 396.4648 -313.656111) (xy 396.513019 -313.646267) (xy 396.562194 -313.644286) (xy 396.611049 -313.650218)
			(xy 396.65832 -313.66391) (xy 396.702782 -313.685008) (xy 396.743285 -313.712964) (xy 396.778778 -313.747056)
			(xy 396.808343 -313.7864) (xy 396.831214 -313.829977) (xy 396.846798 -313.876658) (xy 396.854693 -313.925235)
			(xy 396.855188 -313.949842) (xy 398.143996 -313.949842) (xy 398.147956 -313.900788) (xy 398.159733 -313.853004)
			(xy 398.179024 -313.807728) (xy 398.205327 -313.766132) (xy 398.237962 -313.729295) (xy 398.276083 -313.69817)
			(xy 398.318704 -313.673563) (xy 398.36472 -313.656111) (xy 398.412939 -313.646267) (xy 398.462114 -313.644286)
			(xy 398.510969 -313.650218) (xy 398.55824 -313.66391) (xy 398.602702 -313.685008) (xy 398.643205 -313.712964)
			(xy 398.678698 -313.747056) (xy 398.708263 -313.7864) (xy 398.731134 -313.829977) (xy 398.746718 -313.876658)
			(xy 398.754613 -313.925235) (xy 398.755108 -313.949842) (xy 400.04417 -313.949842) (xy 400.04813 -313.900788)
			(xy 400.059907 -313.853004) (xy 400.079198 -313.807728) (xy 400.105501 -313.766132) (xy 400.138136 -313.729295)
			(xy 400.176257 -313.69817) (xy 400.218878 -313.673563) (xy 400.264894 -313.656111) (xy 400.313113 -313.646267)
			(xy 400.362288 -313.644286) (xy 400.411143 -313.650218) (xy 400.458414 -313.66391) (xy 400.502876 -313.685008)
			(xy 400.543379 -313.712964) (xy 400.578872 -313.747056) (xy 400.608437 -313.7864) (xy 400.631308 -313.829977)
			(xy 400.646892 -313.876658) (xy 400.654787 -313.925235) (xy 400.655282 -313.949842) (xy 401.94409 -313.949842)
			(xy 401.94805 -313.900788) (xy 401.959827 -313.853004) (xy 401.979118 -313.807728) (xy 402.005421 -313.766132)
			(xy 402.038056 -313.729295) (xy 402.076177 -313.69817) (xy 402.118798 -313.673563) (xy 402.164814 -313.656111)
			(xy 402.213033 -313.646267) (xy 402.262208 -313.644286) (xy 402.311063 -313.650218) (xy 402.358334 -313.66391)
			(xy 402.402796 -313.685008) (xy 402.443299 -313.712964) (xy 402.478792 -313.747056) (xy 402.508357 -313.7864)
			(xy 402.531228 -313.829977) (xy 402.546812 -313.876658) (xy 402.554707 -313.925235) (xy 402.555202 -313.949842)
			(xy 403.84401 -313.949842) (xy 403.84797 -313.900788) (xy 403.859747 -313.853004) (xy 403.879038 -313.807728)
			(xy 403.905341 -313.766132) (xy 403.937976 -313.729295) (xy 403.976097 -313.69817) (xy 404.018718 -313.673563)
			(xy 404.064734 -313.656111) (xy 404.112953 -313.646267) (xy 404.162128 -313.644286) (xy 404.210983 -313.650218)
			(xy 404.258254 -313.66391) (xy 404.302716 -313.685008) (xy 404.343219 -313.712964) (xy 404.378712 -313.747056)
			(xy 404.408277 -313.7864) (xy 404.431148 -313.829977) (xy 404.446732 -313.876658) (xy 404.454627 -313.925235)
			(xy 404.455122 -313.949842) (xy 405.744184 -313.949842) (xy 405.748144 -313.900788) (xy 405.759921 -313.853004)
			(xy 405.779212 -313.807728) (xy 405.805515 -313.766132) (xy 405.83815 -313.729295) (xy 405.876271 -313.69817)
			(xy 405.918892 -313.673563) (xy 405.964908 -313.656111) (xy 406.013127 -313.646267) (xy 406.062302 -313.644286)
			(xy 406.111157 -313.650218) (xy 406.158428 -313.66391) (xy 406.20289 -313.685008) (xy 406.243393 -313.712964)
			(xy 406.278886 -313.747056) (xy 406.308451 -313.7864) (xy 406.331322 -313.829977) (xy 406.346906 -313.876658)
			(xy 406.354801 -313.925235) (xy 406.355296 -313.949842) (xy 407.644104 -313.949842) (xy 407.648064 -313.900788)
			(xy 407.659841 -313.853004) (xy 407.679132 -313.807728) (xy 407.705435 -313.766132) (xy 407.73807 -313.729295)
			(xy 407.776191 -313.69817) (xy 407.818812 -313.673563) (xy 407.864828 -313.656111) (xy 407.913047 -313.646267)
			(xy 407.962222 -313.644286) (xy 408.011077 -313.650218) (xy 408.058348 -313.66391) (xy 408.10281 -313.685008)
			(xy 408.143313 -313.712964) (xy 408.178806 -313.747056) (xy 408.208371 -313.7864) (xy 408.231242 -313.829977)
			(xy 408.246826 -313.876658) (xy 408.254721 -313.925235) (xy 408.255216 -313.949842) (xy 409.544024 -313.949842)
			(xy 409.547984 -313.900788) (xy 409.559761 -313.853004) (xy 409.579052 -313.807728) (xy 409.605355 -313.766132)
			(xy 409.63799 -313.729295) (xy 409.676111 -313.69817) (xy 409.718732 -313.673563) (xy 409.764748 -313.656111)
			(xy 409.812967 -313.646267) (xy 409.862142 -313.644286) (xy 409.910997 -313.650218) (xy 409.958268 -313.66391)
			(xy 410.00273 -313.685008) (xy 410.043233 -313.712964) (xy 410.078726 -313.747056) (xy 410.108291 -313.7864)
			(xy 410.131162 -313.829977) (xy 410.146746 -313.876658) (xy 410.154641 -313.925235) (xy 410.155136 -313.949842)
			(xy 411.444198 -313.949842) (xy 411.448158 -313.900788) (xy 411.459935 -313.853004) (xy 411.479226 -313.807728)
			(xy 411.505529 -313.766132) (xy 411.538164 -313.729295) (xy 411.576285 -313.69817) (xy 411.618906 -313.673563)
			(xy 411.664922 -313.656111) (xy 411.713141 -313.646267) (xy 411.762316 -313.644286) (xy 411.811171 -313.650218)
			(xy 411.858442 -313.66391) (xy 411.902904 -313.685008) (xy 411.943407 -313.712964) (xy 411.9789 -313.747056)
			(xy 412.008465 -313.7864) (xy 412.031336 -313.829977) (xy 412.04692 -313.876658) (xy 412.054815 -313.925235)
			(xy 412.05531 -313.949842) (xy 413.344118 -313.949842) (xy 413.348078 -313.900788) (xy 413.359855 -313.853004)
			(xy 413.379146 -313.807728) (xy 413.405449 -313.766132) (xy 413.438084 -313.729295) (xy 413.476205 -313.69817)
			(xy 413.518826 -313.673563) (xy 413.564842 -313.656111) (xy 413.613061 -313.646267) (xy 413.662236 -313.644286)
			(xy 413.711091 -313.650218) (xy 413.758362 -313.66391) (xy 413.802824 -313.685008) (xy 413.843327 -313.712964)
			(xy 413.87882 -313.747056) (xy 413.908385 -313.7864) (xy 413.931256 -313.829977) (xy 413.94684 -313.876658)
			(xy 413.954735 -313.925235) (xy 413.95523 -313.949842) (xy 415.244038 -313.949842) (xy 415.247998 -313.900788)
			(xy 415.259775 -313.853004) (xy 415.279066 -313.807728) (xy 415.305369 -313.766132) (xy 415.338004 -313.729295)
			(xy 415.376125 -313.69817) (xy 415.418746 -313.673563) (xy 415.464762 -313.656111) (xy 415.512981 -313.646267)
			(xy 415.562156 -313.644286) (xy 415.611011 -313.650218) (xy 415.658282 -313.66391) (xy 415.702744 -313.685008)
			(xy 415.743247 -313.712964) (xy 415.77874 -313.747056) (xy 415.808305 -313.7864) (xy 415.831176 -313.829977)
			(xy 415.84676 -313.876658) (xy 415.854655 -313.925235) (xy 415.85515 -313.949842) (xy 417.144212 -313.949842)
			(xy 417.148172 -313.900788) (xy 417.159949 -313.853004) (xy 417.17924 -313.807728) (xy 417.205543 -313.766132)
			(xy 417.238178 -313.729295) (xy 417.276299 -313.69817) (xy 417.31892 -313.673563) (xy 417.364936 -313.656111)
			(xy 417.413155 -313.646267) (xy 417.46233 -313.644286) (xy 417.511185 -313.650218) (xy 417.558456 -313.66391)
			(xy 417.602918 -313.685008) (xy 417.643421 -313.712964) (xy 417.678914 -313.747056) (xy 417.708479 -313.7864)
			(xy 417.73135 -313.829977) (xy 417.746934 -313.876658) (xy 417.754829 -313.925235) (xy 417.755324 -313.949842)
			(xy 419.044132 -313.949842) (xy 419.048092 -313.900788) (xy 419.059869 -313.853004) (xy 419.07916 -313.807728)
			(xy 419.105463 -313.766132) (xy 419.138098 -313.729295) (xy 419.176219 -313.69817) (xy 419.21884 -313.673563)
			(xy 419.264856 -313.656111) (xy 419.313075 -313.646267) (xy 419.36225 -313.644286) (xy 419.411105 -313.650218)
			(xy 419.458376 -313.66391) (xy 419.502838 -313.685008) (xy 419.543341 -313.712964) (xy 419.578834 -313.747056)
			(xy 419.608399 -313.7864) (xy 419.63127 -313.829977) (xy 419.646854 -313.876658) (xy 419.654749 -313.925235)
			(xy 419.655244 -313.949842) (xy 420.944052 -313.949842) (xy 420.948012 -313.900788) (xy 420.959789 -313.853004)
			(xy 420.97908 -313.807728) (xy 421.005383 -313.766132) (xy 421.038018 -313.729295) (xy 421.076139 -313.69817)
			(xy 421.11876 -313.673563) (xy 421.164776 -313.656111) (xy 421.212995 -313.646267) (xy 421.26217 -313.644286)
			(xy 421.311025 -313.650218) (xy 421.358296 -313.66391) (xy 421.402758 -313.685008) (xy 421.443261 -313.712964)
			(xy 421.478754 -313.747056) (xy 421.508319 -313.7864) (xy 421.53119 -313.829977) (xy 421.546774 -313.876658)
			(xy 421.554669 -313.925235) (xy 421.555164 -313.949842) (xy 422.844226 -313.949842) (xy 422.848186 -313.900788)
			(xy 422.859963 -313.853004) (xy 422.879254 -313.807728) (xy 422.905557 -313.766132) (xy 422.938192 -313.729295)
			(xy 422.976313 -313.69817) (xy 423.018934 -313.673563) (xy 423.06495 -313.656111) (xy 423.113169 -313.646267)
			(xy 423.162344 -313.644286) (xy 423.211199 -313.650218) (xy 423.25847 -313.66391) (xy 423.302932 -313.685008)
			(xy 423.343435 -313.712964) (xy 423.378928 -313.747056) (xy 423.408493 -313.7864) (xy 423.431364 -313.829977)
			(xy 423.446948 -313.876658) (xy 423.454843 -313.925235) (xy 423.455338 -313.949842) (xy 424.744146 -313.949842)
			(xy 424.748106 -313.900788) (xy 424.759883 -313.853004) (xy 424.779174 -313.807728) (xy 424.805477 -313.766132)
			(xy 424.838112 -313.729295) (xy 424.876233 -313.69817) (xy 424.918854 -313.673563) (xy 424.96487 -313.656111)
			(xy 425.013089 -313.646267) (xy 425.062264 -313.644286) (xy 425.111119 -313.650218) (xy 425.15839 -313.66391)
			(xy 425.202852 -313.685008) (xy 425.243355 -313.712964) (xy 425.278848 -313.747056) (xy 425.308413 -313.7864)
			(xy 425.331284 -313.829977) (xy 425.346868 -313.876658) (xy 425.354763 -313.925235) (xy 425.355258 -313.949842)
			(xy 426.644066 -313.949842) (xy 426.648026 -313.900788) (xy 426.659803 -313.853004) (xy 426.679094 -313.807728)
			(xy 426.705397 -313.766132) (xy 426.738032 -313.729295) (xy 426.776153 -313.69817) (xy 426.818774 -313.673563)
			(xy 426.86479 -313.656111) (xy 426.913009 -313.646267) (xy 426.962184 -313.644286) (xy 427.011039 -313.650218)
			(xy 427.05831 -313.66391) (xy 427.102772 -313.685008) (xy 427.143275 -313.712964) (xy 427.178768 -313.747056)
			(xy 427.208333 -313.7864) (xy 427.231204 -313.829977) (xy 427.246788 -313.876658) (xy 427.254683 -313.925235)
			(xy 427.255178 -313.949842) (xy 428.543986 -313.949842) (xy 428.547946 -313.900788) (xy 428.559723 -313.853004)
			(xy 428.579014 -313.807728) (xy 428.605317 -313.766132) (xy 428.637952 -313.729295) (xy 428.676073 -313.69817)
			(xy 428.718694 -313.673563) (xy 428.76471 -313.656111) (xy 428.812929 -313.646267) (xy 428.862104 -313.644286)
			(xy 428.910959 -313.650218) (xy 428.95823 -313.66391) (xy 429.002692 -313.685008) (xy 429.043195 -313.712964)
			(xy 429.078688 -313.747056) (xy 429.108253 -313.7864) (xy 429.131124 -313.829977) (xy 429.146708 -313.876658)
			(xy 429.154603 -313.925235) (xy 429.155098 -313.949842) (xy 429.154603 -313.974449) (xy 429.146708 -314.023026)
			(xy 429.131124 -314.069707) (xy 429.108253 -314.113284) (xy 429.078688 -314.152628) (xy 429.043195 -314.18672)
			(xy 429.002692 -314.214676) (xy 428.95823 -314.235774) (xy 428.910959 -314.249466) (xy 428.862104 -314.255398)
			(xy 428.812929 -314.253417) (xy 428.76471 -314.243573) (xy 428.718694 -314.226121) (xy 428.676073 -314.201514)
			(xy 428.637952 -314.170389) (xy 428.605317 -314.133552) (xy 428.579014 -314.091956) (xy 428.559723 -314.04668)
			(xy 428.547946 -313.998896) (xy 428.543986 -313.949842) (xy 427.255178 -313.949842) (xy 427.254683 -313.974449)
			(xy 427.246788 -314.023026) (xy 427.231204 -314.069707) (xy 427.208333 -314.113284) (xy 427.178768 -314.152628)
			(xy 427.143275 -314.18672) (xy 427.102772 -314.214676) (xy 427.05831 -314.235774) (xy 427.011039 -314.249466)
			(xy 426.962184 -314.255398) (xy 426.913009 -314.253417) (xy 426.86479 -314.243573) (xy 426.818774 -314.226121)
			(xy 426.776153 -314.201514) (xy 426.738032 -314.170389) (xy 426.705397 -314.133552) (xy 426.679094 -314.091956)
			(xy 426.659803 -314.04668) (xy 426.648026 -313.998896) (xy 426.644066 -313.949842) (xy 425.355258 -313.949842)
			(xy 425.354763 -313.974449) (xy 425.346868 -314.023026) (xy 425.331284 -314.069707) (xy 425.308413 -314.113284)
			(xy 425.278848 -314.152628) (xy 425.243355 -314.18672) (xy 425.202852 -314.214676) (xy 425.15839 -314.235774)
			(xy 425.111119 -314.249466) (xy 425.062264 -314.255398) (xy 425.013089 -314.253417) (xy 424.96487 -314.243573)
			(xy 424.918854 -314.226121) (xy 424.876233 -314.201514) (xy 424.838112 -314.170389) (xy 424.805477 -314.133552)
			(xy 424.779174 -314.091956) (xy 424.759883 -314.04668) (xy 424.748106 -313.998896) (xy 424.744146 -313.949842)
			(xy 423.455338 -313.949842) (xy 423.454843 -313.974449) (xy 423.446948 -314.023026) (xy 423.431364 -314.069707)
			(xy 423.408493 -314.113284) (xy 423.378928 -314.152628) (xy 423.343435 -314.18672) (xy 423.302932 -314.214676)
			(xy 423.25847 -314.235774) (xy 423.211199 -314.249466) (xy 423.162344 -314.255398) (xy 423.113169 -314.253417)
			(xy 423.06495 -314.243573) (xy 423.018934 -314.226121) (xy 422.976313 -314.201514) (xy 422.938192 -314.170389)
			(xy 422.905557 -314.133552) (xy 422.879254 -314.091956) (xy 422.859963 -314.04668) (xy 422.848186 -313.998896)
			(xy 422.844226 -313.949842) (xy 421.555164 -313.949842) (xy 421.554669 -313.974449) (xy 421.546774 -314.023026)
			(xy 421.53119 -314.069707) (xy 421.508319 -314.113284) (xy 421.478754 -314.152628) (xy 421.443261 -314.18672)
			(xy 421.402758 -314.214676) (xy 421.358296 -314.235774) (xy 421.311025 -314.249466) (xy 421.26217 -314.255398)
			(xy 421.212995 -314.253417) (xy 421.164776 -314.243573) (xy 421.11876 -314.226121) (xy 421.076139 -314.201514)
			(xy 421.038018 -314.170389) (xy 421.005383 -314.133552) (xy 420.97908 -314.091956) (xy 420.959789 -314.04668)
			(xy 420.948012 -313.998896) (xy 420.944052 -313.949842) (xy 419.655244 -313.949842) (xy 419.654749 -313.974449)
			(xy 419.646854 -314.023026) (xy 419.63127 -314.069707) (xy 419.608399 -314.113284) (xy 419.578834 -314.152628)
			(xy 419.543341 -314.18672) (xy 419.502838 -314.214676) (xy 419.458376 -314.235774) (xy 419.411105 -314.249466)
			(xy 419.36225 -314.255398) (xy 419.313075 -314.253417) (xy 419.264856 -314.243573) (xy 419.21884 -314.226121)
			(xy 419.176219 -314.201514) (xy 419.138098 -314.170389) (xy 419.105463 -314.133552) (xy 419.07916 -314.091956)
			(xy 419.059869 -314.04668) (xy 419.048092 -313.998896) (xy 419.044132 -313.949842) (xy 417.755324 -313.949842)
			(xy 417.754829 -313.974449) (xy 417.746934 -314.023026) (xy 417.73135 -314.069707) (xy 417.708479 -314.113284)
			(xy 417.678914 -314.152628) (xy 417.643421 -314.18672) (xy 417.602918 -314.214676) (xy 417.558456 -314.235774)
			(xy 417.511185 -314.249466) (xy 417.46233 -314.255398) (xy 417.413155 -314.253417) (xy 417.364936 -314.243573)
			(xy 417.31892 -314.226121) (xy 417.276299 -314.201514) (xy 417.238178 -314.170389) (xy 417.205543 -314.133552)
			(xy 417.17924 -314.091956) (xy 417.159949 -314.04668) (xy 417.148172 -313.998896) (xy 417.144212 -313.949842)
			(xy 415.85515 -313.949842) (xy 415.854655 -313.974449) (xy 415.84676 -314.023026) (xy 415.831176 -314.069707)
			(xy 415.808305 -314.113284) (xy 415.77874 -314.152628) (xy 415.743247 -314.18672) (xy 415.702744 -314.214676)
			(xy 415.658282 -314.235774) (xy 415.611011 -314.249466) (xy 415.562156 -314.255398) (xy 415.512981 -314.253417)
			(xy 415.464762 -314.243573) (xy 415.418746 -314.226121) (xy 415.376125 -314.201514) (xy 415.338004 -314.170389)
			(xy 415.305369 -314.133552) (xy 415.279066 -314.091956) (xy 415.259775 -314.04668) (xy 415.247998 -313.998896)
			(xy 415.244038 -313.949842) (xy 413.95523 -313.949842) (xy 413.954735 -313.974449) (xy 413.94684 -314.023026)
			(xy 413.931256 -314.069707) (xy 413.908385 -314.113284) (xy 413.87882 -314.152628) (xy 413.843327 -314.18672)
			(xy 413.802824 -314.214676) (xy 413.758362 -314.235774) (xy 413.711091 -314.249466) (xy 413.662236 -314.255398)
			(xy 413.613061 -314.253417) (xy 413.564842 -314.243573) (xy 413.518826 -314.226121) (xy 413.476205 -314.201514)
			(xy 413.438084 -314.170389) (xy 413.405449 -314.133552) (xy 413.379146 -314.091956) (xy 413.359855 -314.04668)
			(xy 413.348078 -313.998896) (xy 413.344118 -313.949842) (xy 412.05531 -313.949842) (xy 412.054815 -313.974449)
			(xy 412.04692 -314.023026) (xy 412.031336 -314.069707) (xy 412.008465 -314.113284) (xy 411.9789 -314.152628)
			(xy 411.943407 -314.18672) (xy 411.902904 -314.214676) (xy 411.858442 -314.235774) (xy 411.811171 -314.249466)
			(xy 411.762316 -314.255398) (xy 411.713141 -314.253417) (xy 411.664922 -314.243573) (xy 411.618906 -314.226121)
			(xy 411.576285 -314.201514) (xy 411.538164 -314.170389) (xy 411.505529 -314.133552) (xy 411.479226 -314.091956)
			(xy 411.459935 -314.04668) (xy 411.448158 -313.998896) (xy 411.444198 -313.949842) (xy 410.155136 -313.949842)
			(xy 410.154641 -313.974449) (xy 410.146746 -314.023026) (xy 410.131162 -314.069707) (xy 410.108291 -314.113284)
			(xy 410.078726 -314.152628) (xy 410.043233 -314.18672) (xy 410.00273 -314.214676) (xy 409.958268 -314.235774)
			(xy 409.910997 -314.249466) (xy 409.862142 -314.255398) (xy 409.812967 -314.253417) (xy 409.764748 -314.243573)
			(xy 409.718732 -314.226121) (xy 409.676111 -314.201514) (xy 409.63799 -314.170389) (xy 409.605355 -314.133552)
			(xy 409.579052 -314.091956) (xy 409.559761 -314.04668) (xy 409.547984 -313.998896) (xy 409.544024 -313.949842)
			(xy 408.255216 -313.949842) (xy 408.254721 -313.974449) (xy 408.246826 -314.023026) (xy 408.231242 -314.069707)
			(xy 408.208371 -314.113284) (xy 408.178806 -314.152628) (xy 408.143313 -314.18672) (xy 408.10281 -314.214676)
			(xy 408.058348 -314.235774) (xy 408.011077 -314.249466) (xy 407.962222 -314.255398) (xy 407.913047 -314.253417)
			(xy 407.864828 -314.243573) (xy 407.818812 -314.226121) (xy 407.776191 -314.201514) (xy 407.73807 -314.170389)
			(xy 407.705435 -314.133552) (xy 407.679132 -314.091956) (xy 407.659841 -314.04668) (xy 407.648064 -313.998896)
			(xy 407.644104 -313.949842) (xy 406.355296 -313.949842) (xy 406.354801 -313.974449) (xy 406.346906 -314.023026)
			(xy 406.331322 -314.069707) (xy 406.308451 -314.113284) (xy 406.278886 -314.152628) (xy 406.243393 -314.18672)
			(xy 406.20289 -314.214676) (xy 406.158428 -314.235774) (xy 406.111157 -314.249466) (xy 406.062302 -314.255398)
			(xy 406.013127 -314.253417) (xy 405.964908 -314.243573) (xy 405.918892 -314.226121) (xy 405.876271 -314.201514)
			(xy 405.83815 -314.170389) (xy 405.805515 -314.133552) (xy 405.779212 -314.091956) (xy 405.759921 -314.04668)
			(xy 405.748144 -313.998896) (xy 405.744184 -313.949842) (xy 404.455122 -313.949842) (xy 404.454627 -313.974449)
			(xy 404.446732 -314.023026) (xy 404.431148 -314.069707) (xy 404.408277 -314.113284) (xy 404.378712 -314.152628)
			(xy 404.343219 -314.18672) (xy 404.302716 -314.214676) (xy 404.258254 -314.235774) (xy 404.210983 -314.249466)
			(xy 404.162128 -314.255398) (xy 404.112953 -314.253417) (xy 404.064734 -314.243573) (xy 404.018718 -314.226121)
			(xy 403.976097 -314.201514) (xy 403.937976 -314.170389) (xy 403.905341 -314.133552) (xy 403.879038 -314.091956)
			(xy 403.859747 -314.04668) (xy 403.84797 -313.998896) (xy 403.84401 -313.949842) (xy 402.555202 -313.949842)
			(xy 402.554707 -313.974449) (xy 402.546812 -314.023026) (xy 402.531228 -314.069707) (xy 402.508357 -314.113284)
			(xy 402.478792 -314.152628) (xy 402.443299 -314.18672) (xy 402.402796 -314.214676) (xy 402.358334 -314.235774)
			(xy 402.311063 -314.249466) (xy 402.262208 -314.255398) (xy 402.213033 -314.253417) (xy 402.164814 -314.243573)
			(xy 402.118798 -314.226121) (xy 402.076177 -314.201514) (xy 402.038056 -314.170389) (xy 402.005421 -314.133552)
			(xy 401.979118 -314.091956) (xy 401.959827 -314.04668) (xy 401.94805 -313.998896) (xy 401.94409 -313.949842)
			(xy 400.655282 -313.949842) (xy 400.654787 -313.974449) (xy 400.646892 -314.023026) (xy 400.631308 -314.069707)
			(xy 400.608437 -314.113284) (xy 400.578872 -314.152628) (xy 400.543379 -314.18672) (xy 400.502876 -314.214676)
			(xy 400.458414 -314.235774) (xy 400.411143 -314.249466) (xy 400.362288 -314.255398) (xy 400.313113 -314.253417)
			(xy 400.264894 -314.243573) (xy 400.218878 -314.226121) (xy 400.176257 -314.201514) (xy 400.138136 -314.170389)
			(xy 400.105501 -314.133552) (xy 400.079198 -314.091956) (xy 400.059907 -314.04668) (xy 400.04813 -313.998896)
			(xy 400.04417 -313.949842) (xy 398.755108 -313.949842) (xy 398.754613 -313.974449) (xy 398.746718 -314.023026)
			(xy 398.731134 -314.069707) (xy 398.708263 -314.113284) (xy 398.678698 -314.152628) (xy 398.643205 -314.18672)
			(xy 398.602702 -314.214676) (xy 398.55824 -314.235774) (xy 398.510969 -314.249466) (xy 398.462114 -314.255398)
			(xy 398.412939 -314.253417) (xy 398.36472 -314.243573) (xy 398.318704 -314.226121) (xy 398.276083 -314.201514)
			(xy 398.237962 -314.170389) (xy 398.205327 -314.133552) (xy 398.179024 -314.091956) (xy 398.159733 -314.04668)
			(xy 398.147956 -313.998896) (xy 398.143996 -313.949842) (xy 396.855188 -313.949842) (xy 396.854693 -313.974449)
			(xy 396.846798 -314.023026) (xy 396.831214 -314.069707) (xy 396.808343 -314.113284) (xy 396.778778 -314.152628)
			(xy 396.743285 -314.18672) (xy 396.702782 -314.214676) (xy 396.65832 -314.235774) (xy 396.611049 -314.249466)
			(xy 396.562194 -314.255398) (xy 396.513019 -314.253417) (xy 396.4648 -314.243573) (xy 396.418784 -314.226121)
			(xy 396.376163 -314.201514) (xy 396.338042 -314.170389) (xy 396.305407 -314.133552) (xy 396.279104 -314.091956)
			(xy 396.259813 -314.04668) (xy 396.248036 -313.998896) (xy 396.244076 -313.949842) (xy 394.955268 -313.949842)
			(xy 394.954773 -313.974449) (xy 394.946878 -314.023026) (xy 394.931294 -314.069707) (xy 394.908423 -314.113284)
			(xy 394.878858 -314.152628) (xy 394.843365 -314.18672) (xy 394.802862 -314.214676) (xy 394.7584 -314.235774)
			(xy 394.711129 -314.249466) (xy 394.662274 -314.255398) (xy 394.613099 -314.253417) (xy 394.56488 -314.243573)
			(xy 394.518864 -314.226121) (xy 394.476243 -314.201514) (xy 394.438122 -314.170389) (xy 394.405487 -314.133552)
			(xy 394.379184 -314.091956) (xy 394.359893 -314.04668) (xy 394.348116 -313.998896) (xy 394.344156 -313.949842)
			(xy 393.055094 -313.949842) (xy 393.054599 -313.974449) (xy 393.046704 -314.023026) (xy 393.03112 -314.069707)
			(xy 393.008249 -314.113284) (xy 392.978684 -314.152628) (xy 392.943191 -314.18672) (xy 392.902688 -314.214676)
			(xy 392.858226 -314.235774) (xy 392.810955 -314.249466) (xy 392.7621 -314.255398) (xy 392.712925 -314.253417)
			(xy 392.664706 -314.243573) (xy 392.61869 -314.226121) (xy 392.576069 -314.201514) (xy 392.537948 -314.170389)
			(xy 392.505313 -314.133552) (xy 392.47901 -314.091956) (xy 392.459719 -314.04668) (xy 392.447942 -313.998896)
			(xy 392.443982 -313.949842) (xy 391.155174 -313.949842) (xy 391.154679 -313.974449) (xy 391.146784 -314.023026)
			(xy 391.1312 -314.069707) (xy 391.108329 -314.113284) (xy 391.078764 -314.152628) (xy 391.043271 -314.18672)
			(xy 391.002768 -314.214676) (xy 390.958306 -314.235774) (xy 390.911035 -314.249466) (xy 390.86218 -314.255398)
			(xy 390.813005 -314.253417) (xy 390.764786 -314.243573) (xy 390.71877 -314.226121) (xy 390.676149 -314.201514)
			(xy 390.638028 -314.170389) (xy 390.605393 -314.133552) (xy 390.57909 -314.091956) (xy 390.559799 -314.04668)
			(xy 390.548022 -313.998896) (xy 390.544062 -313.949842) (xy 389.255254 -313.949842) (xy 389.254759 -313.974449)
			(xy 389.246864 -314.023026) (xy 389.23128 -314.069707) (xy 389.208409 -314.113284) (xy 389.178844 -314.152628)
			(xy 389.143351 -314.18672) (xy 389.102848 -314.214676) (xy 389.058386 -314.235774) (xy 389.011115 -314.249466)
			(xy 388.96226 -314.255398) (xy 388.913085 -314.253417) (xy 388.864866 -314.243573) (xy 388.81885 -314.226121)
			(xy 388.776229 -314.201514) (xy 388.738108 -314.170389) (xy 388.705473 -314.133552) (xy 388.67917 -314.091956)
			(xy 388.659879 -314.04668) (xy 388.648102 -313.998896) (xy 388.644142 -313.949842) (xy 387.355334 -313.949842)
			(xy 387.354839 -313.974449) (xy 387.346944 -314.023026) (xy 387.33136 -314.069707) (xy 387.308489 -314.113284)
			(xy 387.278924 -314.152628) (xy 387.243431 -314.18672) (xy 387.202928 -314.214676) (xy 387.158466 -314.235774)
			(xy 387.111195 -314.249466) (xy 387.06234 -314.255398) (xy 387.013165 -314.253417) (xy 386.964946 -314.243573)
			(xy 386.91893 -314.226121) (xy 386.876309 -314.201514) (xy 386.838188 -314.170389) (xy 386.805553 -314.133552)
			(xy 386.77925 -314.091956) (xy 386.759959 -314.04668) (xy 386.748182 -313.998896) (xy 386.744222 -313.949842)
			(xy 313.055 -313.949842) (xy 313.054505 -313.974449) (xy 313.04661 -314.023026) (xy 313.031026 -314.069707)
			(xy 313.008155 -314.113284) (xy 312.97859 -314.152628) (xy 312.943097 -314.18672) (xy 312.902594 -314.214676)
			(xy 312.858132 -314.235774) (xy 312.810861 -314.249466) (xy 312.762006 -314.255398) (xy 312.712831 -314.253417)
			(xy 312.664612 -314.243573) (xy 312.618596 -314.226121) (xy 312.575975 -314.201514) (xy 312.537854 -314.170389)
			(xy 312.505219 -314.133552) (xy 312.478916 -314.091956) (xy 312.459625 -314.04668) (xy 312.447848 -313.998896)
			(xy 312.443888 -313.949842) (xy 311.15508 -313.949842) (xy 311.154585 -313.974449) (xy 311.14669 -314.023026)
			(xy 311.131106 -314.069707) (xy 311.108235 -314.113284) (xy 311.07867 -314.152628) (xy 311.043177 -314.18672)
			(xy 311.002674 -314.214676) (xy 310.958212 -314.235774) (xy 310.910941 -314.249466) (xy 310.862086 -314.255398)
			(xy 310.812911 -314.253417) (xy 310.764692 -314.243573) (xy 310.718676 -314.226121) (xy 310.676055 -314.201514)
			(xy 310.637934 -314.170389) (xy 310.605299 -314.133552) (xy 310.578996 -314.091956) (xy 310.559705 -314.04668)
			(xy 310.547928 -313.998896) (xy 310.543968 -313.949842) (xy 309.25516 -313.949842) (xy 309.254665 -313.974449)
			(xy 309.24677 -314.023026) (xy 309.231186 -314.069707) (xy 309.208315 -314.113284) (xy 309.17875 -314.152628)
			(xy 309.143257 -314.18672) (xy 309.102754 -314.214676) (xy 309.058292 -314.235774) (xy 309.011021 -314.249466)
			(xy 308.962166 -314.255398) (xy 308.912991 -314.253417) (xy 308.864772 -314.243573) (xy 308.818756 -314.226121)
			(xy 308.776135 -314.201514) (xy 308.738014 -314.170389) (xy 308.705379 -314.133552) (xy 308.679076 -314.091956)
			(xy 308.659785 -314.04668) (xy 308.648008 -313.998896) (xy 308.644048 -313.949842) (xy 307.35524 -313.949842)
			(xy 307.354745 -313.974449) (xy 307.34685 -314.023026) (xy 307.331266 -314.069707) (xy 307.308395 -314.113284)
			(xy 307.27883 -314.152628) (xy 307.243337 -314.18672) (xy 307.202834 -314.214676) (xy 307.158372 -314.235774)
			(xy 307.111101 -314.249466) (xy 307.062246 -314.255398) (xy 307.013071 -314.253417) (xy 306.964852 -314.243573)
			(xy 306.918836 -314.226121) (xy 306.876215 -314.201514) (xy 306.838094 -314.170389) (xy 306.805459 -314.133552)
			(xy 306.779156 -314.091956) (xy 306.759865 -314.04668) (xy 306.748088 -313.998896) (xy 306.744128 -313.949842)
			(xy 305.455066 -313.949842) (xy 305.454571 -313.974449) (xy 305.446676 -314.023026) (xy 305.431092 -314.069707)
			(xy 305.408221 -314.113284) (xy 305.378656 -314.152628) (xy 305.343163 -314.18672) (xy 305.30266 -314.214676)
			(xy 305.258198 -314.235774) (xy 305.210927 -314.249466) (xy 305.162072 -314.255398) (xy 305.112897 -314.253417)
			(xy 305.064678 -314.243573) (xy 305.018662 -314.226121) (xy 304.976041 -314.201514) (xy 304.93792 -314.170389)
			(xy 304.905285 -314.133552) (xy 304.878982 -314.091956) (xy 304.859691 -314.04668) (xy 304.847914 -313.998896)
			(xy 304.843954 -313.949842) (xy 303.555146 -313.949842) (xy 303.554651 -313.974449) (xy 303.546756 -314.023026)
			(xy 303.531172 -314.069707) (xy 303.508301 -314.113284) (xy 303.478736 -314.152628) (xy 303.443243 -314.18672)
			(xy 303.40274 -314.214676) (xy 303.358278 -314.235774) (xy 303.311007 -314.249466) (xy 303.262152 -314.255398)
			(xy 303.212977 -314.253417) (xy 303.164758 -314.243573) (xy 303.118742 -314.226121) (xy 303.076121 -314.201514)
			(xy 303.038 -314.170389) (xy 303.005365 -314.133552) (xy 302.979062 -314.091956) (xy 302.959771 -314.04668)
			(xy 302.947994 -313.998896) (xy 302.944034 -313.949842) (xy 301.655226 -313.949842) (xy 301.654731 -313.974449)
			(xy 301.646836 -314.023026) (xy 301.631252 -314.069707) (xy 301.608381 -314.113284) (xy 301.578816 -314.152628)
			(xy 301.543323 -314.18672) (xy 301.50282 -314.214676) (xy 301.458358 -314.235774) (xy 301.411087 -314.249466)
			(xy 301.362232 -314.255398) (xy 301.313057 -314.253417) (xy 301.264838 -314.243573) (xy 301.218822 -314.226121)
			(xy 301.176201 -314.201514) (xy 301.13808 -314.170389) (xy 301.105445 -314.133552) (xy 301.079142 -314.091956)
			(xy 301.059851 -314.04668) (xy 301.048074 -313.998896) (xy 301.044114 -313.949842) (xy 299.755052 -313.949842)
			(xy 299.754557 -313.974449) (xy 299.746662 -314.023026) (xy 299.731078 -314.069707) (xy 299.708207 -314.113284)
			(xy 299.678642 -314.152628) (xy 299.643149 -314.18672) (xy 299.602646 -314.214676) (xy 299.558184 -314.235774)
			(xy 299.510913 -314.249466) (xy 299.462058 -314.255398) (xy 299.412883 -314.253417) (xy 299.364664 -314.243573)
			(xy 299.318648 -314.226121) (xy 299.276027 -314.201514) (xy 299.237906 -314.170389) (xy 299.205271 -314.133552)
			(xy 299.178968 -314.091956) (xy 299.159677 -314.04668) (xy 299.1479 -313.998896) (xy 299.14394 -313.949842)
			(xy 297.855132 -313.949842) (xy 297.854637 -313.974449) (xy 297.846742 -314.023026) (xy 297.831158 -314.069707)
			(xy 297.808287 -314.113284) (xy 297.778722 -314.152628) (xy 297.743229 -314.18672) (xy 297.702726 -314.214676)
			(xy 297.658264 -314.235774) (xy 297.610993 -314.249466) (xy 297.562138 -314.255398) (xy 297.512963 -314.253417)
			(xy 297.464744 -314.243573) (xy 297.418728 -314.226121) (xy 297.376107 -314.201514) (xy 297.337986 -314.170389)
			(xy 297.305351 -314.133552) (xy 297.279048 -314.091956) (xy 297.259757 -314.04668) (xy 297.24798 -313.998896)
			(xy 297.24402 -313.949842) (xy 295.955212 -313.949842) (xy 295.954717 -313.974449) (xy 295.946822 -314.023026)
			(xy 295.931238 -314.069707) (xy 295.908367 -314.113284) (xy 295.878802 -314.152628) (xy 295.843309 -314.18672)
			(xy 295.802806 -314.214676) (xy 295.758344 -314.235774) (xy 295.711073 -314.249466) (xy 295.662218 -314.255398)
			(xy 295.613043 -314.253417) (xy 295.564824 -314.243573) (xy 295.518808 -314.226121) (xy 295.476187 -314.201514)
			(xy 295.438066 -314.170389) (xy 295.405431 -314.133552) (xy 295.379128 -314.091956) (xy 295.359837 -314.04668)
			(xy 295.34806 -313.998896) (xy 295.3441 -313.949842) (xy 294.055038 -313.949842) (xy 294.054543 -313.974449)
			(xy 294.046648 -314.023026) (xy 294.031064 -314.069707) (xy 294.008193 -314.113284) (xy 293.978628 -314.152628)
			(xy 293.943135 -314.18672) (xy 293.902632 -314.214676) (xy 293.85817 -314.235774) (xy 293.810899 -314.249466)
			(xy 293.762044 -314.255398) (xy 293.712869 -314.253417) (xy 293.66465 -314.243573) (xy 293.618634 -314.226121)
			(xy 293.576013 -314.201514) (xy 293.537892 -314.170389) (xy 293.505257 -314.133552) (xy 293.478954 -314.091956)
			(xy 293.459663 -314.04668) (xy 293.447886 -313.998896) (xy 293.443926 -313.949842) (xy 292.155118 -313.949842)
			(xy 292.154623 -313.974449) (xy 292.146728 -314.023026) (xy 292.131144 -314.069707) (xy 292.108273 -314.113284)
			(xy 292.078708 -314.152628) (xy 292.043215 -314.18672) (xy 292.002712 -314.214676) (xy 291.95825 -314.235774)
			(xy 291.910979 -314.249466) (xy 291.862124 -314.255398) (xy 291.812949 -314.253417) (xy 291.76473 -314.243573)
			(xy 291.718714 -314.226121) (xy 291.676093 -314.201514) (xy 291.637972 -314.170389) (xy 291.605337 -314.133552)
			(xy 291.579034 -314.091956) (xy 291.559743 -314.04668) (xy 291.547966 -313.998896) (xy 291.544006 -313.949842)
			(xy 290.255198 -313.949842) (xy 290.254703 -313.974449) (xy 290.246808 -314.023026) (xy 290.231224 -314.069707)
			(xy 290.208353 -314.113284) (xy 290.178788 -314.152628) (xy 290.143295 -314.18672) (xy 290.102792 -314.214676)
			(xy 290.05833 -314.235774) (xy 290.011059 -314.249466) (xy 289.962204 -314.255398) (xy 289.913029 -314.253417)
			(xy 289.86481 -314.243573) (xy 289.818794 -314.226121) (xy 289.776173 -314.201514) (xy 289.738052 -314.170389)
			(xy 289.705417 -314.133552) (xy 289.679114 -314.091956) (xy 289.659823 -314.04668) (xy 289.648046 -313.998896)
			(xy 289.644086 -313.949842) (xy 288.355024 -313.949842) (xy 288.354529 -313.974449) (xy 288.346634 -314.023026)
			(xy 288.33105 -314.069707) (xy 288.308179 -314.113284) (xy 288.278614 -314.152628) (xy 288.243121 -314.18672)
			(xy 288.202618 -314.214676) (xy 288.158156 -314.235774) (xy 288.110885 -314.249466) (xy 288.06203 -314.255398)
			(xy 288.012855 -314.253417) (xy 287.964636 -314.243573) (xy 287.91862 -314.226121) (xy 287.875999 -314.201514)
			(xy 287.837878 -314.170389) (xy 287.805243 -314.133552) (xy 287.77894 -314.091956) (xy 287.759649 -314.04668)
			(xy 287.747872 -313.998896) (xy 287.743912 -313.949842) (xy 286.455104 -313.949842) (xy 286.454609 -313.974449)
			(xy 286.446714 -314.023026) (xy 286.43113 -314.069707) (xy 286.408259 -314.113284) (xy 286.378694 -314.152628)
			(xy 286.343201 -314.18672) (xy 286.302698 -314.214676) (xy 286.258236 -314.235774) (xy 286.210965 -314.249466)
			(xy 286.16211 -314.255398) (xy 286.112935 -314.253417) (xy 286.064716 -314.243573) (xy 286.0187 -314.226121)
			(xy 285.976079 -314.201514) (xy 285.937958 -314.170389) (xy 285.905323 -314.133552) (xy 285.87902 -314.091956)
			(xy 285.859729 -314.04668) (xy 285.847952 -313.998896) (xy 285.843992 -313.949842) (xy 284.555184 -313.949842)
			(xy 284.554689 -313.974449) (xy 284.546794 -314.023026) (xy 284.53121 -314.069707) (xy 284.508339 -314.113284)
			(xy 284.478774 -314.152628) (xy 284.443281 -314.18672) (xy 284.402778 -314.214676) (xy 284.358316 -314.235774)
			(xy 284.311045 -314.249466) (xy 284.26219 -314.255398) (xy 284.213015 -314.253417) (xy 284.164796 -314.243573)
			(xy 284.11878 -314.226121) (xy 284.076159 -314.201514) (xy 284.038038 -314.170389) (xy 284.005403 -314.133552)
			(xy 283.9791 -314.091956) (xy 283.959809 -314.04668) (xy 283.948032 -313.998896) (xy 283.944072 -313.949842)
			(xy 282.65501 -313.949842) (xy 282.654515 -313.974449) (xy 282.64662 -314.023026) (xy 282.631036 -314.069707)
			(xy 282.608165 -314.113284) (xy 282.5786 -314.152628) (xy 282.543107 -314.18672) (xy 282.502604 -314.214676)
			(xy 282.458142 -314.235774) (xy 282.410871 -314.249466) (xy 282.362016 -314.255398) (xy 282.312841 -314.253417)
			(xy 282.264622 -314.243573) (xy 282.218606 -314.226121) (xy 282.175985 -314.201514) (xy 282.137864 -314.170389)
			(xy 282.105229 -314.133552) (xy 282.078926 -314.091956) (xy 282.059635 -314.04668) (xy 282.047858 -313.998896)
			(xy 282.043898 -313.949842) (xy 280.75509 -313.949842) (xy 280.754595 -313.974449) (xy 280.7467 -314.023026)
			(xy 280.731116 -314.069707) (xy 280.708245 -314.113284) (xy 280.67868 -314.152628) (xy 280.643187 -314.18672)
			(xy 280.602684 -314.214676) (xy 280.558222 -314.235774) (xy 280.510951 -314.249466) (xy 280.462096 -314.255398)
			(xy 280.412921 -314.253417) (xy 280.364702 -314.243573) (xy 280.318686 -314.226121) (xy 280.276065 -314.201514)
			(xy 280.237944 -314.170389) (xy 280.205309 -314.133552) (xy 280.179006 -314.091956) (xy 280.159715 -314.04668)
			(xy 280.147938 -313.998896) (xy 280.143978 -313.949842) (xy 278.85517 -313.949842) (xy 278.854675 -313.974449)
			(xy 278.84678 -314.023026) (xy 278.831196 -314.069707) (xy 278.808325 -314.113284) (xy 278.77876 -314.152628)
			(xy 278.743267 -314.18672) (xy 278.702764 -314.214676) (xy 278.658302 -314.235774) (xy 278.611031 -314.249466)
			(xy 278.562176 -314.255398) (xy 278.513001 -314.253417) (xy 278.464782 -314.243573) (xy 278.418766 -314.226121)
			(xy 278.376145 -314.201514) (xy 278.338024 -314.170389) (xy 278.305389 -314.133552) (xy 278.279086 -314.091956)
			(xy 278.259795 -314.04668) (xy 278.248018 -313.998896) (xy 278.244058 -313.949842) (xy 276.954996 -313.949842)
			(xy 276.954501 -313.974449) (xy 276.946606 -314.023026) (xy 276.931022 -314.069707) (xy 276.908151 -314.113284)
			(xy 276.878586 -314.152628) (xy 276.843093 -314.18672) (xy 276.80259 -314.214676) (xy 276.758128 -314.235774)
			(xy 276.710857 -314.249466) (xy 276.662002 -314.255398) (xy 276.612827 -314.253417) (xy 276.564608 -314.243573)
			(xy 276.518592 -314.226121) (xy 276.475971 -314.201514) (xy 276.43785 -314.170389) (xy 276.405215 -314.133552)
			(xy 276.378912 -314.091956) (xy 276.359621 -314.04668) (xy 276.347844 -313.998896) (xy 276.343884 -313.949842)
			(xy 275.055076 -313.949842) (xy 275.054581 -313.974449) (xy 275.046686 -314.023026) (xy 275.031102 -314.069707)
			(xy 275.008231 -314.113284) (xy 274.978666 -314.152628) (xy 274.943173 -314.18672) (xy 274.90267 -314.214676)
			(xy 274.858208 -314.235774) (xy 274.810937 -314.249466) (xy 274.762082 -314.255398) (xy 274.712907 -314.253417)
			(xy 274.664688 -314.243573) (xy 274.618672 -314.226121) (xy 274.576051 -314.201514) (xy 274.53793 -314.170389)
			(xy 274.505295 -314.133552) (xy 274.478992 -314.091956) (xy 274.459701 -314.04668) (xy 274.447924 -313.998896)
			(xy 274.443964 -313.949842) (xy 273.155156 -313.949842) (xy 273.154661 -313.974449) (xy 273.146766 -314.023026)
			(xy 273.131182 -314.069707) (xy 273.108311 -314.113284) (xy 273.078746 -314.152628) (xy 273.043253 -314.18672)
			(xy 273.00275 -314.214676) (xy 272.958288 -314.235774) (xy 272.911017 -314.249466) (xy 272.862162 -314.255398)
			(xy 272.812987 -314.253417) (xy 272.764768 -314.243573) (xy 272.718752 -314.226121) (xy 272.676131 -314.201514)
			(xy 272.63801 -314.170389) (xy 272.605375 -314.133552) (xy 272.579072 -314.091956) (xy 272.559781 -314.04668)
			(xy 272.548004 -313.998896) (xy 272.544044 -313.949842) (xy 271.255236 -313.949842) (xy 271.254741 -313.974449)
			(xy 271.246846 -314.023026) (xy 271.231262 -314.069707) (xy 271.208391 -314.113284) (xy 271.178826 -314.152628)
			(xy 271.143333 -314.18672) (xy 271.10283 -314.214676) (xy 271.058368 -314.235774) (xy 271.011097 -314.249466)
			(xy 270.962242 -314.255398) (xy 270.913067 -314.253417) (xy 270.864848 -314.243573) (xy 270.818832 -314.226121)
			(xy 270.776211 -314.201514) (xy 270.73809 -314.170389) (xy 270.705455 -314.133552) (xy 270.679152 -314.091956)
			(xy 270.659861 -314.04668) (xy 270.648084 -313.998896) (xy 270.644124 -313.949842) (xy 196.955156 -313.949842)
			(xy 196.954661 -313.974449) (xy 196.946766 -314.023026) (xy 196.931182 -314.069707) (xy 196.908311 -314.113284)
			(xy 196.878746 -314.152628) (xy 196.843253 -314.18672) (xy 196.80275 -314.214676) (xy 196.758288 -314.235774)
			(xy 196.711017 -314.249466) (xy 196.662162 -314.255398) (xy 196.612987 -314.253417) (xy 196.564768 -314.243573)
			(xy 196.518752 -314.226121) (xy 196.476131 -314.201514) (xy 196.43801 -314.170389) (xy 196.405375 -314.133552)
			(xy 196.379072 -314.091956) (xy 196.359781 -314.04668) (xy 196.348004 -313.998896) (xy 196.344044 -313.949842)
			(xy 195.055236 -313.949842) (xy 195.054741 -313.974449) (xy 195.046846 -314.023026) (xy 195.031262 -314.069707)
			(xy 195.008391 -314.113284) (xy 194.978826 -314.152628) (xy 194.943333 -314.18672) (xy 194.90283 -314.214676)
			(xy 194.858368 -314.235774) (xy 194.811097 -314.249466) (xy 194.762242 -314.255398) (xy 194.713067 -314.253417)
			(xy 194.664848 -314.243573) (xy 194.618832 -314.226121) (xy 194.576211 -314.201514) (xy 194.53809 -314.170389)
			(xy 194.505455 -314.133552) (xy 194.479152 -314.091956) (xy 194.459861 -314.04668) (xy 194.448084 -313.998896)
			(xy 194.444124 -313.949842) (xy 193.155316 -313.949842) (xy 193.154821 -313.974449) (xy 193.146926 -314.023026)
			(xy 193.131342 -314.069707) (xy 193.108471 -314.113284) (xy 193.078906 -314.152628) (xy 193.043413 -314.18672)
			(xy 193.00291 -314.214676) (xy 192.958448 -314.235774) (xy 192.911177 -314.249466) (xy 192.862322 -314.255398)
			(xy 192.813147 -314.253417) (xy 192.764928 -314.243573) (xy 192.718912 -314.226121) (xy 192.676291 -314.201514)
			(xy 192.63817 -314.170389) (xy 192.605535 -314.133552) (xy 192.579232 -314.091956) (xy 192.559941 -314.04668)
			(xy 192.548164 -313.998896) (xy 192.544204 -313.949842) (xy 191.255396 -313.949842) (xy 191.254901 -313.974449)
			(xy 191.247006 -314.023026) (xy 191.231422 -314.069707) (xy 191.208551 -314.113284) (xy 191.178986 -314.152628)
			(xy 191.143493 -314.18672) (xy 191.10299 -314.214676) (xy 191.058528 -314.235774) (xy 191.011257 -314.249466)
			(xy 190.962402 -314.255398) (xy 190.913227 -314.253417) (xy 190.865008 -314.243573) (xy 190.818992 -314.226121)
			(xy 190.776371 -314.201514) (xy 190.73825 -314.170389) (xy 190.705615 -314.133552) (xy 190.679312 -314.091956)
			(xy 190.660021 -314.04668) (xy 190.648244 -313.998896) (xy 190.644284 -313.949842) (xy 189.355222 -313.949842)
			(xy 189.354727 -313.974449) (xy 189.346832 -314.023026) (xy 189.331248 -314.069707) (xy 189.308377 -314.113284)
			(xy 189.278812 -314.152628) (xy 189.243319 -314.18672) (xy 189.202816 -314.214676) (xy 189.158354 -314.235774)
			(xy 189.111083 -314.249466) (xy 189.062228 -314.255398) (xy 189.013053 -314.253417) (xy 188.964834 -314.243573)
			(xy 188.918818 -314.226121) (xy 188.876197 -314.201514) (xy 188.838076 -314.170389) (xy 188.805441 -314.133552)
			(xy 188.779138 -314.091956) (xy 188.759847 -314.04668) (xy 188.74807 -313.998896) (xy 188.74411 -313.949842)
			(xy 187.455302 -313.949842) (xy 187.454807 -313.974449) (xy 187.446912 -314.023026) (xy 187.431328 -314.069707)
			(xy 187.408457 -314.113284) (xy 187.378892 -314.152628) (xy 187.343399 -314.18672) (xy 187.302896 -314.214676)
			(xy 187.258434 -314.235774) (xy 187.211163 -314.249466) (xy 187.162308 -314.255398) (xy 187.113133 -314.253417)
			(xy 187.064914 -314.243573) (xy 187.018898 -314.226121) (xy 186.976277 -314.201514) (xy 186.938156 -314.170389)
			(xy 186.905521 -314.133552) (xy 186.879218 -314.091956) (xy 186.859927 -314.04668) (xy 186.84815 -313.998896)
			(xy 186.84419 -313.949842) (xy 185.555382 -313.949842) (xy 185.554887 -313.974449) (xy 185.546992 -314.023026)
			(xy 185.531408 -314.069707) (xy 185.508537 -314.113284) (xy 185.478972 -314.152628) (xy 185.443479 -314.18672)
			(xy 185.402976 -314.214676) (xy 185.358514 -314.235774) (xy 185.311243 -314.249466) (xy 185.262388 -314.255398)
			(xy 185.213213 -314.253417) (xy 185.164994 -314.243573) (xy 185.118978 -314.226121) (xy 185.076357 -314.201514)
			(xy 185.038236 -314.170389) (xy 185.005601 -314.133552) (xy 184.979298 -314.091956) (xy 184.960007 -314.04668)
			(xy 184.94823 -313.998896) (xy 184.94427 -313.949842) (xy 183.655208 -313.949842) (xy 183.654713 -313.974449)
			(xy 183.646818 -314.023026) (xy 183.631234 -314.069707) (xy 183.608363 -314.113284) (xy 183.578798 -314.152628)
			(xy 183.543305 -314.18672) (xy 183.502802 -314.214676) (xy 183.45834 -314.235774) (xy 183.411069 -314.249466)
			(xy 183.362214 -314.255398) (xy 183.313039 -314.253417) (xy 183.26482 -314.243573) (xy 183.218804 -314.226121)
			(xy 183.176183 -314.201514) (xy 183.138062 -314.170389) (xy 183.105427 -314.133552) (xy 183.079124 -314.091956)
			(xy 183.059833 -314.04668) (xy 183.048056 -313.998896) (xy 183.044096 -313.949842) (xy 181.755288 -313.949842)
			(xy 181.754793 -313.974449) (xy 181.746898 -314.023026) (xy 181.731314 -314.069707) (xy 181.708443 -314.113284)
			(xy 181.678878 -314.152628) (xy 181.643385 -314.18672) (xy 181.602882 -314.214676) (xy 181.55842 -314.235774)
			(xy 181.511149 -314.249466) (xy 181.462294 -314.255398) (xy 181.413119 -314.253417) (xy 181.3649 -314.243573)
			(xy 181.318884 -314.226121) (xy 181.276263 -314.201514) (xy 181.238142 -314.170389) (xy 181.205507 -314.133552)
			(xy 181.179204 -314.091956) (xy 181.159913 -314.04668) (xy 181.148136 -313.998896) (xy 181.144176 -313.949842)
			(xy 179.855368 -313.949842) (xy 179.854873 -313.974449) (xy 179.846978 -314.023026) (xy 179.831394 -314.069707)
			(xy 179.808523 -314.113284) (xy 179.778958 -314.152628) (xy 179.743465 -314.18672) (xy 179.702962 -314.214676)
			(xy 179.6585 -314.235774) (xy 179.611229 -314.249466) (xy 179.562374 -314.255398) (xy 179.513199 -314.253417)
			(xy 179.46498 -314.243573) (xy 179.418964 -314.226121) (xy 179.376343 -314.201514) (xy 179.338222 -314.170389)
			(xy 179.305587 -314.133552) (xy 179.279284 -314.091956) (xy 179.259993 -314.04668) (xy 179.248216 -313.998896)
			(xy 179.244256 -313.949842) (xy 177.955194 -313.949842) (xy 177.954699 -313.974449) (xy 177.946804 -314.023026)
			(xy 177.93122 -314.069707) (xy 177.908349 -314.113284) (xy 177.878784 -314.152628) (xy 177.843291 -314.18672)
			(xy 177.802788 -314.214676) (xy 177.758326 -314.235774) (xy 177.711055 -314.249466) (xy 177.6622 -314.255398)
			(xy 177.613025 -314.253417) (xy 177.564806 -314.243573) (xy 177.51879 -314.226121) (xy 177.476169 -314.201514)
			(xy 177.438048 -314.170389) (xy 177.405413 -314.133552) (xy 177.37911 -314.091956) (xy 177.359819 -314.04668)
			(xy 177.348042 -313.998896) (xy 177.344082 -313.949842) (xy 176.055274 -313.949842) (xy 176.054779 -313.974449)
			(xy 176.046884 -314.023026) (xy 176.0313 -314.069707) (xy 176.008429 -314.113284) (xy 175.978864 -314.152628)
			(xy 175.943371 -314.18672) (xy 175.902868 -314.214676) (xy 175.858406 -314.235774) (xy 175.811135 -314.249466)
			(xy 175.76228 -314.255398) (xy 175.713105 -314.253417) (xy 175.664886 -314.243573) (xy 175.61887 -314.226121)
			(xy 175.576249 -314.201514) (xy 175.538128 -314.170389) (xy 175.505493 -314.133552) (xy 175.47919 -314.091956)
			(xy 175.459899 -314.04668) (xy 175.448122 -313.998896) (xy 175.444162 -313.949842) (xy 174.155354 -313.949842)
			(xy 174.154859 -313.974449) (xy 174.146964 -314.023026) (xy 174.13138 -314.069707) (xy 174.108509 -314.113284)
			(xy 174.078944 -314.152628) (xy 174.043451 -314.18672) (xy 174.002948 -314.214676) (xy 173.958486 -314.235774)
			(xy 173.911215 -314.249466) (xy 173.86236 -314.255398) (xy 173.813185 -314.253417) (xy 173.764966 -314.243573)
			(xy 173.71895 -314.226121) (xy 173.676329 -314.201514) (xy 173.638208 -314.170389) (xy 173.605573 -314.133552)
			(xy 173.57927 -314.091956) (xy 173.559979 -314.04668) (xy 173.548202 -313.998896) (xy 173.544242 -313.949842)
			(xy 172.25518 -313.949842) (xy 172.254685 -313.974449) (xy 172.24679 -314.023026) (xy 172.231206 -314.069707)
			(xy 172.208335 -314.113284) (xy 172.17877 -314.152628) (xy 172.143277 -314.18672) (xy 172.102774 -314.214676)
			(xy 172.058312 -314.235774) (xy 172.011041 -314.249466) (xy 171.962186 -314.255398) (xy 171.913011 -314.253417)
			(xy 171.864792 -314.243573) (xy 171.818776 -314.226121) (xy 171.776155 -314.201514) (xy 171.738034 -314.170389)
			(xy 171.705399 -314.133552) (xy 171.679096 -314.091956) (xy 171.659805 -314.04668) (xy 171.648028 -313.998896)
			(xy 171.644068 -313.949842) (xy 170.35526 -313.949842) (xy 170.354765 -313.974449) (xy 170.34687 -314.023026)
			(xy 170.331286 -314.069707) (xy 170.308415 -314.113284) (xy 170.27885 -314.152628) (xy 170.243357 -314.18672)
			(xy 170.202854 -314.214676) (xy 170.158392 -314.235774) (xy 170.111121 -314.249466) (xy 170.062266 -314.255398)
			(xy 170.013091 -314.253417) (xy 169.964872 -314.243573) (xy 169.918856 -314.226121) (xy 169.876235 -314.201514)
			(xy 169.838114 -314.170389) (xy 169.805479 -314.133552) (xy 169.779176 -314.091956) (xy 169.759885 -314.04668)
			(xy 169.748108 -313.998896) (xy 169.744148 -313.949842) (xy 168.45534 -313.949842) (xy 168.454845 -313.974449)
			(xy 168.44695 -314.023026) (xy 168.431366 -314.069707) (xy 168.408495 -314.113284) (xy 168.37893 -314.152628)
			(xy 168.343437 -314.18672) (xy 168.302934 -314.214676) (xy 168.258472 -314.235774) (xy 168.211201 -314.249466)
			(xy 168.162346 -314.255398) (xy 168.113171 -314.253417) (xy 168.064952 -314.243573) (xy 168.018936 -314.226121)
			(xy 167.976315 -314.201514) (xy 167.938194 -314.170389) (xy 167.905559 -314.133552) (xy 167.879256 -314.091956)
			(xy 167.859965 -314.04668) (xy 167.848188 -313.998896) (xy 167.844228 -313.949842) (xy 166.555166 -313.949842)
			(xy 166.554671 -313.974449) (xy 166.546776 -314.023026) (xy 166.531192 -314.069707) (xy 166.508321 -314.113284)
			(xy 166.478756 -314.152628) (xy 166.443263 -314.18672) (xy 166.40276 -314.214676) (xy 166.358298 -314.235774)
			(xy 166.311027 -314.249466) (xy 166.262172 -314.255398) (xy 166.212997 -314.253417) (xy 166.164778 -314.243573)
			(xy 166.118762 -314.226121) (xy 166.076141 -314.201514) (xy 166.03802 -314.170389) (xy 166.005385 -314.133552)
			(xy 165.979082 -314.091956) (xy 165.959791 -314.04668) (xy 165.948014 -313.998896) (xy 165.944054 -313.949842)
			(xy 164.655246 -313.949842) (xy 164.654751 -313.974449) (xy 164.646856 -314.023026) (xy 164.631272 -314.069707)
			(xy 164.608401 -314.113284) (xy 164.578836 -314.152628) (xy 164.543343 -314.18672) (xy 164.50284 -314.214676)
			(xy 164.458378 -314.235774) (xy 164.411107 -314.249466) (xy 164.362252 -314.255398) (xy 164.313077 -314.253417)
			(xy 164.264858 -314.243573) (xy 164.218842 -314.226121) (xy 164.176221 -314.201514) (xy 164.1381 -314.170389)
			(xy 164.105465 -314.133552) (xy 164.079162 -314.091956) (xy 164.059871 -314.04668) (xy 164.048094 -313.998896)
			(xy 164.044134 -313.949842) (xy 162.755326 -313.949842) (xy 162.754831 -313.974449) (xy 162.746936 -314.023026)
			(xy 162.731352 -314.069707) (xy 162.708481 -314.113284) (xy 162.678916 -314.152628) (xy 162.643423 -314.18672)
			(xy 162.60292 -314.214676) (xy 162.558458 -314.235774) (xy 162.511187 -314.249466) (xy 162.462332 -314.255398)
			(xy 162.413157 -314.253417) (xy 162.364938 -314.243573) (xy 162.318922 -314.226121) (xy 162.276301 -314.201514)
			(xy 162.23818 -314.170389) (xy 162.205545 -314.133552) (xy 162.179242 -314.091956) (xy 162.159951 -314.04668)
			(xy 162.148174 -313.998896) (xy 162.144214 -313.949842) (xy 160.855152 -313.949842) (xy 160.854657 -313.974449)
			(xy 160.846762 -314.023026) (xy 160.831178 -314.069707) (xy 160.808307 -314.113284) (xy 160.778742 -314.152628)
			(xy 160.743249 -314.18672) (xy 160.702746 -314.214676) (xy 160.658284 -314.235774) (xy 160.611013 -314.249466)
			(xy 160.562158 -314.255398) (xy 160.512983 -314.253417) (xy 160.464764 -314.243573) (xy 160.418748 -314.226121)
			(xy 160.376127 -314.201514) (xy 160.338006 -314.170389) (xy 160.305371 -314.133552) (xy 160.279068 -314.091956)
			(xy 160.259777 -314.04668) (xy 160.248 -313.998896) (xy 160.24404 -313.949842) (xy 158.955232 -313.949842)
			(xy 158.954737 -313.974449) (xy 158.946842 -314.023026) (xy 158.931258 -314.069707) (xy 158.908387 -314.113284)
			(xy 158.878822 -314.152628) (xy 158.843329 -314.18672) (xy 158.802826 -314.214676) (xy 158.758364 -314.235774)
			(xy 158.711093 -314.249466) (xy 158.662238 -314.255398) (xy 158.613063 -314.253417) (xy 158.564844 -314.243573)
			(xy 158.518828 -314.226121) (xy 158.476207 -314.201514) (xy 158.438086 -314.170389) (xy 158.405451 -314.133552)
			(xy 158.379148 -314.091956) (xy 158.359857 -314.04668) (xy 158.34808 -313.998896) (xy 158.34412 -313.949842)
			(xy 157.055312 -313.949842) (xy 157.054817 -313.974449) (xy 157.046922 -314.023026) (xy 157.031338 -314.069707)
			(xy 157.008467 -314.113284) (xy 156.978902 -314.152628) (xy 156.943409 -314.18672) (xy 156.902906 -314.214676)
			(xy 156.858444 -314.235774) (xy 156.811173 -314.249466) (xy 156.762318 -314.255398) (xy 156.713143 -314.253417)
			(xy 156.664924 -314.243573) (xy 156.618908 -314.226121) (xy 156.576287 -314.201514) (xy 156.538166 -314.170389)
			(xy 156.505531 -314.133552) (xy 156.479228 -314.091956) (xy 156.459937 -314.04668) (xy 156.44816 -313.998896)
			(xy 156.4442 -313.949842) (xy 155.155392 -313.949842) (xy 155.154897 -313.974449) (xy 155.147002 -314.023026)
			(xy 155.131418 -314.069707) (xy 155.108547 -314.113284) (xy 155.078982 -314.152628) (xy 155.043489 -314.18672)
			(xy 155.002986 -314.214676) (xy 154.958524 -314.235774) (xy 154.911253 -314.249466) (xy 154.862398 -314.255398)
			(xy 154.813223 -314.253417) (xy 154.765004 -314.243573) (xy 154.718988 -314.226121) (xy 154.676367 -314.201514)
			(xy 154.638246 -314.170389) (xy 154.605611 -314.133552) (xy 154.579308 -314.091956) (xy 154.560017 -314.04668)
			(xy 154.54824 -313.998896) (xy 154.54428 -313.949842) (xy 80.855058 -313.949842) (xy 80.854563 -313.974449)
			(xy 80.846668 -314.023026) (xy 80.831084 -314.069707) (xy 80.808213 -314.113284) (xy 80.778648 -314.152628)
			(xy 80.743155 -314.18672) (xy 80.702652 -314.214676) (xy 80.65819 -314.235774) (xy 80.610919 -314.249466)
			(xy 80.562064 -314.255398) (xy 80.512889 -314.253417) (xy 80.46467 -314.243573) (xy 80.418654 -314.226121)
			(xy 80.376033 -314.201514) (xy 80.337912 -314.170389) (xy 80.305277 -314.133552) (xy 80.278974 -314.091956)
			(xy 80.259683 -314.04668) (xy 80.247906 -313.998896) (xy 80.243946 -313.949842) (xy 78.955138 -313.949842)
			(xy 78.954643 -313.974449) (xy 78.946748 -314.023026) (xy 78.931164 -314.069707) (xy 78.908293 -314.113284)
			(xy 78.878728 -314.152628) (xy 78.843235 -314.18672) (xy 78.802732 -314.214676) (xy 78.75827 -314.235774)
			(xy 78.710999 -314.249466) (xy 78.662144 -314.255398) (xy 78.612969 -314.253417) (xy 78.56475 -314.243573)
			(xy 78.518734 -314.226121) (xy 78.476113 -314.201514) (xy 78.437992 -314.170389) (xy 78.405357 -314.133552)
			(xy 78.379054 -314.091956) (xy 78.359763 -314.04668) (xy 78.347986 -313.998896) (xy 78.344026 -313.949842)
			(xy 77.055218 -313.949842) (xy 77.054723 -313.974449) (xy 77.046828 -314.023026) (xy 77.031244 -314.069707)
			(xy 77.008373 -314.113284) (xy 76.978808 -314.152628) (xy 76.943315 -314.18672) (xy 76.902812 -314.214676)
			(xy 76.85835 -314.235774) (xy 76.811079 -314.249466) (xy 76.762224 -314.255398) (xy 76.713049 -314.253417)
			(xy 76.66483 -314.243573) (xy 76.618814 -314.226121) (xy 76.576193 -314.201514) (xy 76.538072 -314.170389)
			(xy 76.505437 -314.133552) (xy 76.479134 -314.091956) (xy 76.459843 -314.04668) (xy 76.448066 -313.998896)
			(xy 76.444106 -313.949842) (xy 75.155298 -313.949842) (xy 75.154803 -313.974449) (xy 75.146908 -314.023026)
			(xy 75.131324 -314.069707) (xy 75.108453 -314.113284) (xy 75.078888 -314.152628) (xy 75.043395 -314.18672)
			(xy 75.002892 -314.214676) (xy 74.95843 -314.235774) (xy 74.911159 -314.249466) (xy 74.862304 -314.255398)
			(xy 74.813129 -314.253417) (xy 74.76491 -314.243573) (xy 74.718894 -314.226121) (xy 74.676273 -314.201514)
			(xy 74.638152 -314.170389) (xy 74.605517 -314.133552) (xy 74.579214 -314.091956) (xy 74.559923 -314.04668)
			(xy 74.548146 -313.998896) (xy 74.544186 -313.949842) (xy 73.255124 -313.949842) (xy 73.254629 -313.974449)
			(xy 73.246734 -314.023026) (xy 73.23115 -314.069707) (xy 73.208279 -314.113284) (xy 73.178714 -314.152628)
			(xy 73.143221 -314.18672) (xy 73.102718 -314.214676) (xy 73.058256 -314.235774) (xy 73.010985 -314.249466)
			(xy 72.96213 -314.255398) (xy 72.912955 -314.253417) (xy 72.864736 -314.243573) (xy 72.81872 -314.226121)
			(xy 72.776099 -314.201514) (xy 72.737978 -314.170389) (xy 72.705343 -314.133552) (xy 72.67904 -314.091956)
			(xy 72.659749 -314.04668) (xy 72.647972 -313.998896) (xy 72.644012 -313.949842) (xy 71.355204 -313.949842)
			(xy 71.354709 -313.974449) (xy 71.346814 -314.023026) (xy 71.33123 -314.069707) (xy 71.308359 -314.113284)
			(xy 71.278794 -314.152628) (xy 71.243301 -314.18672) (xy 71.202798 -314.214676) (xy 71.158336 -314.235774)
			(xy 71.111065 -314.249466) (xy 71.06221 -314.255398) (xy 71.013035 -314.253417) (xy 70.964816 -314.243573)
			(xy 70.9188 -314.226121) (xy 70.876179 -314.201514) (xy 70.838058 -314.170389) (xy 70.805423 -314.133552)
			(xy 70.77912 -314.091956) (xy 70.759829 -314.04668) (xy 70.748052 -313.998896) (xy 70.744092 -313.949842)
			(xy 69.455284 -313.949842) (xy 69.454789 -313.974449) (xy 69.446894 -314.023026) (xy 69.43131 -314.069707)
			(xy 69.408439 -314.113284) (xy 69.378874 -314.152628) (xy 69.343381 -314.18672) (xy 69.302878 -314.214676)
			(xy 69.258416 -314.235774) (xy 69.211145 -314.249466) (xy 69.16229 -314.255398) (xy 69.113115 -314.253417)
			(xy 69.064896 -314.243573) (xy 69.01888 -314.226121) (xy 68.976259 -314.201514) (xy 68.938138 -314.170389)
			(xy 68.905503 -314.133552) (xy 68.8792 -314.091956) (xy 68.859909 -314.04668) (xy 68.848132 -313.998896)
			(xy 68.844172 -313.949842) (xy 67.55511 -313.949842) (xy 67.554615 -313.974449) (xy 67.54672 -314.023026)
			(xy 67.531136 -314.069707) (xy 67.508265 -314.113284) (xy 67.4787 -314.152628) (xy 67.443207 -314.18672)
			(xy 67.402704 -314.214676) (xy 67.358242 -314.235774) (xy 67.310971 -314.249466) (xy 67.262116 -314.255398)
			(xy 67.212941 -314.253417) (xy 67.164722 -314.243573) (xy 67.118706 -314.226121) (xy 67.076085 -314.201514)
			(xy 67.037964 -314.170389) (xy 67.005329 -314.133552) (xy 66.979026 -314.091956) (xy 66.959735 -314.04668)
			(xy 66.947958 -313.998896) (xy 66.943998 -313.949842) (xy 65.65519 -313.949842) (xy 65.654695 -313.974449)
			(xy 65.6468 -314.023026) (xy 65.631216 -314.069707) (xy 65.608345 -314.113284) (xy 65.57878 -314.152628)
			(xy 65.543287 -314.18672) (xy 65.502784 -314.214676) (xy 65.458322 -314.235774) (xy 65.411051 -314.249466)
			(xy 65.362196 -314.255398) (xy 65.313021 -314.253417) (xy 65.264802 -314.243573) (xy 65.218786 -314.226121)
			(xy 65.176165 -314.201514) (xy 65.138044 -314.170389) (xy 65.105409 -314.133552) (xy 65.079106 -314.091956)
			(xy 65.059815 -314.04668) (xy 65.048038 -313.998896) (xy 65.044078 -313.949842) (xy 63.75527 -313.949842)
			(xy 63.754775 -313.974449) (xy 63.74688 -314.023026) (xy 63.731296 -314.069707) (xy 63.708425 -314.113284)
			(xy 63.67886 -314.152628) (xy 63.643367 -314.18672) (xy 63.602864 -314.214676) (xy 63.558402 -314.235774)
			(xy 63.511131 -314.249466) (xy 63.462276 -314.255398) (xy 63.413101 -314.253417) (xy 63.364882 -314.243573)
			(xy 63.318866 -314.226121) (xy 63.276245 -314.201514) (xy 63.238124 -314.170389) (xy 63.205489 -314.133552)
			(xy 63.179186 -314.091956) (xy 63.159895 -314.04668) (xy 63.148118 -313.998896) (xy 63.144158 -313.949842)
			(xy 61.855096 -313.949842) (xy 61.854601 -313.974449) (xy 61.846706 -314.023026) (xy 61.831122 -314.069707)
			(xy 61.808251 -314.113284) (xy 61.778686 -314.152628) (xy 61.743193 -314.18672) (xy 61.70269 -314.214676)
			(xy 61.658228 -314.235774) (xy 61.610957 -314.249466) (xy 61.562102 -314.255398) (xy 61.512927 -314.253417)
			(xy 61.464708 -314.243573) (xy 61.418692 -314.226121) (xy 61.376071 -314.201514) (xy 61.33795 -314.170389)
			(xy 61.305315 -314.133552) (xy 61.279012 -314.091956) (xy 61.259721 -314.04668) (xy 61.247944 -313.998896)
			(xy 61.243984 -313.949842) (xy 59.955176 -313.949842) (xy 59.954681 -313.974449) (xy 59.946786 -314.023026)
			(xy 59.931202 -314.069707) (xy 59.908331 -314.113284) (xy 59.878766 -314.152628) (xy 59.843273 -314.18672)
			(xy 59.80277 -314.214676) (xy 59.758308 -314.235774) (xy 59.711037 -314.249466) (xy 59.662182 -314.255398)
			(xy 59.613007 -314.253417) (xy 59.564788 -314.243573) (xy 59.518772 -314.226121) (xy 59.476151 -314.201514)
			(xy 59.43803 -314.170389) (xy 59.405395 -314.133552) (xy 59.379092 -314.091956) (xy 59.359801 -314.04668)
			(xy 59.348024 -313.998896) (xy 59.344064 -313.949842) (xy 58.055256 -313.949842) (xy 58.054761 -313.974449)
			(xy 58.046866 -314.023026) (xy 58.031282 -314.069707) (xy 58.008411 -314.113284) (xy 57.978846 -314.152628)
			(xy 57.943353 -314.18672) (xy 57.90285 -314.214676) (xy 57.858388 -314.235774) (xy 57.811117 -314.249466)
			(xy 57.762262 -314.255398) (xy 57.713087 -314.253417) (xy 57.664868 -314.243573) (xy 57.618852 -314.226121)
			(xy 57.576231 -314.201514) (xy 57.53811 -314.170389) (xy 57.505475 -314.133552) (xy 57.479172 -314.091956)
			(xy 57.459881 -314.04668) (xy 57.448104 -313.998896) (xy 57.444144 -313.949842) (xy 56.155082 -313.949842)
			(xy 56.154587 -313.974449) (xy 56.146692 -314.023026) (xy 56.131108 -314.069707) (xy 56.108237 -314.113284)
			(xy 56.078672 -314.152628) (xy 56.043179 -314.18672) (xy 56.002676 -314.214676) (xy 55.958214 -314.235774)
			(xy 55.910943 -314.249466) (xy 55.862088 -314.255398) (xy 55.812913 -314.253417) (xy 55.764694 -314.243573)
			(xy 55.718678 -314.226121) (xy 55.676057 -314.201514) (xy 55.637936 -314.170389) (xy 55.605301 -314.133552)
			(xy 55.578998 -314.091956) (xy 55.559707 -314.04668) (xy 55.54793 -313.998896) (xy 55.54397 -313.949842)
			(xy 54.255162 -313.949842) (xy 54.254667 -313.974449) (xy 54.246772 -314.023026) (xy 54.231188 -314.069707)
			(xy 54.208317 -314.113284) (xy 54.178752 -314.152628) (xy 54.143259 -314.18672) (xy 54.102756 -314.214676)
			(xy 54.058294 -314.235774) (xy 54.011023 -314.249466) (xy 53.962168 -314.255398) (xy 53.912993 -314.253417)
			(xy 53.864774 -314.243573) (xy 53.818758 -314.226121) (xy 53.776137 -314.201514) (xy 53.738016 -314.170389)
			(xy 53.705381 -314.133552) (xy 53.679078 -314.091956) (xy 53.659787 -314.04668) (xy 53.64801 -313.998896)
			(xy 53.64405 -313.949842) (xy 52.355242 -313.949842) (xy 52.354747 -313.974449) (xy 52.346852 -314.023026)
			(xy 52.331268 -314.069707) (xy 52.308397 -314.113284) (xy 52.278832 -314.152628) (xy 52.243339 -314.18672)
			(xy 52.202836 -314.214676) (xy 52.158374 -314.235774) (xy 52.111103 -314.249466) (xy 52.062248 -314.255398)
			(xy 52.013073 -314.253417) (xy 51.964854 -314.243573) (xy 51.918838 -314.226121) (xy 51.876217 -314.201514)
			(xy 51.838096 -314.170389) (xy 51.805461 -314.133552) (xy 51.779158 -314.091956) (xy 51.759867 -314.04668)
			(xy 51.74809 -313.998896) (xy 51.74413 -313.949842) (xy 50.455068 -313.949842) (xy 50.454573 -313.974449)
			(xy 50.446678 -314.023026) (xy 50.431094 -314.069707) (xy 50.408223 -314.113284) (xy 50.378658 -314.152628)
			(xy 50.343165 -314.18672) (xy 50.302662 -314.214676) (xy 50.2582 -314.235774) (xy 50.210929 -314.249466)
			(xy 50.162074 -314.255398) (xy 50.112899 -314.253417) (xy 50.06468 -314.243573) (xy 50.018664 -314.226121)
			(xy 49.976043 -314.201514) (xy 49.937922 -314.170389) (xy 49.905287 -314.133552) (xy 49.878984 -314.091956)
			(xy 49.859693 -314.04668) (xy 49.847916 -313.998896) (xy 49.843956 -313.949842) (xy 48.555148 -313.949842)
			(xy 48.554653 -313.974449) (xy 48.546758 -314.023026) (xy 48.531174 -314.069707) (xy 48.508303 -314.113284)
			(xy 48.478738 -314.152628) (xy 48.443245 -314.18672) (xy 48.402742 -314.214676) (xy 48.35828 -314.235774)
			(xy 48.311009 -314.249466) (xy 48.262154 -314.255398) (xy 48.212979 -314.253417) (xy 48.16476 -314.243573)
			(xy 48.118744 -314.226121) (xy 48.076123 -314.201514) (xy 48.038002 -314.170389) (xy 48.005367 -314.133552)
			(xy 47.979064 -314.091956) (xy 47.959773 -314.04668) (xy 47.947996 -313.998896) (xy 47.944036 -313.949842)
			(xy 46.655228 -313.949842) (xy 46.654733 -313.974449) (xy 46.646838 -314.023026) (xy 46.631254 -314.069707)
			(xy 46.608383 -314.113284) (xy 46.578818 -314.152628) (xy 46.543325 -314.18672) (xy 46.502822 -314.214676)
			(xy 46.45836 -314.235774) (xy 46.411089 -314.249466) (xy 46.362234 -314.255398) (xy 46.313059 -314.253417)
			(xy 46.26484 -314.243573) (xy 46.218824 -314.226121) (xy 46.176203 -314.201514) (xy 46.138082 -314.170389)
			(xy 46.105447 -314.133552) (xy 46.079144 -314.091956) (xy 46.059853 -314.04668) (xy 46.048076 -313.998896)
			(xy 46.044116 -313.949842) (xy 44.755054 -313.949842) (xy 44.754559 -313.974449) (xy 44.746664 -314.023026)
			(xy 44.73108 -314.069707) (xy 44.708209 -314.113284) (xy 44.678644 -314.152628) (xy 44.643151 -314.18672)
			(xy 44.602648 -314.214676) (xy 44.558186 -314.235774) (xy 44.510915 -314.249466) (xy 44.46206 -314.255398)
			(xy 44.412885 -314.253417) (xy 44.364666 -314.243573) (xy 44.31865 -314.226121) (xy 44.276029 -314.201514)
			(xy 44.237908 -314.170389) (xy 44.205273 -314.133552) (xy 44.17897 -314.091956) (xy 44.159679 -314.04668)
			(xy 44.147902 -313.998896) (xy 44.143942 -313.949842) (xy 42.855134 -313.949842) (xy 42.854639 -313.974449)
			(xy 42.846744 -314.023026) (xy 42.83116 -314.069707) (xy 42.808289 -314.113284) (xy 42.778724 -314.152628)
			(xy 42.743231 -314.18672) (xy 42.702728 -314.214676) (xy 42.658266 -314.235774) (xy 42.610995 -314.249466)
			(xy 42.56214 -314.255398) (xy 42.512965 -314.253417) (xy 42.464746 -314.243573) (xy 42.41873 -314.226121)
			(xy 42.376109 -314.201514) (xy 42.337988 -314.170389) (xy 42.305353 -314.133552) (xy 42.27905 -314.091956)
			(xy 42.259759 -314.04668) (xy 42.247982 -313.998896) (xy 42.244022 -313.949842) (xy 40.955214 -313.949842)
			(xy 40.954719 -313.974449) (xy 40.946824 -314.023026) (xy 40.93124 -314.069707) (xy 40.908369 -314.113284)
			(xy 40.878804 -314.152628) (xy 40.843311 -314.18672) (xy 40.802808 -314.214676) (xy 40.758346 -314.235774)
			(xy 40.711075 -314.249466) (xy 40.66222 -314.255398) (xy 40.613045 -314.253417) (xy 40.564826 -314.243573)
			(xy 40.51881 -314.226121) (xy 40.476189 -314.201514) (xy 40.438068 -314.170389) (xy 40.405433 -314.133552)
			(xy 40.37913 -314.091956) (xy 40.359839 -314.04668) (xy 40.348062 -313.998896) (xy 40.344102 -313.949842)
			(xy 39.055294 -313.949842) (xy 39.054799 -313.974449) (xy 39.046904 -314.023026) (xy 39.03132 -314.069707)
			(xy 39.008449 -314.113284) (xy 38.978884 -314.152628) (xy 38.943391 -314.18672) (xy 38.902888 -314.214676)
			(xy 38.858426 -314.235774) (xy 38.811155 -314.249466) (xy 38.7623 -314.255398) (xy 38.713125 -314.253417)
			(xy 38.664906 -314.243573) (xy 38.61889 -314.226121) (xy 38.576269 -314.201514) (xy 38.538148 -314.170389)
			(xy 38.505513 -314.133552) (xy 38.47921 -314.091956) (xy 38.459919 -314.04668) (xy 38.448142 -313.998896)
			(xy 38.444182 -313.949842) (xy 0.508 -313.949842) (xy 0.508 -314.899802) (xy 36.544008 -314.899802)
			(xy 36.547968 -314.850748) (xy 36.559745 -314.802964) (xy 36.579036 -314.757688) (xy 36.605339 -314.716092)
			(xy 36.637974 -314.679255) (xy 36.676095 -314.64813) (xy 36.718716 -314.623523) (xy 36.764732 -314.606071)
			(xy 36.812951 -314.596227) (xy 36.862126 -314.594246) (xy 36.910981 -314.600178) (xy 36.958252 -314.61387)
			(xy 37.002714 -314.634968) (xy 37.043217 -314.662924) (xy 37.07871 -314.697016) (xy 37.108275 -314.73636)
			(xy 37.131146 -314.779937) (xy 37.14673 -314.826618) (xy 37.154625 -314.875195) (xy 37.15512 -314.899802)
			(xy 37.493968 -314.899802) (xy 37.497928 -314.850748) (xy 37.509705 -314.802964) (xy 37.528996 -314.757688)
			(xy 37.555299 -314.716092) (xy 37.587934 -314.679255) (xy 37.626055 -314.64813) (xy 37.668676 -314.623523)
			(xy 37.714692 -314.606071) (xy 37.762911 -314.596227) (xy 37.812086 -314.594246) (xy 37.860941 -314.600178)
			(xy 37.908212 -314.61387) (xy 37.952674 -314.634968) (xy 37.993177 -314.662924) (xy 38.02867 -314.697016)
			(xy 38.058235 -314.73636) (xy 38.081106 -314.779937) (xy 38.09669 -314.826618) (xy 38.104585 -314.875195)
			(xy 38.10508 -314.899802) (xy 81.19416 -314.899802) (xy 81.19812 -314.850748) (xy 81.209897 -314.802964)
			(xy 81.229188 -314.757688) (xy 81.255491 -314.716092) (xy 81.288126 -314.679255) (xy 81.326247 -314.64813)
			(xy 81.368868 -314.623523) (xy 81.414884 -314.606071) (xy 81.463103 -314.596227) (xy 81.512278 -314.594246)
			(xy 81.561133 -314.600178) (xy 81.608404 -314.61387) (xy 81.652866 -314.634968) (xy 81.693369 -314.662924)
			(xy 81.728862 -314.697016) (xy 81.758427 -314.73636) (xy 81.781298 -314.779937) (xy 81.796882 -314.826618)
			(xy 81.804777 -314.875195) (xy 81.805272 -314.899802) (xy 82.14412 -314.899802) (xy 82.14808 -314.850748)
			(xy 82.159857 -314.802964) (xy 82.179148 -314.757688) (xy 82.205451 -314.716092) (xy 82.238086 -314.679255)
			(xy 82.276207 -314.64813) (xy 82.318828 -314.623523) (xy 82.364844 -314.606071) (xy 82.413063 -314.596227)
			(xy 82.462238 -314.594246) (xy 82.511093 -314.600178) (xy 82.558364 -314.61387) (xy 82.602826 -314.634968)
			(xy 82.643329 -314.662924) (xy 82.678822 -314.697016) (xy 82.708387 -314.73636) (xy 82.731258 -314.779937)
			(xy 82.746842 -314.826618) (xy 82.754737 -314.875195) (xy 82.755232 -314.899802) (xy 152.644106 -314.899802)
			(xy 152.648066 -314.850748) (xy 152.659843 -314.802964) (xy 152.679134 -314.757688) (xy 152.705437 -314.716092)
			(xy 152.738072 -314.679255) (xy 152.776193 -314.64813) (xy 152.818814 -314.623523) (xy 152.86483 -314.606071)
			(xy 152.913049 -314.596227) (xy 152.962224 -314.594246) (xy 153.011079 -314.600178) (xy 153.05835 -314.61387)
			(xy 153.102812 -314.634968) (xy 153.143315 -314.662924) (xy 153.178808 -314.697016) (xy 153.208373 -314.73636)
			(xy 153.231244 -314.779937) (xy 153.246828 -314.826618) (xy 153.254723 -314.875195) (xy 153.255218 -314.899802)
			(xy 153.594066 -314.899802) (xy 153.598026 -314.850748) (xy 153.609803 -314.802964) (xy 153.629094 -314.757688)
			(xy 153.655397 -314.716092) (xy 153.688032 -314.679255) (xy 153.726153 -314.64813) (xy 153.768774 -314.623523)
			(xy 153.81479 -314.606071) (xy 153.863009 -314.596227) (xy 153.912184 -314.594246) (xy 153.961039 -314.600178)
			(xy 154.00831 -314.61387) (xy 154.052772 -314.634968) (xy 154.093275 -314.662924) (xy 154.128768 -314.697016)
			(xy 154.158333 -314.73636) (xy 154.181204 -314.779937) (xy 154.196788 -314.826618) (xy 154.204683 -314.875195)
			(xy 154.205178 -314.899802) (xy 197.294258 -314.899802) (xy 197.298218 -314.850748) (xy 197.309995 -314.802964)
			(xy 197.329286 -314.757688) (xy 197.355589 -314.716092) (xy 197.388224 -314.679255) (xy 197.426345 -314.64813)
			(xy 197.468966 -314.623523) (xy 197.514982 -314.606071) (xy 197.563201 -314.596227) (xy 197.612376 -314.594246)
			(xy 197.661231 -314.600178) (xy 197.708502 -314.61387) (xy 197.752964 -314.634968) (xy 197.793467 -314.662924)
			(xy 197.82896 -314.697016) (xy 197.858525 -314.73636) (xy 197.881396 -314.779937) (xy 197.89698 -314.826618)
			(xy 197.904875 -314.875195) (xy 197.90537 -314.899802) (xy 198.244218 -314.899802) (xy 198.248178 -314.850748)
			(xy 198.259955 -314.802964) (xy 198.279246 -314.757688) (xy 198.305549 -314.716092) (xy 198.338184 -314.679255)
			(xy 198.376305 -314.64813) (xy 198.418926 -314.623523) (xy 198.464942 -314.606071) (xy 198.513161 -314.596227)
			(xy 198.562336 -314.594246) (xy 198.611191 -314.600178) (xy 198.658462 -314.61387) (xy 198.702924 -314.634968)
			(xy 198.743427 -314.662924) (xy 198.77892 -314.697016) (xy 198.808485 -314.73636) (xy 198.831356 -314.779937)
			(xy 198.84694 -314.826618) (xy 198.854835 -314.875195) (xy 198.85533 -314.899802) (xy 268.74395 -314.899802)
			(xy 268.74791 -314.850748) (xy 268.759687 -314.802964) (xy 268.778978 -314.757688) (xy 268.805281 -314.716092)
			(xy 268.837916 -314.679255) (xy 268.876037 -314.64813) (xy 268.918658 -314.623523) (xy 268.964674 -314.606071)
			(xy 269.012893 -314.596227) (xy 269.062068 -314.594246) (xy 269.110923 -314.600178) (xy 269.158194 -314.61387)
			(xy 269.202656 -314.634968) (xy 269.243159 -314.662924) (xy 269.278652 -314.697016) (xy 269.308217 -314.73636)
			(xy 269.331088 -314.779937) (xy 269.346672 -314.826618) (xy 269.354567 -314.875195) (xy 269.355062 -314.899802)
			(xy 269.69391 -314.899802) (xy 269.69787 -314.850748) (xy 269.709647 -314.802964) (xy 269.728938 -314.757688)
			(xy 269.755241 -314.716092) (xy 269.787876 -314.679255) (xy 269.825997 -314.64813) (xy 269.868618 -314.623523)
			(xy 269.914634 -314.606071) (xy 269.962853 -314.596227) (xy 270.012028 -314.594246) (xy 270.060883 -314.600178)
			(xy 270.108154 -314.61387) (xy 270.152616 -314.634968) (xy 270.193119 -314.662924) (xy 270.228612 -314.697016)
			(xy 270.258177 -314.73636) (xy 270.281048 -314.779937) (xy 270.296632 -314.826618) (xy 270.304527 -314.875195)
			(xy 270.305022 -314.899802) (xy 313.394102 -314.899802) (xy 313.398062 -314.850748) (xy 313.409839 -314.802964)
			(xy 313.42913 -314.757688) (xy 313.455433 -314.716092) (xy 313.488068 -314.679255) (xy 313.526189 -314.64813)
			(xy 313.56881 -314.623523) (xy 313.614826 -314.606071) (xy 313.663045 -314.596227) (xy 313.71222 -314.594246)
			(xy 313.761075 -314.600178) (xy 313.808346 -314.61387) (xy 313.852808 -314.634968) (xy 313.893311 -314.662924)
			(xy 313.928804 -314.697016) (xy 313.958369 -314.73636) (xy 313.98124 -314.779937) (xy 313.996824 -314.826618)
			(xy 314.004719 -314.875195) (xy 314.005214 -314.899802) (xy 314.344062 -314.899802) (xy 314.348022 -314.850748)
			(xy 314.359799 -314.802964) (xy 314.37909 -314.757688) (xy 314.405393 -314.716092) (xy 314.438028 -314.679255)
			(xy 314.476149 -314.64813) (xy 314.51877 -314.623523) (xy 314.564786 -314.606071) (xy 314.613005 -314.596227)
			(xy 314.66218 -314.594246) (xy 314.711035 -314.600178) (xy 314.758306 -314.61387) (xy 314.802768 -314.634968)
			(xy 314.843271 -314.662924) (xy 314.878764 -314.697016) (xy 314.908329 -314.73636) (xy 314.9312 -314.779937)
			(xy 314.946784 -314.826618) (xy 314.954679 -314.875195) (xy 314.955174 -314.899802) (xy 384.844048 -314.899802)
			(xy 384.848008 -314.850748) (xy 384.859785 -314.802964) (xy 384.879076 -314.757688) (xy 384.905379 -314.716092)
			(xy 384.938014 -314.679255) (xy 384.976135 -314.64813) (xy 385.018756 -314.623523) (xy 385.064772 -314.606071)
			(xy 385.112991 -314.596227) (xy 385.162166 -314.594246) (xy 385.211021 -314.600178) (xy 385.258292 -314.61387)
			(xy 385.302754 -314.634968) (xy 385.343257 -314.662924) (xy 385.37875 -314.697016) (xy 385.408315 -314.73636)
			(xy 385.431186 -314.779937) (xy 385.44677 -314.826618) (xy 385.454665 -314.875195) (xy 385.45516 -314.899802)
			(xy 385.794008 -314.899802) (xy 385.797968 -314.850748) (xy 385.809745 -314.802964) (xy 385.829036 -314.757688)
			(xy 385.855339 -314.716092) (xy 385.887974 -314.679255) (xy 385.926095 -314.64813) (xy 385.968716 -314.623523)
			(xy 386.014732 -314.606071) (xy 386.062951 -314.596227) (xy 386.112126 -314.594246) (xy 386.160981 -314.600178)
			(xy 386.208252 -314.61387) (xy 386.252714 -314.634968) (xy 386.293217 -314.662924) (xy 386.32871 -314.697016)
			(xy 386.358275 -314.73636) (xy 386.381146 -314.779937) (xy 386.39673 -314.826618) (xy 386.404625 -314.875195)
			(xy 386.40512 -314.899802) (xy 429.4942 -314.899802) (xy 429.49816 -314.850748) (xy 429.509937 -314.802964)
			(xy 429.529228 -314.757688) (xy 429.555531 -314.716092) (xy 429.588166 -314.679255) (xy 429.626287 -314.64813)
			(xy 429.668908 -314.623523) (xy 429.714924 -314.606071) (xy 429.763143 -314.596227) (xy 429.812318 -314.594246)
			(xy 429.861173 -314.600178) (xy 429.908444 -314.61387) (xy 429.952906 -314.634968) (xy 429.993409 -314.662924)
			(xy 430.028902 -314.697016) (xy 430.058467 -314.73636) (xy 430.081338 -314.779937) (xy 430.096922 -314.826618)
			(xy 430.104817 -314.875195) (xy 430.105312 -314.899802) (xy 430.44416 -314.899802) (xy 430.44812 -314.850748)
			(xy 430.459897 -314.802964) (xy 430.479188 -314.757688) (xy 430.505491 -314.716092) (xy 430.538126 -314.679255)
			(xy 430.576247 -314.64813) (xy 430.618868 -314.623523) (xy 430.664884 -314.606071) (xy 430.713103 -314.596227)
			(xy 430.762278 -314.594246) (xy 430.811133 -314.600178) (xy 430.858404 -314.61387) (xy 430.902866 -314.634968)
			(xy 430.943369 -314.662924) (xy 430.978862 -314.697016) (xy 431.008427 -314.73636) (xy 431.031298 -314.779937)
			(xy 431.046882 -314.826618) (xy 431.054777 -314.875195) (xy 431.055272 -314.899802) (xy 431.054777 -314.924409)
			(xy 431.046882 -314.972986) (xy 431.031298 -315.019667) (xy 431.008427 -315.063244) (xy 430.978862 -315.102588)
			(xy 430.943369 -315.13668) (xy 430.902866 -315.164636) (xy 430.858404 -315.185734) (xy 430.811133 -315.199426)
			(xy 430.762278 -315.205358) (xy 430.713103 -315.203377) (xy 430.664884 -315.193533) (xy 430.618868 -315.176081)
			(xy 430.576247 -315.151474) (xy 430.538126 -315.120349) (xy 430.505491 -315.083512) (xy 430.479188 -315.041916)
			(xy 430.459897 -314.99664) (xy 430.44812 -314.948856) (xy 430.44416 -314.899802) (xy 430.105312 -314.899802)
			(xy 430.104817 -314.924409) (xy 430.096922 -314.972986) (xy 430.081338 -315.019667) (xy 430.058467 -315.063244)
			(xy 430.028902 -315.102588) (xy 429.993409 -315.13668) (xy 429.952906 -315.164636) (xy 429.908444 -315.185734)
			(xy 429.861173 -315.199426) (xy 429.812318 -315.205358) (xy 429.763143 -315.203377) (xy 429.714924 -315.193533)
			(xy 429.668908 -315.176081) (xy 429.626287 -315.151474) (xy 429.588166 -315.120349) (xy 429.555531 -315.083512)
			(xy 429.529228 -315.041916) (xy 429.509937 -314.99664) (xy 429.49816 -314.948856) (xy 429.4942 -314.899802)
			(xy 386.40512 -314.899802) (xy 386.404625 -314.924409) (xy 386.39673 -314.972986) (xy 386.381146 -315.019667)
			(xy 386.358275 -315.063244) (xy 386.32871 -315.102588) (xy 386.293217 -315.13668) (xy 386.252714 -315.164636)
			(xy 386.208252 -315.185734) (xy 386.160981 -315.199426) (xy 386.112126 -315.205358) (xy 386.062951 -315.203377)
			(xy 386.014732 -315.193533) (xy 385.968716 -315.176081) (xy 385.926095 -315.151474) (xy 385.887974 -315.120349)
			(xy 385.855339 -315.083512) (xy 385.829036 -315.041916) (xy 385.809745 -314.99664) (xy 385.797968 -314.948856)
			(xy 385.794008 -314.899802) (xy 385.45516 -314.899802) (xy 385.454665 -314.924409) (xy 385.44677 -314.972986)
			(xy 385.431186 -315.019667) (xy 385.408315 -315.063244) (xy 385.37875 -315.102588) (xy 385.343257 -315.13668)
			(xy 385.302754 -315.164636) (xy 385.258292 -315.185734) (xy 385.211021 -315.199426) (xy 385.162166 -315.205358)
			(xy 385.112991 -315.203377) (xy 385.064772 -315.193533) (xy 385.018756 -315.176081) (xy 384.976135 -315.151474)
			(xy 384.938014 -315.120349) (xy 384.905379 -315.083512) (xy 384.879076 -315.041916) (xy 384.859785 -314.99664)
			(xy 384.848008 -314.948856) (xy 384.844048 -314.899802) (xy 314.955174 -314.899802) (xy 314.954679 -314.924409)
			(xy 314.946784 -314.972986) (xy 314.9312 -315.019667) (xy 314.908329 -315.063244) (xy 314.878764 -315.102588)
			(xy 314.843271 -315.13668) (xy 314.802768 -315.164636) (xy 314.758306 -315.185734) (xy 314.711035 -315.199426)
			(xy 314.66218 -315.205358) (xy 314.613005 -315.203377) (xy 314.564786 -315.193533) (xy 314.51877 -315.176081)
			(xy 314.476149 -315.151474) (xy 314.438028 -315.120349) (xy 314.405393 -315.083512) (xy 314.37909 -315.041916)
			(xy 314.359799 -314.99664) (xy 314.348022 -314.948856) (xy 314.344062 -314.899802) (xy 314.005214 -314.899802)
			(xy 314.004719 -314.924409) (xy 313.996824 -314.972986) (xy 313.98124 -315.019667) (xy 313.958369 -315.063244)
			(xy 313.928804 -315.102588) (xy 313.893311 -315.13668) (xy 313.852808 -315.164636) (xy 313.808346 -315.185734)
			(xy 313.761075 -315.199426) (xy 313.71222 -315.205358) (xy 313.663045 -315.203377) (xy 313.614826 -315.193533)
			(xy 313.56881 -315.176081) (xy 313.526189 -315.151474) (xy 313.488068 -315.120349) (xy 313.455433 -315.083512)
			(xy 313.42913 -315.041916) (xy 313.409839 -314.99664) (xy 313.398062 -314.948856) (xy 313.394102 -314.899802)
			(xy 270.305022 -314.899802) (xy 270.304527 -314.924409) (xy 270.296632 -314.972986) (xy 270.281048 -315.019667)
			(xy 270.258177 -315.063244) (xy 270.228612 -315.102588) (xy 270.193119 -315.13668) (xy 270.152616 -315.164636)
			(xy 270.108154 -315.185734) (xy 270.060883 -315.199426) (xy 270.012028 -315.205358) (xy 269.962853 -315.203377)
			(xy 269.914634 -315.193533) (xy 269.868618 -315.176081) (xy 269.825997 -315.151474) (xy 269.787876 -315.120349)
			(xy 269.755241 -315.083512) (xy 269.728938 -315.041916) (xy 269.709647 -314.99664) (xy 269.69787 -314.948856)
			(xy 269.69391 -314.899802) (xy 269.355062 -314.899802) (xy 269.354567 -314.924409) (xy 269.346672 -314.972986)
			(xy 269.331088 -315.019667) (xy 269.308217 -315.063244) (xy 269.278652 -315.102588) (xy 269.243159 -315.13668)
			(xy 269.202656 -315.164636) (xy 269.158194 -315.185734) (xy 269.110923 -315.199426) (xy 269.062068 -315.205358)
			(xy 269.012893 -315.203377) (xy 268.964674 -315.193533) (xy 268.918658 -315.176081) (xy 268.876037 -315.151474)
			(xy 268.837916 -315.120349) (xy 268.805281 -315.083512) (xy 268.778978 -315.041916) (xy 268.759687 -314.99664)
			(xy 268.74791 -314.948856) (xy 268.74395 -314.899802) (xy 198.85533 -314.899802) (xy 198.854835 -314.924409)
			(xy 198.84694 -314.972986) (xy 198.831356 -315.019667) (xy 198.808485 -315.063244) (xy 198.77892 -315.102588)
			(xy 198.743427 -315.13668) (xy 198.702924 -315.164636) (xy 198.658462 -315.185734) (xy 198.611191 -315.199426)
			(xy 198.562336 -315.205358) (xy 198.513161 -315.203377) (xy 198.464942 -315.193533) (xy 198.418926 -315.176081)
			(xy 198.376305 -315.151474) (xy 198.338184 -315.120349) (xy 198.305549 -315.083512) (xy 198.279246 -315.041916)
			(xy 198.259955 -314.99664) (xy 198.248178 -314.948856) (xy 198.244218 -314.899802) (xy 197.90537 -314.899802)
			(xy 197.904875 -314.924409) (xy 197.89698 -314.972986) (xy 197.881396 -315.019667) (xy 197.858525 -315.063244)
			(xy 197.82896 -315.102588) (xy 197.793467 -315.13668) (xy 197.752964 -315.164636) (xy 197.708502 -315.185734)
			(xy 197.661231 -315.199426) (xy 197.612376 -315.205358) (xy 197.563201 -315.203377) (xy 197.514982 -315.193533)
			(xy 197.468966 -315.176081) (xy 197.426345 -315.151474) (xy 197.388224 -315.120349) (xy 197.355589 -315.083512)
			(xy 197.329286 -315.041916) (xy 197.309995 -314.99664) (xy 197.298218 -314.948856) (xy 197.294258 -314.899802)
			(xy 154.205178 -314.899802) (xy 154.204683 -314.924409) (xy 154.196788 -314.972986) (xy 154.181204 -315.019667)
			(xy 154.158333 -315.063244) (xy 154.128768 -315.102588) (xy 154.093275 -315.13668) (xy 154.052772 -315.164636)
			(xy 154.00831 -315.185734) (xy 153.961039 -315.199426) (xy 153.912184 -315.205358) (xy 153.863009 -315.203377)
			(xy 153.81479 -315.193533) (xy 153.768774 -315.176081) (xy 153.726153 -315.151474) (xy 153.688032 -315.120349)
			(xy 153.655397 -315.083512) (xy 153.629094 -315.041916) (xy 153.609803 -314.99664) (xy 153.598026 -314.948856)
			(xy 153.594066 -314.899802) (xy 153.255218 -314.899802) (xy 153.254723 -314.924409) (xy 153.246828 -314.972986)
			(xy 153.231244 -315.019667) (xy 153.208373 -315.063244) (xy 153.178808 -315.102588) (xy 153.143315 -315.13668)
			(xy 153.102812 -315.164636) (xy 153.05835 -315.185734) (xy 153.011079 -315.199426) (xy 152.962224 -315.205358)
			(xy 152.913049 -315.203377) (xy 152.86483 -315.193533) (xy 152.818814 -315.176081) (xy 152.776193 -315.151474)
			(xy 152.738072 -315.120349) (xy 152.705437 -315.083512) (xy 152.679134 -315.041916) (xy 152.659843 -314.99664)
			(xy 152.648066 -314.948856) (xy 152.644106 -314.899802) (xy 82.755232 -314.899802) (xy 82.754737 -314.924409)
			(xy 82.746842 -314.972986) (xy 82.731258 -315.019667) (xy 82.708387 -315.063244) (xy 82.678822 -315.102588)
			(xy 82.643329 -315.13668) (xy 82.602826 -315.164636) (xy 82.558364 -315.185734) (xy 82.511093 -315.199426)
			(xy 82.462238 -315.205358) (xy 82.413063 -315.203377) (xy 82.364844 -315.193533) (xy 82.318828 -315.176081)
			(xy 82.276207 -315.151474) (xy 82.238086 -315.120349) (xy 82.205451 -315.083512) (xy 82.179148 -315.041916)
			(xy 82.159857 -314.99664) (xy 82.14808 -314.948856) (xy 82.14412 -314.899802) (xy 81.805272 -314.899802)
			(xy 81.804777 -314.924409) (xy 81.796882 -314.972986) (xy 81.781298 -315.019667) (xy 81.758427 -315.063244)
			(xy 81.728862 -315.102588) (xy 81.693369 -315.13668) (xy 81.652866 -315.164636) (xy 81.608404 -315.185734)
			(xy 81.561133 -315.199426) (xy 81.512278 -315.205358) (xy 81.463103 -315.203377) (xy 81.414884 -315.193533)
			(xy 81.368868 -315.176081) (xy 81.326247 -315.151474) (xy 81.288126 -315.120349) (xy 81.255491 -315.083512)
			(xy 81.229188 -315.041916) (xy 81.209897 -314.99664) (xy 81.19812 -314.948856) (xy 81.19416 -314.899802)
			(xy 38.10508 -314.899802) (xy 38.104585 -314.924409) (xy 38.09669 -314.972986) (xy 38.081106 -315.019667)
			(xy 38.058235 -315.063244) (xy 38.02867 -315.102588) (xy 37.993177 -315.13668) (xy 37.952674 -315.164636)
			(xy 37.908212 -315.185734) (xy 37.860941 -315.199426) (xy 37.812086 -315.205358) (xy 37.762911 -315.203377)
			(xy 37.714692 -315.193533) (xy 37.668676 -315.176081) (xy 37.626055 -315.151474) (xy 37.587934 -315.120349)
			(xy 37.555299 -315.083512) (xy 37.528996 -315.041916) (xy 37.509705 -314.99664) (xy 37.497928 -314.948856)
			(xy 37.493968 -314.899802) (xy 37.15512 -314.899802) (xy 37.154625 -314.924409) (xy 37.14673 -314.972986)
			(xy 37.131146 -315.019667) (xy 37.108275 -315.063244) (xy 37.07871 -315.102588) (xy 37.043217 -315.13668)
			(xy 37.002714 -315.164636) (xy 36.958252 -315.185734) (xy 36.910981 -315.199426) (xy 36.862126 -315.205358)
			(xy 36.812951 -315.203377) (xy 36.764732 -315.193533) (xy 36.718716 -315.176081) (xy 36.676095 -315.151474)
			(xy 36.637974 -315.120349) (xy 36.605339 -315.083512) (xy 36.579036 -315.041916) (xy 36.559745 -314.99664)
			(xy 36.547968 -314.948856) (xy 36.544008 -314.899802) (xy 0.508 -314.899802) (xy 0.508 -315.849762)
			(xy 50.79417 -315.849762) (xy 50.79813 -315.800708) (xy 50.809907 -315.752924) (xy 50.829198 -315.707648)
			(xy 50.855501 -315.666052) (xy 50.888136 -315.629215) (xy 50.926257 -315.59809) (xy 50.968878 -315.573483)
			(xy 51.014894 -315.556031) (xy 51.063113 -315.546187) (xy 51.112288 -315.544206) (xy 51.161143 -315.550138)
			(xy 51.208414 -315.56383) (xy 51.252876 -315.584928) (xy 51.293379 -315.612884) (xy 51.328872 -315.646976)
			(xy 51.358437 -315.68632) (xy 51.381308 -315.729897) (xy 51.396892 -315.776578) (xy 51.404787 -315.825155)
			(xy 51.405282 -315.849762) (xy 52.69409 -315.849762) (xy 52.69805 -315.800708) (xy 52.709827 -315.752924)
			(xy 52.729118 -315.707648) (xy 52.755421 -315.666052) (xy 52.788056 -315.629215) (xy 52.826177 -315.59809)
			(xy 52.868798 -315.573483) (xy 52.914814 -315.556031) (xy 52.963033 -315.546187) (xy 53.012208 -315.544206)
			(xy 53.061063 -315.550138) (xy 53.108334 -315.56383) (xy 53.152796 -315.584928) (xy 53.193299 -315.612884)
			(xy 53.228792 -315.646976) (xy 53.258357 -315.68632) (xy 53.281228 -315.729897) (xy 53.296812 -315.776578)
			(xy 53.304707 -315.825155) (xy 53.305202 -315.849762) (xy 54.59401 -315.849762) (xy 54.59797 -315.800708)
			(xy 54.609747 -315.752924) (xy 54.629038 -315.707648) (xy 54.655341 -315.666052) (xy 54.687976 -315.629215)
			(xy 54.726097 -315.59809) (xy 54.768718 -315.573483) (xy 54.814734 -315.556031) (xy 54.862953 -315.546187)
			(xy 54.912128 -315.544206) (xy 54.960983 -315.550138) (xy 55.008254 -315.56383) (xy 55.052716 -315.584928)
			(xy 55.093219 -315.612884) (xy 55.128712 -315.646976) (xy 55.158277 -315.68632) (xy 55.181148 -315.729897)
			(xy 55.196732 -315.776578) (xy 55.204627 -315.825155) (xy 55.205122 -315.849762) (xy 56.494184 -315.849762)
			(xy 56.498144 -315.800708) (xy 56.509921 -315.752924) (xy 56.529212 -315.707648) (xy 56.555515 -315.666052)
			(xy 56.58815 -315.629215) (xy 56.626271 -315.59809) (xy 56.668892 -315.573483) (xy 56.714908 -315.556031)
			(xy 56.763127 -315.546187) (xy 56.812302 -315.544206) (xy 56.861157 -315.550138) (xy 56.908428 -315.56383)
			(xy 56.95289 -315.584928) (xy 56.993393 -315.612884) (xy 57.028886 -315.646976) (xy 57.058451 -315.68632)
			(xy 57.081322 -315.729897) (xy 57.096906 -315.776578) (xy 57.104801 -315.825155) (xy 57.105296 -315.849762)
			(xy 58.394104 -315.849762) (xy 58.398064 -315.800708) (xy 58.409841 -315.752924) (xy 58.429132 -315.707648)
			(xy 58.455435 -315.666052) (xy 58.48807 -315.629215) (xy 58.526191 -315.59809) (xy 58.568812 -315.573483)
			(xy 58.614828 -315.556031) (xy 58.663047 -315.546187) (xy 58.712222 -315.544206) (xy 58.761077 -315.550138)
			(xy 58.808348 -315.56383) (xy 58.85281 -315.584928) (xy 58.893313 -315.612884) (xy 58.928806 -315.646976)
			(xy 58.958371 -315.68632) (xy 58.981242 -315.729897) (xy 58.996826 -315.776578) (xy 59.004721 -315.825155)
			(xy 59.005216 -315.849762) (xy 60.294024 -315.849762) (xy 60.297984 -315.800708) (xy 60.309761 -315.752924)
			(xy 60.329052 -315.707648) (xy 60.355355 -315.666052) (xy 60.38799 -315.629215) (xy 60.426111 -315.59809)
			(xy 60.468732 -315.573483) (xy 60.514748 -315.556031) (xy 60.562967 -315.546187) (xy 60.612142 -315.544206)
			(xy 60.660997 -315.550138) (xy 60.708268 -315.56383) (xy 60.75273 -315.584928) (xy 60.793233 -315.612884)
			(xy 60.828726 -315.646976) (xy 60.858291 -315.68632) (xy 60.881162 -315.729897) (xy 60.896746 -315.776578)
			(xy 60.904641 -315.825155) (xy 60.905136 -315.849762) (xy 62.193944 -315.849762) (xy 62.197904 -315.800708)
			(xy 62.209681 -315.752924) (xy 62.228972 -315.707648) (xy 62.255275 -315.666052) (xy 62.28791 -315.629215)
			(xy 62.326031 -315.59809) (xy 62.368652 -315.573483) (xy 62.414668 -315.556031) (xy 62.462887 -315.546187)
			(xy 62.512062 -315.544206) (xy 62.560917 -315.550138) (xy 62.608188 -315.56383) (xy 62.65265 -315.584928)
			(xy 62.693153 -315.612884) (xy 62.728646 -315.646976) (xy 62.758211 -315.68632) (xy 62.781082 -315.729897)
			(xy 62.796666 -315.776578) (xy 62.804561 -315.825155) (xy 62.805056 -315.849762) (xy 64.094118 -315.849762)
			(xy 64.098078 -315.800708) (xy 64.109855 -315.752924) (xy 64.129146 -315.707648) (xy 64.155449 -315.666052)
			(xy 64.188084 -315.629215) (xy 64.226205 -315.59809) (xy 64.268826 -315.573483) (xy 64.314842 -315.556031)
			(xy 64.363061 -315.546187) (xy 64.412236 -315.544206) (xy 64.461091 -315.550138) (xy 64.508362 -315.56383)
			(xy 64.552824 -315.584928) (xy 64.593327 -315.612884) (xy 64.62882 -315.646976) (xy 64.658385 -315.68632)
			(xy 64.681256 -315.729897) (xy 64.69684 -315.776578) (xy 64.704735 -315.825155) (xy 64.70523 -315.849762)
			(xy 73.593972 -315.849762) (xy 73.597932 -315.800708) (xy 73.609709 -315.752924) (xy 73.629 -315.707648)
			(xy 73.655303 -315.666052) (xy 73.687938 -315.629215) (xy 73.726059 -315.59809) (xy 73.76868 -315.573483)
			(xy 73.814696 -315.556031) (xy 73.862915 -315.546187) (xy 73.91209 -315.544206) (xy 73.960945 -315.550138)
			(xy 74.008216 -315.56383) (xy 74.052678 -315.584928) (xy 74.093181 -315.612884) (xy 74.128674 -315.646976)
			(xy 74.158239 -315.68632) (xy 74.18111 -315.729897) (xy 74.196694 -315.776578) (xy 74.204589 -315.825155)
			(xy 74.205084 -315.849762) (xy 75.494146 -315.849762) (xy 75.498106 -315.800708) (xy 75.509883 -315.752924)
			(xy 75.529174 -315.707648) (xy 75.555477 -315.666052) (xy 75.588112 -315.629215) (xy 75.626233 -315.59809)
			(xy 75.668854 -315.573483) (xy 75.71487 -315.556031) (xy 75.763089 -315.546187) (xy 75.812264 -315.544206)
			(xy 75.861119 -315.550138) (xy 75.90839 -315.56383) (xy 75.952852 -315.584928) (xy 75.993355 -315.612884)
			(xy 76.028848 -315.646976) (xy 76.058413 -315.68632) (xy 76.081284 -315.729897) (xy 76.096868 -315.776578)
			(xy 76.104763 -315.825155) (xy 76.105258 -315.849762) (xy 77.394066 -315.849762) (xy 77.398026 -315.800708)
			(xy 77.409803 -315.752924) (xy 77.429094 -315.707648) (xy 77.455397 -315.666052) (xy 77.488032 -315.629215)
			(xy 77.526153 -315.59809) (xy 77.568774 -315.573483) (xy 77.61479 -315.556031) (xy 77.663009 -315.546187)
			(xy 77.712184 -315.544206) (xy 77.761039 -315.550138) (xy 77.80831 -315.56383) (xy 77.852772 -315.584928)
			(xy 77.893275 -315.612884) (xy 77.928768 -315.646976) (xy 77.958333 -315.68632) (xy 77.981204 -315.729897)
			(xy 77.996788 -315.776578) (xy 78.004683 -315.825155) (xy 78.005178 -315.849762) (xy 79.293986 -315.849762)
			(xy 79.297946 -315.800708) (xy 79.309723 -315.752924) (xy 79.329014 -315.707648) (xy 79.355317 -315.666052)
			(xy 79.387952 -315.629215) (xy 79.426073 -315.59809) (xy 79.468694 -315.573483) (xy 79.51471 -315.556031)
			(xy 79.562929 -315.546187) (xy 79.612104 -315.544206) (xy 79.660959 -315.550138) (xy 79.70823 -315.56383)
			(xy 79.752692 -315.584928) (xy 79.793195 -315.612884) (xy 79.828688 -315.646976) (xy 79.858253 -315.68632)
			(xy 79.881124 -315.729897) (xy 79.896708 -315.776578) (xy 79.904603 -315.825155) (xy 79.905098 -315.849762)
			(xy 155.49424 -315.849762) (xy 155.4982 -315.800708) (xy 155.509977 -315.752924) (xy 155.529268 -315.707648)
			(xy 155.555571 -315.666052) (xy 155.588206 -315.629215) (xy 155.626327 -315.59809) (xy 155.668948 -315.573483)
			(xy 155.714964 -315.556031) (xy 155.763183 -315.546187) (xy 155.812358 -315.544206) (xy 155.861213 -315.550138)
			(xy 155.908484 -315.56383) (xy 155.952946 -315.584928) (xy 155.993449 -315.612884) (xy 156.028942 -315.646976)
			(xy 156.058507 -315.68632) (xy 156.081378 -315.729897) (xy 156.096962 -315.776578) (xy 156.104857 -315.825155)
			(xy 156.105352 -315.849762) (xy 157.39416 -315.849762) (xy 157.39812 -315.800708) (xy 157.409897 -315.752924)
			(xy 157.429188 -315.707648) (xy 157.455491 -315.666052) (xy 157.488126 -315.629215) (xy 157.526247 -315.59809)
			(xy 157.568868 -315.573483) (xy 157.614884 -315.556031) (xy 157.663103 -315.546187) (xy 157.712278 -315.544206)
			(xy 157.761133 -315.550138) (xy 157.808404 -315.56383) (xy 157.852866 -315.584928) (xy 157.893369 -315.612884)
			(xy 157.928862 -315.646976) (xy 157.958427 -315.68632) (xy 157.981298 -315.729897) (xy 157.996882 -315.776578)
			(xy 158.004777 -315.825155) (xy 158.005272 -315.849762) (xy 159.29408 -315.849762) (xy 159.29804 -315.800708)
			(xy 159.309817 -315.752924) (xy 159.329108 -315.707648) (xy 159.355411 -315.666052) (xy 159.388046 -315.629215)
			(xy 159.426167 -315.59809) (xy 159.468788 -315.573483) (xy 159.514804 -315.556031) (xy 159.563023 -315.546187)
			(xy 159.612198 -315.544206) (xy 159.661053 -315.550138) (xy 159.708324 -315.56383) (xy 159.752786 -315.584928)
			(xy 159.793289 -315.612884) (xy 159.828782 -315.646976) (xy 159.858347 -315.68632) (xy 159.881218 -315.729897)
			(xy 159.896802 -315.776578) (xy 159.904697 -315.825155) (xy 159.905192 -315.849762) (xy 161.194254 -315.849762)
			(xy 161.198214 -315.800708) (xy 161.209991 -315.752924) (xy 161.229282 -315.707648) (xy 161.255585 -315.666052)
			(xy 161.28822 -315.629215) (xy 161.326341 -315.59809) (xy 161.368962 -315.573483) (xy 161.414978 -315.556031)
			(xy 161.463197 -315.546187) (xy 161.512372 -315.544206) (xy 161.561227 -315.550138) (xy 161.608498 -315.56383)
			(xy 161.65296 -315.584928) (xy 161.693463 -315.612884) (xy 161.728956 -315.646976) (xy 161.758521 -315.68632)
			(xy 161.781392 -315.729897) (xy 161.796976 -315.776578) (xy 161.804871 -315.825155) (xy 161.805366 -315.849762)
			(xy 163.094174 -315.849762) (xy 163.098134 -315.800708) (xy 163.109911 -315.752924) (xy 163.129202 -315.707648)
			(xy 163.155505 -315.666052) (xy 163.18814 -315.629215) (xy 163.226261 -315.59809) (xy 163.268882 -315.573483)
			(xy 163.314898 -315.556031) (xy 163.363117 -315.546187) (xy 163.412292 -315.544206) (xy 163.461147 -315.550138)
			(xy 163.508418 -315.56383) (xy 163.55288 -315.584928) (xy 163.593383 -315.612884) (xy 163.628876 -315.646976)
			(xy 163.658441 -315.68632) (xy 163.681312 -315.729897) (xy 163.696896 -315.776578) (xy 163.704791 -315.825155)
			(xy 163.705286 -315.849762) (xy 164.994094 -315.849762) (xy 164.998054 -315.800708) (xy 165.009831 -315.752924)
			(xy 165.029122 -315.707648) (xy 165.055425 -315.666052) (xy 165.08806 -315.629215) (xy 165.126181 -315.59809)
			(xy 165.168802 -315.573483) (xy 165.214818 -315.556031) (xy 165.263037 -315.546187) (xy 165.312212 -315.544206)
			(xy 165.361067 -315.550138) (xy 165.408338 -315.56383) (xy 165.4528 -315.584928) (xy 165.493303 -315.612884)
			(xy 165.528796 -315.646976) (xy 165.558361 -315.68632) (xy 165.581232 -315.729897) (xy 165.596816 -315.776578)
			(xy 165.604711 -315.825155) (xy 165.605206 -315.849762) (xy 182.094136 -315.849762) (xy 182.098096 -315.800708)
			(xy 182.109873 -315.752924) (xy 182.129164 -315.707648) (xy 182.155467 -315.666052) (xy 182.188102 -315.629215)
			(xy 182.226223 -315.59809) (xy 182.268844 -315.573483) (xy 182.31486 -315.556031) (xy 182.363079 -315.546187)
			(xy 182.412254 -315.544206) (xy 182.461109 -315.550138) (xy 182.50838 -315.56383) (xy 182.552842 -315.584928)
			(xy 182.593345 -315.612884) (xy 182.628838 -315.646976) (xy 182.658403 -315.68632) (xy 182.681274 -315.729897)
			(xy 182.696858 -315.776578) (xy 182.704753 -315.825155) (xy 182.705248 -315.849762) (xy 183.994056 -315.849762)
			(xy 183.998016 -315.800708) (xy 184.009793 -315.752924) (xy 184.029084 -315.707648) (xy 184.055387 -315.666052)
			(xy 184.088022 -315.629215) (xy 184.126143 -315.59809) (xy 184.168764 -315.573483) (xy 184.21478 -315.556031)
			(xy 184.262999 -315.546187) (xy 184.312174 -315.544206) (xy 184.361029 -315.550138) (xy 184.4083 -315.56383)
			(xy 184.452762 -315.584928) (xy 184.493265 -315.612884) (xy 184.528758 -315.646976) (xy 184.558323 -315.68632)
			(xy 184.581194 -315.729897) (xy 184.596778 -315.776578) (xy 184.604673 -315.825155) (xy 184.605168 -315.849762)
			(xy 185.89423 -315.849762) (xy 185.89819 -315.800708) (xy 185.909967 -315.752924) (xy 185.929258 -315.707648)
			(xy 185.955561 -315.666052) (xy 185.988196 -315.629215) (xy 186.026317 -315.59809) (xy 186.068938 -315.573483)
			(xy 186.114954 -315.556031) (xy 186.163173 -315.546187) (xy 186.212348 -315.544206) (xy 186.261203 -315.550138)
			(xy 186.308474 -315.56383) (xy 186.352936 -315.584928) (xy 186.393439 -315.612884) (xy 186.428932 -315.646976)
			(xy 186.458497 -315.68632) (xy 186.481368 -315.729897) (xy 186.496952 -315.776578) (xy 186.504847 -315.825155)
			(xy 186.505342 -315.849762) (xy 187.79415 -315.849762) (xy 187.79811 -315.800708) (xy 187.809887 -315.752924)
			(xy 187.829178 -315.707648) (xy 187.855481 -315.666052) (xy 187.888116 -315.629215) (xy 187.926237 -315.59809)
			(xy 187.968858 -315.573483) (xy 188.014874 -315.556031) (xy 188.063093 -315.546187) (xy 188.112268 -315.544206)
			(xy 188.161123 -315.550138) (xy 188.208394 -315.56383) (xy 188.252856 -315.584928) (xy 188.293359 -315.612884)
			(xy 188.328852 -315.646976) (xy 188.358417 -315.68632) (xy 188.381288 -315.729897) (xy 188.396872 -315.776578)
			(xy 188.404767 -315.825155) (xy 188.405262 -315.849762) (xy 282.994112 -315.849762) (xy 282.998072 -315.800708)
			(xy 283.009849 -315.752924) (xy 283.02914 -315.707648) (xy 283.055443 -315.666052) (xy 283.088078 -315.629215)
			(xy 283.126199 -315.59809) (xy 283.16882 -315.573483) (xy 283.214836 -315.556031) (xy 283.263055 -315.546187)
			(xy 283.31223 -315.544206) (xy 283.361085 -315.550138) (xy 283.408356 -315.56383) (xy 283.452818 -315.584928)
			(xy 283.493321 -315.612884) (xy 283.528814 -315.646976) (xy 283.558379 -315.68632) (xy 283.58125 -315.729897)
			(xy 283.596834 -315.776578) (xy 283.604729 -315.825155) (xy 283.605224 -315.849762) (xy 284.894032 -315.849762)
			(xy 284.897992 -315.800708) (xy 284.909769 -315.752924) (xy 284.92906 -315.707648) (xy 284.955363 -315.666052)
			(xy 284.987998 -315.629215) (xy 285.026119 -315.59809) (xy 285.06874 -315.573483) (xy 285.114756 -315.556031)
			(xy 285.162975 -315.546187) (xy 285.21215 -315.544206) (xy 285.261005 -315.550138) (xy 285.308276 -315.56383)
			(xy 285.352738 -315.584928) (xy 285.393241 -315.612884) (xy 285.428734 -315.646976) (xy 285.458299 -315.68632)
			(xy 285.48117 -315.729897) (xy 285.496754 -315.776578) (xy 285.504649 -315.825155) (xy 285.505144 -315.849762)
			(xy 286.793952 -315.849762) (xy 286.797912 -315.800708) (xy 286.809689 -315.752924) (xy 286.82898 -315.707648)
			(xy 286.855283 -315.666052) (xy 286.887918 -315.629215) (xy 286.926039 -315.59809) (xy 286.96866 -315.573483)
			(xy 287.014676 -315.556031) (xy 287.062895 -315.546187) (xy 287.11207 -315.544206) (xy 287.160925 -315.550138)
			(xy 287.208196 -315.56383) (xy 287.252658 -315.584928) (xy 287.293161 -315.612884) (xy 287.328654 -315.646976)
			(xy 287.358219 -315.68632) (xy 287.38109 -315.729897) (xy 287.396674 -315.776578) (xy 287.404569 -315.825155)
			(xy 287.405064 -315.849762) (xy 288.694126 -315.849762) (xy 288.698086 -315.800708) (xy 288.709863 -315.752924)
			(xy 288.729154 -315.707648) (xy 288.755457 -315.666052) (xy 288.788092 -315.629215) (xy 288.826213 -315.59809)
			(xy 288.868834 -315.573483) (xy 288.91485 -315.556031) (xy 288.963069 -315.546187) (xy 289.012244 -315.544206)
			(xy 289.061099 -315.550138) (xy 289.10837 -315.56383) (xy 289.152832 -315.584928) (xy 289.193335 -315.612884)
			(xy 289.228828 -315.646976) (xy 289.258393 -315.68632) (xy 289.281264 -315.729897) (xy 289.296848 -315.776578)
			(xy 289.304743 -315.825155) (xy 289.305238 -315.849762) (xy 290.594046 -315.849762) (xy 290.598006 -315.800708)
			(xy 290.609783 -315.752924) (xy 290.629074 -315.707648) (xy 290.655377 -315.666052) (xy 290.688012 -315.629215)
			(xy 290.726133 -315.59809) (xy 290.768754 -315.573483) (xy 290.81477 -315.556031) (xy 290.862989 -315.546187)
			(xy 290.912164 -315.544206) (xy 290.961019 -315.550138) (xy 291.00829 -315.56383) (xy 291.052752 -315.584928)
			(xy 291.093255 -315.612884) (xy 291.128748 -315.646976) (xy 291.158313 -315.68632) (xy 291.181184 -315.729897)
			(xy 291.196768 -315.776578) (xy 291.204663 -315.825155) (xy 291.205158 -315.849762) (xy 292.493966 -315.849762)
			(xy 292.497926 -315.800708) (xy 292.509703 -315.752924) (xy 292.528994 -315.707648) (xy 292.555297 -315.666052)
			(xy 292.587932 -315.629215) (xy 292.626053 -315.59809) (xy 292.668674 -315.573483) (xy 292.71469 -315.556031)
			(xy 292.762909 -315.546187) (xy 292.812084 -315.544206) (xy 292.860939 -315.550138) (xy 292.90821 -315.56383)
			(xy 292.952672 -315.584928) (xy 292.993175 -315.612884) (xy 293.028668 -315.646976) (xy 293.058233 -315.68632)
			(xy 293.081104 -315.729897) (xy 293.096688 -315.776578) (xy 293.104583 -315.825155) (xy 293.105078 -315.849762)
			(xy 294.393886 -315.849762) (xy 294.397846 -315.800708) (xy 294.409623 -315.752924) (xy 294.428914 -315.707648)
			(xy 294.455217 -315.666052) (xy 294.487852 -315.629215) (xy 294.525973 -315.59809) (xy 294.568594 -315.573483)
			(xy 294.61461 -315.556031) (xy 294.662829 -315.546187) (xy 294.712004 -315.544206) (xy 294.760859 -315.550138)
			(xy 294.80813 -315.56383) (xy 294.852592 -315.584928) (xy 294.893095 -315.612884) (xy 294.928588 -315.646976)
			(xy 294.958153 -315.68632) (xy 294.981024 -315.729897) (xy 294.996608 -315.776578) (xy 295.004503 -315.825155)
			(xy 295.004998 -315.849762) (xy 296.29406 -315.849762) (xy 296.29802 -315.800708) (xy 296.309797 -315.752924)
			(xy 296.329088 -315.707648) (xy 296.355391 -315.666052) (xy 296.388026 -315.629215) (xy 296.426147 -315.59809)
			(xy 296.468768 -315.573483) (xy 296.514784 -315.556031) (xy 296.563003 -315.546187) (xy 296.612178 -315.544206)
			(xy 296.661033 -315.550138) (xy 296.708304 -315.56383) (xy 296.752766 -315.584928) (xy 296.793269 -315.612884)
			(xy 296.828762 -315.646976) (xy 296.858327 -315.68632) (xy 296.881198 -315.729897) (xy 296.896782 -315.776578)
			(xy 296.904677 -315.825155) (xy 296.905172 -315.849762) (xy 305.793914 -315.849762) (xy 305.797874 -315.800708)
			(xy 305.809651 -315.752924) (xy 305.828942 -315.707648) (xy 305.855245 -315.666052) (xy 305.88788 -315.629215)
			(xy 305.926001 -315.59809) (xy 305.968622 -315.573483) (xy 306.014638 -315.556031) (xy 306.062857 -315.546187)
			(xy 306.112032 -315.544206) (xy 306.160887 -315.550138) (xy 306.208158 -315.56383) (xy 306.25262 -315.584928)
			(xy 306.293123 -315.612884) (xy 306.328616 -315.646976) (xy 306.358181 -315.68632) (xy 306.381052 -315.729897)
			(xy 306.396636 -315.776578) (xy 306.404531 -315.825155) (xy 306.405026 -315.849762) (xy 307.694088 -315.849762)
			(xy 307.698048 -315.800708) (xy 307.709825 -315.752924) (xy 307.729116 -315.707648) (xy 307.755419 -315.666052)
			(xy 307.788054 -315.629215) (xy 307.826175 -315.59809) (xy 307.868796 -315.573483) (xy 307.914812 -315.556031)
			(xy 307.963031 -315.546187) (xy 308.012206 -315.544206) (xy 308.061061 -315.550138) (xy 308.108332 -315.56383)
			(xy 308.152794 -315.584928) (xy 308.193297 -315.612884) (xy 308.22879 -315.646976) (xy 308.258355 -315.68632)
			(xy 308.281226 -315.729897) (xy 308.29681 -315.776578) (xy 308.304705 -315.825155) (xy 308.3052 -315.849762)
			(xy 309.594008 -315.849762) (xy 309.597968 -315.800708) (xy 309.609745 -315.752924) (xy 309.629036 -315.707648)
			(xy 309.655339 -315.666052) (xy 309.687974 -315.629215) (xy 309.726095 -315.59809) (xy 309.768716 -315.573483)
			(xy 309.814732 -315.556031) (xy 309.862951 -315.546187) (xy 309.912126 -315.544206) (xy 309.960981 -315.550138)
			(xy 310.008252 -315.56383) (xy 310.052714 -315.584928) (xy 310.093217 -315.612884) (xy 310.12871 -315.646976)
			(xy 310.158275 -315.68632) (xy 310.181146 -315.729897) (xy 310.19673 -315.776578) (xy 310.204625 -315.825155)
			(xy 310.20512 -315.849762) (xy 311.493928 -315.849762) (xy 311.497888 -315.800708) (xy 311.509665 -315.752924)
			(xy 311.528956 -315.707648) (xy 311.555259 -315.666052) (xy 311.587894 -315.629215) (xy 311.626015 -315.59809)
			(xy 311.668636 -315.573483) (xy 311.714652 -315.556031) (xy 311.762871 -315.546187) (xy 311.812046 -315.544206)
			(xy 311.860901 -315.550138) (xy 311.908172 -315.56383) (xy 311.952634 -315.584928) (xy 311.993137 -315.612884)
			(xy 312.02863 -315.646976) (xy 312.058195 -315.68632) (xy 312.081066 -315.729897) (xy 312.09665 -315.776578)
			(xy 312.104545 -315.825155) (xy 312.10504 -315.849762) (xy 387.694182 -315.849762) (xy 387.698142 -315.800708)
			(xy 387.709919 -315.752924) (xy 387.72921 -315.707648) (xy 387.755513 -315.666052) (xy 387.788148 -315.629215)
			(xy 387.826269 -315.59809) (xy 387.86889 -315.573483) (xy 387.914906 -315.556031) (xy 387.963125 -315.546187)
			(xy 388.0123 -315.544206) (xy 388.061155 -315.550138) (xy 388.108426 -315.56383) (xy 388.152888 -315.584928)
			(xy 388.193391 -315.612884) (xy 388.228884 -315.646976) (xy 388.258449 -315.68632) (xy 388.28132 -315.729897)
			(xy 388.296904 -315.776578) (xy 388.304799 -315.825155) (xy 388.305294 -315.849762) (xy 389.594102 -315.849762)
			(xy 389.598062 -315.800708) (xy 389.609839 -315.752924) (xy 389.62913 -315.707648) (xy 389.655433 -315.666052)
			(xy 389.688068 -315.629215) (xy 389.726189 -315.59809) (xy 389.76881 -315.573483) (xy 389.814826 -315.556031)
			(xy 389.863045 -315.546187) (xy 389.91222 -315.544206) (xy 389.961075 -315.550138) (xy 390.008346 -315.56383)
			(xy 390.052808 -315.584928) (xy 390.093311 -315.612884) (xy 390.128804 -315.646976) (xy 390.158369 -315.68632)
			(xy 390.18124 -315.729897) (xy 390.196824 -315.776578) (xy 390.204719 -315.825155) (xy 390.205214 -315.849762)
			(xy 391.494022 -315.849762) (xy 391.497982 -315.800708) (xy 391.509759 -315.752924) (xy 391.52905 -315.707648)
			(xy 391.555353 -315.666052) (xy 391.587988 -315.629215) (xy 391.626109 -315.59809) (xy 391.66873 -315.573483)
			(xy 391.714746 -315.556031) (xy 391.762965 -315.546187) (xy 391.81214 -315.544206) (xy 391.860995 -315.550138)
			(xy 391.908266 -315.56383) (xy 391.952728 -315.584928) (xy 391.993231 -315.612884) (xy 392.028724 -315.646976)
			(xy 392.058289 -315.68632) (xy 392.08116 -315.729897) (xy 392.096744 -315.776578) (xy 392.104639 -315.825155)
			(xy 392.105134 -315.849762) (xy 393.394196 -315.849762) (xy 393.398156 -315.800708) (xy 393.409933 -315.752924)
			(xy 393.429224 -315.707648) (xy 393.455527 -315.666052) (xy 393.488162 -315.629215) (xy 393.526283 -315.59809)
			(xy 393.568904 -315.573483) (xy 393.61492 -315.556031) (xy 393.663139 -315.546187) (xy 393.712314 -315.544206)
			(xy 393.761169 -315.550138) (xy 393.80844 -315.56383) (xy 393.852902 -315.584928) (xy 393.893405 -315.612884)
			(xy 393.928898 -315.646976) (xy 393.958463 -315.68632) (xy 393.981334 -315.729897) (xy 393.996918 -315.776578)
			(xy 394.004813 -315.825155) (xy 394.005308 -315.849762) (xy 395.294116 -315.849762) (xy 395.298076 -315.800708)
			(xy 395.309853 -315.752924) (xy 395.329144 -315.707648) (xy 395.355447 -315.666052) (xy 395.388082 -315.629215)
			(xy 395.426203 -315.59809) (xy 395.468824 -315.573483) (xy 395.51484 -315.556031) (xy 395.563059 -315.546187)
			(xy 395.612234 -315.544206) (xy 395.661089 -315.550138) (xy 395.70836 -315.56383) (xy 395.752822 -315.584928)
			(xy 395.793325 -315.612884) (xy 395.828818 -315.646976) (xy 395.858383 -315.68632) (xy 395.881254 -315.729897)
			(xy 395.896838 -315.776578) (xy 395.904733 -315.825155) (xy 395.905228 -315.849762) (xy 397.194036 -315.849762)
			(xy 397.197996 -315.800708) (xy 397.209773 -315.752924) (xy 397.229064 -315.707648) (xy 397.255367 -315.666052)
			(xy 397.288002 -315.629215) (xy 397.326123 -315.59809) (xy 397.368744 -315.573483) (xy 397.41476 -315.556031)
			(xy 397.462979 -315.546187) (xy 397.512154 -315.544206) (xy 397.561009 -315.550138) (xy 397.60828 -315.56383)
			(xy 397.652742 -315.584928) (xy 397.693245 -315.612884) (xy 397.728738 -315.646976) (xy 397.758303 -315.68632)
			(xy 397.781174 -315.729897) (xy 397.796758 -315.776578) (xy 397.804653 -315.825155) (xy 397.805148 -315.849762)
			(xy 414.294078 -315.849762) (xy 414.298038 -315.800708) (xy 414.309815 -315.752924) (xy 414.329106 -315.707648)
			(xy 414.355409 -315.666052) (xy 414.388044 -315.629215) (xy 414.426165 -315.59809) (xy 414.468786 -315.573483)
			(xy 414.514802 -315.556031) (xy 414.563021 -315.546187) (xy 414.612196 -315.544206) (xy 414.661051 -315.550138)
			(xy 414.708322 -315.56383) (xy 414.752784 -315.584928) (xy 414.793287 -315.612884) (xy 414.82878 -315.646976)
			(xy 414.858345 -315.68632) (xy 414.881216 -315.729897) (xy 414.8968 -315.776578) (xy 414.904695 -315.825155)
			(xy 414.90519 -315.849762) (xy 416.193998 -315.849762) (xy 416.197958 -315.800708) (xy 416.209735 -315.752924)
			(xy 416.229026 -315.707648) (xy 416.255329 -315.666052) (xy 416.287964 -315.629215) (xy 416.326085 -315.59809)
			(xy 416.368706 -315.573483) (xy 416.414722 -315.556031) (xy 416.462941 -315.546187) (xy 416.512116 -315.544206)
			(xy 416.560971 -315.550138) (xy 416.608242 -315.56383) (xy 416.652704 -315.584928) (xy 416.693207 -315.612884)
			(xy 416.7287 -315.646976) (xy 416.758265 -315.68632) (xy 416.781136 -315.729897) (xy 416.79672 -315.776578)
			(xy 416.804615 -315.825155) (xy 416.80511 -315.849762) (xy 418.094172 -315.849762) (xy 418.098132 -315.800708)
			(xy 418.109909 -315.752924) (xy 418.1292 -315.707648) (xy 418.155503 -315.666052) (xy 418.188138 -315.629215)
			(xy 418.226259 -315.59809) (xy 418.26888 -315.573483) (xy 418.314896 -315.556031) (xy 418.363115 -315.546187)
			(xy 418.41229 -315.544206) (xy 418.461145 -315.550138) (xy 418.508416 -315.56383) (xy 418.552878 -315.584928)
			(xy 418.593381 -315.612884) (xy 418.628874 -315.646976) (xy 418.658439 -315.68632) (xy 418.68131 -315.729897)
			(xy 418.696894 -315.776578) (xy 418.704789 -315.825155) (xy 418.705284 -315.849762) (xy 419.994092 -315.849762)
			(xy 419.998052 -315.800708) (xy 420.009829 -315.752924) (xy 420.02912 -315.707648) (xy 420.055423 -315.666052)
			(xy 420.088058 -315.629215) (xy 420.126179 -315.59809) (xy 420.1688 -315.573483) (xy 420.214816 -315.556031)
			(xy 420.263035 -315.546187) (xy 420.31221 -315.544206) (xy 420.361065 -315.550138) (xy 420.408336 -315.56383)
			(xy 420.452798 -315.584928) (xy 420.493301 -315.612884) (xy 420.528794 -315.646976) (xy 420.558359 -315.68632)
			(xy 420.58123 -315.729897) (xy 420.596814 -315.776578) (xy 420.604709 -315.825155) (xy 420.605204 -315.849762)
			(xy 420.604709 -315.874369) (xy 420.596814 -315.922946) (xy 420.58123 -315.969627) (xy 420.558359 -316.013204)
			(xy 420.528794 -316.052548) (xy 420.493301 -316.08664) (xy 420.452798 -316.114596) (xy 420.408336 -316.135694)
			(xy 420.361065 -316.149386) (xy 420.31221 -316.155318) (xy 420.263035 -316.153337) (xy 420.214816 -316.143493)
			(xy 420.1688 -316.126041) (xy 420.126179 -316.101434) (xy 420.088058 -316.070309) (xy 420.055423 -316.033472)
			(xy 420.02912 -315.991876) (xy 420.009829 -315.9466) (xy 419.998052 -315.898816) (xy 419.994092 -315.849762)
			(xy 418.705284 -315.849762) (xy 418.704789 -315.874369) (xy 418.696894 -315.922946) (xy 418.68131 -315.969627)
			(xy 418.658439 -316.013204) (xy 418.628874 -316.052548) (xy 418.593381 -316.08664) (xy 418.552878 -316.114596)
			(xy 418.508416 -316.135694) (xy 418.461145 -316.149386) (xy 418.41229 -316.155318) (xy 418.363115 -316.153337)
			(xy 418.314896 -316.143493) (xy 418.26888 -316.126041) (xy 418.226259 -316.101434) (xy 418.188138 -316.070309)
			(xy 418.155503 -316.033472) (xy 418.1292 -315.991876) (xy 418.109909 -315.9466) (xy 418.098132 -315.898816)
			(xy 418.094172 -315.849762) (xy 416.80511 -315.849762) (xy 416.804615 -315.874369) (xy 416.79672 -315.922946)
			(xy 416.781136 -315.969627) (xy 416.758265 -316.013204) (xy 416.7287 -316.052548) (xy 416.693207 -316.08664)
			(xy 416.652704 -316.114596) (xy 416.608242 -316.135694) (xy 416.560971 -316.149386) (xy 416.512116 -316.155318)
			(xy 416.462941 -316.153337) (xy 416.414722 -316.143493) (xy 416.368706 -316.126041) (xy 416.326085 -316.101434)
			(xy 416.287964 -316.070309) (xy 416.255329 -316.033472) (xy 416.229026 -315.991876) (xy 416.209735 -315.9466)
			(xy 416.197958 -315.898816) (xy 416.193998 -315.849762) (xy 414.90519 -315.849762) (xy 414.904695 -315.874369)
			(xy 414.8968 -315.922946) (xy 414.881216 -315.969627) (xy 414.858345 -316.013204) (xy 414.82878 -316.052548)
			(xy 414.793287 -316.08664) (xy 414.752784 -316.114596) (xy 414.708322 -316.135694) (xy 414.661051 -316.149386)
			(xy 414.612196 -316.155318) (xy 414.563021 -316.153337) (xy 414.514802 -316.143493) (xy 414.468786 -316.126041)
			(xy 414.426165 -316.101434) (xy 414.388044 -316.070309) (xy 414.355409 -316.033472) (xy 414.329106 -315.991876)
			(xy 414.309815 -315.9466) (xy 414.298038 -315.898816) (xy 414.294078 -315.849762) (xy 397.805148 -315.849762)
			(xy 397.804653 -315.874369) (xy 397.796758 -315.922946) (xy 397.781174 -315.969627) (xy 397.758303 -316.013204)
			(xy 397.728738 -316.052548) (xy 397.693245 -316.08664) (xy 397.652742 -316.114596) (xy 397.60828 -316.135694)
			(xy 397.561009 -316.149386) (xy 397.512154 -316.155318) (xy 397.462979 -316.153337) (xy 397.41476 -316.143493)
			(xy 397.368744 -316.126041) (xy 397.326123 -316.101434) (xy 397.288002 -316.070309) (xy 397.255367 -316.033472)
			(xy 397.229064 -315.991876) (xy 397.209773 -315.9466) (xy 397.197996 -315.898816) (xy 397.194036 -315.849762)
			(xy 395.905228 -315.849762) (xy 395.904733 -315.874369) (xy 395.896838 -315.922946) (xy 395.881254 -315.969627)
			(xy 395.858383 -316.013204) (xy 395.828818 -316.052548) (xy 395.793325 -316.08664) (xy 395.752822 -316.114596)
			(xy 395.70836 -316.135694) (xy 395.661089 -316.149386) (xy 395.612234 -316.155318) (xy 395.563059 -316.153337)
			(xy 395.51484 -316.143493) (xy 395.468824 -316.126041) (xy 395.426203 -316.101434) (xy 395.388082 -316.070309)
			(xy 395.355447 -316.033472) (xy 395.329144 -315.991876) (xy 395.309853 -315.9466) (xy 395.298076 -315.898816)
			(xy 395.294116 -315.849762) (xy 394.005308 -315.849762) (xy 394.004813 -315.874369) (xy 393.996918 -315.922946)
			(xy 393.981334 -315.969627) (xy 393.958463 -316.013204) (xy 393.928898 -316.052548) (xy 393.893405 -316.08664)
			(xy 393.852902 -316.114596) (xy 393.80844 -316.135694) (xy 393.761169 -316.149386) (xy 393.712314 -316.155318)
			(xy 393.663139 -316.153337) (xy 393.61492 -316.143493) (xy 393.568904 -316.126041) (xy 393.526283 -316.101434)
			(xy 393.488162 -316.070309) (xy 393.455527 -316.033472) (xy 393.429224 -315.991876) (xy 393.409933 -315.9466)
			(xy 393.398156 -315.898816) (xy 393.394196 -315.849762) (xy 392.105134 -315.849762) (xy 392.104639 -315.874369)
			(xy 392.096744 -315.922946) (xy 392.08116 -315.969627) (xy 392.058289 -316.013204) (xy 392.028724 -316.052548)
			(xy 391.993231 -316.08664) (xy 391.952728 -316.114596) (xy 391.908266 -316.135694) (xy 391.860995 -316.149386)
			(xy 391.81214 -316.155318) (xy 391.762965 -316.153337) (xy 391.714746 -316.143493) (xy 391.66873 -316.126041)
			(xy 391.626109 -316.101434) (xy 391.587988 -316.070309) (xy 391.555353 -316.033472) (xy 391.52905 -315.991876)
			(xy 391.509759 -315.9466) (xy 391.497982 -315.898816) (xy 391.494022 -315.849762) (xy 390.205214 -315.849762)
			(xy 390.204719 -315.874369) (xy 390.196824 -315.922946) (xy 390.18124 -315.969627) (xy 390.158369 -316.013204)
			(xy 390.128804 -316.052548) (xy 390.093311 -316.08664) (xy 390.052808 -316.114596) (xy 390.008346 -316.135694)
			(xy 389.961075 -316.149386) (xy 389.91222 -316.155318) (xy 389.863045 -316.153337) (xy 389.814826 -316.143493)
			(xy 389.76881 -316.126041) (xy 389.726189 -316.101434) (xy 389.688068 -316.070309) (xy 389.655433 -316.033472)
			(xy 389.62913 -315.991876) (xy 389.609839 -315.9466) (xy 389.598062 -315.898816) (xy 389.594102 -315.849762)
			(xy 388.305294 -315.849762) (xy 388.304799 -315.874369) (xy 388.296904 -315.922946) (xy 388.28132 -315.969627)
			(xy 388.258449 -316.013204) (xy 388.228884 -316.052548) (xy 388.193391 -316.08664) (xy 388.152888 -316.114596)
			(xy 388.108426 -316.135694) (xy 388.061155 -316.149386) (xy 388.0123 -316.155318) (xy 387.963125 -316.153337)
			(xy 387.914906 -316.143493) (xy 387.86889 -316.126041) (xy 387.826269 -316.101434) (xy 387.788148 -316.070309)
			(xy 387.755513 -316.033472) (xy 387.72921 -315.991876) (xy 387.709919 -315.9466) (xy 387.698142 -315.898816)
			(xy 387.694182 -315.849762) (xy 312.10504 -315.849762) (xy 312.104545 -315.874369) (xy 312.09665 -315.922946)
			(xy 312.081066 -315.969627) (xy 312.058195 -316.013204) (xy 312.02863 -316.052548) (xy 311.993137 -316.08664)
			(xy 311.952634 -316.114596) (xy 311.908172 -316.135694) (xy 311.860901 -316.149386) (xy 311.812046 -316.155318)
			(xy 311.762871 -316.153337) (xy 311.714652 -316.143493) (xy 311.668636 -316.126041) (xy 311.626015 -316.101434)
			(xy 311.587894 -316.070309) (xy 311.555259 -316.033472) (xy 311.528956 -315.991876) (xy 311.509665 -315.9466)
			(xy 311.497888 -315.898816) (xy 311.493928 -315.849762) (xy 310.20512 -315.849762) (xy 310.204625 -315.874369)
			(xy 310.19673 -315.922946) (xy 310.181146 -315.969627) (xy 310.158275 -316.013204) (xy 310.12871 -316.052548)
			(xy 310.093217 -316.08664) (xy 310.052714 -316.114596) (xy 310.008252 -316.135694) (xy 309.960981 -316.149386)
			(xy 309.912126 -316.155318) (xy 309.862951 -316.153337) (xy 309.814732 -316.143493) (xy 309.768716 -316.126041)
			(xy 309.726095 -316.101434) (xy 309.687974 -316.070309) (xy 309.655339 -316.033472) (xy 309.629036 -315.991876)
			(xy 309.609745 -315.9466) (xy 309.597968 -315.898816) (xy 309.594008 -315.849762) (xy 308.3052 -315.849762)
			(xy 308.304705 -315.874369) (xy 308.29681 -315.922946) (xy 308.281226 -315.969627) (xy 308.258355 -316.013204)
			(xy 308.22879 -316.052548) (xy 308.193297 -316.08664) (xy 308.152794 -316.114596) (xy 308.108332 -316.135694)
			(xy 308.061061 -316.149386) (xy 308.012206 -316.155318) (xy 307.963031 -316.153337) (xy 307.914812 -316.143493)
			(xy 307.868796 -316.126041) (xy 307.826175 -316.101434) (xy 307.788054 -316.070309) (xy 307.755419 -316.033472)
			(xy 307.729116 -315.991876) (xy 307.709825 -315.9466) (xy 307.698048 -315.898816) (xy 307.694088 -315.849762)
			(xy 306.405026 -315.849762) (xy 306.404531 -315.874369) (xy 306.396636 -315.922946) (xy 306.381052 -315.969627)
			(xy 306.358181 -316.013204) (xy 306.328616 -316.052548) (xy 306.293123 -316.08664) (xy 306.25262 -316.114596)
			(xy 306.208158 -316.135694) (xy 306.160887 -316.149386) (xy 306.112032 -316.155318) (xy 306.062857 -316.153337)
			(xy 306.014638 -316.143493) (xy 305.968622 -316.126041) (xy 305.926001 -316.101434) (xy 305.88788 -316.070309)
			(xy 305.855245 -316.033472) (xy 305.828942 -315.991876) (xy 305.809651 -315.9466) (xy 305.797874 -315.898816)
			(xy 305.793914 -315.849762) (xy 296.905172 -315.849762) (xy 296.904677 -315.874369) (xy 296.896782 -315.922946)
			(xy 296.881198 -315.969627) (xy 296.858327 -316.013204) (xy 296.828762 -316.052548) (xy 296.793269 -316.08664)
			(xy 296.752766 -316.114596) (xy 296.708304 -316.135694) (xy 296.661033 -316.149386) (xy 296.612178 -316.155318)
			(xy 296.563003 -316.153337) (xy 296.514784 -316.143493) (xy 296.468768 -316.126041) (xy 296.426147 -316.101434)
			(xy 296.388026 -316.070309) (xy 296.355391 -316.033472) (xy 296.329088 -315.991876) (xy 296.309797 -315.9466)
			(xy 296.29802 -315.898816) (xy 296.29406 -315.849762) (xy 295.004998 -315.849762) (xy 295.004503 -315.874369)
			(xy 294.996608 -315.922946) (xy 294.981024 -315.969627) (xy 294.958153 -316.013204) (xy 294.928588 -316.052548)
			(xy 294.893095 -316.08664) (xy 294.852592 -316.114596) (xy 294.80813 -316.135694) (xy 294.760859 -316.149386)
			(xy 294.712004 -316.155318) (xy 294.662829 -316.153337) (xy 294.61461 -316.143493) (xy 294.568594 -316.126041)
			(xy 294.525973 -316.101434) (xy 294.487852 -316.070309) (xy 294.455217 -316.033472) (xy 294.428914 -315.991876)
			(xy 294.409623 -315.9466) (xy 294.397846 -315.898816) (xy 294.393886 -315.849762) (xy 293.105078 -315.849762)
			(xy 293.104583 -315.874369) (xy 293.096688 -315.922946) (xy 293.081104 -315.969627) (xy 293.058233 -316.013204)
			(xy 293.028668 -316.052548) (xy 292.993175 -316.08664) (xy 292.952672 -316.114596) (xy 292.90821 -316.135694)
			(xy 292.860939 -316.149386) (xy 292.812084 -316.155318) (xy 292.762909 -316.153337) (xy 292.71469 -316.143493)
			(xy 292.668674 -316.126041) (xy 292.626053 -316.101434) (xy 292.587932 -316.070309) (xy 292.555297 -316.033472)
			(xy 292.528994 -315.991876) (xy 292.509703 -315.9466) (xy 292.497926 -315.898816) (xy 292.493966 -315.849762)
			(xy 291.205158 -315.849762) (xy 291.204663 -315.874369) (xy 291.196768 -315.922946) (xy 291.181184 -315.969627)
			(xy 291.158313 -316.013204) (xy 291.128748 -316.052548) (xy 291.093255 -316.08664) (xy 291.052752 -316.114596)
			(xy 291.00829 -316.135694) (xy 290.961019 -316.149386) (xy 290.912164 -316.155318) (xy 290.862989 -316.153337)
			(xy 290.81477 -316.143493) (xy 290.768754 -316.126041) (xy 290.726133 -316.101434) (xy 290.688012 -316.070309)
			(xy 290.655377 -316.033472) (xy 290.629074 -315.991876) (xy 290.609783 -315.9466) (xy 290.598006 -315.898816)
			(xy 290.594046 -315.849762) (xy 289.305238 -315.849762) (xy 289.304743 -315.874369) (xy 289.296848 -315.922946)
			(xy 289.281264 -315.969627) (xy 289.258393 -316.013204) (xy 289.228828 -316.052548) (xy 289.193335 -316.08664)
			(xy 289.152832 -316.114596) (xy 289.10837 -316.135694) (xy 289.061099 -316.149386) (xy 289.012244 -316.155318)
			(xy 288.963069 -316.153337) (xy 288.91485 -316.143493) (xy 288.868834 -316.126041) (xy 288.826213 -316.101434)
			(xy 288.788092 -316.070309) (xy 288.755457 -316.033472) (xy 288.729154 -315.991876) (xy 288.709863 -315.9466)
			(xy 288.698086 -315.898816) (xy 288.694126 -315.849762) (xy 287.405064 -315.849762) (xy 287.404569 -315.874369)
			(xy 287.396674 -315.922946) (xy 287.38109 -315.969627) (xy 287.358219 -316.013204) (xy 287.328654 -316.052548)
			(xy 287.293161 -316.08664) (xy 287.252658 -316.114596) (xy 287.208196 -316.135694) (xy 287.160925 -316.149386)
			(xy 287.11207 -316.155318) (xy 287.062895 -316.153337) (xy 287.014676 -316.143493) (xy 286.96866 -316.126041)
			(xy 286.926039 -316.101434) (xy 286.887918 -316.070309) (xy 286.855283 -316.033472) (xy 286.82898 -315.991876)
			(xy 286.809689 -315.9466) (xy 286.797912 -315.898816) (xy 286.793952 -315.849762) (xy 285.505144 -315.849762)
			(xy 285.504649 -315.874369) (xy 285.496754 -315.922946) (xy 285.48117 -315.969627) (xy 285.458299 -316.013204)
			(xy 285.428734 -316.052548) (xy 285.393241 -316.08664) (xy 285.352738 -316.114596) (xy 285.308276 -316.135694)
			(xy 285.261005 -316.149386) (xy 285.21215 -316.155318) (xy 285.162975 -316.153337) (xy 285.114756 -316.143493)
			(xy 285.06874 -316.126041) (xy 285.026119 -316.101434) (xy 284.987998 -316.070309) (xy 284.955363 -316.033472)
			(xy 284.92906 -315.991876) (xy 284.909769 -315.9466) (xy 284.897992 -315.898816) (xy 284.894032 -315.849762)
			(xy 283.605224 -315.849762) (xy 283.604729 -315.874369) (xy 283.596834 -315.922946) (xy 283.58125 -315.969627)
			(xy 283.558379 -316.013204) (xy 283.528814 -316.052548) (xy 283.493321 -316.08664) (xy 283.452818 -316.114596)
			(xy 283.408356 -316.135694) (xy 283.361085 -316.149386) (xy 283.31223 -316.155318) (xy 283.263055 -316.153337)
			(xy 283.214836 -316.143493) (xy 283.16882 -316.126041) (xy 283.126199 -316.101434) (xy 283.088078 -316.070309)
			(xy 283.055443 -316.033472) (xy 283.02914 -315.991876) (xy 283.009849 -315.9466) (xy 282.998072 -315.898816)
			(xy 282.994112 -315.849762) (xy 188.405262 -315.849762) (xy 188.404767 -315.874369) (xy 188.396872 -315.922946)
			(xy 188.381288 -315.969627) (xy 188.358417 -316.013204) (xy 188.328852 -316.052548) (xy 188.293359 -316.08664)
			(xy 188.252856 -316.114596) (xy 188.208394 -316.135694) (xy 188.161123 -316.149386) (xy 188.112268 -316.155318)
			(xy 188.063093 -316.153337) (xy 188.014874 -316.143493) (xy 187.968858 -316.126041) (xy 187.926237 -316.101434)
			(xy 187.888116 -316.070309) (xy 187.855481 -316.033472) (xy 187.829178 -315.991876) (xy 187.809887 -315.9466)
			(xy 187.79811 -315.898816) (xy 187.79415 -315.849762) (xy 186.505342 -315.849762) (xy 186.504847 -315.874369)
			(xy 186.496952 -315.922946) (xy 186.481368 -315.969627) (xy 186.458497 -316.013204) (xy 186.428932 -316.052548)
			(xy 186.393439 -316.08664) (xy 186.352936 -316.114596) (xy 186.308474 -316.135694) (xy 186.261203 -316.149386)
			(xy 186.212348 -316.155318) (xy 186.163173 -316.153337) (xy 186.114954 -316.143493) (xy 186.068938 -316.126041)
			(xy 186.026317 -316.101434) (xy 185.988196 -316.070309) (xy 185.955561 -316.033472) (xy 185.929258 -315.991876)
			(xy 185.909967 -315.9466) (xy 185.89819 -315.898816) (xy 185.89423 -315.849762) (xy 184.605168 -315.849762)
			(xy 184.604673 -315.874369) (xy 184.596778 -315.922946) (xy 184.581194 -315.969627) (xy 184.558323 -316.013204)
			(xy 184.528758 -316.052548) (xy 184.493265 -316.08664) (xy 184.452762 -316.114596) (xy 184.4083 -316.135694)
			(xy 184.361029 -316.149386) (xy 184.312174 -316.155318) (xy 184.262999 -316.153337) (xy 184.21478 -316.143493)
			(xy 184.168764 -316.126041) (xy 184.126143 -316.101434) (xy 184.088022 -316.070309) (xy 184.055387 -316.033472)
			(xy 184.029084 -315.991876) (xy 184.009793 -315.9466) (xy 183.998016 -315.898816) (xy 183.994056 -315.849762)
			(xy 182.705248 -315.849762) (xy 182.704753 -315.874369) (xy 182.696858 -315.922946) (xy 182.681274 -315.969627)
			(xy 182.658403 -316.013204) (xy 182.628838 -316.052548) (xy 182.593345 -316.08664) (xy 182.552842 -316.114596)
			(xy 182.50838 -316.135694) (xy 182.461109 -316.149386) (xy 182.412254 -316.155318) (xy 182.363079 -316.153337)
			(xy 182.31486 -316.143493) (xy 182.268844 -316.126041) (xy 182.226223 -316.101434) (xy 182.188102 -316.070309)
			(xy 182.155467 -316.033472) (xy 182.129164 -315.991876) (xy 182.109873 -315.9466) (xy 182.098096 -315.898816)
			(xy 182.094136 -315.849762) (xy 165.605206 -315.849762) (xy 165.604711 -315.874369) (xy 165.596816 -315.922946)
			(xy 165.581232 -315.969627) (xy 165.558361 -316.013204) (xy 165.528796 -316.052548) (xy 165.493303 -316.08664)
			(xy 165.4528 -316.114596) (xy 165.408338 -316.135694) (xy 165.361067 -316.149386) (xy 165.312212 -316.155318)
			(xy 165.263037 -316.153337) (xy 165.214818 -316.143493) (xy 165.168802 -316.126041) (xy 165.126181 -316.101434)
			(xy 165.08806 -316.070309) (xy 165.055425 -316.033472) (xy 165.029122 -315.991876) (xy 165.009831 -315.9466)
			(xy 164.998054 -315.898816) (xy 164.994094 -315.849762) (xy 163.705286 -315.849762) (xy 163.704791 -315.874369)
			(xy 163.696896 -315.922946) (xy 163.681312 -315.969627) (xy 163.658441 -316.013204) (xy 163.628876 -316.052548)
			(xy 163.593383 -316.08664) (xy 163.55288 -316.114596) (xy 163.508418 -316.135694) (xy 163.461147 -316.149386)
			(xy 163.412292 -316.155318) (xy 163.363117 -316.153337) (xy 163.314898 -316.143493) (xy 163.268882 -316.126041)
			(xy 163.226261 -316.101434) (xy 163.18814 -316.070309) (xy 163.155505 -316.033472) (xy 163.129202 -315.991876)
			(xy 163.109911 -315.9466) (xy 163.098134 -315.898816) (xy 163.094174 -315.849762) (xy 161.805366 -315.849762)
			(xy 161.804871 -315.874369) (xy 161.796976 -315.922946) (xy 161.781392 -315.969627) (xy 161.758521 -316.013204)
			(xy 161.728956 -316.052548) (xy 161.693463 -316.08664) (xy 161.65296 -316.114596) (xy 161.608498 -316.135694)
			(xy 161.561227 -316.149386) (xy 161.512372 -316.155318) (xy 161.463197 -316.153337) (xy 161.414978 -316.143493)
			(xy 161.368962 -316.126041) (xy 161.326341 -316.101434) (xy 161.28822 -316.070309) (xy 161.255585 -316.033472)
			(xy 161.229282 -315.991876) (xy 161.209991 -315.9466) (xy 161.198214 -315.898816) (xy 161.194254 -315.849762)
			(xy 159.905192 -315.849762) (xy 159.904697 -315.874369) (xy 159.896802 -315.922946) (xy 159.881218 -315.969627)
			(xy 159.858347 -316.013204) (xy 159.828782 -316.052548) (xy 159.793289 -316.08664) (xy 159.752786 -316.114596)
			(xy 159.708324 -316.135694) (xy 159.661053 -316.149386) (xy 159.612198 -316.155318) (xy 159.563023 -316.153337)
			(xy 159.514804 -316.143493) (xy 159.468788 -316.126041) (xy 159.426167 -316.101434) (xy 159.388046 -316.070309)
			(xy 159.355411 -316.033472) (xy 159.329108 -315.991876) (xy 159.309817 -315.9466) (xy 159.29804 -315.898816)
			(xy 159.29408 -315.849762) (xy 158.005272 -315.849762) (xy 158.004777 -315.874369) (xy 157.996882 -315.922946)
			(xy 157.981298 -315.969627) (xy 157.958427 -316.013204) (xy 157.928862 -316.052548) (xy 157.893369 -316.08664)
			(xy 157.852866 -316.114596) (xy 157.808404 -316.135694) (xy 157.761133 -316.149386) (xy 157.712278 -316.155318)
			(xy 157.663103 -316.153337) (xy 157.614884 -316.143493) (xy 157.568868 -316.126041) (xy 157.526247 -316.101434)
			(xy 157.488126 -316.070309) (xy 157.455491 -316.033472) (xy 157.429188 -315.991876) (xy 157.409897 -315.9466)
			(xy 157.39812 -315.898816) (xy 157.39416 -315.849762) (xy 156.105352 -315.849762) (xy 156.104857 -315.874369)
			(xy 156.096962 -315.922946) (xy 156.081378 -315.969627) (xy 156.058507 -316.013204) (xy 156.028942 -316.052548)
			(xy 155.993449 -316.08664) (xy 155.952946 -316.114596) (xy 155.908484 -316.135694) (xy 155.861213 -316.149386)
			(xy 155.812358 -316.155318) (xy 155.763183 -316.153337) (xy 155.714964 -316.143493) (xy 155.668948 -316.126041)
			(xy 155.626327 -316.101434) (xy 155.588206 -316.070309) (xy 155.555571 -316.033472) (xy 155.529268 -315.991876)
			(xy 155.509977 -315.9466) (xy 155.4982 -315.898816) (xy 155.49424 -315.849762) (xy 79.905098 -315.849762)
			(xy 79.904603 -315.874369) (xy 79.896708 -315.922946) (xy 79.881124 -315.969627) (xy 79.858253 -316.013204)
			(xy 79.828688 -316.052548) (xy 79.793195 -316.08664) (xy 79.752692 -316.114596) (xy 79.70823 -316.135694)
			(xy 79.660959 -316.149386) (xy 79.612104 -316.155318) (xy 79.562929 -316.153337) (xy 79.51471 -316.143493)
			(xy 79.468694 -316.126041) (xy 79.426073 -316.101434) (xy 79.387952 -316.070309) (xy 79.355317 -316.033472)
			(xy 79.329014 -315.991876) (xy 79.309723 -315.9466) (xy 79.297946 -315.898816) (xy 79.293986 -315.849762)
			(xy 78.005178 -315.849762) (xy 78.004683 -315.874369) (xy 77.996788 -315.922946) (xy 77.981204 -315.969627)
			(xy 77.958333 -316.013204) (xy 77.928768 -316.052548) (xy 77.893275 -316.08664) (xy 77.852772 -316.114596)
			(xy 77.80831 -316.135694) (xy 77.761039 -316.149386) (xy 77.712184 -316.155318) (xy 77.663009 -316.153337)
			(xy 77.61479 -316.143493) (xy 77.568774 -316.126041) (xy 77.526153 -316.101434) (xy 77.488032 -316.070309)
			(xy 77.455397 -316.033472) (xy 77.429094 -315.991876) (xy 77.409803 -315.9466) (xy 77.398026 -315.898816)
			(xy 77.394066 -315.849762) (xy 76.105258 -315.849762) (xy 76.104763 -315.874369) (xy 76.096868 -315.922946)
			(xy 76.081284 -315.969627) (xy 76.058413 -316.013204) (xy 76.028848 -316.052548) (xy 75.993355 -316.08664)
			(xy 75.952852 -316.114596) (xy 75.90839 -316.135694) (xy 75.861119 -316.149386) (xy 75.812264 -316.155318)
			(xy 75.763089 -316.153337) (xy 75.71487 -316.143493) (xy 75.668854 -316.126041) (xy 75.626233 -316.101434)
			(xy 75.588112 -316.070309) (xy 75.555477 -316.033472) (xy 75.529174 -315.991876) (xy 75.509883 -315.9466)
			(xy 75.498106 -315.898816) (xy 75.494146 -315.849762) (xy 74.205084 -315.849762) (xy 74.204589 -315.874369)
			(xy 74.196694 -315.922946) (xy 74.18111 -315.969627) (xy 74.158239 -316.013204) (xy 74.128674 -316.052548)
			(xy 74.093181 -316.08664) (xy 74.052678 -316.114596) (xy 74.008216 -316.135694) (xy 73.960945 -316.149386)
			(xy 73.91209 -316.155318) (xy 73.862915 -316.153337) (xy 73.814696 -316.143493) (xy 73.76868 -316.126041)
			(xy 73.726059 -316.101434) (xy 73.687938 -316.070309) (xy 73.655303 -316.033472) (xy 73.629 -315.991876)
			(xy 73.609709 -315.9466) (xy 73.597932 -315.898816) (xy 73.593972 -315.849762) (xy 64.70523 -315.849762)
			(xy 64.704735 -315.874369) (xy 64.69684 -315.922946) (xy 64.681256 -315.969627) (xy 64.658385 -316.013204)
			(xy 64.62882 -316.052548) (xy 64.593327 -316.08664) (xy 64.552824 -316.114596) (xy 64.508362 -316.135694)
			(xy 64.461091 -316.149386) (xy 64.412236 -316.155318) (xy 64.363061 -316.153337) (xy 64.314842 -316.143493)
			(xy 64.268826 -316.126041) (xy 64.226205 -316.101434) (xy 64.188084 -316.070309) (xy 64.155449 -316.033472)
			(xy 64.129146 -315.991876) (xy 64.109855 -315.9466) (xy 64.098078 -315.898816) (xy 64.094118 -315.849762)
			(xy 62.805056 -315.849762) (xy 62.804561 -315.874369) (xy 62.796666 -315.922946) (xy 62.781082 -315.969627)
			(xy 62.758211 -316.013204) (xy 62.728646 -316.052548) (xy 62.693153 -316.08664) (xy 62.65265 -316.114596)
			(xy 62.608188 -316.135694) (xy 62.560917 -316.149386) (xy 62.512062 -316.155318) (xy 62.462887 -316.153337)
			(xy 62.414668 -316.143493) (xy 62.368652 -316.126041) (xy 62.326031 -316.101434) (xy 62.28791 -316.070309)
			(xy 62.255275 -316.033472) (xy 62.228972 -315.991876) (xy 62.209681 -315.9466) (xy 62.197904 -315.898816)
			(xy 62.193944 -315.849762) (xy 60.905136 -315.849762) (xy 60.904641 -315.874369) (xy 60.896746 -315.922946)
			(xy 60.881162 -315.969627) (xy 60.858291 -316.013204) (xy 60.828726 -316.052548) (xy 60.793233 -316.08664)
			(xy 60.75273 -316.114596) (xy 60.708268 -316.135694) (xy 60.660997 -316.149386) (xy 60.612142 -316.155318)
			(xy 60.562967 -316.153337) (xy 60.514748 -316.143493) (xy 60.468732 -316.126041) (xy 60.426111 -316.101434)
			(xy 60.38799 -316.070309) (xy 60.355355 -316.033472) (xy 60.329052 -315.991876) (xy 60.309761 -315.9466)
			(xy 60.297984 -315.898816) (xy 60.294024 -315.849762) (xy 59.005216 -315.849762) (xy 59.004721 -315.874369)
			(xy 58.996826 -315.922946) (xy 58.981242 -315.969627) (xy 58.958371 -316.013204) (xy 58.928806 -316.052548)
			(xy 58.893313 -316.08664) (xy 58.85281 -316.114596) (xy 58.808348 -316.135694) (xy 58.761077 -316.149386)
			(xy 58.712222 -316.155318) (xy 58.663047 -316.153337) (xy 58.614828 -316.143493) (xy 58.568812 -316.126041)
			(xy 58.526191 -316.101434) (xy 58.48807 -316.070309) (xy 58.455435 -316.033472) (xy 58.429132 -315.991876)
			(xy 58.409841 -315.9466) (xy 58.398064 -315.898816) (xy 58.394104 -315.849762) (xy 57.105296 -315.849762)
			(xy 57.104801 -315.874369) (xy 57.096906 -315.922946) (xy 57.081322 -315.969627) (xy 57.058451 -316.013204)
			(xy 57.028886 -316.052548) (xy 56.993393 -316.08664) (xy 56.95289 -316.114596) (xy 56.908428 -316.135694)
			(xy 56.861157 -316.149386) (xy 56.812302 -316.155318) (xy 56.763127 -316.153337) (xy 56.714908 -316.143493)
			(xy 56.668892 -316.126041) (xy 56.626271 -316.101434) (xy 56.58815 -316.070309) (xy 56.555515 -316.033472)
			(xy 56.529212 -315.991876) (xy 56.509921 -315.9466) (xy 56.498144 -315.898816) (xy 56.494184 -315.849762)
			(xy 55.205122 -315.849762) (xy 55.204627 -315.874369) (xy 55.196732 -315.922946) (xy 55.181148 -315.969627)
			(xy 55.158277 -316.013204) (xy 55.128712 -316.052548) (xy 55.093219 -316.08664) (xy 55.052716 -316.114596)
			(xy 55.008254 -316.135694) (xy 54.960983 -316.149386) (xy 54.912128 -316.155318) (xy 54.862953 -316.153337)
			(xy 54.814734 -316.143493) (xy 54.768718 -316.126041) (xy 54.726097 -316.101434) (xy 54.687976 -316.070309)
			(xy 54.655341 -316.033472) (xy 54.629038 -315.991876) (xy 54.609747 -315.9466) (xy 54.59797 -315.898816)
			(xy 54.59401 -315.849762) (xy 53.305202 -315.849762) (xy 53.304707 -315.874369) (xy 53.296812 -315.922946)
			(xy 53.281228 -315.969627) (xy 53.258357 -316.013204) (xy 53.228792 -316.052548) (xy 53.193299 -316.08664)
			(xy 53.152796 -316.114596) (xy 53.108334 -316.135694) (xy 53.061063 -316.149386) (xy 53.012208 -316.155318)
			(xy 52.963033 -316.153337) (xy 52.914814 -316.143493) (xy 52.868798 -316.126041) (xy 52.826177 -316.101434)
			(xy 52.788056 -316.070309) (xy 52.755421 -316.033472) (xy 52.729118 -315.991876) (xy 52.709827 -315.9466)
			(xy 52.69805 -315.898816) (xy 52.69409 -315.849762) (xy 51.405282 -315.849762) (xy 51.404787 -315.874369)
			(xy 51.396892 -315.922946) (xy 51.381308 -315.969627) (xy 51.358437 -316.013204) (xy 51.328872 -316.052548)
			(xy 51.293379 -316.08664) (xy 51.252876 -316.114596) (xy 51.208414 -316.135694) (xy 51.161143 -316.149386)
			(xy 51.112288 -316.155318) (xy 51.063113 -316.153337) (xy 51.014894 -316.143493) (xy 50.968878 -316.126041)
			(xy 50.926257 -316.101434) (xy 50.888136 -316.070309) (xy 50.855501 -316.033472) (xy 50.829198 -315.991876)
			(xy 50.809907 -315.9466) (xy 50.79813 -315.898816) (xy 50.79417 -315.849762) (xy 0.508 -315.849762)
			(xy 0.508 -316.799722) (xy 50.79417 -316.799722) (xy 50.79813 -316.750668) (xy 50.809907 -316.702884)
			(xy 50.829198 -316.657608) (xy 50.855501 -316.616012) (xy 50.888136 -316.579175) (xy 50.926257 -316.54805)
			(xy 50.968878 -316.523443) (xy 51.014894 -316.505991) (xy 51.063113 -316.496147) (xy 51.112288 -316.494166)
			(xy 51.161143 -316.500098) (xy 51.208414 -316.51379) (xy 51.252876 -316.534888) (xy 51.293379 -316.562844)
			(xy 51.328872 -316.596936) (xy 51.358437 -316.63628) (xy 51.381308 -316.679857) (xy 51.396892 -316.726538)
			(xy 51.404787 -316.775115) (xy 51.405282 -316.799722) (xy 52.69409 -316.799722) (xy 52.69805 -316.750668)
			(xy 52.709827 -316.702884) (xy 52.729118 -316.657608) (xy 52.755421 -316.616012) (xy 52.788056 -316.579175)
			(xy 52.826177 -316.54805) (xy 52.868798 -316.523443) (xy 52.914814 -316.505991) (xy 52.963033 -316.496147)
			(xy 53.012208 -316.494166) (xy 53.061063 -316.500098) (xy 53.108334 -316.51379) (xy 53.152796 -316.534888)
			(xy 53.193299 -316.562844) (xy 53.228792 -316.596936) (xy 53.258357 -316.63628) (xy 53.281228 -316.679857)
			(xy 53.296812 -316.726538) (xy 53.304707 -316.775115) (xy 53.305202 -316.799722) (xy 54.59401 -316.799722)
			(xy 54.59797 -316.750668) (xy 54.609747 -316.702884) (xy 54.629038 -316.657608) (xy 54.655341 -316.616012)
			(xy 54.687976 -316.579175) (xy 54.726097 -316.54805) (xy 54.768718 -316.523443) (xy 54.814734 -316.505991)
			(xy 54.862953 -316.496147) (xy 54.912128 -316.494166) (xy 54.960983 -316.500098) (xy 55.008254 -316.51379)
			(xy 55.052716 -316.534888) (xy 55.093219 -316.562844) (xy 55.128712 -316.596936) (xy 55.158277 -316.63628)
			(xy 55.181148 -316.679857) (xy 55.196732 -316.726538) (xy 55.204627 -316.775115) (xy 55.205122 -316.799722)
			(xy 56.494184 -316.799722) (xy 56.498144 -316.750668) (xy 56.509921 -316.702884) (xy 56.529212 -316.657608)
			(xy 56.555515 -316.616012) (xy 56.58815 -316.579175) (xy 56.626271 -316.54805) (xy 56.668892 -316.523443)
			(xy 56.714908 -316.505991) (xy 56.763127 -316.496147) (xy 56.812302 -316.494166) (xy 56.861157 -316.500098)
			(xy 56.908428 -316.51379) (xy 56.95289 -316.534888) (xy 56.993393 -316.562844) (xy 57.028886 -316.596936)
			(xy 57.058451 -316.63628) (xy 57.081322 -316.679857) (xy 57.096906 -316.726538) (xy 57.104801 -316.775115)
			(xy 57.105296 -316.799722) (xy 58.394104 -316.799722) (xy 58.398064 -316.750668) (xy 58.409841 -316.702884)
			(xy 58.429132 -316.657608) (xy 58.455435 -316.616012) (xy 58.48807 -316.579175) (xy 58.526191 -316.54805)
			(xy 58.568812 -316.523443) (xy 58.614828 -316.505991) (xy 58.663047 -316.496147) (xy 58.712222 -316.494166)
			(xy 58.761077 -316.500098) (xy 58.808348 -316.51379) (xy 58.85281 -316.534888) (xy 58.893313 -316.562844)
			(xy 58.928806 -316.596936) (xy 58.958371 -316.63628) (xy 58.981242 -316.679857) (xy 58.996826 -316.726538)
			(xy 59.004721 -316.775115) (xy 59.005216 -316.799722) (xy 60.294024 -316.799722) (xy 60.297984 -316.750668)
			(xy 60.309761 -316.702884) (xy 60.329052 -316.657608) (xy 60.355355 -316.616012) (xy 60.38799 -316.579175)
			(xy 60.426111 -316.54805) (xy 60.468732 -316.523443) (xy 60.514748 -316.505991) (xy 60.562967 -316.496147)
			(xy 60.612142 -316.494166) (xy 60.660997 -316.500098) (xy 60.708268 -316.51379) (xy 60.75273 -316.534888)
			(xy 60.793233 -316.562844) (xy 60.828726 -316.596936) (xy 60.858291 -316.63628) (xy 60.881162 -316.679857)
			(xy 60.896746 -316.726538) (xy 60.904641 -316.775115) (xy 60.905136 -316.799722) (xy 62.193944 -316.799722)
			(xy 62.197904 -316.750668) (xy 62.209681 -316.702884) (xy 62.228972 -316.657608) (xy 62.255275 -316.616012)
			(xy 62.28791 -316.579175) (xy 62.326031 -316.54805) (xy 62.368652 -316.523443) (xy 62.414668 -316.505991)
			(xy 62.462887 -316.496147) (xy 62.512062 -316.494166) (xy 62.560917 -316.500098) (xy 62.608188 -316.51379)
			(xy 62.65265 -316.534888) (xy 62.693153 -316.562844) (xy 62.728646 -316.596936) (xy 62.758211 -316.63628)
			(xy 62.781082 -316.679857) (xy 62.796666 -316.726538) (xy 62.804561 -316.775115) (xy 62.805056 -316.799722)
			(xy 64.094118 -316.799722) (xy 64.098078 -316.750668) (xy 64.109855 -316.702884) (xy 64.129146 -316.657608)
			(xy 64.155449 -316.616012) (xy 64.188084 -316.579175) (xy 64.226205 -316.54805) (xy 64.268826 -316.523443)
			(xy 64.314842 -316.505991) (xy 64.363061 -316.496147) (xy 64.412236 -316.494166) (xy 64.461091 -316.500098)
			(xy 64.508362 -316.51379) (xy 64.552824 -316.534888) (xy 64.593327 -316.562844) (xy 64.62882 -316.596936)
			(xy 64.658385 -316.63628) (xy 64.681256 -316.679857) (xy 64.69684 -316.726538) (xy 64.704735 -316.775115)
			(xy 64.70523 -316.799722) (xy 73.593972 -316.799722) (xy 73.597932 -316.750668) (xy 73.609709 -316.702884)
			(xy 73.629 -316.657608) (xy 73.655303 -316.616012) (xy 73.687938 -316.579175) (xy 73.726059 -316.54805)
			(xy 73.76868 -316.523443) (xy 73.814696 -316.505991) (xy 73.862915 -316.496147) (xy 73.91209 -316.494166)
			(xy 73.960945 -316.500098) (xy 74.008216 -316.51379) (xy 74.052678 -316.534888) (xy 74.093181 -316.562844)
			(xy 74.128674 -316.596936) (xy 74.158239 -316.63628) (xy 74.18111 -316.679857) (xy 74.196694 -316.726538)
			(xy 74.204589 -316.775115) (xy 74.205084 -316.799722) (xy 75.494146 -316.799722) (xy 75.498106 -316.750668)
			(xy 75.509883 -316.702884) (xy 75.529174 -316.657608) (xy 75.555477 -316.616012) (xy 75.588112 -316.579175)
			(xy 75.626233 -316.54805) (xy 75.668854 -316.523443) (xy 75.71487 -316.505991) (xy 75.763089 -316.496147)
			(xy 75.812264 -316.494166) (xy 75.861119 -316.500098) (xy 75.90839 -316.51379) (xy 75.952852 -316.534888)
			(xy 75.993355 -316.562844) (xy 76.028848 -316.596936) (xy 76.058413 -316.63628) (xy 76.081284 -316.679857)
			(xy 76.096868 -316.726538) (xy 76.104763 -316.775115) (xy 76.105258 -316.799722) (xy 77.394066 -316.799722)
			(xy 77.398026 -316.750668) (xy 77.409803 -316.702884) (xy 77.429094 -316.657608) (xy 77.455397 -316.616012)
			(xy 77.488032 -316.579175) (xy 77.526153 -316.54805) (xy 77.568774 -316.523443) (xy 77.61479 -316.505991)
			(xy 77.663009 -316.496147) (xy 77.712184 -316.494166) (xy 77.761039 -316.500098) (xy 77.80831 -316.51379)
			(xy 77.852772 -316.534888) (xy 77.893275 -316.562844) (xy 77.928768 -316.596936) (xy 77.958333 -316.63628)
			(xy 77.981204 -316.679857) (xy 77.996788 -316.726538) (xy 78.004683 -316.775115) (xy 78.005178 -316.799722)
			(xy 79.293986 -316.799722) (xy 79.297946 -316.750668) (xy 79.309723 -316.702884) (xy 79.329014 -316.657608)
			(xy 79.355317 -316.616012) (xy 79.387952 -316.579175) (xy 79.426073 -316.54805) (xy 79.468694 -316.523443)
			(xy 79.51471 -316.505991) (xy 79.562929 -316.496147) (xy 79.612104 -316.494166) (xy 79.660959 -316.500098)
			(xy 79.70823 -316.51379) (xy 79.752692 -316.534888) (xy 79.793195 -316.562844) (xy 79.828688 -316.596936)
			(xy 79.858253 -316.63628) (xy 79.881124 -316.679857) (xy 79.896708 -316.726538) (xy 79.904603 -316.775115)
			(xy 79.905098 -316.799722) (xy 81.19416 -316.799722) (xy 81.19812 -316.750668) (xy 81.209897 -316.702884)
			(xy 81.229188 -316.657608) (xy 81.255491 -316.616012) (xy 81.288126 -316.579175) (xy 81.326247 -316.54805)
			(xy 81.368868 -316.523443) (xy 81.414884 -316.505991) (xy 81.463103 -316.496147) (xy 81.512278 -316.494166)
			(xy 81.561133 -316.500098) (xy 81.608404 -316.51379) (xy 81.652866 -316.534888) (xy 81.693369 -316.562844)
			(xy 81.728862 -316.596936) (xy 81.758427 -316.63628) (xy 81.781298 -316.679857) (xy 81.796882 -316.726538)
			(xy 81.804777 -316.775115) (xy 81.805272 -316.799722) (xy 82.14412 -316.799722) (xy 82.14808 -316.750668)
			(xy 82.159857 -316.702884) (xy 82.179148 -316.657608) (xy 82.205451 -316.616012) (xy 82.238086 -316.579175)
			(xy 82.276207 -316.54805) (xy 82.318828 -316.523443) (xy 82.364844 -316.505991) (xy 82.413063 -316.496147)
			(xy 82.462238 -316.494166) (xy 82.511093 -316.500098) (xy 82.558364 -316.51379) (xy 82.602826 -316.534888)
			(xy 82.643329 -316.562844) (xy 82.678822 -316.596936) (xy 82.708387 -316.63628) (xy 82.731258 -316.679857)
			(xy 82.746842 -316.726538) (xy 82.754737 -316.775115) (xy 82.755232 -316.799722) (xy 152.644106 -316.799722)
			(xy 152.648066 -316.750668) (xy 152.659843 -316.702884) (xy 152.679134 -316.657608) (xy 152.705437 -316.616012)
			(xy 152.738072 -316.579175) (xy 152.776193 -316.54805) (xy 152.818814 -316.523443) (xy 152.86483 -316.505991)
			(xy 152.913049 -316.496147) (xy 152.962224 -316.494166) (xy 153.011079 -316.500098) (xy 153.05835 -316.51379)
			(xy 153.102812 -316.534888) (xy 153.143315 -316.562844) (xy 153.178808 -316.596936) (xy 153.208373 -316.63628)
			(xy 153.231244 -316.679857) (xy 153.246828 -316.726538) (xy 153.254723 -316.775115) (xy 153.255218 -316.799722)
			(xy 153.594066 -316.799722) (xy 153.598026 -316.750668) (xy 153.609803 -316.702884) (xy 153.629094 -316.657608)
			(xy 153.655397 -316.616012) (xy 153.688032 -316.579175) (xy 153.726153 -316.54805) (xy 153.768774 -316.523443)
			(xy 153.81479 -316.505991) (xy 153.863009 -316.496147) (xy 153.912184 -316.494166) (xy 153.961039 -316.500098)
			(xy 154.00831 -316.51379) (xy 154.052772 -316.534888) (xy 154.093275 -316.562844) (xy 154.128768 -316.596936)
			(xy 154.158333 -316.63628) (xy 154.181204 -316.679857) (xy 154.196788 -316.726538) (xy 154.204683 -316.775115)
			(xy 154.205178 -316.799722) (xy 155.49424 -316.799722) (xy 155.4982 -316.750668) (xy 155.509977 -316.702884)
			(xy 155.529268 -316.657608) (xy 155.555571 -316.616012) (xy 155.588206 -316.579175) (xy 155.626327 -316.54805)
			(xy 155.668948 -316.523443) (xy 155.714964 -316.505991) (xy 155.763183 -316.496147) (xy 155.812358 -316.494166)
			(xy 155.861213 -316.500098) (xy 155.908484 -316.51379) (xy 155.952946 -316.534888) (xy 155.993449 -316.562844)
			(xy 156.028942 -316.596936) (xy 156.058507 -316.63628) (xy 156.081378 -316.679857) (xy 156.096962 -316.726538)
			(xy 156.104857 -316.775115) (xy 156.105352 -316.799722) (xy 157.39416 -316.799722) (xy 157.39812 -316.750668)
			(xy 157.409897 -316.702884) (xy 157.429188 -316.657608) (xy 157.455491 -316.616012) (xy 157.488126 -316.579175)
			(xy 157.526247 -316.54805) (xy 157.568868 -316.523443) (xy 157.614884 -316.505991) (xy 157.663103 -316.496147)
			(xy 157.712278 -316.494166) (xy 157.761133 -316.500098) (xy 157.808404 -316.51379) (xy 157.852866 -316.534888)
			(xy 157.893369 -316.562844) (xy 157.928862 -316.596936) (xy 157.958427 -316.63628) (xy 157.981298 -316.679857)
			(xy 157.996882 -316.726538) (xy 158.004777 -316.775115) (xy 158.005272 -316.799722) (xy 159.29408 -316.799722)
			(xy 159.29804 -316.750668) (xy 159.309817 -316.702884) (xy 159.329108 -316.657608) (xy 159.355411 -316.616012)
			(xy 159.388046 -316.579175) (xy 159.426167 -316.54805) (xy 159.468788 -316.523443) (xy 159.514804 -316.505991)
			(xy 159.563023 -316.496147) (xy 159.612198 -316.494166) (xy 159.661053 -316.500098) (xy 159.708324 -316.51379)
			(xy 159.752786 -316.534888) (xy 159.793289 -316.562844) (xy 159.828782 -316.596936) (xy 159.858347 -316.63628)
			(xy 159.881218 -316.679857) (xy 159.896802 -316.726538) (xy 159.904697 -316.775115) (xy 159.905192 -316.799722)
			(xy 161.194254 -316.799722) (xy 161.198214 -316.750668) (xy 161.209991 -316.702884) (xy 161.229282 -316.657608)
			(xy 161.255585 -316.616012) (xy 161.28822 -316.579175) (xy 161.326341 -316.54805) (xy 161.368962 -316.523443)
			(xy 161.414978 -316.505991) (xy 161.463197 -316.496147) (xy 161.512372 -316.494166) (xy 161.561227 -316.500098)
			(xy 161.608498 -316.51379) (xy 161.65296 -316.534888) (xy 161.693463 -316.562844) (xy 161.728956 -316.596936)
			(xy 161.758521 -316.63628) (xy 161.781392 -316.679857) (xy 161.796976 -316.726538) (xy 161.804871 -316.775115)
			(xy 161.805366 -316.799722) (xy 163.094174 -316.799722) (xy 163.098134 -316.750668) (xy 163.109911 -316.702884)
			(xy 163.129202 -316.657608) (xy 163.155505 -316.616012) (xy 163.18814 -316.579175) (xy 163.226261 -316.54805)
			(xy 163.268882 -316.523443) (xy 163.314898 -316.505991) (xy 163.363117 -316.496147) (xy 163.412292 -316.494166)
			(xy 163.461147 -316.500098) (xy 163.508418 -316.51379) (xy 163.55288 -316.534888) (xy 163.593383 -316.562844)
			(xy 163.628876 -316.596936) (xy 163.658441 -316.63628) (xy 163.681312 -316.679857) (xy 163.696896 -316.726538)
			(xy 163.704791 -316.775115) (xy 163.705286 -316.799722) (xy 164.994094 -316.799722) (xy 164.998054 -316.750668)
			(xy 165.009831 -316.702884) (xy 165.029122 -316.657608) (xy 165.055425 -316.616012) (xy 165.08806 -316.579175)
			(xy 165.126181 -316.54805) (xy 165.168802 -316.523443) (xy 165.214818 -316.505991) (xy 165.263037 -316.496147)
			(xy 165.312212 -316.494166) (xy 165.361067 -316.500098) (xy 165.408338 -316.51379) (xy 165.4528 -316.534888)
			(xy 165.493303 -316.562844) (xy 165.528796 -316.596936) (xy 165.558361 -316.63628) (xy 165.581232 -316.679857)
			(xy 165.596816 -316.726538) (xy 165.604711 -316.775115) (xy 165.605206 -316.799722) (xy 182.094136 -316.799722)
			(xy 182.098096 -316.750668) (xy 182.109873 -316.702884) (xy 182.129164 -316.657608) (xy 182.155467 -316.616012)
			(xy 182.188102 -316.579175) (xy 182.226223 -316.54805) (xy 182.268844 -316.523443) (xy 182.31486 -316.505991)
			(xy 182.363079 -316.496147) (xy 182.412254 -316.494166) (xy 182.461109 -316.500098) (xy 182.50838 -316.51379)
			(xy 182.552842 -316.534888) (xy 182.593345 -316.562844) (xy 182.628838 -316.596936) (xy 182.658403 -316.63628)
			(xy 182.681274 -316.679857) (xy 182.696858 -316.726538) (xy 182.704753 -316.775115) (xy 182.705248 -316.799722)
			(xy 183.994056 -316.799722) (xy 183.998016 -316.750668) (xy 184.009793 -316.702884) (xy 184.029084 -316.657608)
			(xy 184.055387 -316.616012) (xy 184.088022 -316.579175) (xy 184.126143 -316.54805) (xy 184.168764 -316.523443)
			(xy 184.21478 -316.505991) (xy 184.262999 -316.496147) (xy 184.312174 -316.494166) (xy 184.361029 -316.500098)
			(xy 184.4083 -316.51379) (xy 184.452762 -316.534888) (xy 184.493265 -316.562844) (xy 184.528758 -316.596936)
			(xy 184.558323 -316.63628) (xy 184.581194 -316.679857) (xy 184.596778 -316.726538) (xy 184.604673 -316.775115)
			(xy 184.605168 -316.799722) (xy 185.89423 -316.799722) (xy 185.89819 -316.750668) (xy 185.909967 -316.702884)
			(xy 185.929258 -316.657608) (xy 185.955561 -316.616012) (xy 185.988196 -316.579175) (xy 186.026317 -316.54805)
			(xy 186.068938 -316.523443) (xy 186.114954 -316.505991) (xy 186.163173 -316.496147) (xy 186.212348 -316.494166)
			(xy 186.261203 -316.500098) (xy 186.308474 -316.51379) (xy 186.352936 -316.534888) (xy 186.393439 -316.562844)
			(xy 186.428932 -316.596936) (xy 186.458497 -316.63628) (xy 186.481368 -316.679857) (xy 186.496952 -316.726538)
			(xy 186.504847 -316.775115) (xy 186.505342 -316.799722) (xy 187.79415 -316.799722) (xy 187.79811 -316.750668)
			(xy 187.809887 -316.702884) (xy 187.829178 -316.657608) (xy 187.855481 -316.616012) (xy 187.888116 -316.579175)
			(xy 187.926237 -316.54805) (xy 187.968858 -316.523443) (xy 188.014874 -316.505991) (xy 188.063093 -316.496147)
			(xy 188.112268 -316.494166) (xy 188.161123 -316.500098) (xy 188.208394 -316.51379) (xy 188.252856 -316.534888)
			(xy 188.293359 -316.562844) (xy 188.328852 -316.596936) (xy 188.358417 -316.63628) (xy 188.381288 -316.679857)
			(xy 188.396872 -316.726538) (xy 188.404767 -316.775115) (xy 188.405262 -316.799722) (xy 282.994112 -316.799722)
			(xy 282.998072 -316.750668) (xy 283.009849 -316.702884) (xy 283.02914 -316.657608) (xy 283.055443 -316.616012)
			(xy 283.088078 -316.579175) (xy 283.126199 -316.54805) (xy 283.16882 -316.523443) (xy 283.214836 -316.505991)
			(xy 283.263055 -316.496147) (xy 283.31223 -316.494166) (xy 283.361085 -316.500098) (xy 283.408356 -316.51379)
			(xy 283.452818 -316.534888) (xy 283.493321 -316.562844) (xy 283.528814 -316.596936) (xy 283.558379 -316.63628)
			(xy 283.58125 -316.679857) (xy 283.596834 -316.726538) (xy 283.604729 -316.775115) (xy 283.605224 -316.799722)
			(xy 284.894032 -316.799722) (xy 284.897992 -316.750668) (xy 284.909769 -316.702884) (xy 284.92906 -316.657608)
			(xy 284.955363 -316.616012) (xy 284.987998 -316.579175) (xy 285.026119 -316.54805) (xy 285.06874 -316.523443)
			(xy 285.114756 -316.505991) (xy 285.162975 -316.496147) (xy 285.21215 -316.494166) (xy 285.261005 -316.500098)
			(xy 285.308276 -316.51379) (xy 285.352738 -316.534888) (xy 285.393241 -316.562844) (xy 285.428734 -316.596936)
			(xy 285.458299 -316.63628) (xy 285.48117 -316.679857) (xy 285.496754 -316.726538) (xy 285.504649 -316.775115)
			(xy 285.505144 -316.799722) (xy 286.793952 -316.799722) (xy 286.797912 -316.750668) (xy 286.809689 -316.702884)
			(xy 286.82898 -316.657608) (xy 286.855283 -316.616012) (xy 286.887918 -316.579175) (xy 286.926039 -316.54805)
			(xy 286.96866 -316.523443) (xy 287.014676 -316.505991) (xy 287.062895 -316.496147) (xy 287.11207 -316.494166)
			(xy 287.160925 -316.500098) (xy 287.208196 -316.51379) (xy 287.252658 -316.534888) (xy 287.293161 -316.562844)
			(xy 287.328654 -316.596936) (xy 287.358219 -316.63628) (xy 287.38109 -316.679857) (xy 287.396674 -316.726538)
			(xy 287.404569 -316.775115) (xy 287.405064 -316.799722) (xy 288.694126 -316.799722) (xy 288.698086 -316.750668)
			(xy 288.709863 -316.702884) (xy 288.729154 -316.657608) (xy 288.755457 -316.616012) (xy 288.788092 -316.579175)
			(xy 288.826213 -316.54805) (xy 288.868834 -316.523443) (xy 288.91485 -316.505991) (xy 288.963069 -316.496147)
			(xy 289.012244 -316.494166) (xy 289.061099 -316.500098) (xy 289.10837 -316.51379) (xy 289.152832 -316.534888)
			(xy 289.193335 -316.562844) (xy 289.228828 -316.596936) (xy 289.258393 -316.63628) (xy 289.281264 -316.679857)
			(xy 289.296848 -316.726538) (xy 289.304743 -316.775115) (xy 289.305238 -316.799722) (xy 290.594046 -316.799722)
			(xy 290.598006 -316.750668) (xy 290.609783 -316.702884) (xy 290.629074 -316.657608) (xy 290.655377 -316.616012)
			(xy 290.688012 -316.579175) (xy 290.726133 -316.54805) (xy 290.768754 -316.523443) (xy 290.81477 -316.505991)
			(xy 290.862989 -316.496147) (xy 290.912164 -316.494166) (xy 290.961019 -316.500098) (xy 291.00829 -316.51379)
			(xy 291.052752 -316.534888) (xy 291.093255 -316.562844) (xy 291.128748 -316.596936) (xy 291.158313 -316.63628)
			(xy 291.181184 -316.679857) (xy 291.196768 -316.726538) (xy 291.204663 -316.775115) (xy 291.205158 -316.799722)
			(xy 292.493966 -316.799722) (xy 292.497926 -316.750668) (xy 292.509703 -316.702884) (xy 292.528994 -316.657608)
			(xy 292.555297 -316.616012) (xy 292.587932 -316.579175) (xy 292.626053 -316.54805) (xy 292.668674 -316.523443)
			(xy 292.71469 -316.505991) (xy 292.762909 -316.496147) (xy 292.812084 -316.494166) (xy 292.860939 -316.500098)
			(xy 292.90821 -316.51379) (xy 292.952672 -316.534888) (xy 292.993175 -316.562844) (xy 293.028668 -316.596936)
			(xy 293.058233 -316.63628) (xy 293.081104 -316.679857) (xy 293.096688 -316.726538) (xy 293.104583 -316.775115)
			(xy 293.105078 -316.799722) (xy 294.393886 -316.799722) (xy 294.397846 -316.750668) (xy 294.409623 -316.702884)
			(xy 294.428914 -316.657608) (xy 294.455217 -316.616012) (xy 294.487852 -316.579175) (xy 294.525973 -316.54805)
			(xy 294.568594 -316.523443) (xy 294.61461 -316.505991) (xy 294.662829 -316.496147) (xy 294.712004 -316.494166)
			(xy 294.760859 -316.500098) (xy 294.80813 -316.51379) (xy 294.852592 -316.534888) (xy 294.893095 -316.562844)
			(xy 294.928588 -316.596936) (xy 294.958153 -316.63628) (xy 294.981024 -316.679857) (xy 294.996608 -316.726538)
			(xy 295.004503 -316.775115) (xy 295.004998 -316.799722) (xy 296.29406 -316.799722) (xy 296.29802 -316.750668)
			(xy 296.309797 -316.702884) (xy 296.329088 -316.657608) (xy 296.355391 -316.616012) (xy 296.388026 -316.579175)
			(xy 296.426147 -316.54805) (xy 296.468768 -316.523443) (xy 296.514784 -316.505991) (xy 296.563003 -316.496147)
			(xy 296.612178 -316.494166) (xy 296.661033 -316.500098) (xy 296.708304 -316.51379) (xy 296.752766 -316.534888)
			(xy 296.793269 -316.562844) (xy 296.828762 -316.596936) (xy 296.858327 -316.63628) (xy 296.881198 -316.679857)
			(xy 296.896782 -316.726538) (xy 296.904677 -316.775115) (xy 296.905172 -316.799722) (xy 305.793914 -316.799722)
			(xy 305.797874 -316.750668) (xy 305.809651 -316.702884) (xy 305.828942 -316.657608) (xy 305.855245 -316.616012)
			(xy 305.88788 -316.579175) (xy 305.926001 -316.54805) (xy 305.968622 -316.523443) (xy 306.014638 -316.505991)
			(xy 306.062857 -316.496147) (xy 306.112032 -316.494166) (xy 306.160887 -316.500098) (xy 306.208158 -316.51379)
			(xy 306.25262 -316.534888) (xy 306.293123 -316.562844) (xy 306.328616 -316.596936) (xy 306.358181 -316.63628)
			(xy 306.381052 -316.679857) (xy 306.396636 -316.726538) (xy 306.404531 -316.775115) (xy 306.405026 -316.799722)
			(xy 307.694088 -316.799722) (xy 307.698048 -316.750668) (xy 307.709825 -316.702884) (xy 307.729116 -316.657608)
			(xy 307.755419 -316.616012) (xy 307.788054 -316.579175) (xy 307.826175 -316.54805) (xy 307.868796 -316.523443)
			(xy 307.914812 -316.505991) (xy 307.963031 -316.496147) (xy 308.012206 -316.494166) (xy 308.061061 -316.500098)
			(xy 308.108332 -316.51379) (xy 308.152794 -316.534888) (xy 308.193297 -316.562844) (xy 308.22879 -316.596936)
			(xy 308.258355 -316.63628) (xy 308.281226 -316.679857) (xy 308.29681 -316.726538) (xy 308.304705 -316.775115)
			(xy 308.3052 -316.799722) (xy 309.594008 -316.799722) (xy 309.597968 -316.750668) (xy 309.609745 -316.702884)
			(xy 309.629036 -316.657608) (xy 309.655339 -316.616012) (xy 309.687974 -316.579175) (xy 309.726095 -316.54805)
			(xy 309.768716 -316.523443) (xy 309.814732 -316.505991) (xy 309.862951 -316.496147) (xy 309.912126 -316.494166)
			(xy 309.960981 -316.500098) (xy 310.008252 -316.51379) (xy 310.052714 -316.534888) (xy 310.093217 -316.562844)
			(xy 310.12871 -316.596936) (xy 310.158275 -316.63628) (xy 310.181146 -316.679857) (xy 310.19673 -316.726538)
			(xy 310.204625 -316.775115) (xy 310.20512 -316.799722) (xy 311.493928 -316.799722) (xy 311.497888 -316.750668)
			(xy 311.509665 -316.702884) (xy 311.528956 -316.657608) (xy 311.555259 -316.616012) (xy 311.587894 -316.579175)
			(xy 311.626015 -316.54805) (xy 311.668636 -316.523443) (xy 311.714652 -316.505991) (xy 311.762871 -316.496147)
			(xy 311.812046 -316.494166) (xy 311.860901 -316.500098) (xy 311.908172 -316.51379) (xy 311.952634 -316.534888)
			(xy 311.993137 -316.562844) (xy 312.02863 -316.596936) (xy 312.058195 -316.63628) (xy 312.081066 -316.679857)
			(xy 312.09665 -316.726538) (xy 312.104545 -316.775115) (xy 312.10504 -316.799722) (xy 313.394102 -316.799722)
			(xy 313.398062 -316.750668) (xy 313.409839 -316.702884) (xy 313.42913 -316.657608) (xy 313.455433 -316.616012)
			(xy 313.488068 -316.579175) (xy 313.526189 -316.54805) (xy 313.56881 -316.523443) (xy 313.614826 -316.505991)
			(xy 313.663045 -316.496147) (xy 313.71222 -316.494166) (xy 313.761075 -316.500098) (xy 313.808346 -316.51379)
			(xy 313.852808 -316.534888) (xy 313.893311 -316.562844) (xy 313.928804 -316.596936) (xy 313.958369 -316.63628)
			(xy 313.98124 -316.679857) (xy 313.996824 -316.726538) (xy 314.004719 -316.775115) (xy 314.005214 -316.799722)
			(xy 314.344062 -316.799722) (xy 314.348022 -316.750668) (xy 314.359799 -316.702884) (xy 314.37909 -316.657608)
			(xy 314.405393 -316.616012) (xy 314.438028 -316.579175) (xy 314.476149 -316.54805) (xy 314.51877 -316.523443)
			(xy 314.564786 -316.505991) (xy 314.613005 -316.496147) (xy 314.66218 -316.494166) (xy 314.711035 -316.500098)
			(xy 314.758306 -316.51379) (xy 314.802768 -316.534888) (xy 314.843271 -316.562844) (xy 314.878764 -316.596936)
			(xy 314.908329 -316.63628) (xy 314.9312 -316.679857) (xy 314.946784 -316.726538) (xy 314.954679 -316.775115)
			(xy 314.955174 -316.799722) (xy 384.844048 -316.799722) (xy 384.848008 -316.750668) (xy 384.859785 -316.702884)
			(xy 384.879076 -316.657608) (xy 384.905379 -316.616012) (xy 384.938014 -316.579175) (xy 384.976135 -316.54805)
			(xy 385.018756 -316.523443) (xy 385.064772 -316.505991) (xy 385.112991 -316.496147) (xy 385.162166 -316.494166)
			(xy 385.211021 -316.500098) (xy 385.258292 -316.51379) (xy 385.302754 -316.534888) (xy 385.343257 -316.562844)
			(xy 385.37875 -316.596936) (xy 385.408315 -316.63628) (xy 385.431186 -316.679857) (xy 385.44677 -316.726538)
			(xy 385.454665 -316.775115) (xy 385.45516 -316.799722) (xy 385.794008 -316.799722) (xy 385.797968 -316.750668)
			(xy 385.809745 -316.702884) (xy 385.829036 -316.657608) (xy 385.855339 -316.616012) (xy 385.887974 -316.579175)
			(xy 385.926095 -316.54805) (xy 385.968716 -316.523443) (xy 386.014732 -316.505991) (xy 386.062951 -316.496147)
			(xy 386.112126 -316.494166) (xy 386.160981 -316.500098) (xy 386.208252 -316.51379) (xy 386.252714 -316.534888)
			(xy 386.293217 -316.562844) (xy 386.32871 -316.596936) (xy 386.358275 -316.63628) (xy 386.381146 -316.679857)
			(xy 386.39673 -316.726538) (xy 386.404625 -316.775115) (xy 386.40512 -316.799722) (xy 387.694182 -316.799722)
			(xy 387.698142 -316.750668) (xy 387.709919 -316.702884) (xy 387.72921 -316.657608) (xy 387.755513 -316.616012)
			(xy 387.788148 -316.579175) (xy 387.826269 -316.54805) (xy 387.86889 -316.523443) (xy 387.914906 -316.505991)
			(xy 387.963125 -316.496147) (xy 388.0123 -316.494166) (xy 388.061155 -316.500098) (xy 388.108426 -316.51379)
			(xy 388.152888 -316.534888) (xy 388.193391 -316.562844) (xy 388.228884 -316.596936) (xy 388.258449 -316.63628)
			(xy 388.28132 -316.679857) (xy 388.296904 -316.726538) (xy 388.304799 -316.775115) (xy 388.305294 -316.799722)
			(xy 389.594102 -316.799722) (xy 389.598062 -316.750668) (xy 389.609839 -316.702884) (xy 389.62913 -316.657608)
			(xy 389.655433 -316.616012) (xy 389.688068 -316.579175) (xy 389.726189 -316.54805) (xy 389.76881 -316.523443)
			(xy 389.814826 -316.505991) (xy 389.863045 -316.496147) (xy 389.91222 -316.494166) (xy 389.961075 -316.500098)
			(xy 390.008346 -316.51379) (xy 390.052808 -316.534888) (xy 390.093311 -316.562844) (xy 390.128804 -316.596936)
			(xy 390.158369 -316.63628) (xy 390.18124 -316.679857) (xy 390.196824 -316.726538) (xy 390.204719 -316.775115)
			(xy 390.205214 -316.799722) (xy 391.494022 -316.799722) (xy 391.497982 -316.750668) (xy 391.509759 -316.702884)
			(xy 391.52905 -316.657608) (xy 391.555353 -316.616012) (xy 391.587988 -316.579175) (xy 391.626109 -316.54805)
			(xy 391.66873 -316.523443) (xy 391.714746 -316.505991) (xy 391.762965 -316.496147) (xy 391.81214 -316.494166)
			(xy 391.860995 -316.500098) (xy 391.908266 -316.51379) (xy 391.952728 -316.534888) (xy 391.993231 -316.562844)
			(xy 392.028724 -316.596936) (xy 392.058289 -316.63628) (xy 392.08116 -316.679857) (xy 392.096744 -316.726538)
			(xy 392.104639 -316.775115) (xy 392.105134 -316.799722) (xy 393.394196 -316.799722) (xy 393.398156 -316.750668)
			(xy 393.409933 -316.702884) (xy 393.429224 -316.657608) (xy 393.455527 -316.616012) (xy 393.488162 -316.579175)
			(xy 393.526283 -316.54805) (xy 393.568904 -316.523443) (xy 393.61492 -316.505991) (xy 393.663139 -316.496147)
			(xy 393.712314 -316.494166) (xy 393.761169 -316.500098) (xy 393.80844 -316.51379) (xy 393.852902 -316.534888)
			(xy 393.893405 -316.562844) (xy 393.928898 -316.596936) (xy 393.958463 -316.63628) (xy 393.981334 -316.679857)
			(xy 393.996918 -316.726538) (xy 394.004813 -316.775115) (xy 394.005308 -316.799722) (xy 395.294116 -316.799722)
			(xy 395.298076 -316.750668) (xy 395.309853 -316.702884) (xy 395.329144 -316.657608) (xy 395.355447 -316.616012)
			(xy 395.388082 -316.579175) (xy 395.426203 -316.54805) (xy 395.468824 -316.523443) (xy 395.51484 -316.505991)
			(xy 395.563059 -316.496147) (xy 395.612234 -316.494166) (xy 395.661089 -316.500098) (xy 395.70836 -316.51379)
			(xy 395.752822 -316.534888) (xy 395.793325 -316.562844) (xy 395.828818 -316.596936) (xy 395.858383 -316.63628)
			(xy 395.881254 -316.679857) (xy 395.896838 -316.726538) (xy 395.904733 -316.775115) (xy 395.905228 -316.799722)
			(xy 397.194036 -316.799722) (xy 397.197996 -316.750668) (xy 397.209773 -316.702884) (xy 397.229064 -316.657608)
			(xy 397.255367 -316.616012) (xy 397.288002 -316.579175) (xy 397.326123 -316.54805) (xy 397.368744 -316.523443)
			(xy 397.41476 -316.505991) (xy 397.462979 -316.496147) (xy 397.512154 -316.494166) (xy 397.561009 -316.500098)
			(xy 397.60828 -316.51379) (xy 397.652742 -316.534888) (xy 397.693245 -316.562844) (xy 397.728738 -316.596936)
			(xy 397.758303 -316.63628) (xy 397.781174 -316.679857) (xy 397.796758 -316.726538) (xy 397.804653 -316.775115)
			(xy 397.805148 -316.799722) (xy 414.294078 -316.799722) (xy 414.298038 -316.750668) (xy 414.309815 -316.702884)
			(xy 414.329106 -316.657608) (xy 414.355409 -316.616012) (xy 414.388044 -316.579175) (xy 414.426165 -316.54805)
			(xy 414.468786 -316.523443) (xy 414.514802 -316.505991) (xy 414.563021 -316.496147) (xy 414.612196 -316.494166)
			(xy 414.661051 -316.500098) (xy 414.708322 -316.51379) (xy 414.752784 -316.534888) (xy 414.793287 -316.562844)
			(xy 414.82878 -316.596936) (xy 414.858345 -316.63628) (xy 414.881216 -316.679857) (xy 414.8968 -316.726538)
			(xy 414.904695 -316.775115) (xy 414.90519 -316.799722) (xy 416.193998 -316.799722) (xy 416.197958 -316.750668)
			(xy 416.209735 -316.702884) (xy 416.229026 -316.657608) (xy 416.255329 -316.616012) (xy 416.287964 -316.579175)
			(xy 416.326085 -316.54805) (xy 416.368706 -316.523443) (xy 416.414722 -316.505991) (xy 416.462941 -316.496147)
			(xy 416.512116 -316.494166) (xy 416.560971 -316.500098) (xy 416.608242 -316.51379) (xy 416.652704 -316.534888)
			(xy 416.693207 -316.562844) (xy 416.7287 -316.596936) (xy 416.758265 -316.63628) (xy 416.781136 -316.679857)
			(xy 416.79672 -316.726538) (xy 416.804615 -316.775115) (xy 416.80511 -316.799722) (xy 418.094172 -316.799722)
			(xy 418.098132 -316.750668) (xy 418.109909 -316.702884) (xy 418.1292 -316.657608) (xy 418.155503 -316.616012)
			(xy 418.188138 -316.579175) (xy 418.226259 -316.54805) (xy 418.26888 -316.523443) (xy 418.314896 -316.505991)
			(xy 418.363115 -316.496147) (xy 418.41229 -316.494166) (xy 418.461145 -316.500098) (xy 418.508416 -316.51379)
			(xy 418.552878 -316.534888) (xy 418.593381 -316.562844) (xy 418.628874 -316.596936) (xy 418.658439 -316.63628)
			(xy 418.68131 -316.679857) (xy 418.696894 -316.726538) (xy 418.704789 -316.775115) (xy 418.705284 -316.799722)
			(xy 419.994092 -316.799722) (xy 419.998052 -316.750668) (xy 420.009829 -316.702884) (xy 420.02912 -316.657608)
			(xy 420.055423 -316.616012) (xy 420.088058 -316.579175) (xy 420.126179 -316.54805) (xy 420.1688 -316.523443)
			(xy 420.214816 -316.505991) (xy 420.263035 -316.496147) (xy 420.31221 -316.494166) (xy 420.361065 -316.500098)
			(xy 420.408336 -316.51379) (xy 420.452798 -316.534888) (xy 420.493301 -316.562844) (xy 420.528794 -316.596936)
			(xy 420.558359 -316.63628) (xy 420.58123 -316.679857) (xy 420.596814 -316.726538) (xy 420.604709 -316.775115)
			(xy 420.605204 -316.799722) (xy 420.604709 -316.824329) (xy 420.596814 -316.872906) (xy 420.58123 -316.919587)
			(xy 420.558359 -316.963164) (xy 420.528794 -317.002508) (xy 420.493301 -317.0366) (xy 420.452798 -317.064556)
			(xy 420.408336 -317.085654) (xy 420.361065 -317.099346) (xy 420.31221 -317.105278) (xy 420.263035 -317.103297)
			(xy 420.214816 -317.093453) (xy 420.1688 -317.076001) (xy 420.126179 -317.051394) (xy 420.088058 -317.020269)
			(xy 420.055423 -316.983432) (xy 420.02912 -316.941836) (xy 420.009829 -316.89656) (xy 419.998052 -316.848776)
			(xy 419.994092 -316.799722) (xy 418.705284 -316.799722) (xy 418.704789 -316.824329) (xy 418.696894 -316.872906)
			(xy 418.68131 -316.919587) (xy 418.658439 -316.963164) (xy 418.628874 -317.002508) (xy 418.593381 -317.0366)
			(xy 418.552878 -317.064556) (xy 418.508416 -317.085654) (xy 418.461145 -317.099346) (xy 418.41229 -317.105278)
			(xy 418.363115 -317.103297) (xy 418.314896 -317.093453) (xy 418.26888 -317.076001) (xy 418.226259 -317.051394)
			(xy 418.188138 -317.020269) (xy 418.155503 -316.983432) (xy 418.1292 -316.941836) (xy 418.109909 -316.89656)
			(xy 418.098132 -316.848776) (xy 418.094172 -316.799722) (xy 416.80511 -316.799722) (xy 416.804615 -316.824329)
			(xy 416.79672 -316.872906) (xy 416.781136 -316.919587) (xy 416.758265 -316.963164) (xy 416.7287 -317.002508)
			(xy 416.693207 -317.0366) (xy 416.652704 -317.064556) (xy 416.608242 -317.085654) (xy 416.560971 -317.099346)
			(xy 416.512116 -317.105278) (xy 416.462941 -317.103297) (xy 416.414722 -317.093453) (xy 416.368706 -317.076001)
			(xy 416.326085 -317.051394) (xy 416.287964 -317.020269) (xy 416.255329 -316.983432) (xy 416.229026 -316.941836)
			(xy 416.209735 -316.89656) (xy 416.197958 -316.848776) (xy 416.193998 -316.799722) (xy 414.90519 -316.799722)
			(xy 414.904695 -316.824329) (xy 414.8968 -316.872906) (xy 414.881216 -316.919587) (xy 414.858345 -316.963164)
			(xy 414.82878 -317.002508) (xy 414.793287 -317.0366) (xy 414.752784 -317.064556) (xy 414.708322 -317.085654)
			(xy 414.661051 -317.099346) (xy 414.612196 -317.105278) (xy 414.563021 -317.103297) (xy 414.514802 -317.093453)
			(xy 414.468786 -317.076001) (xy 414.426165 -317.051394) (xy 414.388044 -317.020269) (xy 414.355409 -316.983432)
			(xy 414.329106 -316.941836) (xy 414.309815 -316.89656) (xy 414.298038 -316.848776) (xy 414.294078 -316.799722)
			(xy 397.805148 -316.799722) (xy 397.804653 -316.824329) (xy 397.796758 -316.872906) (xy 397.781174 -316.919587)
			(xy 397.758303 -316.963164) (xy 397.728738 -317.002508) (xy 397.693245 -317.0366) (xy 397.652742 -317.064556)
			(xy 397.60828 -317.085654) (xy 397.561009 -317.099346) (xy 397.512154 -317.105278) (xy 397.462979 -317.103297)
			(xy 397.41476 -317.093453) (xy 397.368744 -317.076001) (xy 397.326123 -317.051394) (xy 397.288002 -317.020269)
			(xy 397.255367 -316.983432) (xy 397.229064 -316.941836) (xy 397.209773 -316.89656) (xy 397.197996 -316.848776)
			(xy 397.194036 -316.799722) (xy 395.905228 -316.799722) (xy 395.904733 -316.824329) (xy 395.896838 -316.872906)
			(xy 395.881254 -316.919587) (xy 395.858383 -316.963164) (xy 395.828818 -317.002508) (xy 395.793325 -317.0366)
			(xy 395.752822 -317.064556) (xy 395.70836 -317.085654) (xy 395.661089 -317.099346) (xy 395.612234 -317.105278)
			(xy 395.563059 -317.103297) (xy 395.51484 -317.093453) (xy 395.468824 -317.076001) (xy 395.426203 -317.051394)
			(xy 395.388082 -317.020269) (xy 395.355447 -316.983432) (xy 395.329144 -316.941836) (xy 395.309853 -316.89656)
			(xy 395.298076 -316.848776) (xy 395.294116 -316.799722) (xy 394.005308 -316.799722) (xy 394.004813 -316.824329)
			(xy 393.996918 -316.872906) (xy 393.981334 -316.919587) (xy 393.958463 -316.963164) (xy 393.928898 -317.002508)
			(xy 393.893405 -317.0366) (xy 393.852902 -317.064556) (xy 393.80844 -317.085654) (xy 393.761169 -317.099346)
			(xy 393.712314 -317.105278) (xy 393.663139 -317.103297) (xy 393.61492 -317.093453) (xy 393.568904 -317.076001)
			(xy 393.526283 -317.051394) (xy 393.488162 -317.020269) (xy 393.455527 -316.983432) (xy 393.429224 -316.941836)
			(xy 393.409933 -316.89656) (xy 393.398156 -316.848776) (xy 393.394196 -316.799722) (xy 392.105134 -316.799722)
			(xy 392.104639 -316.824329) (xy 392.096744 -316.872906) (xy 392.08116 -316.919587) (xy 392.058289 -316.963164)
			(xy 392.028724 -317.002508) (xy 391.993231 -317.0366) (xy 391.952728 -317.064556) (xy 391.908266 -317.085654)
			(xy 391.860995 -317.099346) (xy 391.81214 -317.105278) (xy 391.762965 -317.103297) (xy 391.714746 -317.093453)
			(xy 391.66873 -317.076001) (xy 391.626109 -317.051394) (xy 391.587988 -317.020269) (xy 391.555353 -316.983432)
			(xy 391.52905 -316.941836) (xy 391.509759 -316.89656) (xy 391.497982 -316.848776) (xy 391.494022 -316.799722)
			(xy 390.205214 -316.799722) (xy 390.204719 -316.824329) (xy 390.196824 -316.872906) (xy 390.18124 -316.919587)
			(xy 390.158369 -316.963164) (xy 390.128804 -317.002508) (xy 390.093311 -317.0366) (xy 390.052808 -317.064556)
			(xy 390.008346 -317.085654) (xy 389.961075 -317.099346) (xy 389.91222 -317.105278) (xy 389.863045 -317.103297)
			(xy 389.814826 -317.093453) (xy 389.76881 -317.076001) (xy 389.726189 -317.051394) (xy 389.688068 -317.020269)
			(xy 389.655433 -316.983432) (xy 389.62913 -316.941836) (xy 389.609839 -316.89656) (xy 389.598062 -316.848776)
			(xy 389.594102 -316.799722) (xy 388.305294 -316.799722) (xy 388.304799 -316.824329) (xy 388.296904 -316.872906)
			(xy 388.28132 -316.919587) (xy 388.258449 -316.963164) (xy 388.228884 -317.002508) (xy 388.193391 -317.0366)
			(xy 388.152888 -317.064556) (xy 388.108426 -317.085654) (xy 388.061155 -317.099346) (xy 388.0123 -317.105278)
			(xy 387.963125 -317.103297) (xy 387.914906 -317.093453) (xy 387.86889 -317.076001) (xy 387.826269 -317.051394)
			(xy 387.788148 -317.020269) (xy 387.755513 -316.983432) (xy 387.72921 -316.941836) (xy 387.709919 -316.89656)
			(xy 387.698142 -316.848776) (xy 387.694182 -316.799722) (xy 386.40512 -316.799722) (xy 386.404625 -316.824329)
			(xy 386.39673 -316.872906) (xy 386.381146 -316.919587) (xy 386.358275 -316.963164) (xy 386.32871 -317.002508)
			(xy 386.293217 -317.0366) (xy 386.252714 -317.064556) (xy 386.208252 -317.085654) (xy 386.160981 -317.099346)
			(xy 386.112126 -317.105278) (xy 386.062951 -317.103297) (xy 386.014732 -317.093453) (xy 385.968716 -317.076001)
			(xy 385.926095 -317.051394) (xy 385.887974 -317.020269) (xy 385.855339 -316.983432) (xy 385.829036 -316.941836)
			(xy 385.809745 -316.89656) (xy 385.797968 -316.848776) (xy 385.794008 -316.799722) (xy 385.45516 -316.799722)
			(xy 385.454665 -316.824329) (xy 385.44677 -316.872906) (xy 385.431186 -316.919587) (xy 385.408315 -316.963164)
			(xy 385.37875 -317.002508) (xy 385.343257 -317.0366) (xy 385.302754 -317.064556) (xy 385.258292 -317.085654)
			(xy 385.211021 -317.099346) (xy 385.162166 -317.105278) (xy 385.112991 -317.103297) (xy 385.064772 -317.093453)
			(xy 385.018756 -317.076001) (xy 384.976135 -317.051394) (xy 384.938014 -317.020269) (xy 384.905379 -316.983432)
			(xy 384.879076 -316.941836) (xy 384.859785 -316.89656) (xy 384.848008 -316.848776) (xy 384.844048 -316.799722)
			(xy 314.955174 -316.799722) (xy 314.954679 -316.824329) (xy 314.946784 -316.872906) (xy 314.9312 -316.919587)
			(xy 314.908329 -316.963164) (xy 314.878764 -317.002508) (xy 314.843271 -317.0366) (xy 314.802768 -317.064556)
			(xy 314.758306 -317.085654) (xy 314.711035 -317.099346) (xy 314.66218 -317.105278) (xy 314.613005 -317.103297)
			(xy 314.564786 -317.093453) (xy 314.51877 -317.076001) (xy 314.476149 -317.051394) (xy 314.438028 -317.020269)
			(xy 314.405393 -316.983432) (xy 314.37909 -316.941836) (xy 314.359799 -316.89656) (xy 314.348022 -316.848776)
			(xy 314.344062 -316.799722) (xy 314.005214 -316.799722) (xy 314.004719 -316.824329) (xy 313.996824 -316.872906)
			(xy 313.98124 -316.919587) (xy 313.958369 -316.963164) (xy 313.928804 -317.002508) (xy 313.893311 -317.0366)
			(xy 313.852808 -317.064556) (xy 313.808346 -317.085654) (xy 313.761075 -317.099346) (xy 313.71222 -317.105278)
			(xy 313.663045 -317.103297) (xy 313.614826 -317.093453) (xy 313.56881 -317.076001) (xy 313.526189 -317.051394)
			(xy 313.488068 -317.020269) (xy 313.455433 -316.983432) (xy 313.42913 -316.941836) (xy 313.409839 -316.89656)
			(xy 313.398062 -316.848776) (xy 313.394102 -316.799722) (xy 312.10504 -316.799722) (xy 312.104545 -316.824329)
			(xy 312.09665 -316.872906) (xy 312.081066 -316.919587) (xy 312.058195 -316.963164) (xy 312.02863 -317.002508)
			(xy 311.993137 -317.0366) (xy 311.952634 -317.064556) (xy 311.908172 -317.085654) (xy 311.860901 -317.099346)
			(xy 311.812046 -317.105278) (xy 311.762871 -317.103297) (xy 311.714652 -317.093453) (xy 311.668636 -317.076001)
			(xy 311.626015 -317.051394) (xy 311.587894 -317.020269) (xy 311.555259 -316.983432) (xy 311.528956 -316.941836)
			(xy 311.509665 -316.89656) (xy 311.497888 -316.848776) (xy 311.493928 -316.799722) (xy 310.20512 -316.799722)
			(xy 310.204625 -316.824329) (xy 310.19673 -316.872906) (xy 310.181146 -316.919587) (xy 310.158275 -316.963164)
			(xy 310.12871 -317.002508) (xy 310.093217 -317.0366) (xy 310.052714 -317.064556) (xy 310.008252 -317.085654)
			(xy 309.960981 -317.099346) (xy 309.912126 -317.105278) (xy 309.862951 -317.103297) (xy 309.814732 -317.093453)
			(xy 309.768716 -317.076001) (xy 309.726095 -317.051394) (xy 309.687974 -317.020269) (xy 309.655339 -316.983432)
			(xy 309.629036 -316.941836) (xy 309.609745 -316.89656) (xy 309.597968 -316.848776) (xy 309.594008 -316.799722)
			(xy 308.3052 -316.799722) (xy 308.304705 -316.824329) (xy 308.29681 -316.872906) (xy 308.281226 -316.919587)
			(xy 308.258355 -316.963164) (xy 308.22879 -317.002508) (xy 308.193297 -317.0366) (xy 308.152794 -317.064556)
			(xy 308.108332 -317.085654) (xy 308.061061 -317.099346) (xy 308.012206 -317.105278) (xy 307.963031 -317.103297)
			(xy 307.914812 -317.093453) (xy 307.868796 -317.076001) (xy 307.826175 -317.051394) (xy 307.788054 -317.020269)
			(xy 307.755419 -316.983432) (xy 307.729116 -316.941836) (xy 307.709825 -316.89656) (xy 307.698048 -316.848776)
			(xy 307.694088 -316.799722) (xy 306.405026 -316.799722) (xy 306.404531 -316.824329) (xy 306.396636 -316.872906)
			(xy 306.381052 -316.919587) (xy 306.358181 -316.963164) (xy 306.328616 -317.002508) (xy 306.293123 -317.0366)
			(xy 306.25262 -317.064556) (xy 306.208158 -317.085654) (xy 306.160887 -317.099346) (xy 306.112032 -317.105278)
			(xy 306.062857 -317.103297) (xy 306.014638 -317.093453) (xy 305.968622 -317.076001) (xy 305.926001 -317.051394)
			(xy 305.88788 -317.020269) (xy 305.855245 -316.983432) (xy 305.828942 -316.941836) (xy 305.809651 -316.89656)
			(xy 305.797874 -316.848776) (xy 305.793914 -316.799722) (xy 296.905172 -316.799722) (xy 296.904677 -316.824329)
			(xy 296.896782 -316.872906) (xy 296.881198 -316.919587) (xy 296.858327 -316.963164) (xy 296.828762 -317.002508)
			(xy 296.793269 -317.0366) (xy 296.752766 -317.064556) (xy 296.708304 -317.085654) (xy 296.661033 -317.099346)
			(xy 296.612178 -317.105278) (xy 296.563003 -317.103297) (xy 296.514784 -317.093453) (xy 296.468768 -317.076001)
			(xy 296.426147 -317.051394) (xy 296.388026 -317.020269) (xy 296.355391 -316.983432) (xy 296.329088 -316.941836)
			(xy 296.309797 -316.89656) (xy 296.29802 -316.848776) (xy 296.29406 -316.799722) (xy 295.004998 -316.799722)
			(xy 295.004503 -316.824329) (xy 294.996608 -316.872906) (xy 294.981024 -316.919587) (xy 294.958153 -316.963164)
			(xy 294.928588 -317.002508) (xy 294.893095 -317.0366) (xy 294.852592 -317.064556) (xy 294.80813 -317.085654)
			(xy 294.760859 -317.099346) (xy 294.712004 -317.105278) (xy 294.662829 -317.103297) (xy 294.61461 -317.093453)
			(xy 294.568594 -317.076001) (xy 294.525973 -317.051394) (xy 294.487852 -317.020269) (xy 294.455217 -316.983432)
			(xy 294.428914 -316.941836) (xy 294.409623 -316.89656) (xy 294.397846 -316.848776) (xy 294.393886 -316.799722)
			(xy 293.105078 -316.799722) (xy 293.104583 -316.824329) (xy 293.096688 -316.872906) (xy 293.081104 -316.919587)
			(xy 293.058233 -316.963164) (xy 293.028668 -317.002508) (xy 292.993175 -317.0366) (xy 292.952672 -317.064556)
			(xy 292.90821 -317.085654) (xy 292.860939 -317.099346) (xy 292.812084 -317.105278) (xy 292.762909 -317.103297)
			(xy 292.71469 -317.093453) (xy 292.668674 -317.076001) (xy 292.626053 -317.051394) (xy 292.587932 -317.020269)
			(xy 292.555297 -316.983432) (xy 292.528994 -316.941836) (xy 292.509703 -316.89656) (xy 292.497926 -316.848776)
			(xy 292.493966 -316.799722) (xy 291.205158 -316.799722) (xy 291.204663 -316.824329) (xy 291.196768 -316.872906)
			(xy 291.181184 -316.919587) (xy 291.158313 -316.963164) (xy 291.128748 -317.002508) (xy 291.093255 -317.0366)
			(xy 291.052752 -317.064556) (xy 291.00829 -317.085654) (xy 290.961019 -317.099346) (xy 290.912164 -317.105278)
			(xy 290.862989 -317.103297) (xy 290.81477 -317.093453) (xy 290.768754 -317.076001) (xy 290.726133 -317.051394)
			(xy 290.688012 -317.020269) (xy 290.655377 -316.983432) (xy 290.629074 -316.941836) (xy 290.609783 -316.89656)
			(xy 290.598006 -316.848776) (xy 290.594046 -316.799722) (xy 289.305238 -316.799722) (xy 289.304743 -316.824329)
			(xy 289.296848 -316.872906) (xy 289.281264 -316.919587) (xy 289.258393 -316.963164) (xy 289.228828 -317.002508)
			(xy 289.193335 -317.0366) (xy 289.152832 -317.064556) (xy 289.10837 -317.085654) (xy 289.061099 -317.099346)
			(xy 289.012244 -317.105278) (xy 288.963069 -317.103297) (xy 288.91485 -317.093453) (xy 288.868834 -317.076001)
			(xy 288.826213 -317.051394) (xy 288.788092 -317.020269) (xy 288.755457 -316.983432) (xy 288.729154 -316.941836)
			(xy 288.709863 -316.89656) (xy 288.698086 -316.848776) (xy 288.694126 -316.799722) (xy 287.405064 -316.799722)
			(xy 287.404569 -316.824329) (xy 287.396674 -316.872906) (xy 287.38109 -316.919587) (xy 287.358219 -316.963164)
			(xy 287.328654 -317.002508) (xy 287.293161 -317.0366) (xy 287.252658 -317.064556) (xy 287.208196 -317.085654)
			(xy 287.160925 -317.099346) (xy 287.11207 -317.105278) (xy 287.062895 -317.103297) (xy 287.014676 -317.093453)
			(xy 286.96866 -317.076001) (xy 286.926039 -317.051394) (xy 286.887918 -317.020269) (xy 286.855283 -316.983432)
			(xy 286.82898 -316.941836) (xy 286.809689 -316.89656) (xy 286.797912 -316.848776) (xy 286.793952 -316.799722)
			(xy 285.505144 -316.799722) (xy 285.504649 -316.824329) (xy 285.496754 -316.872906) (xy 285.48117 -316.919587)
			(xy 285.458299 -316.963164) (xy 285.428734 -317.002508) (xy 285.393241 -317.0366) (xy 285.352738 -317.064556)
			(xy 285.308276 -317.085654) (xy 285.261005 -317.099346) (xy 285.21215 -317.105278) (xy 285.162975 -317.103297)
			(xy 285.114756 -317.093453) (xy 285.06874 -317.076001) (xy 285.026119 -317.051394) (xy 284.987998 -317.020269)
			(xy 284.955363 -316.983432) (xy 284.92906 -316.941836) (xy 284.909769 -316.89656) (xy 284.897992 -316.848776)
			(xy 284.894032 -316.799722) (xy 283.605224 -316.799722) (xy 283.604729 -316.824329) (xy 283.596834 -316.872906)
			(xy 283.58125 -316.919587) (xy 283.558379 -316.963164) (xy 283.528814 -317.002508) (xy 283.493321 -317.0366)
			(xy 283.452818 -317.064556) (xy 283.408356 -317.085654) (xy 283.361085 -317.099346) (xy 283.31223 -317.105278)
			(xy 283.263055 -317.103297) (xy 283.214836 -317.093453) (xy 283.16882 -317.076001) (xy 283.126199 -317.051394)
			(xy 283.088078 -317.020269) (xy 283.055443 -316.983432) (xy 283.02914 -316.941836) (xy 283.009849 -316.89656)
			(xy 282.998072 -316.848776) (xy 282.994112 -316.799722) (xy 188.405262 -316.799722) (xy 188.404767 -316.824329)
			(xy 188.396872 -316.872906) (xy 188.381288 -316.919587) (xy 188.358417 -316.963164) (xy 188.328852 -317.002508)
			(xy 188.293359 -317.0366) (xy 188.252856 -317.064556) (xy 188.208394 -317.085654) (xy 188.161123 -317.099346)
			(xy 188.112268 -317.105278) (xy 188.063093 -317.103297) (xy 188.014874 -317.093453) (xy 187.968858 -317.076001)
			(xy 187.926237 -317.051394) (xy 187.888116 -317.020269) (xy 187.855481 -316.983432) (xy 187.829178 -316.941836)
			(xy 187.809887 -316.89656) (xy 187.79811 -316.848776) (xy 187.79415 -316.799722) (xy 186.505342 -316.799722)
			(xy 186.504847 -316.824329) (xy 186.496952 -316.872906) (xy 186.481368 -316.919587) (xy 186.458497 -316.963164)
			(xy 186.428932 -317.002508) (xy 186.393439 -317.0366) (xy 186.352936 -317.064556) (xy 186.308474 -317.085654)
			(xy 186.261203 -317.099346) (xy 186.212348 -317.105278) (xy 186.163173 -317.103297) (xy 186.114954 -317.093453)
			(xy 186.068938 -317.076001) (xy 186.026317 -317.051394) (xy 185.988196 -317.020269) (xy 185.955561 -316.983432)
			(xy 185.929258 -316.941836) (xy 185.909967 -316.89656) (xy 185.89819 -316.848776) (xy 185.89423 -316.799722)
			(xy 184.605168 -316.799722) (xy 184.604673 -316.824329) (xy 184.596778 -316.872906) (xy 184.581194 -316.919587)
			(xy 184.558323 -316.963164) (xy 184.528758 -317.002508) (xy 184.493265 -317.0366) (xy 184.452762 -317.064556)
			(xy 184.4083 -317.085654) (xy 184.361029 -317.099346) (xy 184.312174 -317.105278) (xy 184.262999 -317.103297)
			(xy 184.21478 -317.093453) (xy 184.168764 -317.076001) (xy 184.126143 -317.051394) (xy 184.088022 -317.020269)
			(xy 184.055387 -316.983432) (xy 184.029084 -316.941836) (xy 184.009793 -316.89656) (xy 183.998016 -316.848776)
			(xy 183.994056 -316.799722) (xy 182.705248 -316.799722) (xy 182.704753 -316.824329) (xy 182.696858 -316.872906)
			(xy 182.681274 -316.919587) (xy 182.658403 -316.963164) (xy 182.628838 -317.002508) (xy 182.593345 -317.0366)
			(xy 182.552842 -317.064556) (xy 182.50838 -317.085654) (xy 182.461109 -317.099346) (xy 182.412254 -317.105278)
			(xy 182.363079 -317.103297) (xy 182.31486 -317.093453) (xy 182.268844 -317.076001) (xy 182.226223 -317.051394)
			(xy 182.188102 -317.020269) (xy 182.155467 -316.983432) (xy 182.129164 -316.941836) (xy 182.109873 -316.89656)
			(xy 182.098096 -316.848776) (xy 182.094136 -316.799722) (xy 165.605206 -316.799722) (xy 165.604711 -316.824329)
			(xy 165.596816 -316.872906) (xy 165.581232 -316.919587) (xy 165.558361 -316.963164) (xy 165.528796 -317.002508)
			(xy 165.493303 -317.0366) (xy 165.4528 -317.064556) (xy 165.408338 -317.085654) (xy 165.361067 -317.099346)
			(xy 165.312212 -317.105278) (xy 165.263037 -317.103297) (xy 165.214818 -317.093453) (xy 165.168802 -317.076001)
			(xy 165.126181 -317.051394) (xy 165.08806 -317.020269) (xy 165.055425 -316.983432) (xy 165.029122 -316.941836)
			(xy 165.009831 -316.89656) (xy 164.998054 -316.848776) (xy 164.994094 -316.799722) (xy 163.705286 -316.799722)
			(xy 163.704791 -316.824329) (xy 163.696896 -316.872906) (xy 163.681312 -316.919587) (xy 163.658441 -316.963164)
			(xy 163.628876 -317.002508) (xy 163.593383 -317.0366) (xy 163.55288 -317.064556) (xy 163.508418 -317.085654)
			(xy 163.461147 -317.099346) (xy 163.412292 -317.105278) (xy 163.363117 -317.103297) (xy 163.314898 -317.093453)
			(xy 163.268882 -317.076001) (xy 163.226261 -317.051394) (xy 163.18814 -317.020269) (xy 163.155505 -316.983432)
			(xy 163.129202 -316.941836) (xy 163.109911 -316.89656) (xy 163.098134 -316.848776) (xy 163.094174 -316.799722)
			(xy 161.805366 -316.799722) (xy 161.804871 -316.824329) (xy 161.796976 -316.872906) (xy 161.781392 -316.919587)
			(xy 161.758521 -316.963164) (xy 161.728956 -317.002508) (xy 161.693463 -317.0366) (xy 161.65296 -317.064556)
			(xy 161.608498 -317.085654) (xy 161.561227 -317.099346) (xy 161.512372 -317.105278) (xy 161.463197 -317.103297)
			(xy 161.414978 -317.093453) (xy 161.368962 -317.076001) (xy 161.326341 -317.051394) (xy 161.28822 -317.020269)
			(xy 161.255585 -316.983432) (xy 161.229282 -316.941836) (xy 161.209991 -316.89656) (xy 161.198214 -316.848776)
			(xy 161.194254 -316.799722) (xy 159.905192 -316.799722) (xy 159.904697 -316.824329) (xy 159.896802 -316.872906)
			(xy 159.881218 -316.919587) (xy 159.858347 -316.963164) (xy 159.828782 -317.002508) (xy 159.793289 -317.0366)
			(xy 159.752786 -317.064556) (xy 159.708324 -317.085654) (xy 159.661053 -317.099346) (xy 159.612198 -317.105278)
			(xy 159.563023 -317.103297) (xy 159.514804 -317.093453) (xy 159.468788 -317.076001) (xy 159.426167 -317.051394)
			(xy 159.388046 -317.020269) (xy 159.355411 -316.983432) (xy 159.329108 -316.941836) (xy 159.309817 -316.89656)
			(xy 159.29804 -316.848776) (xy 159.29408 -316.799722) (xy 158.005272 -316.799722) (xy 158.004777 -316.824329)
			(xy 157.996882 -316.872906) (xy 157.981298 -316.919587) (xy 157.958427 -316.963164) (xy 157.928862 -317.002508)
			(xy 157.893369 -317.0366) (xy 157.852866 -317.064556) (xy 157.808404 -317.085654) (xy 157.761133 -317.099346)
			(xy 157.712278 -317.105278) (xy 157.663103 -317.103297) (xy 157.614884 -317.093453) (xy 157.568868 -317.076001)
			(xy 157.526247 -317.051394) (xy 157.488126 -317.020269) (xy 157.455491 -316.983432) (xy 157.429188 -316.941836)
			(xy 157.409897 -316.89656) (xy 157.39812 -316.848776) (xy 157.39416 -316.799722) (xy 156.105352 -316.799722)
			(xy 156.104857 -316.824329) (xy 156.096962 -316.872906) (xy 156.081378 -316.919587) (xy 156.058507 -316.963164)
			(xy 156.028942 -317.002508) (xy 155.993449 -317.0366) (xy 155.952946 -317.064556) (xy 155.908484 -317.085654)
			(xy 155.861213 -317.099346) (xy 155.812358 -317.105278) (xy 155.763183 -317.103297) (xy 155.714964 -317.093453)
			(xy 155.668948 -317.076001) (xy 155.626327 -317.051394) (xy 155.588206 -317.020269) (xy 155.555571 -316.983432)
			(xy 155.529268 -316.941836) (xy 155.509977 -316.89656) (xy 155.4982 -316.848776) (xy 155.49424 -316.799722)
			(xy 154.205178 -316.799722) (xy 154.204683 -316.824329) (xy 154.196788 -316.872906) (xy 154.181204 -316.919587)
			(xy 154.158333 -316.963164) (xy 154.128768 -317.002508) (xy 154.093275 -317.0366) (xy 154.052772 -317.064556)
			(xy 154.00831 -317.085654) (xy 153.961039 -317.099346) (xy 153.912184 -317.105278) (xy 153.863009 -317.103297)
			(xy 153.81479 -317.093453) (xy 153.768774 -317.076001) (xy 153.726153 -317.051394) (xy 153.688032 -317.020269)
			(xy 153.655397 -316.983432) (xy 153.629094 -316.941836) (xy 153.609803 -316.89656) (xy 153.598026 -316.848776)
			(xy 153.594066 -316.799722) (xy 153.255218 -316.799722) (xy 153.254723 -316.824329) (xy 153.246828 -316.872906)
			(xy 153.231244 -316.919587) (xy 153.208373 -316.963164) (xy 153.178808 -317.002508) (xy 153.143315 -317.0366)
			(xy 153.102812 -317.064556) (xy 153.05835 -317.085654) (xy 153.011079 -317.099346) (xy 152.962224 -317.105278)
			(xy 152.913049 -317.103297) (xy 152.86483 -317.093453) (xy 152.818814 -317.076001) (xy 152.776193 -317.051394)
			(xy 152.738072 -317.020269) (xy 152.705437 -316.983432) (xy 152.679134 -316.941836) (xy 152.659843 -316.89656)
			(xy 152.648066 -316.848776) (xy 152.644106 -316.799722) (xy 82.755232 -316.799722) (xy 82.754737 -316.824329)
			(xy 82.746842 -316.872906) (xy 82.731258 -316.919587) (xy 82.708387 -316.963164) (xy 82.678822 -317.002508)
			(xy 82.643329 -317.0366) (xy 82.602826 -317.064556) (xy 82.558364 -317.085654) (xy 82.511093 -317.099346)
			(xy 82.462238 -317.105278) (xy 82.413063 -317.103297) (xy 82.364844 -317.093453) (xy 82.318828 -317.076001)
			(xy 82.276207 -317.051394) (xy 82.238086 -317.020269) (xy 82.205451 -316.983432) (xy 82.179148 -316.941836)
			(xy 82.159857 -316.89656) (xy 82.14808 -316.848776) (xy 82.14412 -316.799722) (xy 81.805272 -316.799722)
			(xy 81.804777 -316.824329) (xy 81.796882 -316.872906) (xy 81.781298 -316.919587) (xy 81.758427 -316.963164)
			(xy 81.728862 -317.002508) (xy 81.693369 -317.0366) (xy 81.652866 -317.064556) (xy 81.608404 -317.085654)
			(xy 81.561133 -317.099346) (xy 81.512278 -317.105278) (xy 81.463103 -317.103297) (xy 81.414884 -317.093453)
			(xy 81.368868 -317.076001) (xy 81.326247 -317.051394) (xy 81.288126 -317.020269) (xy 81.255491 -316.983432)
			(xy 81.229188 -316.941836) (xy 81.209897 -316.89656) (xy 81.19812 -316.848776) (xy 81.19416 -316.799722)
			(xy 79.905098 -316.799722) (xy 79.904603 -316.824329) (xy 79.896708 -316.872906) (xy 79.881124 -316.919587)
			(xy 79.858253 -316.963164) (xy 79.828688 -317.002508) (xy 79.793195 -317.0366) (xy 79.752692 -317.064556)
			(xy 79.70823 -317.085654) (xy 79.660959 -317.099346) (xy 79.612104 -317.105278) (xy 79.562929 -317.103297)
			(xy 79.51471 -317.093453) (xy 79.468694 -317.076001) (xy 79.426073 -317.051394) (xy 79.387952 -317.020269)
			(xy 79.355317 -316.983432) (xy 79.329014 -316.941836) (xy 79.309723 -316.89656) (xy 79.297946 -316.848776)
			(xy 79.293986 -316.799722) (xy 78.005178 -316.799722) (xy 78.004683 -316.824329) (xy 77.996788 -316.872906)
			(xy 77.981204 -316.919587) (xy 77.958333 -316.963164) (xy 77.928768 -317.002508) (xy 77.893275 -317.0366)
			(xy 77.852772 -317.064556) (xy 77.80831 -317.085654) (xy 77.761039 -317.099346) (xy 77.712184 -317.105278)
			(xy 77.663009 -317.103297) (xy 77.61479 -317.093453) (xy 77.568774 -317.076001) (xy 77.526153 -317.051394)
			(xy 77.488032 -317.020269) (xy 77.455397 -316.983432) (xy 77.429094 -316.941836) (xy 77.409803 -316.89656)
			(xy 77.398026 -316.848776) (xy 77.394066 -316.799722) (xy 76.105258 -316.799722) (xy 76.104763 -316.824329)
			(xy 76.096868 -316.872906) (xy 76.081284 -316.919587) (xy 76.058413 -316.963164) (xy 76.028848 -317.002508)
			(xy 75.993355 -317.0366) (xy 75.952852 -317.064556) (xy 75.90839 -317.085654) (xy 75.861119 -317.099346)
			(xy 75.812264 -317.105278) (xy 75.763089 -317.103297) (xy 75.71487 -317.093453) (xy 75.668854 -317.076001)
			(xy 75.626233 -317.051394) (xy 75.588112 -317.020269) (xy 75.555477 -316.983432) (xy 75.529174 -316.941836)
			(xy 75.509883 -316.89656) (xy 75.498106 -316.848776) (xy 75.494146 -316.799722) (xy 74.205084 -316.799722)
			(xy 74.204589 -316.824329) (xy 74.196694 -316.872906) (xy 74.18111 -316.919587) (xy 74.158239 -316.963164)
			(xy 74.128674 -317.002508) (xy 74.093181 -317.0366) (xy 74.052678 -317.064556) (xy 74.008216 -317.085654)
			(xy 73.960945 -317.099346) (xy 73.91209 -317.105278) (xy 73.862915 -317.103297) (xy 73.814696 -317.093453)
			(xy 73.76868 -317.076001) (xy 73.726059 -317.051394) (xy 73.687938 -317.020269) (xy 73.655303 -316.983432)
			(xy 73.629 -316.941836) (xy 73.609709 -316.89656) (xy 73.597932 -316.848776) (xy 73.593972 -316.799722)
			(xy 64.70523 -316.799722) (xy 64.704735 -316.824329) (xy 64.69684 -316.872906) (xy 64.681256 -316.919587)
			(xy 64.658385 -316.963164) (xy 64.62882 -317.002508) (xy 64.593327 -317.0366) (xy 64.552824 -317.064556)
			(xy 64.508362 -317.085654) (xy 64.461091 -317.099346) (xy 64.412236 -317.105278) (xy 64.363061 -317.103297)
			(xy 64.314842 -317.093453) (xy 64.268826 -317.076001) (xy 64.226205 -317.051394) (xy 64.188084 -317.020269)
			(xy 64.155449 -316.983432) (xy 64.129146 -316.941836) (xy 64.109855 -316.89656) (xy 64.098078 -316.848776)
			(xy 64.094118 -316.799722) (xy 62.805056 -316.799722) (xy 62.804561 -316.824329) (xy 62.796666 -316.872906)
			(xy 62.781082 -316.919587) (xy 62.758211 -316.963164) (xy 62.728646 -317.002508) (xy 62.693153 -317.0366)
			(xy 62.65265 -317.064556) (xy 62.608188 -317.085654) (xy 62.560917 -317.099346) (xy 62.512062 -317.105278)
			(xy 62.462887 -317.103297) (xy 62.414668 -317.093453) (xy 62.368652 -317.076001) (xy 62.326031 -317.051394)
			(xy 62.28791 -317.020269) (xy 62.255275 -316.983432) (xy 62.228972 -316.941836) (xy 62.209681 -316.89656)
			(xy 62.197904 -316.848776) (xy 62.193944 -316.799722) (xy 60.905136 -316.799722) (xy 60.904641 -316.824329)
			(xy 60.896746 -316.872906) (xy 60.881162 -316.919587) (xy 60.858291 -316.963164) (xy 60.828726 -317.002508)
			(xy 60.793233 -317.0366) (xy 60.75273 -317.064556) (xy 60.708268 -317.085654) (xy 60.660997 -317.099346)
			(xy 60.612142 -317.105278) (xy 60.562967 -317.103297) (xy 60.514748 -317.093453) (xy 60.468732 -317.076001)
			(xy 60.426111 -317.051394) (xy 60.38799 -317.020269) (xy 60.355355 -316.983432) (xy 60.329052 -316.941836)
			(xy 60.309761 -316.89656) (xy 60.297984 -316.848776) (xy 60.294024 -316.799722) (xy 59.005216 -316.799722)
			(xy 59.004721 -316.824329) (xy 58.996826 -316.872906) (xy 58.981242 -316.919587) (xy 58.958371 -316.963164)
			(xy 58.928806 -317.002508) (xy 58.893313 -317.0366) (xy 58.85281 -317.064556) (xy 58.808348 -317.085654)
			(xy 58.761077 -317.099346) (xy 58.712222 -317.105278) (xy 58.663047 -317.103297) (xy 58.614828 -317.093453)
			(xy 58.568812 -317.076001) (xy 58.526191 -317.051394) (xy 58.48807 -317.020269) (xy 58.455435 -316.983432)
			(xy 58.429132 -316.941836) (xy 58.409841 -316.89656) (xy 58.398064 -316.848776) (xy 58.394104 -316.799722)
			(xy 57.105296 -316.799722) (xy 57.104801 -316.824329) (xy 57.096906 -316.872906) (xy 57.081322 -316.919587)
			(xy 57.058451 -316.963164) (xy 57.028886 -317.002508) (xy 56.993393 -317.0366) (xy 56.95289 -317.064556)
			(xy 56.908428 -317.085654) (xy 56.861157 -317.099346) (xy 56.812302 -317.105278) (xy 56.763127 -317.103297)
			(xy 56.714908 -317.093453) (xy 56.668892 -317.076001) (xy 56.626271 -317.051394) (xy 56.58815 -317.020269)
			(xy 56.555515 -316.983432) (xy 56.529212 -316.941836) (xy 56.509921 -316.89656) (xy 56.498144 -316.848776)
			(xy 56.494184 -316.799722) (xy 55.205122 -316.799722) (xy 55.204627 -316.824329) (xy 55.196732 -316.872906)
			(xy 55.181148 -316.919587) (xy 55.158277 -316.963164) (xy 55.128712 -317.002508) (xy 55.093219 -317.0366)
			(xy 55.052716 -317.064556) (xy 55.008254 -317.085654) (xy 54.960983 -317.099346) (xy 54.912128 -317.105278)
			(xy 54.862953 -317.103297) (xy 54.814734 -317.093453) (xy 54.768718 -317.076001) (xy 54.726097 -317.051394)
			(xy 54.687976 -317.020269) (xy 54.655341 -316.983432) (xy 54.629038 -316.941836) (xy 54.609747 -316.89656)
			(xy 54.59797 -316.848776) (xy 54.59401 -316.799722) (xy 53.305202 -316.799722) (xy 53.304707 -316.824329)
			(xy 53.296812 -316.872906) (xy 53.281228 -316.919587) (xy 53.258357 -316.963164) (xy 53.228792 -317.002508)
			(xy 53.193299 -317.0366) (xy 53.152796 -317.064556) (xy 53.108334 -317.085654) (xy 53.061063 -317.099346)
			(xy 53.012208 -317.105278) (xy 52.963033 -317.103297) (xy 52.914814 -317.093453) (xy 52.868798 -317.076001)
			(xy 52.826177 -317.051394) (xy 52.788056 -317.020269) (xy 52.755421 -316.983432) (xy 52.729118 -316.941836)
			(xy 52.709827 -316.89656) (xy 52.69805 -316.848776) (xy 52.69409 -316.799722) (xy 51.405282 -316.799722)
			(xy 51.404787 -316.824329) (xy 51.396892 -316.872906) (xy 51.381308 -316.919587) (xy 51.358437 -316.963164)
			(xy 51.328872 -317.002508) (xy 51.293379 -317.0366) (xy 51.252876 -317.064556) (xy 51.208414 -317.085654)
			(xy 51.161143 -317.099346) (xy 51.112288 -317.105278) (xy 51.063113 -317.103297) (xy 51.014894 -317.093453)
			(xy 50.968878 -317.076001) (xy 50.926257 -317.051394) (xy 50.888136 -317.020269) (xy 50.855501 -316.983432)
			(xy 50.829198 -316.941836) (xy 50.809907 -316.89656) (xy 50.79813 -316.848776) (xy 50.79417 -316.799722)
			(xy 0.508 -316.799722) (xy 0.508 -317.749936) (xy 51.74413 -317.749936) (xy 51.74809 -317.700882)
			(xy 51.759867 -317.653098) (xy 51.779158 -317.607822) (xy 51.805461 -317.566226) (xy 51.838096 -317.529389)
			(xy 51.876217 -317.498264) (xy 51.918838 -317.473657) (xy 51.964854 -317.456205) (xy 52.013073 -317.446361)
			(xy 52.062248 -317.44438) (xy 52.111103 -317.450312) (xy 52.158374 -317.464004) (xy 52.202836 -317.485102)
			(xy 52.243339 -317.513058) (xy 52.278832 -317.54715) (xy 52.308397 -317.586494) (xy 52.331268 -317.630071)
			(xy 52.346852 -317.676752) (xy 52.354747 -317.725329) (xy 52.355242 -317.749936) (xy 53.64405 -317.749936)
			(xy 53.64801 -317.700882) (xy 53.659787 -317.653098) (xy 53.679078 -317.607822) (xy 53.705381 -317.566226)
			(xy 53.738016 -317.529389) (xy 53.776137 -317.498264) (xy 53.818758 -317.473657) (xy 53.864774 -317.456205)
			(xy 53.912993 -317.446361) (xy 53.962168 -317.44438) (xy 54.011023 -317.450312) (xy 54.058294 -317.464004)
			(xy 54.102756 -317.485102) (xy 54.143259 -317.513058) (xy 54.178752 -317.54715) (xy 54.208317 -317.586494)
			(xy 54.231188 -317.630071) (xy 54.246772 -317.676752) (xy 54.254667 -317.725329) (xy 54.255162 -317.749936)
			(xy 55.54397 -317.749936) (xy 55.54793 -317.700882) (xy 55.559707 -317.653098) (xy 55.578998 -317.607822)
			(xy 55.605301 -317.566226) (xy 55.637936 -317.529389) (xy 55.676057 -317.498264) (xy 55.718678 -317.473657)
			(xy 55.764694 -317.456205) (xy 55.812913 -317.446361) (xy 55.862088 -317.44438) (xy 55.910943 -317.450312)
			(xy 55.958214 -317.464004) (xy 56.002676 -317.485102) (xy 56.043179 -317.513058) (xy 56.078672 -317.54715)
			(xy 56.108237 -317.586494) (xy 56.131108 -317.630071) (xy 56.146692 -317.676752) (xy 56.154587 -317.725329)
			(xy 56.155082 -317.749936) (xy 57.444144 -317.749936) (xy 57.448104 -317.700882) (xy 57.459881 -317.653098)
			(xy 57.479172 -317.607822) (xy 57.505475 -317.566226) (xy 57.53811 -317.529389) (xy 57.576231 -317.498264)
			(xy 57.618852 -317.473657) (xy 57.664868 -317.456205) (xy 57.713087 -317.446361) (xy 57.762262 -317.44438)
			(xy 57.811117 -317.450312) (xy 57.858388 -317.464004) (xy 57.90285 -317.485102) (xy 57.943353 -317.513058)
			(xy 57.978846 -317.54715) (xy 58.008411 -317.586494) (xy 58.031282 -317.630071) (xy 58.046866 -317.676752)
			(xy 58.054761 -317.725329) (xy 58.055256 -317.749936) (xy 59.344064 -317.749936) (xy 59.348024 -317.700882)
			(xy 59.359801 -317.653098) (xy 59.379092 -317.607822) (xy 59.405395 -317.566226) (xy 59.43803 -317.529389)
			(xy 59.476151 -317.498264) (xy 59.518772 -317.473657) (xy 59.564788 -317.456205) (xy 59.613007 -317.446361)
			(xy 59.662182 -317.44438) (xy 59.711037 -317.450312) (xy 59.758308 -317.464004) (xy 59.80277 -317.485102)
			(xy 59.843273 -317.513058) (xy 59.878766 -317.54715) (xy 59.908331 -317.586494) (xy 59.931202 -317.630071)
			(xy 59.946786 -317.676752) (xy 59.954681 -317.725329) (xy 59.955176 -317.749936) (xy 61.243984 -317.749936)
			(xy 61.247944 -317.700882) (xy 61.259721 -317.653098) (xy 61.279012 -317.607822) (xy 61.305315 -317.566226)
			(xy 61.33795 -317.529389) (xy 61.376071 -317.498264) (xy 61.418692 -317.473657) (xy 61.464708 -317.456205)
			(xy 61.512927 -317.446361) (xy 61.562102 -317.44438) (xy 61.610957 -317.450312) (xy 61.658228 -317.464004)
			(xy 61.70269 -317.485102) (xy 61.743193 -317.513058) (xy 61.778686 -317.54715) (xy 61.808251 -317.586494)
			(xy 61.831122 -317.630071) (xy 61.846706 -317.676752) (xy 61.854601 -317.725329) (xy 61.855096 -317.749936)
			(xy 63.144158 -317.749936) (xy 63.148118 -317.700882) (xy 63.159895 -317.653098) (xy 63.179186 -317.607822)
			(xy 63.205489 -317.566226) (xy 63.238124 -317.529389) (xy 63.276245 -317.498264) (xy 63.318866 -317.473657)
			(xy 63.364882 -317.456205) (xy 63.413101 -317.446361) (xy 63.462276 -317.44438) (xy 63.511131 -317.450312)
			(xy 63.558402 -317.464004) (xy 63.602864 -317.485102) (xy 63.643367 -317.513058) (xy 63.67886 -317.54715)
			(xy 63.708425 -317.586494) (xy 63.731296 -317.630071) (xy 63.74688 -317.676752) (xy 63.754775 -317.725329)
			(xy 63.75527 -317.749936) (xy 65.044078 -317.749936) (xy 65.048038 -317.700882) (xy 65.059815 -317.653098)
			(xy 65.079106 -317.607822) (xy 65.105409 -317.566226) (xy 65.138044 -317.529389) (xy 65.176165 -317.498264)
			(xy 65.218786 -317.473657) (xy 65.264802 -317.456205) (xy 65.313021 -317.446361) (xy 65.362196 -317.44438)
			(xy 65.411051 -317.450312) (xy 65.458322 -317.464004) (xy 65.502784 -317.485102) (xy 65.543287 -317.513058)
			(xy 65.57878 -317.54715) (xy 65.608345 -317.586494) (xy 65.631216 -317.630071) (xy 65.6468 -317.676752)
			(xy 65.654695 -317.725329) (xy 65.65519 -317.749936) (xy 74.544186 -317.749936) (xy 74.548146 -317.700882)
			(xy 74.559923 -317.653098) (xy 74.579214 -317.607822) (xy 74.605517 -317.566226) (xy 74.638152 -317.529389)
			(xy 74.676273 -317.498264) (xy 74.718894 -317.473657) (xy 74.76491 -317.456205) (xy 74.813129 -317.446361)
			(xy 74.862304 -317.44438) (xy 74.911159 -317.450312) (xy 74.95843 -317.464004) (xy 75.002892 -317.485102)
			(xy 75.043395 -317.513058) (xy 75.078888 -317.54715) (xy 75.108453 -317.586494) (xy 75.131324 -317.630071)
			(xy 75.146908 -317.676752) (xy 75.154803 -317.725329) (xy 75.155298 -317.749936) (xy 76.444106 -317.749936)
			(xy 76.448066 -317.700882) (xy 76.459843 -317.653098) (xy 76.479134 -317.607822) (xy 76.505437 -317.566226)
			(xy 76.538072 -317.529389) (xy 76.576193 -317.498264) (xy 76.618814 -317.473657) (xy 76.66483 -317.456205)
			(xy 76.713049 -317.446361) (xy 76.762224 -317.44438) (xy 76.811079 -317.450312) (xy 76.85835 -317.464004)
			(xy 76.902812 -317.485102) (xy 76.943315 -317.513058) (xy 76.978808 -317.54715) (xy 77.008373 -317.586494)
			(xy 77.031244 -317.630071) (xy 77.046828 -317.676752) (xy 77.054723 -317.725329) (xy 77.055218 -317.749936)
			(xy 78.344026 -317.749936) (xy 78.347986 -317.700882) (xy 78.359763 -317.653098) (xy 78.379054 -317.607822)
			(xy 78.405357 -317.566226) (xy 78.437992 -317.529389) (xy 78.476113 -317.498264) (xy 78.518734 -317.473657)
			(xy 78.56475 -317.456205) (xy 78.612969 -317.446361) (xy 78.662144 -317.44438) (xy 78.710999 -317.450312)
			(xy 78.75827 -317.464004) (xy 78.802732 -317.485102) (xy 78.843235 -317.513058) (xy 78.878728 -317.54715)
			(xy 78.908293 -317.586494) (xy 78.931164 -317.630071) (xy 78.946748 -317.676752) (xy 78.954643 -317.725329)
			(xy 78.955138 -317.749936) (xy 80.243946 -317.749936) (xy 80.247906 -317.700882) (xy 80.259683 -317.653098)
			(xy 80.278974 -317.607822) (xy 80.305277 -317.566226) (xy 80.337912 -317.529389) (xy 80.376033 -317.498264)
			(xy 80.418654 -317.473657) (xy 80.46467 -317.456205) (xy 80.512889 -317.446361) (xy 80.562064 -317.44438)
			(xy 80.610919 -317.450312) (xy 80.65819 -317.464004) (xy 80.702652 -317.485102) (xy 80.743155 -317.513058)
			(xy 80.778648 -317.54715) (xy 80.808213 -317.586494) (xy 80.831084 -317.630071) (xy 80.846668 -317.676752)
			(xy 80.854563 -317.725329) (xy 80.855058 -317.749936) (xy 154.54428 -317.749936) (xy 154.54824 -317.700882)
			(xy 154.560017 -317.653098) (xy 154.579308 -317.607822) (xy 154.605611 -317.566226) (xy 154.638246 -317.529389)
			(xy 154.676367 -317.498264) (xy 154.718988 -317.473657) (xy 154.765004 -317.456205) (xy 154.813223 -317.446361)
			(xy 154.862398 -317.44438) (xy 154.911253 -317.450312) (xy 154.958524 -317.464004) (xy 155.002986 -317.485102)
			(xy 155.043489 -317.513058) (xy 155.078982 -317.54715) (xy 155.108547 -317.586494) (xy 155.131418 -317.630071)
			(xy 155.147002 -317.676752) (xy 155.154897 -317.725329) (xy 155.155392 -317.749936) (xy 156.4442 -317.749936)
			(xy 156.44816 -317.700882) (xy 156.459937 -317.653098) (xy 156.479228 -317.607822) (xy 156.505531 -317.566226)
			(xy 156.538166 -317.529389) (xy 156.576287 -317.498264) (xy 156.618908 -317.473657) (xy 156.664924 -317.456205)
			(xy 156.713143 -317.446361) (xy 156.762318 -317.44438) (xy 156.811173 -317.450312) (xy 156.858444 -317.464004)
			(xy 156.902906 -317.485102) (xy 156.943409 -317.513058) (xy 156.978902 -317.54715) (xy 157.008467 -317.586494)
			(xy 157.031338 -317.630071) (xy 157.046922 -317.676752) (xy 157.054817 -317.725329) (xy 157.055312 -317.749936)
			(xy 158.34412 -317.749936) (xy 158.34808 -317.700882) (xy 158.359857 -317.653098) (xy 158.379148 -317.607822)
			(xy 158.405451 -317.566226) (xy 158.438086 -317.529389) (xy 158.476207 -317.498264) (xy 158.518828 -317.473657)
			(xy 158.564844 -317.456205) (xy 158.613063 -317.446361) (xy 158.662238 -317.44438) (xy 158.711093 -317.450312)
			(xy 158.758364 -317.464004) (xy 158.802826 -317.485102) (xy 158.843329 -317.513058) (xy 158.878822 -317.54715)
			(xy 158.908387 -317.586494) (xy 158.931258 -317.630071) (xy 158.946842 -317.676752) (xy 158.954737 -317.725329)
			(xy 158.955232 -317.749936) (xy 160.24404 -317.749936) (xy 160.248 -317.700882) (xy 160.259777 -317.653098)
			(xy 160.279068 -317.607822) (xy 160.305371 -317.566226) (xy 160.338006 -317.529389) (xy 160.376127 -317.498264)
			(xy 160.418748 -317.473657) (xy 160.464764 -317.456205) (xy 160.512983 -317.446361) (xy 160.562158 -317.44438)
			(xy 160.611013 -317.450312) (xy 160.658284 -317.464004) (xy 160.702746 -317.485102) (xy 160.743249 -317.513058)
			(xy 160.778742 -317.54715) (xy 160.808307 -317.586494) (xy 160.831178 -317.630071) (xy 160.846762 -317.676752)
			(xy 160.854657 -317.725329) (xy 160.855152 -317.749936) (xy 162.144214 -317.749936) (xy 162.148174 -317.700882)
			(xy 162.159951 -317.653098) (xy 162.179242 -317.607822) (xy 162.205545 -317.566226) (xy 162.23818 -317.529389)
			(xy 162.276301 -317.498264) (xy 162.318922 -317.473657) (xy 162.364938 -317.456205) (xy 162.413157 -317.446361)
			(xy 162.462332 -317.44438) (xy 162.511187 -317.450312) (xy 162.558458 -317.464004) (xy 162.60292 -317.485102)
			(xy 162.643423 -317.513058) (xy 162.678916 -317.54715) (xy 162.708481 -317.586494) (xy 162.731352 -317.630071)
			(xy 162.746936 -317.676752) (xy 162.754831 -317.725329) (xy 162.755326 -317.749936) (xy 164.044134 -317.749936)
			(xy 164.048094 -317.700882) (xy 164.059871 -317.653098) (xy 164.079162 -317.607822) (xy 164.105465 -317.566226)
			(xy 164.1381 -317.529389) (xy 164.176221 -317.498264) (xy 164.218842 -317.473657) (xy 164.264858 -317.456205)
			(xy 164.313077 -317.446361) (xy 164.362252 -317.44438) (xy 164.411107 -317.450312) (xy 164.458378 -317.464004)
			(xy 164.50284 -317.485102) (xy 164.543343 -317.513058) (xy 164.578836 -317.54715) (xy 164.608401 -317.586494)
			(xy 164.631272 -317.630071) (xy 164.646856 -317.676752) (xy 164.654751 -317.725329) (xy 164.655246 -317.749936)
			(xy 165.944054 -317.749936) (xy 165.948014 -317.700882) (xy 165.959791 -317.653098) (xy 165.979082 -317.607822)
			(xy 166.005385 -317.566226) (xy 166.03802 -317.529389) (xy 166.076141 -317.498264) (xy 166.118762 -317.473657)
			(xy 166.164778 -317.456205) (xy 166.212997 -317.446361) (xy 166.262172 -317.44438) (xy 166.311027 -317.450312)
			(xy 166.358298 -317.464004) (xy 166.40276 -317.485102) (xy 166.443263 -317.513058) (xy 166.478756 -317.54715)
			(xy 166.508321 -317.586494) (xy 166.531192 -317.630071) (xy 166.546776 -317.676752) (xy 166.554671 -317.725329)
			(xy 166.555166 -317.749936) (xy 183.044096 -317.749936) (xy 183.048056 -317.700882) (xy 183.059833 -317.653098)
			(xy 183.079124 -317.607822) (xy 183.105427 -317.566226) (xy 183.138062 -317.529389) (xy 183.176183 -317.498264)
			(xy 183.218804 -317.473657) (xy 183.26482 -317.456205) (xy 183.313039 -317.446361) (xy 183.362214 -317.44438)
			(xy 183.411069 -317.450312) (xy 183.45834 -317.464004) (xy 183.502802 -317.485102) (xy 183.543305 -317.513058)
			(xy 183.578798 -317.54715) (xy 183.608363 -317.586494) (xy 183.631234 -317.630071) (xy 183.646818 -317.676752)
			(xy 183.654713 -317.725329) (xy 183.655208 -317.749936) (xy 184.94427 -317.749936) (xy 184.94823 -317.700882)
			(xy 184.960007 -317.653098) (xy 184.979298 -317.607822) (xy 185.005601 -317.566226) (xy 185.038236 -317.529389)
			(xy 185.076357 -317.498264) (xy 185.118978 -317.473657) (xy 185.164994 -317.456205) (xy 185.213213 -317.446361)
			(xy 185.262388 -317.44438) (xy 185.311243 -317.450312) (xy 185.358514 -317.464004) (xy 185.402976 -317.485102)
			(xy 185.443479 -317.513058) (xy 185.478972 -317.54715) (xy 185.508537 -317.586494) (xy 185.531408 -317.630071)
			(xy 185.546992 -317.676752) (xy 185.554887 -317.725329) (xy 185.555382 -317.749936) (xy 186.84419 -317.749936)
			(xy 186.84815 -317.700882) (xy 186.859927 -317.653098) (xy 186.879218 -317.607822) (xy 186.905521 -317.566226)
			(xy 186.938156 -317.529389) (xy 186.976277 -317.498264) (xy 187.018898 -317.473657) (xy 187.064914 -317.456205)
			(xy 187.113133 -317.446361) (xy 187.162308 -317.44438) (xy 187.211163 -317.450312) (xy 187.258434 -317.464004)
			(xy 187.302896 -317.485102) (xy 187.343399 -317.513058) (xy 187.378892 -317.54715) (xy 187.408457 -317.586494)
			(xy 187.431328 -317.630071) (xy 187.446912 -317.676752) (xy 187.454807 -317.725329) (xy 187.455302 -317.749936)
			(xy 188.74411 -317.749936) (xy 188.74807 -317.700882) (xy 188.759847 -317.653098) (xy 188.779138 -317.607822)
			(xy 188.805441 -317.566226) (xy 188.838076 -317.529389) (xy 188.876197 -317.498264) (xy 188.918818 -317.473657)
			(xy 188.964834 -317.456205) (xy 189.013053 -317.446361) (xy 189.062228 -317.44438) (xy 189.111083 -317.450312)
			(xy 189.158354 -317.464004) (xy 189.202816 -317.485102) (xy 189.243319 -317.513058) (xy 189.278812 -317.54715)
			(xy 189.308377 -317.586494) (xy 189.331248 -317.630071) (xy 189.346832 -317.676752) (xy 189.354727 -317.725329)
			(xy 189.355222 -317.749936) (xy 283.944072 -317.749936) (xy 283.948032 -317.700882) (xy 283.959809 -317.653098)
			(xy 283.9791 -317.607822) (xy 284.005403 -317.566226) (xy 284.038038 -317.529389) (xy 284.076159 -317.498264)
			(xy 284.11878 -317.473657) (xy 284.164796 -317.456205) (xy 284.213015 -317.446361) (xy 284.26219 -317.44438)
			(xy 284.311045 -317.450312) (xy 284.358316 -317.464004) (xy 284.402778 -317.485102) (xy 284.443281 -317.513058)
			(xy 284.478774 -317.54715) (xy 284.508339 -317.586494) (xy 284.53121 -317.630071) (xy 284.546794 -317.676752)
			(xy 284.554689 -317.725329) (xy 284.555184 -317.749936) (xy 285.843992 -317.749936) (xy 285.847952 -317.700882)
			(xy 285.859729 -317.653098) (xy 285.87902 -317.607822) (xy 285.905323 -317.566226) (xy 285.937958 -317.529389)
			(xy 285.976079 -317.498264) (xy 286.0187 -317.473657) (xy 286.064716 -317.456205) (xy 286.112935 -317.446361)
			(xy 286.16211 -317.44438) (xy 286.210965 -317.450312) (xy 286.258236 -317.464004) (xy 286.302698 -317.485102)
			(xy 286.343201 -317.513058) (xy 286.378694 -317.54715) (xy 286.408259 -317.586494) (xy 286.43113 -317.630071)
			(xy 286.446714 -317.676752) (xy 286.454609 -317.725329) (xy 286.455104 -317.749936) (xy 287.743912 -317.749936)
			(xy 287.747872 -317.700882) (xy 287.759649 -317.653098) (xy 287.77894 -317.607822) (xy 287.805243 -317.566226)
			(xy 287.837878 -317.529389) (xy 287.875999 -317.498264) (xy 287.91862 -317.473657) (xy 287.964636 -317.456205)
			(xy 288.012855 -317.446361) (xy 288.06203 -317.44438) (xy 288.110885 -317.450312) (xy 288.158156 -317.464004)
			(xy 288.202618 -317.485102) (xy 288.243121 -317.513058) (xy 288.278614 -317.54715) (xy 288.308179 -317.586494)
			(xy 288.33105 -317.630071) (xy 288.346634 -317.676752) (xy 288.354529 -317.725329) (xy 288.355024 -317.749936)
			(xy 289.644086 -317.749936) (xy 289.648046 -317.700882) (xy 289.659823 -317.653098) (xy 289.679114 -317.607822)
			(xy 289.705417 -317.566226) (xy 289.738052 -317.529389) (xy 289.776173 -317.498264) (xy 289.818794 -317.473657)
			(xy 289.86481 -317.456205) (xy 289.913029 -317.446361) (xy 289.962204 -317.44438) (xy 290.011059 -317.450312)
			(xy 290.05833 -317.464004) (xy 290.102792 -317.485102) (xy 290.143295 -317.513058) (xy 290.178788 -317.54715)
			(xy 290.208353 -317.586494) (xy 290.231224 -317.630071) (xy 290.246808 -317.676752) (xy 290.254703 -317.725329)
			(xy 290.255198 -317.749936) (xy 291.544006 -317.749936) (xy 291.547966 -317.700882) (xy 291.559743 -317.653098)
			(xy 291.579034 -317.607822) (xy 291.605337 -317.566226) (xy 291.637972 -317.529389) (xy 291.676093 -317.498264)
			(xy 291.718714 -317.473657) (xy 291.76473 -317.456205) (xy 291.812949 -317.446361) (xy 291.862124 -317.44438)
			(xy 291.910979 -317.450312) (xy 291.95825 -317.464004) (xy 292.002712 -317.485102) (xy 292.043215 -317.513058)
			(xy 292.078708 -317.54715) (xy 292.108273 -317.586494) (xy 292.131144 -317.630071) (xy 292.146728 -317.676752)
			(xy 292.154623 -317.725329) (xy 292.155118 -317.749936) (xy 293.443926 -317.749936) (xy 293.447886 -317.700882)
			(xy 293.459663 -317.653098) (xy 293.478954 -317.607822) (xy 293.505257 -317.566226) (xy 293.537892 -317.529389)
			(xy 293.576013 -317.498264) (xy 293.618634 -317.473657) (xy 293.66465 -317.456205) (xy 293.712869 -317.446361)
			(xy 293.762044 -317.44438) (xy 293.810899 -317.450312) (xy 293.85817 -317.464004) (xy 293.902632 -317.485102)
			(xy 293.943135 -317.513058) (xy 293.978628 -317.54715) (xy 294.008193 -317.586494) (xy 294.031064 -317.630071)
			(xy 294.046648 -317.676752) (xy 294.054543 -317.725329) (xy 294.055038 -317.749936) (xy 295.3441 -317.749936)
			(xy 295.34806 -317.700882) (xy 295.359837 -317.653098) (xy 295.379128 -317.607822) (xy 295.405431 -317.566226)
			(xy 295.438066 -317.529389) (xy 295.476187 -317.498264) (xy 295.518808 -317.473657) (xy 295.564824 -317.456205)
			(xy 295.613043 -317.446361) (xy 295.662218 -317.44438) (xy 295.711073 -317.450312) (xy 295.758344 -317.464004)
			(xy 295.802806 -317.485102) (xy 295.843309 -317.513058) (xy 295.878802 -317.54715) (xy 295.908367 -317.586494)
			(xy 295.931238 -317.630071) (xy 295.946822 -317.676752) (xy 295.954717 -317.725329) (xy 295.955212 -317.749936)
			(xy 297.24402 -317.749936) (xy 297.24798 -317.700882) (xy 297.259757 -317.653098) (xy 297.279048 -317.607822)
			(xy 297.305351 -317.566226) (xy 297.337986 -317.529389) (xy 297.376107 -317.498264) (xy 297.418728 -317.473657)
			(xy 297.464744 -317.456205) (xy 297.512963 -317.446361) (xy 297.562138 -317.44438) (xy 297.610993 -317.450312)
			(xy 297.658264 -317.464004) (xy 297.702726 -317.485102) (xy 297.743229 -317.513058) (xy 297.778722 -317.54715)
			(xy 297.808287 -317.586494) (xy 297.831158 -317.630071) (xy 297.846742 -317.676752) (xy 297.854637 -317.725329)
			(xy 297.855132 -317.749936) (xy 306.744128 -317.749936) (xy 306.748088 -317.700882) (xy 306.759865 -317.653098)
			(xy 306.779156 -317.607822) (xy 306.805459 -317.566226) (xy 306.838094 -317.529389) (xy 306.876215 -317.498264)
			(xy 306.918836 -317.473657) (xy 306.964852 -317.456205) (xy 307.013071 -317.446361) (xy 307.062246 -317.44438)
			(xy 307.111101 -317.450312) (xy 307.158372 -317.464004) (xy 307.202834 -317.485102) (xy 307.243337 -317.513058)
			(xy 307.27883 -317.54715) (xy 307.308395 -317.586494) (xy 307.331266 -317.630071) (xy 307.34685 -317.676752)
			(xy 307.354745 -317.725329) (xy 307.35524 -317.749936) (xy 308.644048 -317.749936) (xy 308.648008 -317.700882)
			(xy 308.659785 -317.653098) (xy 308.679076 -317.607822) (xy 308.705379 -317.566226) (xy 308.738014 -317.529389)
			(xy 308.776135 -317.498264) (xy 308.818756 -317.473657) (xy 308.864772 -317.456205) (xy 308.912991 -317.446361)
			(xy 308.962166 -317.44438) (xy 309.011021 -317.450312) (xy 309.058292 -317.464004) (xy 309.102754 -317.485102)
			(xy 309.143257 -317.513058) (xy 309.17875 -317.54715) (xy 309.208315 -317.586494) (xy 309.231186 -317.630071)
			(xy 309.24677 -317.676752) (xy 309.254665 -317.725329) (xy 309.25516 -317.749936) (xy 310.543968 -317.749936)
			(xy 310.547928 -317.700882) (xy 310.559705 -317.653098) (xy 310.578996 -317.607822) (xy 310.605299 -317.566226)
			(xy 310.637934 -317.529389) (xy 310.676055 -317.498264) (xy 310.718676 -317.473657) (xy 310.764692 -317.456205)
			(xy 310.812911 -317.446361) (xy 310.862086 -317.44438) (xy 310.910941 -317.450312) (xy 310.958212 -317.464004)
			(xy 311.002674 -317.485102) (xy 311.043177 -317.513058) (xy 311.07867 -317.54715) (xy 311.108235 -317.586494)
			(xy 311.131106 -317.630071) (xy 311.14669 -317.676752) (xy 311.154585 -317.725329) (xy 311.15508 -317.749936)
			(xy 312.443888 -317.749936) (xy 312.447848 -317.700882) (xy 312.459625 -317.653098) (xy 312.478916 -317.607822)
			(xy 312.505219 -317.566226) (xy 312.537854 -317.529389) (xy 312.575975 -317.498264) (xy 312.618596 -317.473657)
			(xy 312.664612 -317.456205) (xy 312.712831 -317.446361) (xy 312.762006 -317.44438) (xy 312.810861 -317.450312)
			(xy 312.858132 -317.464004) (xy 312.902594 -317.485102) (xy 312.943097 -317.513058) (xy 312.97859 -317.54715)
			(xy 313.008155 -317.586494) (xy 313.031026 -317.630071) (xy 313.04661 -317.676752) (xy 313.054505 -317.725329)
			(xy 313.055 -317.749936) (xy 386.744222 -317.749936) (xy 386.748182 -317.700882) (xy 386.759959 -317.653098)
			(xy 386.77925 -317.607822) (xy 386.805553 -317.566226) (xy 386.838188 -317.529389) (xy 386.876309 -317.498264)
			(xy 386.91893 -317.473657) (xy 386.964946 -317.456205) (xy 387.013165 -317.446361) (xy 387.06234 -317.44438)
			(xy 387.111195 -317.450312) (xy 387.158466 -317.464004) (xy 387.202928 -317.485102) (xy 387.243431 -317.513058)
			(xy 387.278924 -317.54715) (xy 387.308489 -317.586494) (xy 387.33136 -317.630071) (xy 387.346944 -317.676752)
			(xy 387.354839 -317.725329) (xy 387.355334 -317.749936) (xy 388.644142 -317.749936) (xy 388.648102 -317.700882)
			(xy 388.659879 -317.653098) (xy 388.67917 -317.607822) (xy 388.705473 -317.566226) (xy 388.738108 -317.529389)
			(xy 388.776229 -317.498264) (xy 388.81885 -317.473657) (xy 388.864866 -317.456205) (xy 388.913085 -317.446361)
			(xy 388.96226 -317.44438) (xy 389.011115 -317.450312) (xy 389.058386 -317.464004) (xy 389.102848 -317.485102)
			(xy 389.143351 -317.513058) (xy 389.178844 -317.54715) (xy 389.208409 -317.586494) (xy 389.23128 -317.630071)
			(xy 389.246864 -317.676752) (xy 389.254759 -317.725329) (xy 389.255254 -317.749936) (xy 390.544062 -317.749936)
			(xy 390.548022 -317.700882) (xy 390.559799 -317.653098) (xy 390.57909 -317.607822) (xy 390.605393 -317.566226)
			(xy 390.638028 -317.529389) (xy 390.676149 -317.498264) (xy 390.71877 -317.473657) (xy 390.764786 -317.456205)
			(xy 390.813005 -317.446361) (xy 390.86218 -317.44438) (xy 390.911035 -317.450312) (xy 390.958306 -317.464004)
			(xy 391.002768 -317.485102) (xy 391.043271 -317.513058) (xy 391.078764 -317.54715) (xy 391.108329 -317.586494)
			(xy 391.1312 -317.630071) (xy 391.146784 -317.676752) (xy 391.154679 -317.725329) (xy 391.155174 -317.749936)
			(xy 392.443982 -317.749936) (xy 392.447942 -317.700882) (xy 392.459719 -317.653098) (xy 392.47901 -317.607822)
			(xy 392.505313 -317.566226) (xy 392.537948 -317.529389) (xy 392.576069 -317.498264) (xy 392.61869 -317.473657)
			(xy 392.664706 -317.456205) (xy 392.712925 -317.446361) (xy 392.7621 -317.44438) (xy 392.810955 -317.450312)
			(xy 392.858226 -317.464004) (xy 392.902688 -317.485102) (xy 392.943191 -317.513058) (xy 392.978684 -317.54715)
			(xy 393.008249 -317.586494) (xy 393.03112 -317.630071) (xy 393.046704 -317.676752) (xy 393.054599 -317.725329)
			(xy 393.055094 -317.749936) (xy 394.344156 -317.749936) (xy 394.348116 -317.700882) (xy 394.359893 -317.653098)
			(xy 394.379184 -317.607822) (xy 394.405487 -317.566226) (xy 394.438122 -317.529389) (xy 394.476243 -317.498264)
			(xy 394.518864 -317.473657) (xy 394.56488 -317.456205) (xy 394.613099 -317.446361) (xy 394.662274 -317.44438)
			(xy 394.711129 -317.450312) (xy 394.7584 -317.464004) (xy 394.802862 -317.485102) (xy 394.843365 -317.513058)
			(xy 394.878858 -317.54715) (xy 394.908423 -317.586494) (xy 394.931294 -317.630071) (xy 394.946878 -317.676752)
			(xy 394.954773 -317.725329) (xy 394.955268 -317.749936) (xy 396.244076 -317.749936) (xy 396.248036 -317.700882)
			(xy 396.259813 -317.653098) (xy 396.279104 -317.607822) (xy 396.305407 -317.566226) (xy 396.338042 -317.529389)
			(xy 396.376163 -317.498264) (xy 396.418784 -317.473657) (xy 396.4648 -317.456205) (xy 396.513019 -317.446361)
			(xy 396.562194 -317.44438) (xy 396.611049 -317.450312) (xy 396.65832 -317.464004) (xy 396.702782 -317.485102)
			(xy 396.743285 -317.513058) (xy 396.778778 -317.54715) (xy 396.808343 -317.586494) (xy 396.831214 -317.630071)
			(xy 396.846798 -317.676752) (xy 396.854693 -317.725329) (xy 396.855188 -317.749936) (xy 398.143996 -317.749936)
			(xy 398.147956 -317.700882) (xy 398.159733 -317.653098) (xy 398.179024 -317.607822) (xy 398.205327 -317.566226)
			(xy 398.237962 -317.529389) (xy 398.276083 -317.498264) (xy 398.318704 -317.473657) (xy 398.36472 -317.456205)
			(xy 398.412939 -317.446361) (xy 398.462114 -317.44438) (xy 398.510969 -317.450312) (xy 398.55824 -317.464004)
			(xy 398.602702 -317.485102) (xy 398.643205 -317.513058) (xy 398.678698 -317.54715) (xy 398.708263 -317.586494)
			(xy 398.731134 -317.630071) (xy 398.746718 -317.676752) (xy 398.754613 -317.725329) (xy 398.755108 -317.749936)
			(xy 415.244038 -317.749936) (xy 415.247998 -317.700882) (xy 415.259775 -317.653098) (xy 415.279066 -317.607822)
			(xy 415.305369 -317.566226) (xy 415.338004 -317.529389) (xy 415.376125 -317.498264) (xy 415.418746 -317.473657)
			(xy 415.464762 -317.456205) (xy 415.512981 -317.446361) (xy 415.562156 -317.44438) (xy 415.611011 -317.450312)
			(xy 415.658282 -317.464004) (xy 415.702744 -317.485102) (xy 415.743247 -317.513058) (xy 415.77874 -317.54715)
			(xy 415.808305 -317.586494) (xy 415.831176 -317.630071) (xy 415.84676 -317.676752) (xy 415.854655 -317.725329)
			(xy 415.85515 -317.749936) (xy 417.144212 -317.749936) (xy 417.148172 -317.700882) (xy 417.159949 -317.653098)
			(xy 417.17924 -317.607822) (xy 417.205543 -317.566226) (xy 417.238178 -317.529389) (xy 417.276299 -317.498264)
			(xy 417.31892 -317.473657) (xy 417.364936 -317.456205) (xy 417.413155 -317.446361) (xy 417.46233 -317.44438)
			(xy 417.511185 -317.450312) (xy 417.558456 -317.464004) (xy 417.602918 -317.485102) (xy 417.643421 -317.513058)
			(xy 417.678914 -317.54715) (xy 417.708479 -317.586494) (xy 417.73135 -317.630071) (xy 417.746934 -317.676752)
			(xy 417.754829 -317.725329) (xy 417.755324 -317.749936) (xy 419.044132 -317.749936) (xy 419.048092 -317.700882)
			(xy 419.059869 -317.653098) (xy 419.07916 -317.607822) (xy 419.105463 -317.566226) (xy 419.138098 -317.529389)
			(xy 419.176219 -317.498264) (xy 419.21884 -317.473657) (xy 419.264856 -317.456205) (xy 419.313075 -317.446361)
			(xy 419.36225 -317.44438) (xy 419.411105 -317.450312) (xy 419.458376 -317.464004) (xy 419.502838 -317.485102)
			(xy 419.543341 -317.513058) (xy 419.578834 -317.54715) (xy 419.608399 -317.586494) (xy 419.63127 -317.630071)
			(xy 419.646854 -317.676752) (xy 419.654749 -317.725329) (xy 419.655244 -317.749936) (xy 420.944052 -317.749936)
			(xy 420.948012 -317.700882) (xy 420.959789 -317.653098) (xy 420.97908 -317.607822) (xy 421.005383 -317.566226)
			(xy 421.038018 -317.529389) (xy 421.076139 -317.498264) (xy 421.11876 -317.473657) (xy 421.164776 -317.456205)
			(xy 421.212995 -317.446361) (xy 421.26217 -317.44438) (xy 421.311025 -317.450312) (xy 421.358296 -317.464004)
			(xy 421.402758 -317.485102) (xy 421.443261 -317.513058) (xy 421.478754 -317.54715) (xy 421.508319 -317.586494)
			(xy 421.53119 -317.630071) (xy 421.546774 -317.676752) (xy 421.554669 -317.725329) (xy 421.555164 -317.749936)
			(xy 421.554669 -317.774543) (xy 421.546774 -317.82312) (xy 421.53119 -317.869801) (xy 421.508319 -317.913378)
			(xy 421.478754 -317.952722) (xy 421.443261 -317.986814) (xy 421.402758 -318.01477) (xy 421.358296 -318.035868)
			(xy 421.311025 -318.04956) (xy 421.26217 -318.055492) (xy 421.212995 -318.053511) (xy 421.164776 -318.043667)
			(xy 421.11876 -318.026215) (xy 421.076139 -318.001608) (xy 421.038018 -317.970483) (xy 421.005383 -317.933646)
			(xy 420.97908 -317.89205) (xy 420.959789 -317.846774) (xy 420.948012 -317.79899) (xy 420.944052 -317.749936)
			(xy 419.655244 -317.749936) (xy 419.654749 -317.774543) (xy 419.646854 -317.82312) (xy 419.63127 -317.869801)
			(xy 419.608399 -317.913378) (xy 419.578834 -317.952722) (xy 419.543341 -317.986814) (xy 419.502838 -318.01477)
			(xy 419.458376 -318.035868) (xy 419.411105 -318.04956) (xy 419.36225 -318.055492) (xy 419.313075 -318.053511)
			(xy 419.264856 -318.043667) (xy 419.21884 -318.026215) (xy 419.176219 -318.001608) (xy 419.138098 -317.970483)
			(xy 419.105463 -317.933646) (xy 419.07916 -317.89205) (xy 419.059869 -317.846774) (xy 419.048092 -317.79899)
			(xy 419.044132 -317.749936) (xy 417.755324 -317.749936) (xy 417.754829 -317.774543) (xy 417.746934 -317.82312)
			(xy 417.73135 -317.869801) (xy 417.708479 -317.913378) (xy 417.678914 -317.952722) (xy 417.643421 -317.986814)
			(xy 417.602918 -318.01477) (xy 417.558456 -318.035868) (xy 417.511185 -318.04956) (xy 417.46233 -318.055492)
			(xy 417.413155 -318.053511) (xy 417.364936 -318.043667) (xy 417.31892 -318.026215) (xy 417.276299 -318.001608)
			(xy 417.238178 -317.970483) (xy 417.205543 -317.933646) (xy 417.17924 -317.89205) (xy 417.159949 -317.846774)
			(xy 417.148172 -317.79899) (xy 417.144212 -317.749936) (xy 415.85515 -317.749936) (xy 415.854655 -317.774543)
			(xy 415.84676 -317.82312) (xy 415.831176 -317.869801) (xy 415.808305 -317.913378) (xy 415.77874 -317.952722)
			(xy 415.743247 -317.986814) (xy 415.702744 -318.01477) (xy 415.658282 -318.035868) (xy 415.611011 -318.04956)
			(xy 415.562156 -318.055492) (xy 415.512981 -318.053511) (xy 415.464762 -318.043667) (xy 415.418746 -318.026215)
			(xy 415.376125 -318.001608) (xy 415.338004 -317.970483) (xy 415.305369 -317.933646) (xy 415.279066 -317.89205)
			(xy 415.259775 -317.846774) (xy 415.247998 -317.79899) (xy 415.244038 -317.749936) (xy 398.755108 -317.749936)
			(xy 398.754613 -317.774543) (xy 398.746718 -317.82312) (xy 398.731134 -317.869801) (xy 398.708263 -317.913378)
			(xy 398.678698 -317.952722) (xy 398.643205 -317.986814) (xy 398.602702 -318.01477) (xy 398.55824 -318.035868)
			(xy 398.510969 -318.04956) (xy 398.462114 -318.055492) (xy 398.412939 -318.053511) (xy 398.36472 -318.043667)
			(xy 398.318704 -318.026215) (xy 398.276083 -318.001608) (xy 398.237962 -317.970483) (xy 398.205327 -317.933646)
			(xy 398.179024 -317.89205) (xy 398.159733 -317.846774) (xy 398.147956 -317.79899) (xy 398.143996 -317.749936)
			(xy 396.855188 -317.749936) (xy 396.854693 -317.774543) (xy 396.846798 -317.82312) (xy 396.831214 -317.869801)
			(xy 396.808343 -317.913378) (xy 396.778778 -317.952722) (xy 396.743285 -317.986814) (xy 396.702782 -318.01477)
			(xy 396.65832 -318.035868) (xy 396.611049 -318.04956) (xy 396.562194 -318.055492) (xy 396.513019 -318.053511)
			(xy 396.4648 -318.043667) (xy 396.418784 -318.026215) (xy 396.376163 -318.001608) (xy 396.338042 -317.970483)
			(xy 396.305407 -317.933646) (xy 396.279104 -317.89205) (xy 396.259813 -317.846774) (xy 396.248036 -317.79899)
			(xy 396.244076 -317.749936) (xy 394.955268 -317.749936) (xy 394.954773 -317.774543) (xy 394.946878 -317.82312)
			(xy 394.931294 -317.869801) (xy 394.908423 -317.913378) (xy 394.878858 -317.952722) (xy 394.843365 -317.986814)
			(xy 394.802862 -318.01477) (xy 394.7584 -318.035868) (xy 394.711129 -318.04956) (xy 394.662274 -318.055492)
			(xy 394.613099 -318.053511) (xy 394.56488 -318.043667) (xy 394.518864 -318.026215) (xy 394.476243 -318.001608)
			(xy 394.438122 -317.970483) (xy 394.405487 -317.933646) (xy 394.379184 -317.89205) (xy 394.359893 -317.846774)
			(xy 394.348116 -317.79899) (xy 394.344156 -317.749936) (xy 393.055094 -317.749936) (xy 393.054599 -317.774543)
			(xy 393.046704 -317.82312) (xy 393.03112 -317.869801) (xy 393.008249 -317.913378) (xy 392.978684 -317.952722)
			(xy 392.943191 -317.986814) (xy 392.902688 -318.01477) (xy 392.858226 -318.035868) (xy 392.810955 -318.04956)
			(xy 392.7621 -318.055492) (xy 392.712925 -318.053511) (xy 392.664706 -318.043667) (xy 392.61869 -318.026215)
			(xy 392.576069 -318.001608) (xy 392.537948 -317.970483) (xy 392.505313 -317.933646) (xy 392.47901 -317.89205)
			(xy 392.459719 -317.846774) (xy 392.447942 -317.79899) (xy 392.443982 -317.749936) (xy 391.155174 -317.749936)
			(xy 391.154679 -317.774543) (xy 391.146784 -317.82312) (xy 391.1312 -317.869801) (xy 391.108329 -317.913378)
			(xy 391.078764 -317.952722) (xy 391.043271 -317.986814) (xy 391.002768 -318.01477) (xy 390.958306 -318.035868)
			(xy 390.911035 -318.04956) (xy 390.86218 -318.055492) (xy 390.813005 -318.053511) (xy 390.764786 -318.043667)
			(xy 390.71877 -318.026215) (xy 390.676149 -318.001608) (xy 390.638028 -317.970483) (xy 390.605393 -317.933646)
			(xy 390.57909 -317.89205) (xy 390.559799 -317.846774) (xy 390.548022 -317.79899) (xy 390.544062 -317.749936)
			(xy 389.255254 -317.749936) (xy 389.254759 -317.774543) (xy 389.246864 -317.82312) (xy 389.23128 -317.869801)
			(xy 389.208409 -317.913378) (xy 389.178844 -317.952722) (xy 389.143351 -317.986814) (xy 389.102848 -318.01477)
			(xy 389.058386 -318.035868) (xy 389.011115 -318.04956) (xy 388.96226 -318.055492) (xy 388.913085 -318.053511)
			(xy 388.864866 -318.043667) (xy 388.81885 -318.026215) (xy 388.776229 -318.001608) (xy 388.738108 -317.970483)
			(xy 388.705473 -317.933646) (xy 388.67917 -317.89205) (xy 388.659879 -317.846774) (xy 388.648102 -317.79899)
			(xy 388.644142 -317.749936) (xy 387.355334 -317.749936) (xy 387.354839 -317.774543) (xy 387.346944 -317.82312)
			(xy 387.33136 -317.869801) (xy 387.308489 -317.913378) (xy 387.278924 -317.952722) (xy 387.243431 -317.986814)
			(xy 387.202928 -318.01477) (xy 387.158466 -318.035868) (xy 387.111195 -318.04956) (xy 387.06234 -318.055492)
			(xy 387.013165 -318.053511) (xy 386.964946 -318.043667) (xy 386.91893 -318.026215) (xy 386.876309 -318.001608)
			(xy 386.838188 -317.970483) (xy 386.805553 -317.933646) (xy 386.77925 -317.89205) (xy 386.759959 -317.846774)
			(xy 386.748182 -317.79899) (xy 386.744222 -317.749936) (xy 313.055 -317.749936) (xy 313.054505 -317.774543)
			(xy 313.04661 -317.82312) (xy 313.031026 -317.869801) (xy 313.008155 -317.913378) (xy 312.97859 -317.952722)
			(xy 312.943097 -317.986814) (xy 312.902594 -318.01477) (xy 312.858132 -318.035868) (xy 312.810861 -318.04956)
			(xy 312.762006 -318.055492) (xy 312.712831 -318.053511) (xy 312.664612 -318.043667) (xy 312.618596 -318.026215)
			(xy 312.575975 -318.001608) (xy 312.537854 -317.970483) (xy 312.505219 -317.933646) (xy 312.478916 -317.89205)
			(xy 312.459625 -317.846774) (xy 312.447848 -317.79899) (xy 312.443888 -317.749936) (xy 311.15508 -317.749936)
			(xy 311.154585 -317.774543) (xy 311.14669 -317.82312) (xy 311.131106 -317.869801) (xy 311.108235 -317.913378)
			(xy 311.07867 -317.952722) (xy 311.043177 -317.986814) (xy 311.002674 -318.01477) (xy 310.958212 -318.035868)
			(xy 310.910941 -318.04956) (xy 310.862086 -318.055492) (xy 310.812911 -318.053511) (xy 310.764692 -318.043667)
			(xy 310.718676 -318.026215) (xy 310.676055 -318.001608) (xy 310.637934 -317.970483) (xy 310.605299 -317.933646)
			(xy 310.578996 -317.89205) (xy 310.559705 -317.846774) (xy 310.547928 -317.79899) (xy 310.543968 -317.749936)
			(xy 309.25516 -317.749936) (xy 309.254665 -317.774543) (xy 309.24677 -317.82312) (xy 309.231186 -317.869801)
			(xy 309.208315 -317.913378) (xy 309.17875 -317.952722) (xy 309.143257 -317.986814) (xy 309.102754 -318.01477)
			(xy 309.058292 -318.035868) (xy 309.011021 -318.04956) (xy 308.962166 -318.055492) (xy 308.912991 -318.053511)
			(xy 308.864772 -318.043667) (xy 308.818756 -318.026215) (xy 308.776135 -318.001608) (xy 308.738014 -317.970483)
			(xy 308.705379 -317.933646) (xy 308.679076 -317.89205) (xy 308.659785 -317.846774) (xy 308.648008 -317.79899)
			(xy 308.644048 -317.749936) (xy 307.35524 -317.749936) (xy 307.354745 -317.774543) (xy 307.34685 -317.82312)
			(xy 307.331266 -317.869801) (xy 307.308395 -317.913378) (xy 307.27883 -317.952722) (xy 307.243337 -317.986814)
			(xy 307.202834 -318.01477) (xy 307.158372 -318.035868) (xy 307.111101 -318.04956) (xy 307.062246 -318.055492)
			(xy 307.013071 -318.053511) (xy 306.964852 -318.043667) (xy 306.918836 -318.026215) (xy 306.876215 -318.001608)
			(xy 306.838094 -317.970483) (xy 306.805459 -317.933646) (xy 306.779156 -317.89205) (xy 306.759865 -317.846774)
			(xy 306.748088 -317.79899) (xy 306.744128 -317.749936) (xy 297.855132 -317.749936) (xy 297.854637 -317.774543)
			(xy 297.846742 -317.82312) (xy 297.831158 -317.869801) (xy 297.808287 -317.913378) (xy 297.778722 -317.952722)
			(xy 297.743229 -317.986814) (xy 297.702726 -318.01477) (xy 297.658264 -318.035868) (xy 297.610993 -318.04956)
			(xy 297.562138 -318.055492) (xy 297.512963 -318.053511) (xy 297.464744 -318.043667) (xy 297.418728 -318.026215)
			(xy 297.376107 -318.001608) (xy 297.337986 -317.970483) (xy 297.305351 -317.933646) (xy 297.279048 -317.89205)
			(xy 297.259757 -317.846774) (xy 297.24798 -317.79899) (xy 297.24402 -317.749936) (xy 295.955212 -317.749936)
			(xy 295.954717 -317.774543) (xy 295.946822 -317.82312) (xy 295.931238 -317.869801) (xy 295.908367 -317.913378)
			(xy 295.878802 -317.952722) (xy 295.843309 -317.986814) (xy 295.802806 -318.01477) (xy 295.758344 -318.035868)
			(xy 295.711073 -318.04956) (xy 295.662218 -318.055492) (xy 295.613043 -318.053511) (xy 295.564824 -318.043667)
			(xy 295.518808 -318.026215) (xy 295.476187 -318.001608) (xy 295.438066 -317.970483) (xy 295.405431 -317.933646)
			(xy 295.379128 -317.89205) (xy 295.359837 -317.846774) (xy 295.34806 -317.79899) (xy 295.3441 -317.749936)
			(xy 294.055038 -317.749936) (xy 294.054543 -317.774543) (xy 294.046648 -317.82312) (xy 294.031064 -317.869801)
			(xy 294.008193 -317.913378) (xy 293.978628 -317.952722) (xy 293.943135 -317.986814) (xy 293.902632 -318.01477)
			(xy 293.85817 -318.035868) (xy 293.810899 -318.04956) (xy 293.762044 -318.055492) (xy 293.712869 -318.053511)
			(xy 293.66465 -318.043667) (xy 293.618634 -318.026215) (xy 293.576013 -318.001608) (xy 293.537892 -317.970483)
			(xy 293.505257 -317.933646) (xy 293.478954 -317.89205) (xy 293.459663 -317.846774) (xy 293.447886 -317.79899)
			(xy 293.443926 -317.749936) (xy 292.155118 -317.749936) (xy 292.154623 -317.774543) (xy 292.146728 -317.82312)
			(xy 292.131144 -317.869801) (xy 292.108273 -317.913378) (xy 292.078708 -317.952722) (xy 292.043215 -317.986814)
			(xy 292.002712 -318.01477) (xy 291.95825 -318.035868) (xy 291.910979 -318.04956) (xy 291.862124 -318.055492)
			(xy 291.812949 -318.053511) (xy 291.76473 -318.043667) (xy 291.718714 -318.026215) (xy 291.676093 -318.001608)
			(xy 291.637972 -317.970483) (xy 291.605337 -317.933646) (xy 291.579034 -317.89205) (xy 291.559743 -317.846774)
			(xy 291.547966 -317.79899) (xy 291.544006 -317.749936) (xy 290.255198 -317.749936) (xy 290.254703 -317.774543)
			(xy 290.246808 -317.82312) (xy 290.231224 -317.869801) (xy 290.208353 -317.913378) (xy 290.178788 -317.952722)
			(xy 290.143295 -317.986814) (xy 290.102792 -318.01477) (xy 290.05833 -318.035868) (xy 290.011059 -318.04956)
			(xy 289.962204 -318.055492) (xy 289.913029 -318.053511) (xy 289.86481 -318.043667) (xy 289.818794 -318.026215)
			(xy 289.776173 -318.001608) (xy 289.738052 -317.970483) (xy 289.705417 -317.933646) (xy 289.679114 -317.89205)
			(xy 289.659823 -317.846774) (xy 289.648046 -317.79899) (xy 289.644086 -317.749936) (xy 288.355024 -317.749936)
			(xy 288.354529 -317.774543) (xy 288.346634 -317.82312) (xy 288.33105 -317.869801) (xy 288.308179 -317.913378)
			(xy 288.278614 -317.952722) (xy 288.243121 -317.986814) (xy 288.202618 -318.01477) (xy 288.158156 -318.035868)
			(xy 288.110885 -318.04956) (xy 288.06203 -318.055492) (xy 288.012855 -318.053511) (xy 287.964636 -318.043667)
			(xy 287.91862 -318.026215) (xy 287.875999 -318.001608) (xy 287.837878 -317.970483) (xy 287.805243 -317.933646)
			(xy 287.77894 -317.89205) (xy 287.759649 -317.846774) (xy 287.747872 -317.79899) (xy 287.743912 -317.749936)
			(xy 286.455104 -317.749936) (xy 286.454609 -317.774543) (xy 286.446714 -317.82312) (xy 286.43113 -317.869801)
			(xy 286.408259 -317.913378) (xy 286.378694 -317.952722) (xy 286.343201 -317.986814) (xy 286.302698 -318.01477)
			(xy 286.258236 -318.035868) (xy 286.210965 -318.04956) (xy 286.16211 -318.055492) (xy 286.112935 -318.053511)
			(xy 286.064716 -318.043667) (xy 286.0187 -318.026215) (xy 285.976079 -318.001608) (xy 285.937958 -317.970483)
			(xy 285.905323 -317.933646) (xy 285.87902 -317.89205) (xy 285.859729 -317.846774) (xy 285.847952 -317.79899)
			(xy 285.843992 -317.749936) (xy 284.555184 -317.749936) (xy 284.554689 -317.774543) (xy 284.546794 -317.82312)
			(xy 284.53121 -317.869801) (xy 284.508339 -317.913378) (xy 284.478774 -317.952722) (xy 284.443281 -317.986814)
			(xy 284.402778 -318.01477) (xy 284.358316 -318.035868) (xy 284.311045 -318.04956) (xy 284.26219 -318.055492)
			(xy 284.213015 -318.053511) (xy 284.164796 -318.043667) (xy 284.11878 -318.026215) (xy 284.076159 -318.001608)
			(xy 284.038038 -317.970483) (xy 284.005403 -317.933646) (xy 283.9791 -317.89205) (xy 283.959809 -317.846774)
			(xy 283.948032 -317.79899) (xy 283.944072 -317.749936) (xy 189.355222 -317.749936) (xy 189.354727 -317.774543)
			(xy 189.346832 -317.82312) (xy 189.331248 -317.869801) (xy 189.308377 -317.913378) (xy 189.278812 -317.952722)
			(xy 189.243319 -317.986814) (xy 189.202816 -318.01477) (xy 189.158354 -318.035868) (xy 189.111083 -318.04956)
			(xy 189.062228 -318.055492) (xy 189.013053 -318.053511) (xy 188.964834 -318.043667) (xy 188.918818 -318.026215)
			(xy 188.876197 -318.001608) (xy 188.838076 -317.970483) (xy 188.805441 -317.933646) (xy 188.779138 -317.89205)
			(xy 188.759847 -317.846774) (xy 188.74807 -317.79899) (xy 188.74411 -317.749936) (xy 187.455302 -317.749936)
			(xy 187.454807 -317.774543) (xy 187.446912 -317.82312) (xy 187.431328 -317.869801) (xy 187.408457 -317.913378)
			(xy 187.378892 -317.952722) (xy 187.343399 -317.986814) (xy 187.302896 -318.01477) (xy 187.258434 -318.035868)
			(xy 187.211163 -318.04956) (xy 187.162308 -318.055492) (xy 187.113133 -318.053511) (xy 187.064914 -318.043667)
			(xy 187.018898 -318.026215) (xy 186.976277 -318.001608) (xy 186.938156 -317.970483) (xy 186.905521 -317.933646)
			(xy 186.879218 -317.89205) (xy 186.859927 -317.846774) (xy 186.84815 -317.79899) (xy 186.84419 -317.749936)
			(xy 185.555382 -317.749936) (xy 185.554887 -317.774543) (xy 185.546992 -317.82312) (xy 185.531408 -317.869801)
			(xy 185.508537 -317.913378) (xy 185.478972 -317.952722) (xy 185.443479 -317.986814) (xy 185.402976 -318.01477)
			(xy 185.358514 -318.035868) (xy 185.311243 -318.04956) (xy 185.262388 -318.055492) (xy 185.213213 -318.053511)
			(xy 185.164994 -318.043667) (xy 185.118978 -318.026215) (xy 185.076357 -318.001608) (xy 185.038236 -317.970483)
			(xy 185.005601 -317.933646) (xy 184.979298 -317.89205) (xy 184.960007 -317.846774) (xy 184.94823 -317.79899)
			(xy 184.94427 -317.749936) (xy 183.655208 -317.749936) (xy 183.654713 -317.774543) (xy 183.646818 -317.82312)
			(xy 183.631234 -317.869801) (xy 183.608363 -317.913378) (xy 183.578798 -317.952722) (xy 183.543305 -317.986814)
			(xy 183.502802 -318.01477) (xy 183.45834 -318.035868) (xy 183.411069 -318.04956) (xy 183.362214 -318.055492)
			(xy 183.313039 -318.053511) (xy 183.26482 -318.043667) (xy 183.218804 -318.026215) (xy 183.176183 -318.001608)
			(xy 183.138062 -317.970483) (xy 183.105427 -317.933646) (xy 183.079124 -317.89205) (xy 183.059833 -317.846774)
			(xy 183.048056 -317.79899) (xy 183.044096 -317.749936) (xy 166.555166 -317.749936) (xy 166.554671 -317.774543)
			(xy 166.546776 -317.82312) (xy 166.531192 -317.869801) (xy 166.508321 -317.913378) (xy 166.478756 -317.952722)
			(xy 166.443263 -317.986814) (xy 166.40276 -318.01477) (xy 166.358298 -318.035868) (xy 166.311027 -318.04956)
			(xy 166.262172 -318.055492) (xy 166.212997 -318.053511) (xy 166.164778 -318.043667) (xy 166.118762 -318.026215)
			(xy 166.076141 -318.001608) (xy 166.03802 -317.970483) (xy 166.005385 -317.933646) (xy 165.979082 -317.89205)
			(xy 165.959791 -317.846774) (xy 165.948014 -317.79899) (xy 165.944054 -317.749936) (xy 164.655246 -317.749936)
			(xy 164.654751 -317.774543) (xy 164.646856 -317.82312) (xy 164.631272 -317.869801) (xy 164.608401 -317.913378)
			(xy 164.578836 -317.952722) (xy 164.543343 -317.986814) (xy 164.50284 -318.01477) (xy 164.458378 -318.035868)
			(xy 164.411107 -318.04956) (xy 164.362252 -318.055492) (xy 164.313077 -318.053511) (xy 164.264858 -318.043667)
			(xy 164.218842 -318.026215) (xy 164.176221 -318.001608) (xy 164.1381 -317.970483) (xy 164.105465 -317.933646)
			(xy 164.079162 -317.89205) (xy 164.059871 -317.846774) (xy 164.048094 -317.79899) (xy 164.044134 -317.749936)
			(xy 162.755326 -317.749936) (xy 162.754831 -317.774543) (xy 162.746936 -317.82312) (xy 162.731352 -317.869801)
			(xy 162.708481 -317.913378) (xy 162.678916 -317.952722) (xy 162.643423 -317.986814) (xy 162.60292 -318.01477)
			(xy 162.558458 -318.035868) (xy 162.511187 -318.04956) (xy 162.462332 -318.055492) (xy 162.413157 -318.053511)
			(xy 162.364938 -318.043667) (xy 162.318922 -318.026215) (xy 162.276301 -318.001608) (xy 162.23818 -317.970483)
			(xy 162.205545 -317.933646) (xy 162.179242 -317.89205) (xy 162.159951 -317.846774) (xy 162.148174 -317.79899)
			(xy 162.144214 -317.749936) (xy 160.855152 -317.749936) (xy 160.854657 -317.774543) (xy 160.846762 -317.82312)
			(xy 160.831178 -317.869801) (xy 160.808307 -317.913378) (xy 160.778742 -317.952722) (xy 160.743249 -317.986814)
			(xy 160.702746 -318.01477) (xy 160.658284 -318.035868) (xy 160.611013 -318.04956) (xy 160.562158 -318.055492)
			(xy 160.512983 -318.053511) (xy 160.464764 -318.043667) (xy 160.418748 -318.026215) (xy 160.376127 -318.001608)
			(xy 160.338006 -317.970483) (xy 160.305371 -317.933646) (xy 160.279068 -317.89205) (xy 160.259777 -317.846774)
			(xy 160.248 -317.79899) (xy 160.24404 -317.749936) (xy 158.955232 -317.749936) (xy 158.954737 -317.774543)
			(xy 158.946842 -317.82312) (xy 158.931258 -317.869801) (xy 158.908387 -317.913378) (xy 158.878822 -317.952722)
			(xy 158.843329 -317.986814) (xy 158.802826 -318.01477) (xy 158.758364 -318.035868) (xy 158.711093 -318.04956)
			(xy 158.662238 -318.055492) (xy 158.613063 -318.053511) (xy 158.564844 -318.043667) (xy 158.518828 -318.026215)
			(xy 158.476207 -318.001608) (xy 158.438086 -317.970483) (xy 158.405451 -317.933646) (xy 158.379148 -317.89205)
			(xy 158.359857 -317.846774) (xy 158.34808 -317.79899) (xy 158.34412 -317.749936) (xy 157.055312 -317.749936)
			(xy 157.054817 -317.774543) (xy 157.046922 -317.82312) (xy 157.031338 -317.869801) (xy 157.008467 -317.913378)
			(xy 156.978902 -317.952722) (xy 156.943409 -317.986814) (xy 156.902906 -318.01477) (xy 156.858444 -318.035868)
			(xy 156.811173 -318.04956) (xy 156.762318 -318.055492) (xy 156.713143 -318.053511) (xy 156.664924 -318.043667)
			(xy 156.618908 -318.026215) (xy 156.576287 -318.001608) (xy 156.538166 -317.970483) (xy 156.505531 -317.933646)
			(xy 156.479228 -317.89205) (xy 156.459937 -317.846774) (xy 156.44816 -317.79899) (xy 156.4442 -317.749936)
			(xy 155.155392 -317.749936) (xy 155.154897 -317.774543) (xy 155.147002 -317.82312) (xy 155.131418 -317.869801)
			(xy 155.108547 -317.913378) (xy 155.078982 -317.952722) (xy 155.043489 -317.986814) (xy 155.002986 -318.01477)
			(xy 154.958524 -318.035868) (xy 154.911253 -318.04956) (xy 154.862398 -318.055492) (xy 154.813223 -318.053511)
			(xy 154.765004 -318.043667) (xy 154.718988 -318.026215) (xy 154.676367 -318.001608) (xy 154.638246 -317.970483)
			(xy 154.605611 -317.933646) (xy 154.579308 -317.89205) (xy 154.560017 -317.846774) (xy 154.54824 -317.79899)
			(xy 154.54428 -317.749936) (xy 80.855058 -317.749936) (xy 80.854563 -317.774543) (xy 80.846668 -317.82312)
			(xy 80.831084 -317.869801) (xy 80.808213 -317.913378) (xy 80.778648 -317.952722) (xy 80.743155 -317.986814)
			(xy 80.702652 -318.01477) (xy 80.65819 -318.035868) (xy 80.610919 -318.04956) (xy 80.562064 -318.055492)
			(xy 80.512889 -318.053511) (xy 80.46467 -318.043667) (xy 80.418654 -318.026215) (xy 80.376033 -318.001608)
			(xy 80.337912 -317.970483) (xy 80.305277 -317.933646) (xy 80.278974 -317.89205) (xy 80.259683 -317.846774)
			(xy 80.247906 -317.79899) (xy 80.243946 -317.749936) (xy 78.955138 -317.749936) (xy 78.954643 -317.774543)
			(xy 78.946748 -317.82312) (xy 78.931164 -317.869801) (xy 78.908293 -317.913378) (xy 78.878728 -317.952722)
			(xy 78.843235 -317.986814) (xy 78.802732 -318.01477) (xy 78.75827 -318.035868) (xy 78.710999 -318.04956)
			(xy 78.662144 -318.055492) (xy 78.612969 -318.053511) (xy 78.56475 -318.043667) (xy 78.518734 -318.026215)
			(xy 78.476113 -318.001608) (xy 78.437992 -317.970483) (xy 78.405357 -317.933646) (xy 78.379054 -317.89205)
			(xy 78.359763 -317.846774) (xy 78.347986 -317.79899) (xy 78.344026 -317.749936) (xy 77.055218 -317.749936)
			(xy 77.054723 -317.774543) (xy 77.046828 -317.82312) (xy 77.031244 -317.869801) (xy 77.008373 -317.913378)
			(xy 76.978808 -317.952722) (xy 76.943315 -317.986814) (xy 76.902812 -318.01477) (xy 76.85835 -318.035868)
			(xy 76.811079 -318.04956) (xy 76.762224 -318.055492) (xy 76.713049 -318.053511) (xy 76.66483 -318.043667)
			(xy 76.618814 -318.026215) (xy 76.576193 -318.001608) (xy 76.538072 -317.970483) (xy 76.505437 -317.933646)
			(xy 76.479134 -317.89205) (xy 76.459843 -317.846774) (xy 76.448066 -317.79899) (xy 76.444106 -317.749936)
			(xy 75.155298 -317.749936) (xy 75.154803 -317.774543) (xy 75.146908 -317.82312) (xy 75.131324 -317.869801)
			(xy 75.108453 -317.913378) (xy 75.078888 -317.952722) (xy 75.043395 -317.986814) (xy 75.002892 -318.01477)
			(xy 74.95843 -318.035868) (xy 74.911159 -318.04956) (xy 74.862304 -318.055492) (xy 74.813129 -318.053511)
			(xy 74.76491 -318.043667) (xy 74.718894 -318.026215) (xy 74.676273 -318.001608) (xy 74.638152 -317.970483)
			(xy 74.605517 -317.933646) (xy 74.579214 -317.89205) (xy 74.559923 -317.846774) (xy 74.548146 -317.79899)
			(xy 74.544186 -317.749936) (xy 65.65519 -317.749936) (xy 65.654695 -317.774543) (xy 65.6468 -317.82312)
			(xy 65.631216 -317.869801) (xy 65.608345 -317.913378) (xy 65.57878 -317.952722) (xy 65.543287 -317.986814)
			(xy 65.502784 -318.01477) (xy 65.458322 -318.035868) (xy 65.411051 -318.04956) (xy 65.362196 -318.055492)
			(xy 65.313021 -318.053511) (xy 65.264802 -318.043667) (xy 65.218786 -318.026215) (xy 65.176165 -318.001608)
			(xy 65.138044 -317.970483) (xy 65.105409 -317.933646) (xy 65.079106 -317.89205) (xy 65.059815 -317.846774)
			(xy 65.048038 -317.79899) (xy 65.044078 -317.749936) (xy 63.75527 -317.749936) (xy 63.754775 -317.774543)
			(xy 63.74688 -317.82312) (xy 63.731296 -317.869801) (xy 63.708425 -317.913378) (xy 63.67886 -317.952722)
			(xy 63.643367 -317.986814) (xy 63.602864 -318.01477) (xy 63.558402 -318.035868) (xy 63.511131 -318.04956)
			(xy 63.462276 -318.055492) (xy 63.413101 -318.053511) (xy 63.364882 -318.043667) (xy 63.318866 -318.026215)
			(xy 63.276245 -318.001608) (xy 63.238124 -317.970483) (xy 63.205489 -317.933646) (xy 63.179186 -317.89205)
			(xy 63.159895 -317.846774) (xy 63.148118 -317.79899) (xy 63.144158 -317.749936) (xy 61.855096 -317.749936)
			(xy 61.854601 -317.774543) (xy 61.846706 -317.82312) (xy 61.831122 -317.869801) (xy 61.808251 -317.913378)
			(xy 61.778686 -317.952722) (xy 61.743193 -317.986814) (xy 61.70269 -318.01477) (xy 61.658228 -318.035868)
			(xy 61.610957 -318.04956) (xy 61.562102 -318.055492) (xy 61.512927 -318.053511) (xy 61.464708 -318.043667)
			(xy 61.418692 -318.026215) (xy 61.376071 -318.001608) (xy 61.33795 -317.970483) (xy 61.305315 -317.933646)
			(xy 61.279012 -317.89205) (xy 61.259721 -317.846774) (xy 61.247944 -317.79899) (xy 61.243984 -317.749936)
			(xy 59.955176 -317.749936) (xy 59.954681 -317.774543) (xy 59.946786 -317.82312) (xy 59.931202 -317.869801)
			(xy 59.908331 -317.913378) (xy 59.878766 -317.952722) (xy 59.843273 -317.986814) (xy 59.80277 -318.01477)
			(xy 59.758308 -318.035868) (xy 59.711037 -318.04956) (xy 59.662182 -318.055492) (xy 59.613007 -318.053511)
			(xy 59.564788 -318.043667) (xy 59.518772 -318.026215) (xy 59.476151 -318.001608) (xy 59.43803 -317.970483)
			(xy 59.405395 -317.933646) (xy 59.379092 -317.89205) (xy 59.359801 -317.846774) (xy 59.348024 -317.79899)
			(xy 59.344064 -317.749936) (xy 58.055256 -317.749936) (xy 58.054761 -317.774543) (xy 58.046866 -317.82312)
			(xy 58.031282 -317.869801) (xy 58.008411 -317.913378) (xy 57.978846 -317.952722) (xy 57.943353 -317.986814)
			(xy 57.90285 -318.01477) (xy 57.858388 -318.035868) (xy 57.811117 -318.04956) (xy 57.762262 -318.055492)
			(xy 57.713087 -318.053511) (xy 57.664868 -318.043667) (xy 57.618852 -318.026215) (xy 57.576231 -318.001608)
			(xy 57.53811 -317.970483) (xy 57.505475 -317.933646) (xy 57.479172 -317.89205) (xy 57.459881 -317.846774)
			(xy 57.448104 -317.79899) (xy 57.444144 -317.749936) (xy 56.155082 -317.749936) (xy 56.154587 -317.774543)
			(xy 56.146692 -317.82312) (xy 56.131108 -317.869801) (xy 56.108237 -317.913378) (xy 56.078672 -317.952722)
			(xy 56.043179 -317.986814) (xy 56.002676 -318.01477) (xy 55.958214 -318.035868) (xy 55.910943 -318.04956)
			(xy 55.862088 -318.055492) (xy 55.812913 -318.053511) (xy 55.764694 -318.043667) (xy 55.718678 -318.026215)
			(xy 55.676057 -318.001608) (xy 55.637936 -317.970483) (xy 55.605301 -317.933646) (xy 55.578998 -317.89205)
			(xy 55.559707 -317.846774) (xy 55.54793 -317.79899) (xy 55.54397 -317.749936) (xy 54.255162 -317.749936)
			(xy 54.254667 -317.774543) (xy 54.246772 -317.82312) (xy 54.231188 -317.869801) (xy 54.208317 -317.913378)
			(xy 54.178752 -317.952722) (xy 54.143259 -317.986814) (xy 54.102756 -318.01477) (xy 54.058294 -318.035868)
			(xy 54.011023 -318.04956) (xy 53.962168 -318.055492) (xy 53.912993 -318.053511) (xy 53.864774 -318.043667)
			(xy 53.818758 -318.026215) (xy 53.776137 -318.001608) (xy 53.738016 -317.970483) (xy 53.705381 -317.933646)
			(xy 53.679078 -317.89205) (xy 53.659787 -317.846774) (xy 53.64801 -317.79899) (xy 53.64405 -317.749936)
			(xy 52.355242 -317.749936) (xy 52.354747 -317.774543) (xy 52.346852 -317.82312) (xy 52.331268 -317.869801)
			(xy 52.308397 -317.913378) (xy 52.278832 -317.952722) (xy 52.243339 -317.986814) (xy 52.202836 -318.01477)
			(xy 52.158374 -318.035868) (xy 52.111103 -318.04956) (xy 52.062248 -318.055492) (xy 52.013073 -318.053511)
			(xy 51.964854 -318.043667) (xy 51.918838 -318.026215) (xy 51.876217 -318.001608) (xy 51.838096 -317.970483)
			(xy 51.805461 -317.933646) (xy 51.779158 -317.89205) (xy 51.759867 -317.846774) (xy 51.74809 -317.79899)
			(xy 51.74413 -317.749936) (xy 0.508 -317.749936) (xy 0.508 -320.900044) (xy 26.882353 -320.900044)
			(xy 26.886342 -320.751504) (xy 26.898299 -320.603391) (xy 26.918189 -320.456134) (xy 26.945954 -320.310158)
			(xy 26.981515 -320.165881) (xy 27.024769 -320.023722) (xy 27.075591 -319.884089) (xy 27.133835 -319.747386)
			(xy 27.199333 -319.614006) (xy 27.271896 -319.484334) (xy 27.351314 -319.358744) (xy 27.437359 -319.237597)
			(xy 27.529783 -319.121244) (xy 27.628319 -319.01002) (xy 27.732683 -318.904245) (xy 27.842575 -318.804225)
			(xy 27.957676 -318.710247) (xy 28.077656 -318.622583) (xy 28.202169 -318.541486) (xy 28.330855 -318.467189)
			(xy 28.463344 -318.399907) (xy 28.599253 -318.339833) (xy 28.738191 -318.287141) (xy 28.879757 -318.241982)
			(xy 29.023543 -318.204487) (xy 29.169134 -318.174765) (xy 29.31611 -318.1529) (xy 29.464049 -318.138956)
			(xy 29.612522 -318.132972) (xy 29.761103 -318.134967) (xy 29.909362 -318.144935) (xy 30.056873 -318.162846)
			(xy 30.203209 -318.188649) (xy 30.34795 -318.222269) (xy 30.490677 -318.263611) (xy 30.63098 -318.312554)
			(xy 30.768453 -318.368957) (xy 30.9027 -318.432658) (xy 31.033335 -318.503474) (xy 31.15998 -318.581199)
			(xy 31.28227 -318.66561) (xy 31.326643 -318.699896) (xy 51.74413 -318.699896) (xy 51.74809 -318.650842)
			(xy 51.759867 -318.603058) (xy 51.779158 -318.557782) (xy 51.805461 -318.516186) (xy 51.838096 -318.479349)
			(xy 51.876217 -318.448224) (xy 51.918838 -318.423617) (xy 51.964854 -318.406165) (xy 52.013073 -318.396321)
			(xy 52.062248 -318.39434) (xy 52.111103 -318.400272) (xy 52.158374 -318.413964) (xy 52.202836 -318.435062)
			(xy 52.243339 -318.463018) (xy 52.278832 -318.49711) (xy 52.308397 -318.536454) (xy 52.331268 -318.580031)
			(xy 52.346852 -318.626712) (xy 52.354747 -318.675289) (xy 52.355242 -318.699896) (xy 53.64405 -318.699896)
			(xy 53.64801 -318.650842) (xy 53.659787 -318.603058) (xy 53.679078 -318.557782) (xy 53.705381 -318.516186)
			(xy 53.738016 -318.479349) (xy 53.776137 -318.448224) (xy 53.818758 -318.423617) (xy 53.864774 -318.406165)
			(xy 53.912993 -318.396321) (xy 53.962168 -318.39434) (xy 54.011023 -318.400272) (xy 54.058294 -318.413964)
			(xy 54.102756 -318.435062) (xy 54.143259 -318.463018) (xy 54.178752 -318.49711) (xy 54.208317 -318.536454)
			(xy 54.231188 -318.580031) (xy 54.246772 -318.626712) (xy 54.254667 -318.675289) (xy 54.255162 -318.699896)
			(xy 55.54397 -318.699896) (xy 55.54793 -318.650842) (xy 55.559707 -318.603058) (xy 55.578998 -318.557782)
			(xy 55.605301 -318.516186) (xy 55.637936 -318.479349) (xy 55.676057 -318.448224) (xy 55.718678 -318.423617)
			(xy 55.764694 -318.406165) (xy 55.812913 -318.396321) (xy 55.862088 -318.39434) (xy 55.910943 -318.400272)
			(xy 55.958214 -318.413964) (xy 56.002676 -318.435062) (xy 56.043179 -318.463018) (xy 56.078672 -318.49711)
			(xy 56.108237 -318.536454) (xy 56.131108 -318.580031) (xy 56.146692 -318.626712) (xy 56.154587 -318.675289)
			(xy 56.155082 -318.699896) (xy 57.444144 -318.699896) (xy 57.448104 -318.650842) (xy 57.459881 -318.603058)
			(xy 57.479172 -318.557782) (xy 57.505475 -318.516186) (xy 57.53811 -318.479349) (xy 57.576231 -318.448224)
			(xy 57.618852 -318.423617) (xy 57.664868 -318.406165) (xy 57.713087 -318.396321) (xy 57.762262 -318.39434)
			(xy 57.811117 -318.400272) (xy 57.858388 -318.413964) (xy 57.90285 -318.435062) (xy 57.943353 -318.463018)
			(xy 57.978846 -318.49711) (xy 58.008411 -318.536454) (xy 58.031282 -318.580031) (xy 58.046866 -318.626712)
			(xy 58.054761 -318.675289) (xy 58.055256 -318.699896) (xy 59.344064 -318.699896) (xy 59.348024 -318.650842)
			(xy 59.359801 -318.603058) (xy 59.379092 -318.557782) (xy 59.405395 -318.516186) (xy 59.43803 -318.479349)
			(xy 59.476151 -318.448224) (xy 59.518772 -318.423617) (xy 59.564788 -318.406165) (xy 59.613007 -318.396321)
			(xy 59.662182 -318.39434) (xy 59.711037 -318.400272) (xy 59.758308 -318.413964) (xy 59.80277 -318.435062)
			(xy 59.843273 -318.463018) (xy 59.878766 -318.49711) (xy 59.908331 -318.536454) (xy 59.931202 -318.580031)
			(xy 59.946786 -318.626712) (xy 59.954681 -318.675289) (xy 59.955176 -318.699896) (xy 61.243984 -318.699896)
			(xy 61.247944 -318.650842) (xy 61.259721 -318.603058) (xy 61.279012 -318.557782) (xy 61.305315 -318.516186)
			(xy 61.33795 -318.479349) (xy 61.376071 -318.448224) (xy 61.418692 -318.423617) (xy 61.464708 -318.406165)
			(xy 61.512927 -318.396321) (xy 61.562102 -318.39434) (xy 61.610957 -318.400272) (xy 61.658228 -318.413964)
			(xy 61.70269 -318.435062) (xy 61.743193 -318.463018) (xy 61.778686 -318.49711) (xy 61.808251 -318.536454)
			(xy 61.831122 -318.580031) (xy 61.846706 -318.626712) (xy 61.854601 -318.675289) (xy 61.855096 -318.699896)
			(xy 63.144158 -318.699896) (xy 63.148118 -318.650842) (xy 63.159895 -318.603058) (xy 63.179186 -318.557782)
			(xy 63.205489 -318.516186) (xy 63.238124 -318.479349) (xy 63.276245 -318.448224) (xy 63.318866 -318.423617)
			(xy 63.364882 -318.406165) (xy 63.413101 -318.396321) (xy 63.462276 -318.39434) (xy 63.511131 -318.400272)
			(xy 63.558402 -318.413964) (xy 63.602864 -318.435062) (xy 63.643367 -318.463018) (xy 63.67886 -318.49711)
			(xy 63.708425 -318.536454) (xy 63.731296 -318.580031) (xy 63.74688 -318.626712) (xy 63.754775 -318.675289)
			(xy 63.75527 -318.699896) (xy 65.044078 -318.699896) (xy 65.048038 -318.650842) (xy 65.059815 -318.603058)
			(xy 65.079106 -318.557782) (xy 65.105409 -318.516186) (xy 65.138044 -318.479349) (xy 65.176165 -318.448224)
			(xy 65.218786 -318.423617) (xy 65.264802 -318.406165) (xy 65.313021 -318.396321) (xy 65.362196 -318.39434)
			(xy 65.411051 -318.400272) (xy 65.458322 -318.413964) (xy 65.502784 -318.435062) (xy 65.543287 -318.463018)
			(xy 65.57878 -318.49711) (xy 65.608345 -318.536454) (xy 65.631216 -318.580031) (xy 65.6468 -318.626712)
			(xy 65.654695 -318.675289) (xy 65.65519 -318.699896) (xy 74.544186 -318.699896) (xy 74.548146 -318.650842)
			(xy 74.559923 -318.603058) (xy 74.579214 -318.557782) (xy 74.605517 -318.516186) (xy 74.638152 -318.479349)
			(xy 74.676273 -318.448224) (xy 74.718894 -318.423617) (xy 74.76491 -318.406165) (xy 74.813129 -318.396321)
			(xy 74.862304 -318.39434) (xy 74.911159 -318.400272) (xy 74.95843 -318.413964) (xy 75.002892 -318.435062)
			(xy 75.043395 -318.463018) (xy 75.078888 -318.49711) (xy 75.108453 -318.536454) (xy 75.131324 -318.580031)
			(xy 75.146908 -318.626712) (xy 75.154803 -318.675289) (xy 75.155298 -318.699896) (xy 76.444106 -318.699896)
			(xy 76.448066 -318.650842) (xy 76.459843 -318.603058) (xy 76.479134 -318.557782) (xy 76.505437 -318.516186)
			(xy 76.538072 -318.479349) (xy 76.576193 -318.448224) (xy 76.618814 -318.423617) (xy 76.66483 -318.406165)
			(xy 76.713049 -318.396321) (xy 76.762224 -318.39434) (xy 76.811079 -318.400272) (xy 76.85835 -318.413964)
			(xy 76.902812 -318.435062) (xy 76.943315 -318.463018) (xy 76.978808 -318.49711) (xy 77.008373 -318.536454)
			(xy 77.031244 -318.580031) (xy 77.046828 -318.626712) (xy 77.054723 -318.675289) (xy 77.055218 -318.699896)
			(xy 78.344026 -318.699896) (xy 78.347986 -318.650842) (xy 78.359763 -318.603058) (xy 78.379054 -318.557782)
			(xy 78.405357 -318.516186) (xy 78.437992 -318.479349) (xy 78.476113 -318.448224) (xy 78.518734 -318.423617)
			(xy 78.56475 -318.406165) (xy 78.612969 -318.396321) (xy 78.662144 -318.39434) (xy 78.710999 -318.400272)
			(xy 78.75827 -318.413964) (xy 78.802732 -318.435062) (xy 78.843235 -318.463018) (xy 78.878728 -318.49711)
			(xy 78.908293 -318.536454) (xy 78.931164 -318.580031) (xy 78.946748 -318.626712) (xy 78.954643 -318.675289)
			(xy 78.955138 -318.699896) (xy 80.243946 -318.699896) (xy 80.247906 -318.650842) (xy 80.259683 -318.603058)
			(xy 80.278974 -318.557782) (xy 80.305277 -318.516186) (xy 80.337912 -318.479349) (xy 80.376033 -318.448224)
			(xy 80.418654 -318.423617) (xy 80.46467 -318.406165) (xy 80.512889 -318.396321) (xy 80.562064 -318.39434)
			(xy 80.610919 -318.400272) (xy 80.65819 -318.413964) (xy 80.702652 -318.435062) (xy 80.743155 -318.463018)
			(xy 80.778648 -318.49711) (xy 80.808213 -318.536454) (xy 80.831084 -318.580031) (xy 80.846668 -318.626712)
			(xy 80.854563 -318.675289) (xy 80.855058 -318.699896) (xy 80.854563 -318.724503) (xy 80.846668 -318.77308)
			(xy 80.831084 -318.819761) (xy 80.808213 -318.863338) (xy 80.778648 -318.902682) (xy 80.743155 -318.936774)
			(xy 80.702652 -318.96473) (xy 80.65819 -318.985828) (xy 80.610919 -318.99952) (xy 80.562064 -319.005452)
			(xy 80.512889 -319.003471) (xy 80.46467 -318.993627) (xy 80.418654 -318.976175) (xy 80.376033 -318.951568)
			(xy 80.337912 -318.920443) (xy 80.305277 -318.883606) (xy 80.278974 -318.84201) (xy 80.259683 -318.796734)
			(xy 80.247906 -318.74895) (xy 80.243946 -318.699896) (xy 78.955138 -318.699896) (xy 78.954643 -318.724503)
			(xy 78.946748 -318.77308) (xy 78.931164 -318.819761) (xy 78.908293 -318.863338) (xy 78.878728 -318.902682)
			(xy 78.843235 -318.936774) (xy 78.802732 -318.96473) (xy 78.75827 -318.985828) (xy 78.710999 -318.99952)
			(xy 78.662144 -319.005452) (xy 78.612969 -319.003471) (xy 78.56475 -318.993627) (xy 78.518734 -318.976175)
			(xy 78.476113 -318.951568) (xy 78.437992 -318.920443) (xy 78.405357 -318.883606) (xy 78.379054 -318.84201)
			(xy 78.359763 -318.796734) (xy 78.347986 -318.74895) (xy 78.344026 -318.699896) (xy 77.055218 -318.699896)
			(xy 77.054723 -318.724503) (xy 77.046828 -318.77308) (xy 77.031244 -318.819761) (xy 77.008373 -318.863338)
			(xy 76.978808 -318.902682) (xy 76.943315 -318.936774) (xy 76.902812 -318.96473) (xy 76.85835 -318.985828)
			(xy 76.811079 -318.99952) (xy 76.762224 -319.005452) (xy 76.713049 -319.003471) (xy 76.66483 -318.993627)
			(xy 76.618814 -318.976175) (xy 76.576193 -318.951568) (xy 76.538072 -318.920443) (xy 76.505437 -318.883606)
			(xy 76.479134 -318.84201) (xy 76.459843 -318.796734) (xy 76.448066 -318.74895) (xy 76.444106 -318.699896)
			(xy 75.155298 -318.699896) (xy 75.154803 -318.724503) (xy 75.146908 -318.77308) (xy 75.131324 -318.819761)
			(xy 75.108453 -318.863338) (xy 75.078888 -318.902682) (xy 75.043395 -318.936774) (xy 75.002892 -318.96473)
			(xy 74.95843 -318.985828) (xy 74.911159 -318.99952) (xy 74.862304 -319.005452) (xy 74.813129 -319.003471)
			(xy 74.76491 -318.993627) (xy 74.718894 -318.976175) (xy 74.676273 -318.951568) (xy 74.638152 -318.920443)
			(xy 74.605517 -318.883606) (xy 74.579214 -318.84201) (xy 74.559923 -318.796734) (xy 74.548146 -318.74895)
			(xy 74.544186 -318.699896) (xy 65.65519 -318.699896) (xy 65.654695 -318.724503) (xy 65.6468 -318.77308)
			(xy 65.631216 -318.819761) (xy 65.608345 -318.863338) (xy 65.57878 -318.902682) (xy 65.543287 -318.936774)
			(xy 65.502784 -318.96473) (xy 65.458322 -318.985828) (xy 65.411051 -318.99952) (xy 65.362196 -319.005452)
			(xy 65.313021 -319.003471) (xy 65.264802 -318.993627) (xy 65.218786 -318.976175) (xy 65.176165 -318.951568)
			(xy 65.138044 -318.920443) (xy 65.105409 -318.883606) (xy 65.079106 -318.84201) (xy 65.059815 -318.796734)
			(xy 65.048038 -318.74895) (xy 65.044078 -318.699896) (xy 63.75527 -318.699896) (xy 63.754775 -318.724503)
			(xy 63.74688 -318.77308) (xy 63.731296 -318.819761) (xy 63.708425 -318.863338) (xy 63.67886 -318.902682)
			(xy 63.643367 -318.936774) (xy 63.602864 -318.96473) (xy 63.558402 -318.985828) (xy 63.511131 -318.99952)
			(xy 63.462276 -319.005452) (xy 63.413101 -319.003471) (xy 63.364882 -318.993627) (xy 63.318866 -318.976175)
			(xy 63.276245 -318.951568) (xy 63.238124 -318.920443) (xy 63.205489 -318.883606) (xy 63.179186 -318.84201)
			(xy 63.159895 -318.796734) (xy 63.148118 -318.74895) (xy 63.144158 -318.699896) (xy 61.855096 -318.699896)
			(xy 61.854601 -318.724503) (xy 61.846706 -318.77308) (xy 61.831122 -318.819761) (xy 61.808251 -318.863338)
			(xy 61.778686 -318.902682) (xy 61.743193 -318.936774) (xy 61.70269 -318.96473) (xy 61.658228 -318.985828)
			(xy 61.610957 -318.99952) (xy 61.562102 -319.005452) (xy 61.512927 -319.003471) (xy 61.464708 -318.993627)
			(xy 61.418692 -318.976175) (xy 61.376071 -318.951568) (xy 61.33795 -318.920443) (xy 61.305315 -318.883606)
			(xy 61.279012 -318.84201) (xy 61.259721 -318.796734) (xy 61.247944 -318.74895) (xy 61.243984 -318.699896)
			(xy 59.955176 -318.699896) (xy 59.954681 -318.724503) (xy 59.946786 -318.77308) (xy 59.931202 -318.819761)
			(xy 59.908331 -318.863338) (xy 59.878766 -318.902682) (xy 59.843273 -318.936774) (xy 59.80277 -318.96473)
			(xy 59.758308 -318.985828) (xy 59.711037 -318.99952) (xy 59.662182 -319.005452) (xy 59.613007 -319.003471)
			(xy 59.564788 -318.993627) (xy 59.518772 -318.976175) (xy 59.476151 -318.951568) (xy 59.43803 -318.920443)
			(xy 59.405395 -318.883606) (xy 59.379092 -318.84201) (xy 59.359801 -318.796734) (xy 59.348024 -318.74895)
			(xy 59.344064 -318.699896) (xy 58.055256 -318.699896) (xy 58.054761 -318.724503) (xy 58.046866 -318.77308)
			(xy 58.031282 -318.819761) (xy 58.008411 -318.863338) (xy 57.978846 -318.902682) (xy 57.943353 -318.936774)
			(xy 57.90285 -318.96473) (xy 57.858388 -318.985828) (xy 57.811117 -318.99952) (xy 57.762262 -319.005452)
			(xy 57.713087 -319.003471) (xy 57.664868 -318.993627) (xy 57.618852 -318.976175) (xy 57.576231 -318.951568)
			(xy 57.53811 -318.920443) (xy 57.505475 -318.883606) (xy 57.479172 -318.84201) (xy 57.459881 -318.796734)
			(xy 57.448104 -318.74895) (xy 57.444144 -318.699896) (xy 56.155082 -318.699896) (xy 56.154587 -318.724503)
			(xy 56.146692 -318.77308) (xy 56.131108 -318.819761) (xy 56.108237 -318.863338) (xy 56.078672 -318.902682)
			(xy 56.043179 -318.936774) (xy 56.002676 -318.96473) (xy 55.958214 -318.985828) (xy 55.910943 -318.99952)
			(xy 55.862088 -319.005452) (xy 55.812913 -319.003471) (xy 55.764694 -318.993627) (xy 55.718678 -318.976175)
			(xy 55.676057 -318.951568) (xy 55.637936 -318.920443) (xy 55.605301 -318.883606) (xy 55.578998 -318.84201)
			(xy 55.559707 -318.796734) (xy 55.54793 -318.74895) (xy 55.54397 -318.699896) (xy 54.255162 -318.699896)
			(xy 54.254667 -318.724503) (xy 54.246772 -318.77308) (xy 54.231188 -318.819761) (xy 54.208317 -318.863338)
			(xy 54.178752 -318.902682) (xy 54.143259 -318.936774) (xy 54.102756 -318.96473) (xy 54.058294 -318.985828)
			(xy 54.011023 -318.99952) (xy 53.962168 -319.005452) (xy 53.912993 -319.003471) (xy 53.864774 -318.993627)
			(xy 53.818758 -318.976175) (xy 53.776137 -318.951568) (xy 53.738016 -318.920443) (xy 53.705381 -318.883606)
			(xy 53.679078 -318.84201) (xy 53.659787 -318.796734) (xy 53.64801 -318.74895) (xy 53.64405 -318.699896)
			(xy 52.355242 -318.699896) (xy 52.354747 -318.724503) (xy 52.346852 -318.77308) (xy 52.331268 -318.819761)
			(xy 52.308397 -318.863338) (xy 52.278832 -318.902682) (xy 52.243339 -318.936774) (xy 52.202836 -318.96473)
			(xy 52.158374 -318.985828) (xy 52.111103 -318.99952) (xy 52.062248 -319.005452) (xy 52.013073 -319.003471)
			(xy 51.964854 -318.993627) (xy 51.918838 -318.976175) (xy 51.876217 -318.951568) (xy 51.838096 -318.920443)
			(xy 51.805461 -318.883606) (xy 51.779158 -318.84201) (xy 51.759867 -318.796734) (xy 51.74809 -318.74895)
			(xy 51.74413 -318.699896) (xy 31.326643 -318.699896) (xy 31.399853 -318.756463) (xy 31.51239 -318.853497)
			(xy 31.619557 -318.956432) (xy 31.721044 -319.064971) (xy 31.816558 -319.1788) (xy 31.905825 -319.297593)
			(xy 31.988586 -319.421005) (xy 32.064604 -319.548683) (xy 32.133659 -319.680256) (xy 32.195552 -319.815347)
			(xy 32.250105 -319.953564) (xy 32.29716 -320.094511) (xy 32.336582 -320.237781) (xy 32.368256 -320.38296)
			(xy 32.392092 -320.529629) (xy 32.408021 -320.677367) (xy 32.415997 -320.825747) (xy 32.416496 -320.900044)
			(xy 86.882487 -320.900044) (xy 86.886476 -320.751504) (xy 86.898433 -320.603391) (xy 86.918323 -320.456134)
			(xy 86.946088 -320.310158) (xy 86.981649 -320.165881) (xy 87.024903 -320.023722) (xy 87.075725 -319.884089)
			(xy 87.133969 -319.747386) (xy 87.199467 -319.614006) (xy 87.27203 -319.484334) (xy 87.351448 -319.358744)
			(xy 87.437493 -319.237597) (xy 87.529917 -319.121244) (xy 87.628453 -319.01002) (xy 87.732817 -318.904245)
			(xy 87.842709 -318.804225) (xy 87.95781 -318.710247) (xy 88.07779 -318.622583) (xy 88.202303 -318.541486)
			(xy 88.330989 -318.467189) (xy 88.463478 -318.399907) (xy 88.599387 -318.339833) (xy 88.738325 -318.287141)
			(xy 88.879891 -318.241982) (xy 89.023677 -318.204487) (xy 89.169268 -318.174765) (xy 89.316244 -318.1529)
			(xy 89.464183 -318.138956) (xy 89.612656 -318.132972) (xy 89.761237 -318.134967) (xy 89.909496 -318.144935)
			(xy 90.057007 -318.162846) (xy 90.203343 -318.188649) (xy 90.348084 -318.222269) (xy 90.490811 -318.263611)
			(xy 90.631114 -318.312554) (xy 90.768587 -318.368957) (xy 90.902834 -318.432658) (xy 91.033469 -318.503474)
			(xy 91.160114 -318.581199) (xy 91.282404 -318.66561) (xy 91.399987 -318.756463) (xy 91.512524 -318.853497)
			(xy 91.619691 -318.956432) (xy 91.721178 -319.064971) (xy 91.816692 -319.1788) (xy 91.905959 -319.297593)
			(xy 91.98872 -319.421005) (xy 92.064738 -319.548683) (xy 92.133793 -319.680256) (xy 92.195686 -319.815347)
			(xy 92.250239 -319.953564) (xy 92.297294 -320.094511) (xy 92.336716 -320.237781) (xy 92.36839 -320.38296)
			(xy 92.392226 -320.529629) (xy 92.408155 -320.677367) (xy 92.416131 -320.825747) (xy 92.41663 -320.900044)
			(xy 142.982451 -320.900044) (xy 142.98644 -320.751504) (xy 142.998397 -320.603391) (xy 143.018287 -320.456134)
			(xy 143.046052 -320.310158) (xy 143.081613 -320.165881) (xy 143.124867 -320.023722) (xy 143.175689 -319.884089)
			(xy 143.233933 -319.747386) (xy 143.299431 -319.614006) (xy 143.371994 -319.484334) (xy 143.451412 -319.358744)
			(xy 143.537457 -319.237597) (xy 143.629881 -319.121244) (xy 143.728417 -319.01002) (xy 143.832781 -318.904245)
			(xy 143.942673 -318.804225) (xy 144.057774 -318.710247) (xy 144.177754 -318.622583) (xy 144.302267 -318.541486)
			(xy 144.430953 -318.467189) (xy 144.563442 -318.399907) (xy 144.699351 -318.339833) (xy 144.838289 -318.287141)
			(xy 144.979855 -318.241982) (xy 145.123641 -318.204487) (xy 145.269232 -318.174765) (xy 145.416208 -318.1529)
			(xy 145.564147 -318.138956) (xy 145.71262 -318.132972) (xy 145.861201 -318.134967) (xy 146.00946 -318.144935)
			(xy 146.156971 -318.162846) (xy 146.303307 -318.188649) (xy 146.448048 -318.222269) (xy 146.590775 -318.263611)
			(xy 146.731078 -318.312554) (xy 146.868551 -318.368957) (xy 147.002798 -318.432658) (xy 147.133433 -318.503474)
			(xy 147.260078 -318.581199) (xy 147.382368 -318.66561) (xy 147.426741 -318.699896) (xy 154.54428 -318.699896)
			(xy 154.54824 -318.650842) (xy 154.560017 -318.603058) (xy 154.579308 -318.557782) (xy 154.605611 -318.516186)
			(xy 154.638246 -318.479349) (xy 154.676367 -318.448224) (xy 154.718988 -318.423617) (xy 154.765004 -318.406165)
			(xy 154.813223 -318.396321) (xy 154.862398 -318.39434) (xy 154.911253 -318.400272) (xy 154.958524 -318.413964)
			(xy 155.002986 -318.435062) (xy 155.043489 -318.463018) (xy 155.078982 -318.49711) (xy 155.108547 -318.536454)
			(xy 155.131418 -318.580031) (xy 155.147002 -318.626712) (xy 155.154897 -318.675289) (xy 155.155392 -318.699896)
			(xy 156.4442 -318.699896) (xy 156.44816 -318.650842) (xy 156.459937 -318.603058) (xy 156.479228 -318.557782)
			(xy 156.505531 -318.516186) (xy 156.538166 -318.479349) (xy 156.576287 -318.448224) (xy 156.618908 -318.423617)
			(xy 156.664924 -318.406165) (xy 156.713143 -318.396321) (xy 156.762318 -318.39434) (xy 156.811173 -318.400272)
			(xy 156.858444 -318.413964) (xy 156.902906 -318.435062) (xy 156.943409 -318.463018) (xy 156.978902 -318.49711)
			(xy 157.008467 -318.536454) (xy 157.031338 -318.580031) (xy 157.046922 -318.626712) (xy 157.054817 -318.675289)
			(xy 157.055312 -318.699896) (xy 158.34412 -318.699896) (xy 158.34808 -318.650842) (xy 158.359857 -318.603058)
			(xy 158.379148 -318.557782) (xy 158.405451 -318.516186) (xy 158.438086 -318.479349) (xy 158.476207 -318.448224)
			(xy 158.518828 -318.423617) (xy 158.564844 -318.406165) (xy 158.613063 -318.396321) (xy 158.662238 -318.39434)
			(xy 158.711093 -318.400272) (xy 158.758364 -318.413964) (xy 158.802826 -318.435062) (xy 158.843329 -318.463018)
			(xy 158.878822 -318.49711) (xy 158.908387 -318.536454) (xy 158.931258 -318.580031) (xy 158.946842 -318.626712)
			(xy 158.954737 -318.675289) (xy 158.955232 -318.699896) (xy 160.24404 -318.699896) (xy 160.248 -318.650842)
			(xy 160.259777 -318.603058) (xy 160.279068 -318.557782) (xy 160.305371 -318.516186) (xy 160.338006 -318.479349)
			(xy 160.376127 -318.448224) (xy 160.418748 -318.423617) (xy 160.464764 -318.406165) (xy 160.512983 -318.396321)
			(xy 160.562158 -318.39434) (xy 160.611013 -318.400272) (xy 160.658284 -318.413964) (xy 160.702746 -318.435062)
			(xy 160.743249 -318.463018) (xy 160.778742 -318.49711) (xy 160.808307 -318.536454) (xy 160.831178 -318.580031)
			(xy 160.846762 -318.626712) (xy 160.854657 -318.675289) (xy 160.855152 -318.699896) (xy 162.144214 -318.699896)
			(xy 162.148174 -318.650842) (xy 162.159951 -318.603058) (xy 162.179242 -318.557782) (xy 162.205545 -318.516186)
			(xy 162.23818 -318.479349) (xy 162.276301 -318.448224) (xy 162.318922 -318.423617) (xy 162.364938 -318.406165)
			(xy 162.413157 -318.396321) (xy 162.462332 -318.39434) (xy 162.511187 -318.400272) (xy 162.558458 -318.413964)
			(xy 162.60292 -318.435062) (xy 162.643423 -318.463018) (xy 162.678916 -318.49711) (xy 162.708481 -318.536454)
			(xy 162.731352 -318.580031) (xy 162.746936 -318.626712) (xy 162.754831 -318.675289) (xy 162.755326 -318.699896)
			(xy 164.044134 -318.699896) (xy 164.048094 -318.650842) (xy 164.059871 -318.603058) (xy 164.079162 -318.557782)
			(xy 164.105465 -318.516186) (xy 164.1381 -318.479349) (xy 164.176221 -318.448224) (xy 164.218842 -318.423617)
			(xy 164.264858 -318.406165) (xy 164.313077 -318.396321) (xy 164.362252 -318.39434) (xy 164.411107 -318.400272)
			(xy 164.458378 -318.413964) (xy 164.50284 -318.435062) (xy 164.543343 -318.463018) (xy 164.578836 -318.49711)
			(xy 164.608401 -318.536454) (xy 164.631272 -318.580031) (xy 164.646856 -318.626712) (xy 164.654751 -318.675289)
			(xy 164.655246 -318.699896) (xy 165.944054 -318.699896) (xy 165.948014 -318.650842) (xy 165.959791 -318.603058)
			(xy 165.979082 -318.557782) (xy 166.005385 -318.516186) (xy 166.03802 -318.479349) (xy 166.076141 -318.448224)
			(xy 166.118762 -318.423617) (xy 166.164778 -318.406165) (xy 166.212997 -318.396321) (xy 166.262172 -318.39434)
			(xy 166.311027 -318.400272) (xy 166.358298 -318.413964) (xy 166.40276 -318.435062) (xy 166.443263 -318.463018)
			(xy 166.478756 -318.49711) (xy 166.508321 -318.536454) (xy 166.531192 -318.580031) (xy 166.546776 -318.626712)
			(xy 166.554671 -318.675289) (xy 166.555166 -318.699896) (xy 183.044096 -318.699896) (xy 183.048056 -318.650842)
			(xy 183.059833 -318.603058) (xy 183.079124 -318.557782) (xy 183.105427 -318.516186) (xy 183.138062 -318.479349)
			(xy 183.176183 -318.448224) (xy 183.218804 -318.423617) (xy 183.26482 -318.406165) (xy 183.313039 -318.396321)
			(xy 183.362214 -318.39434) (xy 183.411069 -318.400272) (xy 183.45834 -318.413964) (xy 183.502802 -318.435062)
			(xy 183.543305 -318.463018) (xy 183.578798 -318.49711) (xy 183.608363 -318.536454) (xy 183.631234 -318.580031)
			(xy 183.646818 -318.626712) (xy 183.654713 -318.675289) (xy 183.655208 -318.699896) (xy 184.94427 -318.699896)
			(xy 184.94823 -318.650842) (xy 184.960007 -318.603058) (xy 184.979298 -318.557782) (xy 185.005601 -318.516186)
			(xy 185.038236 -318.479349) (xy 185.076357 -318.448224) (xy 185.118978 -318.423617) (xy 185.164994 -318.406165)
			(xy 185.213213 -318.396321) (xy 185.262388 -318.39434) (xy 185.311243 -318.400272) (xy 185.358514 -318.413964)
			(xy 185.402976 -318.435062) (xy 185.443479 -318.463018) (xy 185.478972 -318.49711) (xy 185.508537 -318.536454)
			(xy 185.531408 -318.580031) (xy 185.546992 -318.626712) (xy 185.554887 -318.675289) (xy 185.555382 -318.699896)
			(xy 186.84419 -318.699896) (xy 186.84815 -318.650842) (xy 186.859927 -318.603058) (xy 186.879218 -318.557782)
			(xy 186.905521 -318.516186) (xy 186.938156 -318.479349) (xy 186.976277 -318.448224) (xy 187.018898 -318.423617)
			(xy 187.064914 -318.406165) (xy 187.113133 -318.396321) (xy 187.162308 -318.39434) (xy 187.211163 -318.400272)
			(xy 187.258434 -318.413964) (xy 187.302896 -318.435062) (xy 187.343399 -318.463018) (xy 187.378892 -318.49711)
			(xy 187.408457 -318.536454) (xy 187.431328 -318.580031) (xy 187.446912 -318.626712) (xy 187.454807 -318.675289)
			(xy 187.455302 -318.699896) (xy 188.74411 -318.699896) (xy 188.74807 -318.650842) (xy 188.759847 -318.603058)
			(xy 188.779138 -318.557782) (xy 188.805441 -318.516186) (xy 188.838076 -318.479349) (xy 188.876197 -318.448224)
			(xy 188.918818 -318.423617) (xy 188.964834 -318.406165) (xy 189.013053 -318.396321) (xy 189.062228 -318.39434)
			(xy 189.111083 -318.400272) (xy 189.158354 -318.413964) (xy 189.202816 -318.435062) (xy 189.243319 -318.463018)
			(xy 189.278812 -318.49711) (xy 189.308377 -318.536454) (xy 189.331248 -318.580031) (xy 189.346832 -318.626712)
			(xy 189.354727 -318.675289) (xy 189.355222 -318.699896) (xy 189.354727 -318.724503) (xy 189.346832 -318.77308)
			(xy 189.331248 -318.819761) (xy 189.308377 -318.863338) (xy 189.278812 -318.902682) (xy 189.243319 -318.936774)
			(xy 189.202816 -318.96473) (xy 189.158354 -318.985828) (xy 189.111083 -318.99952) (xy 189.062228 -319.005452)
			(xy 189.013053 -319.003471) (xy 188.964834 -318.993627) (xy 188.918818 -318.976175) (xy 188.876197 -318.951568)
			(xy 188.838076 -318.920443) (xy 188.805441 -318.883606) (xy 188.779138 -318.84201) (xy 188.759847 -318.796734)
			(xy 188.74807 -318.74895) (xy 188.74411 -318.699896) (xy 187.455302 -318.699896) (xy 187.454807 -318.724503)
			(xy 187.446912 -318.77308) (xy 187.431328 -318.819761) (xy 187.408457 -318.863338) (xy 187.378892 -318.902682)
			(xy 187.343399 -318.936774) (xy 187.302896 -318.96473) (xy 187.258434 -318.985828) (xy 187.211163 -318.99952)
			(xy 187.162308 -319.005452) (xy 187.113133 -319.003471) (xy 187.064914 -318.993627) (xy 187.018898 -318.976175)
			(xy 186.976277 -318.951568) (xy 186.938156 -318.920443) (xy 186.905521 -318.883606) (xy 186.879218 -318.84201)
			(xy 186.859927 -318.796734) (xy 186.84815 -318.74895) (xy 186.84419 -318.699896) (xy 185.555382 -318.699896)
			(xy 185.554887 -318.724503) (xy 185.546992 -318.77308) (xy 185.531408 -318.819761) (xy 185.508537 -318.863338)
			(xy 185.478972 -318.902682) (xy 185.443479 -318.936774) (xy 185.402976 -318.96473) (xy 185.358514 -318.985828)
			(xy 185.311243 -318.99952) (xy 185.262388 -319.005452) (xy 185.213213 -319.003471) (xy 185.164994 -318.993627)
			(xy 185.118978 -318.976175) (xy 185.076357 -318.951568) (xy 185.038236 -318.920443) (xy 185.005601 -318.883606)
			(xy 184.979298 -318.84201) (xy 184.960007 -318.796734) (xy 184.94823 -318.74895) (xy 184.94427 -318.699896)
			(xy 183.655208 -318.699896) (xy 183.654713 -318.724503) (xy 183.646818 -318.77308) (xy 183.631234 -318.819761)
			(xy 183.608363 -318.863338) (xy 183.578798 -318.902682) (xy 183.543305 -318.936774) (xy 183.502802 -318.96473)
			(xy 183.45834 -318.985828) (xy 183.411069 -318.99952) (xy 183.362214 -319.005452) (xy 183.313039 -319.003471)
			(xy 183.26482 -318.993627) (xy 183.218804 -318.976175) (xy 183.176183 -318.951568) (xy 183.138062 -318.920443)
			(xy 183.105427 -318.883606) (xy 183.079124 -318.84201) (xy 183.059833 -318.796734) (xy 183.048056 -318.74895)
			(xy 183.044096 -318.699896) (xy 166.555166 -318.699896) (xy 166.554671 -318.724503) (xy 166.546776 -318.77308)
			(xy 166.531192 -318.819761) (xy 166.508321 -318.863338) (xy 166.478756 -318.902682) (xy 166.443263 -318.936774)
			(xy 166.40276 -318.96473) (xy 166.358298 -318.985828) (xy 166.311027 -318.99952) (xy 166.262172 -319.005452)
			(xy 166.212997 -319.003471) (xy 166.164778 -318.993627) (xy 166.118762 -318.976175) (xy 166.076141 -318.951568)
			(xy 166.03802 -318.920443) (xy 166.005385 -318.883606) (xy 165.979082 -318.84201) (xy 165.959791 -318.796734)
			(xy 165.948014 -318.74895) (xy 165.944054 -318.699896) (xy 164.655246 -318.699896) (xy 164.654751 -318.724503)
			(xy 164.646856 -318.77308) (xy 164.631272 -318.819761) (xy 164.608401 -318.863338) (xy 164.578836 -318.902682)
			(xy 164.543343 -318.936774) (xy 164.50284 -318.96473) (xy 164.458378 -318.985828) (xy 164.411107 -318.99952)
			(xy 164.362252 -319.005452) (xy 164.313077 -319.003471) (xy 164.264858 -318.993627) (xy 164.218842 -318.976175)
			(xy 164.176221 -318.951568) (xy 164.1381 -318.920443) (xy 164.105465 -318.883606) (xy 164.079162 -318.84201)
			(xy 164.059871 -318.796734) (xy 164.048094 -318.74895) (xy 164.044134 -318.699896) (xy 162.755326 -318.699896)
			(xy 162.754831 -318.724503) (xy 162.746936 -318.77308) (xy 162.731352 -318.819761) (xy 162.708481 -318.863338)
			(xy 162.678916 -318.902682) (xy 162.643423 -318.936774) (xy 162.60292 -318.96473) (xy 162.558458 -318.985828)
			(xy 162.511187 -318.99952) (xy 162.462332 -319.005452) (xy 162.413157 -319.003471) (xy 162.364938 -318.993627)
			(xy 162.318922 -318.976175) (xy 162.276301 -318.951568) (xy 162.23818 -318.920443) (xy 162.205545 -318.883606)
			(xy 162.179242 -318.84201) (xy 162.159951 -318.796734) (xy 162.148174 -318.74895) (xy 162.144214 -318.699896)
			(xy 160.855152 -318.699896) (xy 160.854657 -318.724503) (xy 160.846762 -318.77308) (xy 160.831178 -318.819761)
			(xy 160.808307 -318.863338) (xy 160.778742 -318.902682) (xy 160.743249 -318.936774) (xy 160.702746 -318.96473)
			(xy 160.658284 -318.985828) (xy 160.611013 -318.99952) (xy 160.562158 -319.005452) (xy 160.512983 -319.003471)
			(xy 160.464764 -318.993627) (xy 160.418748 -318.976175) (xy 160.376127 -318.951568) (xy 160.338006 -318.920443)
			(xy 160.305371 -318.883606) (xy 160.279068 -318.84201) (xy 160.259777 -318.796734) (xy 160.248 -318.74895)
			(xy 160.24404 -318.699896) (xy 158.955232 -318.699896) (xy 158.954737 -318.724503) (xy 158.946842 -318.77308)
			(xy 158.931258 -318.819761) (xy 158.908387 -318.863338) (xy 158.878822 -318.902682) (xy 158.843329 -318.936774)
			(xy 158.802826 -318.96473) (xy 158.758364 -318.985828) (xy 158.711093 -318.99952) (xy 158.662238 -319.005452)
			(xy 158.613063 -319.003471) (xy 158.564844 -318.993627) (xy 158.518828 -318.976175) (xy 158.476207 -318.951568)
			(xy 158.438086 -318.920443) (xy 158.405451 -318.883606) (xy 158.379148 -318.84201) (xy 158.359857 -318.796734)
			(xy 158.34808 -318.74895) (xy 158.34412 -318.699896) (xy 157.055312 -318.699896) (xy 157.054817 -318.724503)
			(xy 157.046922 -318.77308) (xy 157.031338 -318.819761) (xy 157.008467 -318.863338) (xy 156.978902 -318.902682)
			(xy 156.943409 -318.936774) (xy 156.902906 -318.96473) (xy 156.858444 -318.985828) (xy 156.811173 -318.99952)
			(xy 156.762318 -319.005452) (xy 156.713143 -319.003471) (xy 156.664924 -318.993627) (xy 156.618908 -318.976175)
			(xy 156.576287 -318.951568) (xy 156.538166 -318.920443) (xy 156.505531 -318.883606) (xy 156.479228 -318.84201)
			(xy 156.459937 -318.796734) (xy 156.44816 -318.74895) (xy 156.4442 -318.699896) (xy 155.155392 -318.699896)
			(xy 155.154897 -318.724503) (xy 155.147002 -318.77308) (xy 155.131418 -318.819761) (xy 155.108547 -318.863338)
			(xy 155.078982 -318.902682) (xy 155.043489 -318.936774) (xy 155.002986 -318.96473) (xy 154.958524 -318.985828)
			(xy 154.911253 -318.99952) (xy 154.862398 -319.005452) (xy 154.813223 -319.003471) (xy 154.765004 -318.993627)
			(xy 154.718988 -318.976175) (xy 154.676367 -318.951568) (xy 154.638246 -318.920443) (xy 154.605611 -318.883606)
			(xy 154.579308 -318.84201) (xy 154.560017 -318.796734) (xy 154.54824 -318.74895) (xy 154.54428 -318.699896)
			(xy 147.426741 -318.699896) (xy 147.499951 -318.756463) (xy 147.612488 -318.853497) (xy 147.719655 -318.956432)
			(xy 147.821142 -319.064971) (xy 147.916656 -319.1788) (xy 148.005923 -319.297593) (xy 148.088684 -319.421005)
			(xy 148.164702 -319.548683) (xy 148.233757 -319.680256) (xy 148.29565 -319.815347) (xy 148.350203 -319.953564)
			(xy 148.397258 -320.094511) (xy 148.43668 -320.237781) (xy 148.468354 -320.38296) (xy 148.49219 -320.529629)
			(xy 148.508119 -320.677367) (xy 148.516095 -320.825747) (xy 148.516594 -320.900044) (xy 202.982331 -320.900044)
			(xy 202.98632 -320.751504) (xy 202.998277 -320.603391) (xy 203.018167 -320.456134) (xy 203.045932 -320.310158)
			(xy 203.081493 -320.165881) (xy 203.124747 -320.023722) (xy 203.175569 -319.884089) (xy 203.233813 -319.747386)
			(xy 203.299311 -319.614006) (xy 203.371874 -319.484334) (xy 203.451292 -319.358744) (xy 203.537337 -319.237597)
			(xy 203.629761 -319.121244) (xy 203.728297 -319.01002) (xy 203.832661 -318.904245) (xy 203.942553 -318.804225)
			(xy 204.057654 -318.710247) (xy 204.177634 -318.622583) (xy 204.302147 -318.541486) (xy 204.430833 -318.467189)
			(xy 204.563322 -318.399907) (xy 204.699231 -318.339833) (xy 204.838169 -318.287141) (xy 204.979735 -318.241982)
			(xy 205.123521 -318.204487) (xy 205.269112 -318.174765) (xy 205.416088 -318.1529) (xy 205.564027 -318.138956)
			(xy 205.7125 -318.132972) (xy 205.861081 -318.134967) (xy 206.00934 -318.144935) (xy 206.156851 -318.162846)
			(xy 206.303187 -318.188649) (xy 206.447928 -318.222269) (xy 206.590655 -318.263611) (xy 206.730958 -318.312554)
			(xy 206.868431 -318.368957) (xy 207.002678 -318.432658) (xy 207.133313 -318.503474) (xy 207.259958 -318.581199)
			(xy 207.382248 -318.66561) (xy 207.499831 -318.756463) (xy 207.612368 -318.853497) (xy 207.719535 -318.956432)
			(xy 207.821022 -319.064971) (xy 207.916536 -319.1788) (xy 208.005803 -319.297593) (xy 208.088564 -319.421005)
			(xy 208.164582 -319.548683) (xy 208.233637 -319.680256) (xy 208.29553 -319.815347) (xy 208.350083 -319.953564)
			(xy 208.397138 -320.094511) (xy 208.43656 -320.237781) (xy 208.468234 -320.38296) (xy 208.49207 -320.529629)
			(xy 208.507999 -320.677367) (xy 208.515975 -320.825747) (xy 208.516474 -320.900044) (xy 259.082549 -320.900044)
			(xy 259.086538 -320.751504) (xy 259.098495 -320.603391) (xy 259.118385 -320.456134) (xy 259.14615 -320.310158)
			(xy 259.181711 -320.165881) (xy 259.224965 -320.023722) (xy 259.275787 -319.884089) (xy 259.334031 -319.747386)
			(xy 259.399529 -319.614006) (xy 259.472092 -319.484334) (xy 259.55151 -319.358744) (xy 259.637555 -319.237597)
			(xy 259.729979 -319.121244) (xy 259.828515 -319.01002) (xy 259.932879 -318.904245) (xy 260.042771 -318.804225)
			(xy 260.157872 -318.710247) (xy 260.277852 -318.622583) (xy 260.402365 -318.541486) (xy 260.531051 -318.467189)
			(xy 260.66354 -318.399907) (xy 260.799449 -318.339833) (xy 260.938387 -318.287141) (xy 261.079953 -318.241982)
			(xy 261.223739 -318.204487) (xy 261.36933 -318.174765) (xy 261.516306 -318.1529) (xy 261.664245 -318.138956)
			(xy 261.812718 -318.132972) (xy 261.961299 -318.134967) (xy 262.109558 -318.144935) (xy 262.257069 -318.162846)
			(xy 262.403405 -318.188649) (xy 262.548146 -318.222269) (xy 262.690873 -318.263611) (xy 262.831176 -318.312554)
			(xy 262.968649 -318.368957) (xy 263.102896 -318.432658) (xy 263.233531 -318.503474) (xy 263.360176 -318.581199)
			(xy 263.482466 -318.66561) (xy 263.526839 -318.699896) (xy 283.944072 -318.699896) (xy 283.948032 -318.650842)
			(xy 283.959809 -318.603058) (xy 283.9791 -318.557782) (xy 284.005403 -318.516186) (xy 284.038038 -318.479349)
			(xy 284.076159 -318.448224) (xy 284.11878 -318.423617) (xy 284.164796 -318.406165) (xy 284.213015 -318.396321)
			(xy 284.26219 -318.39434) (xy 284.311045 -318.400272) (xy 284.358316 -318.413964) (xy 284.402778 -318.435062)
			(xy 284.443281 -318.463018) (xy 284.478774 -318.49711) (xy 284.508339 -318.536454) (xy 284.53121 -318.580031)
			(xy 284.546794 -318.626712) (xy 284.554689 -318.675289) (xy 284.555184 -318.699896) (xy 285.843992 -318.699896)
			(xy 285.847952 -318.650842) (xy 285.859729 -318.603058) (xy 285.87902 -318.557782) (xy 285.905323 -318.516186)
			(xy 285.937958 -318.479349) (xy 285.976079 -318.448224) (xy 286.0187 -318.423617) (xy 286.064716 -318.406165)
			(xy 286.112935 -318.396321) (xy 286.16211 -318.39434) (xy 286.210965 -318.400272) (xy 286.258236 -318.413964)
			(xy 286.302698 -318.435062) (xy 286.343201 -318.463018) (xy 286.378694 -318.49711) (xy 286.408259 -318.536454)
			(xy 286.43113 -318.580031) (xy 286.446714 -318.626712) (xy 286.454609 -318.675289) (xy 286.455104 -318.699896)
			(xy 287.743912 -318.699896) (xy 287.747872 -318.650842) (xy 287.759649 -318.603058) (xy 287.77894 -318.557782)
			(xy 287.805243 -318.516186) (xy 287.837878 -318.479349) (xy 287.875999 -318.448224) (xy 287.91862 -318.423617)
			(xy 287.964636 -318.406165) (xy 288.012855 -318.396321) (xy 288.06203 -318.39434) (xy 288.110885 -318.400272)
			(xy 288.158156 -318.413964) (xy 288.202618 -318.435062) (xy 288.243121 -318.463018) (xy 288.278614 -318.49711)
			(xy 288.308179 -318.536454) (xy 288.33105 -318.580031) (xy 288.346634 -318.626712) (xy 288.354529 -318.675289)
			(xy 288.355024 -318.699896) (xy 289.644086 -318.699896) (xy 289.648046 -318.650842) (xy 289.659823 -318.603058)
			(xy 289.679114 -318.557782) (xy 289.705417 -318.516186) (xy 289.738052 -318.479349) (xy 289.776173 -318.448224)
			(xy 289.818794 -318.423617) (xy 289.86481 -318.406165) (xy 289.913029 -318.396321) (xy 289.962204 -318.39434)
			(xy 290.011059 -318.400272) (xy 290.05833 -318.413964) (xy 290.102792 -318.435062) (xy 290.143295 -318.463018)
			(xy 290.178788 -318.49711) (xy 290.208353 -318.536454) (xy 290.231224 -318.580031) (xy 290.246808 -318.626712)
			(xy 290.254703 -318.675289) (xy 290.255198 -318.699896) (xy 291.544006 -318.699896) (xy 291.547966 -318.650842)
			(xy 291.559743 -318.603058) (xy 291.579034 -318.557782) (xy 291.605337 -318.516186) (xy 291.637972 -318.479349)
			(xy 291.676093 -318.448224) (xy 291.718714 -318.423617) (xy 291.76473 -318.406165) (xy 291.812949 -318.396321)
			(xy 291.862124 -318.39434) (xy 291.910979 -318.400272) (xy 291.95825 -318.413964) (xy 292.002712 -318.435062)
			(xy 292.043215 -318.463018) (xy 292.078708 -318.49711) (xy 292.108273 -318.536454) (xy 292.131144 -318.580031)
			(xy 292.146728 -318.626712) (xy 292.154623 -318.675289) (xy 292.155118 -318.699896) (xy 293.443926 -318.699896)
			(xy 293.447886 -318.650842) (xy 293.459663 -318.603058) (xy 293.478954 -318.557782) (xy 293.505257 -318.516186)
			(xy 293.537892 -318.479349) (xy 293.576013 -318.448224) (xy 293.618634 -318.423617) (xy 293.66465 -318.406165)
			(xy 293.712869 -318.396321) (xy 293.762044 -318.39434) (xy 293.810899 -318.400272) (xy 293.85817 -318.413964)
			(xy 293.902632 -318.435062) (xy 293.943135 -318.463018) (xy 293.978628 -318.49711) (xy 294.008193 -318.536454)
			(xy 294.031064 -318.580031) (xy 294.046648 -318.626712) (xy 294.054543 -318.675289) (xy 294.055038 -318.699896)
			(xy 295.3441 -318.699896) (xy 295.34806 -318.650842) (xy 295.359837 -318.603058) (xy 295.379128 -318.557782)
			(xy 295.405431 -318.516186) (xy 295.438066 -318.479349) (xy 295.476187 -318.448224) (xy 295.518808 -318.423617)
			(xy 295.564824 -318.406165) (xy 295.613043 -318.396321) (xy 295.662218 -318.39434) (xy 295.711073 -318.400272)
			(xy 295.758344 -318.413964) (xy 295.802806 -318.435062) (xy 295.843309 -318.463018) (xy 295.878802 -318.49711)
			(xy 295.908367 -318.536454) (xy 295.931238 -318.580031) (xy 295.946822 -318.626712) (xy 295.954717 -318.675289)
			(xy 295.955212 -318.699896) (xy 297.24402 -318.699896) (xy 297.24798 -318.650842) (xy 297.259757 -318.603058)
			(xy 297.279048 -318.557782) (xy 297.305351 -318.516186) (xy 297.337986 -318.479349) (xy 297.376107 -318.448224)
			(xy 297.418728 -318.423617) (xy 297.464744 -318.406165) (xy 297.512963 -318.396321) (xy 297.562138 -318.39434)
			(xy 297.610993 -318.400272) (xy 297.658264 -318.413964) (xy 297.702726 -318.435062) (xy 297.743229 -318.463018)
			(xy 297.778722 -318.49711) (xy 297.808287 -318.536454) (xy 297.831158 -318.580031) (xy 297.846742 -318.626712)
			(xy 297.854637 -318.675289) (xy 297.855132 -318.699896) (xy 306.744128 -318.699896) (xy 306.748088 -318.650842)
			(xy 306.759865 -318.603058) (xy 306.779156 -318.557782) (xy 306.805459 -318.516186) (xy 306.838094 -318.479349)
			(xy 306.876215 -318.448224) (xy 306.918836 -318.423617) (xy 306.964852 -318.406165) (xy 307.013071 -318.396321)
			(xy 307.062246 -318.39434) (xy 307.111101 -318.400272) (xy 307.158372 -318.413964) (xy 307.202834 -318.435062)
			(xy 307.243337 -318.463018) (xy 307.27883 -318.49711) (xy 307.308395 -318.536454) (xy 307.331266 -318.580031)
			(xy 307.34685 -318.626712) (xy 307.354745 -318.675289) (xy 307.35524 -318.699896) (xy 308.644048 -318.699896)
			(xy 308.648008 -318.650842) (xy 308.659785 -318.603058) (xy 308.679076 -318.557782) (xy 308.705379 -318.516186)
			(xy 308.738014 -318.479349) (xy 308.776135 -318.448224) (xy 308.818756 -318.423617) (xy 308.864772 -318.406165)
			(xy 308.912991 -318.396321) (xy 308.962166 -318.39434) (xy 309.011021 -318.400272) (xy 309.058292 -318.413964)
			(xy 309.102754 -318.435062) (xy 309.143257 -318.463018) (xy 309.17875 -318.49711) (xy 309.208315 -318.536454)
			(xy 309.231186 -318.580031) (xy 309.24677 -318.626712) (xy 309.254665 -318.675289) (xy 309.25516 -318.699896)
			(xy 310.543968 -318.699896) (xy 310.547928 -318.650842) (xy 310.559705 -318.603058) (xy 310.578996 -318.557782)
			(xy 310.605299 -318.516186) (xy 310.637934 -318.479349) (xy 310.676055 -318.448224) (xy 310.718676 -318.423617)
			(xy 310.764692 -318.406165) (xy 310.812911 -318.396321) (xy 310.862086 -318.39434) (xy 310.910941 -318.400272)
			(xy 310.958212 -318.413964) (xy 311.002674 -318.435062) (xy 311.043177 -318.463018) (xy 311.07867 -318.49711)
			(xy 311.108235 -318.536454) (xy 311.131106 -318.580031) (xy 311.14669 -318.626712) (xy 311.154585 -318.675289)
			(xy 311.15508 -318.699896) (xy 312.443888 -318.699896) (xy 312.447848 -318.650842) (xy 312.459625 -318.603058)
			(xy 312.478916 -318.557782) (xy 312.505219 -318.516186) (xy 312.537854 -318.479349) (xy 312.575975 -318.448224)
			(xy 312.618596 -318.423617) (xy 312.664612 -318.406165) (xy 312.712831 -318.396321) (xy 312.762006 -318.39434)
			(xy 312.810861 -318.400272) (xy 312.858132 -318.413964) (xy 312.902594 -318.435062) (xy 312.943097 -318.463018)
			(xy 312.97859 -318.49711) (xy 313.008155 -318.536454) (xy 313.031026 -318.580031) (xy 313.04661 -318.626712)
			(xy 313.054505 -318.675289) (xy 313.055 -318.699896) (xy 313.054505 -318.724503) (xy 313.04661 -318.77308)
			(xy 313.031026 -318.819761) (xy 313.008155 -318.863338) (xy 312.97859 -318.902682) (xy 312.943097 -318.936774)
			(xy 312.902594 -318.96473) (xy 312.858132 -318.985828) (xy 312.810861 -318.99952) (xy 312.762006 -319.005452)
			(xy 312.712831 -319.003471) (xy 312.664612 -318.993627) (xy 312.618596 -318.976175) (xy 312.575975 -318.951568)
			(xy 312.537854 -318.920443) (xy 312.505219 -318.883606) (xy 312.478916 -318.84201) (xy 312.459625 -318.796734)
			(xy 312.447848 -318.74895) (xy 312.443888 -318.699896) (xy 311.15508 -318.699896) (xy 311.154585 -318.724503)
			(xy 311.14669 -318.77308) (xy 311.131106 -318.819761) (xy 311.108235 -318.863338) (xy 311.07867 -318.902682)
			(xy 311.043177 -318.936774) (xy 311.002674 -318.96473) (xy 310.958212 -318.985828) (xy 310.910941 -318.99952)
			(xy 310.862086 -319.005452) (xy 310.812911 -319.003471) (xy 310.764692 -318.993627) (xy 310.718676 -318.976175)
			(xy 310.676055 -318.951568) (xy 310.637934 -318.920443) (xy 310.605299 -318.883606) (xy 310.578996 -318.84201)
			(xy 310.559705 -318.796734) (xy 310.547928 -318.74895) (xy 310.543968 -318.699896) (xy 309.25516 -318.699896)
			(xy 309.254665 -318.724503) (xy 309.24677 -318.77308) (xy 309.231186 -318.819761) (xy 309.208315 -318.863338)
			(xy 309.17875 -318.902682) (xy 309.143257 -318.936774) (xy 309.102754 -318.96473) (xy 309.058292 -318.985828)
			(xy 309.011021 -318.99952) (xy 308.962166 -319.005452) (xy 308.912991 -319.003471) (xy 308.864772 -318.993627)
			(xy 308.818756 -318.976175) (xy 308.776135 -318.951568) (xy 308.738014 -318.920443) (xy 308.705379 -318.883606)
			(xy 308.679076 -318.84201) (xy 308.659785 -318.796734) (xy 308.648008 -318.74895) (xy 308.644048 -318.699896)
			(xy 307.35524 -318.699896) (xy 307.354745 -318.724503) (xy 307.34685 -318.77308) (xy 307.331266 -318.819761)
			(xy 307.308395 -318.863338) (xy 307.27883 -318.902682) (xy 307.243337 -318.936774) (xy 307.202834 -318.96473)
			(xy 307.158372 -318.985828) (xy 307.111101 -318.99952) (xy 307.062246 -319.005452) (xy 307.013071 -319.003471)
			(xy 306.964852 -318.993627) (xy 306.918836 -318.976175) (xy 306.876215 -318.951568) (xy 306.838094 -318.920443)
			(xy 306.805459 -318.883606) (xy 306.779156 -318.84201) (xy 306.759865 -318.796734) (xy 306.748088 -318.74895)
			(xy 306.744128 -318.699896) (xy 297.855132 -318.699896) (xy 297.854637 -318.724503) (xy 297.846742 -318.77308)
			(xy 297.831158 -318.819761) (xy 297.808287 -318.863338) (xy 297.778722 -318.902682) (xy 297.743229 -318.936774)
			(xy 297.702726 -318.96473) (xy 297.658264 -318.985828) (xy 297.610993 -318.99952) (xy 297.562138 -319.005452)
			(xy 297.512963 -319.003471) (xy 297.464744 -318.993627) (xy 297.418728 -318.976175) (xy 297.376107 -318.951568)
			(xy 297.337986 -318.920443) (xy 297.305351 -318.883606) (xy 297.279048 -318.84201) (xy 297.259757 -318.796734)
			(xy 297.24798 -318.74895) (xy 297.24402 -318.699896) (xy 295.955212 -318.699896) (xy 295.954717 -318.724503)
			(xy 295.946822 -318.77308) (xy 295.931238 -318.819761) (xy 295.908367 -318.863338) (xy 295.878802 -318.902682)
			(xy 295.843309 -318.936774) (xy 295.802806 -318.96473) (xy 295.758344 -318.985828) (xy 295.711073 -318.99952)
			(xy 295.662218 -319.005452) (xy 295.613043 -319.003471) (xy 295.564824 -318.993627) (xy 295.518808 -318.976175)
			(xy 295.476187 -318.951568) (xy 295.438066 -318.920443) (xy 295.405431 -318.883606) (xy 295.379128 -318.84201)
			(xy 295.359837 -318.796734) (xy 295.34806 -318.74895) (xy 295.3441 -318.699896) (xy 294.055038 -318.699896)
			(xy 294.054543 -318.724503) (xy 294.046648 -318.77308) (xy 294.031064 -318.819761) (xy 294.008193 -318.863338)
			(xy 293.978628 -318.902682) (xy 293.943135 -318.936774) (xy 293.902632 -318.96473) (xy 293.85817 -318.985828)
			(xy 293.810899 -318.99952) (xy 293.762044 -319.005452) (xy 293.712869 -319.003471) (xy 293.66465 -318.993627)
			(xy 293.618634 -318.976175) (xy 293.576013 -318.951568) (xy 293.537892 -318.920443) (xy 293.505257 -318.883606)
			(xy 293.478954 -318.84201) (xy 293.459663 -318.796734) (xy 293.447886 -318.74895) (xy 293.443926 -318.699896)
			(xy 292.155118 -318.699896) (xy 292.154623 -318.724503) (xy 292.146728 -318.77308) (xy 292.131144 -318.819761)
			(xy 292.108273 -318.863338) (xy 292.078708 -318.902682) (xy 292.043215 -318.936774) (xy 292.002712 -318.96473)
			(xy 291.95825 -318.985828) (xy 291.910979 -318.99952) (xy 291.862124 -319.005452) (xy 291.812949 -319.003471)
			(xy 291.76473 -318.993627) (xy 291.718714 -318.976175) (xy 291.676093 -318.951568) (xy 291.637972 -318.920443)
			(xy 291.605337 -318.883606) (xy 291.579034 -318.84201) (xy 291.559743 -318.796734) (xy 291.547966 -318.74895)
			(xy 291.544006 -318.699896) (xy 290.255198 -318.699896) (xy 290.254703 -318.724503) (xy 290.246808 -318.77308)
			(xy 290.231224 -318.819761) (xy 290.208353 -318.863338) (xy 290.178788 -318.902682) (xy 290.143295 -318.936774)
			(xy 290.102792 -318.96473) (xy 290.05833 -318.985828) (xy 290.011059 -318.99952) (xy 289.962204 -319.005452)
			(xy 289.913029 -319.003471) (xy 289.86481 -318.993627) (xy 289.818794 -318.976175) (xy 289.776173 -318.951568)
			(xy 289.738052 -318.920443) (xy 289.705417 -318.883606) (xy 289.679114 -318.84201) (xy 289.659823 -318.796734)
			(xy 289.648046 -318.74895) (xy 289.644086 -318.699896) (xy 288.355024 -318.699896) (xy 288.354529 -318.724503)
			(xy 288.346634 -318.77308) (xy 288.33105 -318.819761) (xy 288.308179 -318.863338) (xy 288.278614 -318.902682)
			(xy 288.243121 -318.936774) (xy 288.202618 -318.96473) (xy 288.158156 -318.985828) (xy 288.110885 -318.99952)
			(xy 288.06203 -319.005452) (xy 288.012855 -319.003471) (xy 287.964636 -318.993627) (xy 287.91862 -318.976175)
			(xy 287.875999 -318.951568) (xy 287.837878 -318.920443) (xy 287.805243 -318.883606) (xy 287.77894 -318.84201)
			(xy 287.759649 -318.796734) (xy 287.747872 -318.74895) (xy 287.743912 -318.699896) (xy 286.455104 -318.699896)
			(xy 286.454609 -318.724503) (xy 286.446714 -318.77308) (xy 286.43113 -318.819761) (xy 286.408259 -318.863338)
			(xy 286.378694 -318.902682) (xy 286.343201 -318.936774) (xy 286.302698 -318.96473) (xy 286.258236 -318.985828)
			(xy 286.210965 -318.99952) (xy 286.16211 -319.005452) (xy 286.112935 -319.003471) (xy 286.064716 -318.993627)
			(xy 286.0187 -318.976175) (xy 285.976079 -318.951568) (xy 285.937958 -318.920443) (xy 285.905323 -318.883606)
			(xy 285.87902 -318.84201) (xy 285.859729 -318.796734) (xy 285.847952 -318.74895) (xy 285.843992 -318.699896)
			(xy 284.555184 -318.699896) (xy 284.554689 -318.724503) (xy 284.546794 -318.77308) (xy 284.53121 -318.819761)
			(xy 284.508339 -318.863338) (xy 284.478774 -318.902682) (xy 284.443281 -318.936774) (xy 284.402778 -318.96473)
			(xy 284.358316 -318.985828) (xy 284.311045 -318.99952) (xy 284.26219 -319.005452) (xy 284.213015 -319.003471)
			(xy 284.164796 -318.993627) (xy 284.11878 -318.976175) (xy 284.076159 -318.951568) (xy 284.038038 -318.920443)
			(xy 284.005403 -318.883606) (xy 283.9791 -318.84201) (xy 283.959809 -318.796734) (xy 283.948032 -318.74895)
			(xy 283.944072 -318.699896) (xy 263.526839 -318.699896) (xy 263.600049 -318.756463) (xy 263.712586 -318.853497)
			(xy 263.819753 -318.956432) (xy 263.92124 -319.064971) (xy 264.016754 -319.1788) (xy 264.106021 -319.297593)
			(xy 264.188782 -319.421005) (xy 264.2648 -319.548683) (xy 264.333855 -319.680256) (xy 264.395748 -319.815347)
			(xy 264.450301 -319.953564) (xy 264.497356 -320.094511) (xy 264.536778 -320.237781) (xy 264.568452 -320.38296)
			(xy 264.592288 -320.529629) (xy 264.608217 -320.677367) (xy 264.616193 -320.825747) (xy 264.616692 -320.900044)
			(xy 319.082429 -320.900044) (xy 319.086418 -320.751504) (xy 319.098375 -320.603391) (xy 319.118265 -320.456134)
			(xy 319.14603 -320.310158) (xy 319.181591 -320.165881) (xy 319.224845 -320.023722) (xy 319.275667 -319.884089)
			(xy 319.333911 -319.747386) (xy 319.399409 -319.614006) (xy 319.471972 -319.484334) (xy 319.55139 -319.358744)
			(xy 319.637435 -319.237597) (xy 319.729859 -319.121244) (xy 319.828395 -319.01002) (xy 319.932759 -318.904245)
			(xy 320.042651 -318.804225) (xy 320.157752 -318.710247) (xy 320.277732 -318.622583) (xy 320.402245 -318.541486)
			(xy 320.530931 -318.467189) (xy 320.66342 -318.399907) (xy 320.799329 -318.339833) (xy 320.938267 -318.287141)
			(xy 321.079833 -318.241982) (xy 321.223619 -318.204487) (xy 321.36921 -318.174765) (xy 321.516186 -318.1529)
			(xy 321.664125 -318.138956) (xy 321.812598 -318.132972) (xy 321.961179 -318.134967) (xy 322.109438 -318.144935)
			(xy 322.256949 -318.162846) (xy 322.403285 -318.188649) (xy 322.548026 -318.222269) (xy 322.690753 -318.263611)
			(xy 322.831056 -318.312554) (xy 322.968529 -318.368957) (xy 323.102776 -318.432658) (xy 323.233411 -318.503474)
			(xy 323.360056 -318.581199) (xy 323.482346 -318.66561) (xy 323.599929 -318.756463) (xy 323.712466 -318.853497)
			(xy 323.819633 -318.956432) (xy 323.92112 -319.064971) (xy 324.016634 -319.1788) (xy 324.105901 -319.297593)
			(xy 324.188662 -319.421005) (xy 324.26468 -319.548683) (xy 324.333735 -319.680256) (xy 324.395628 -319.815347)
			(xy 324.450181 -319.953564) (xy 324.497236 -320.094511) (xy 324.536658 -320.237781) (xy 324.568332 -320.38296)
			(xy 324.592168 -320.529629) (xy 324.608097 -320.677367) (xy 324.616073 -320.825747) (xy 324.616572 -320.900044)
			(xy 375.182393 -320.900044) (xy 375.186382 -320.751504) (xy 375.198339 -320.603391) (xy 375.218229 -320.456134)
			(xy 375.245994 -320.310158) (xy 375.281555 -320.165881) (xy 375.324809 -320.023722) (xy 375.375631 -319.884089)
			(xy 375.433875 -319.747386) (xy 375.499373 -319.614006) (xy 375.571936 -319.484334) (xy 375.651354 -319.358744)
			(xy 375.737399 -319.237597) (xy 375.829823 -319.121244) (xy 375.928359 -319.01002) (xy 376.032723 -318.904245)
			(xy 376.142615 -318.804225) (xy 376.257716 -318.710247) (xy 376.377696 -318.622583) (xy 376.502209 -318.541486)
			(xy 376.630895 -318.467189) (xy 376.763384 -318.399907) (xy 376.899293 -318.339833) (xy 377.038231 -318.287141)
			(xy 377.179797 -318.241982) (xy 377.323583 -318.204487) (xy 377.469174 -318.174765) (xy 377.61615 -318.1529)
			(xy 377.764089 -318.138956) (xy 377.912562 -318.132972) (xy 378.061143 -318.134967) (xy 378.209402 -318.144935)
			(xy 378.356913 -318.162846) (xy 378.503249 -318.188649) (xy 378.64799 -318.222269) (xy 378.790717 -318.263611)
			(xy 378.93102 -318.312554) (xy 379.068493 -318.368957) (xy 379.20274 -318.432658) (xy 379.333375 -318.503474)
			(xy 379.46002 -318.581199) (xy 379.58231 -318.66561) (xy 379.626683 -318.699896) (xy 386.744222 -318.699896)
			(xy 386.748182 -318.650842) (xy 386.759959 -318.603058) (xy 386.77925 -318.557782) (xy 386.805553 -318.516186)
			(xy 386.838188 -318.479349) (xy 386.876309 -318.448224) (xy 386.91893 -318.423617) (xy 386.964946 -318.406165)
			(xy 387.013165 -318.396321) (xy 387.06234 -318.39434) (xy 387.111195 -318.400272) (xy 387.158466 -318.413964)
			(xy 387.202928 -318.435062) (xy 387.243431 -318.463018) (xy 387.278924 -318.49711) (xy 387.308489 -318.536454)
			(xy 387.33136 -318.580031) (xy 387.346944 -318.626712) (xy 387.354839 -318.675289) (xy 387.355334 -318.699896)
			(xy 388.644142 -318.699896) (xy 388.648102 -318.650842) (xy 388.659879 -318.603058) (xy 388.67917 -318.557782)
			(xy 388.705473 -318.516186) (xy 388.738108 -318.479349) (xy 388.776229 -318.448224) (xy 388.81885 -318.423617)
			(xy 388.864866 -318.406165) (xy 388.913085 -318.396321) (xy 388.96226 -318.39434) (xy 389.011115 -318.400272)
			(xy 389.058386 -318.413964) (xy 389.102848 -318.435062) (xy 389.143351 -318.463018) (xy 389.178844 -318.49711)
			(xy 389.208409 -318.536454) (xy 389.23128 -318.580031) (xy 389.246864 -318.626712) (xy 389.254759 -318.675289)
			(xy 389.255254 -318.699896) (xy 390.544062 -318.699896) (xy 390.548022 -318.650842) (xy 390.559799 -318.603058)
			(xy 390.57909 -318.557782) (xy 390.605393 -318.516186) (xy 390.638028 -318.479349) (xy 390.676149 -318.448224)
			(xy 390.71877 -318.423617) (xy 390.764786 -318.406165) (xy 390.813005 -318.396321) (xy 390.86218 -318.39434)
			(xy 390.911035 -318.400272) (xy 390.958306 -318.413964) (xy 391.002768 -318.435062) (xy 391.043271 -318.463018)
			(xy 391.078764 -318.49711) (xy 391.108329 -318.536454) (xy 391.1312 -318.580031) (xy 391.146784 -318.626712)
			(xy 391.154679 -318.675289) (xy 391.155174 -318.699896) (xy 392.443982 -318.699896) (xy 392.447942 -318.650842)
			(xy 392.459719 -318.603058) (xy 392.47901 -318.557782) (xy 392.505313 -318.516186) (xy 392.537948 -318.479349)
			(xy 392.576069 -318.448224) (xy 392.61869 -318.423617) (xy 392.664706 -318.406165) (xy 392.712925 -318.396321)
			(xy 392.7621 -318.39434) (xy 392.810955 -318.400272) (xy 392.858226 -318.413964) (xy 392.902688 -318.435062)
			(xy 392.943191 -318.463018) (xy 392.978684 -318.49711) (xy 393.008249 -318.536454) (xy 393.03112 -318.580031)
			(xy 393.046704 -318.626712) (xy 393.054599 -318.675289) (xy 393.055094 -318.699896) (xy 394.344156 -318.699896)
			(xy 394.348116 -318.650842) (xy 394.359893 -318.603058) (xy 394.379184 -318.557782) (xy 394.405487 -318.516186)
			(xy 394.438122 -318.479349) (xy 394.476243 -318.448224) (xy 394.518864 -318.423617) (xy 394.56488 -318.406165)
			(xy 394.613099 -318.396321) (xy 394.662274 -318.39434) (xy 394.711129 -318.400272) (xy 394.7584 -318.413964)
			(xy 394.802862 -318.435062) (xy 394.843365 -318.463018) (xy 394.878858 -318.49711) (xy 394.908423 -318.536454)
			(xy 394.931294 -318.580031) (xy 394.946878 -318.626712) (xy 394.954773 -318.675289) (xy 394.955268 -318.699896)
			(xy 396.244076 -318.699896) (xy 396.248036 -318.650842) (xy 396.259813 -318.603058) (xy 396.279104 -318.557782)
			(xy 396.305407 -318.516186) (xy 396.338042 -318.479349) (xy 396.376163 -318.448224) (xy 396.418784 -318.423617)
			(xy 396.4648 -318.406165) (xy 396.513019 -318.396321) (xy 396.562194 -318.39434) (xy 396.611049 -318.400272)
			(xy 396.65832 -318.413964) (xy 396.702782 -318.435062) (xy 396.743285 -318.463018) (xy 396.778778 -318.49711)
			(xy 396.808343 -318.536454) (xy 396.831214 -318.580031) (xy 396.846798 -318.626712) (xy 396.854693 -318.675289)
			(xy 396.855188 -318.699896) (xy 398.143996 -318.699896) (xy 398.147956 -318.650842) (xy 398.159733 -318.603058)
			(xy 398.179024 -318.557782) (xy 398.205327 -318.516186) (xy 398.237962 -318.479349) (xy 398.276083 -318.448224)
			(xy 398.318704 -318.423617) (xy 398.36472 -318.406165) (xy 398.412939 -318.396321) (xy 398.462114 -318.39434)
			(xy 398.510969 -318.400272) (xy 398.55824 -318.413964) (xy 398.602702 -318.435062) (xy 398.643205 -318.463018)
			(xy 398.678698 -318.49711) (xy 398.708263 -318.536454) (xy 398.731134 -318.580031) (xy 398.746718 -318.626712)
			(xy 398.754613 -318.675289) (xy 398.755108 -318.699896) (xy 415.244038 -318.699896) (xy 415.247998 -318.650842)
			(xy 415.259775 -318.603058) (xy 415.279066 -318.557782) (xy 415.305369 -318.516186) (xy 415.338004 -318.479349)
			(xy 415.376125 -318.448224) (xy 415.418746 -318.423617) (xy 415.464762 -318.406165) (xy 415.512981 -318.396321)
			(xy 415.562156 -318.39434) (xy 415.611011 -318.400272) (xy 415.658282 -318.413964) (xy 415.702744 -318.435062)
			(xy 415.743247 -318.463018) (xy 415.77874 -318.49711) (xy 415.808305 -318.536454) (xy 415.831176 -318.580031)
			(xy 415.84676 -318.626712) (xy 415.854655 -318.675289) (xy 415.85515 -318.699896) (xy 417.144212 -318.699896)
			(xy 417.148172 -318.650842) (xy 417.159949 -318.603058) (xy 417.17924 -318.557782) (xy 417.205543 -318.516186)
			(xy 417.238178 -318.479349) (xy 417.276299 -318.448224) (xy 417.31892 -318.423617) (xy 417.364936 -318.406165)
			(xy 417.413155 -318.396321) (xy 417.46233 -318.39434) (xy 417.511185 -318.400272) (xy 417.558456 -318.413964)
			(xy 417.602918 -318.435062) (xy 417.643421 -318.463018) (xy 417.678914 -318.49711) (xy 417.708479 -318.536454)
			(xy 417.73135 -318.580031) (xy 417.746934 -318.626712) (xy 417.754829 -318.675289) (xy 417.755324 -318.699896)
			(xy 419.044132 -318.699896) (xy 419.048092 -318.650842) (xy 419.059869 -318.603058) (xy 419.07916 -318.557782)
			(xy 419.105463 -318.516186) (xy 419.138098 -318.479349) (xy 419.176219 -318.448224) (xy 419.21884 -318.423617)
			(xy 419.264856 -318.406165) (xy 419.313075 -318.396321) (xy 419.36225 -318.39434) (xy 419.411105 -318.400272)
			(xy 419.458376 -318.413964) (xy 419.502838 -318.435062) (xy 419.543341 -318.463018) (xy 419.578834 -318.49711)
			(xy 419.608399 -318.536454) (xy 419.63127 -318.580031) (xy 419.646854 -318.626712) (xy 419.654749 -318.675289)
			(xy 419.655244 -318.699896) (xy 420.944052 -318.699896) (xy 420.948012 -318.650842) (xy 420.959789 -318.603058)
			(xy 420.97908 -318.557782) (xy 421.005383 -318.516186) (xy 421.038018 -318.479349) (xy 421.076139 -318.448224)
			(xy 421.11876 -318.423617) (xy 421.164776 -318.406165) (xy 421.212995 -318.396321) (xy 421.26217 -318.39434)
			(xy 421.311025 -318.400272) (xy 421.358296 -318.413964) (xy 421.402758 -318.435062) (xy 421.443261 -318.463018)
			(xy 421.478754 -318.49711) (xy 421.508319 -318.536454) (xy 421.53119 -318.580031) (xy 421.546774 -318.626712)
			(xy 421.554669 -318.675289) (xy 421.555164 -318.699896) (xy 421.554669 -318.724503) (xy 421.546774 -318.77308)
			(xy 421.53119 -318.819761) (xy 421.508319 -318.863338) (xy 421.478754 -318.902682) (xy 421.443261 -318.936774)
			(xy 421.402758 -318.96473) (xy 421.358296 -318.985828) (xy 421.311025 -318.99952) (xy 421.26217 -319.005452)
			(xy 421.212995 -319.003471) (xy 421.164776 -318.993627) (xy 421.11876 -318.976175) (xy 421.076139 -318.951568)
			(xy 421.038018 -318.920443) (xy 421.005383 -318.883606) (xy 420.97908 -318.84201) (xy 420.959789 -318.796734)
			(xy 420.948012 -318.74895) (xy 420.944052 -318.699896) (xy 419.655244 -318.699896) (xy 419.654749 -318.724503)
			(xy 419.646854 -318.77308) (xy 419.63127 -318.819761) (xy 419.608399 -318.863338) (xy 419.578834 -318.902682)
			(xy 419.543341 -318.936774) (xy 419.502838 -318.96473) (xy 419.458376 -318.985828) (xy 419.411105 -318.99952)
			(xy 419.36225 -319.005452) (xy 419.313075 -319.003471) (xy 419.264856 -318.993627) (xy 419.21884 -318.976175)
			(xy 419.176219 -318.951568) (xy 419.138098 -318.920443) (xy 419.105463 -318.883606) (xy 419.07916 -318.84201)
			(xy 419.059869 -318.796734) (xy 419.048092 -318.74895) (xy 419.044132 -318.699896) (xy 417.755324 -318.699896)
			(xy 417.754829 -318.724503) (xy 417.746934 -318.77308) (xy 417.73135 -318.819761) (xy 417.708479 -318.863338)
			(xy 417.678914 -318.902682) (xy 417.643421 -318.936774) (xy 417.602918 -318.96473) (xy 417.558456 -318.985828)
			(xy 417.511185 -318.99952) (xy 417.46233 -319.005452) (xy 417.413155 -319.003471) (xy 417.364936 -318.993627)
			(xy 417.31892 -318.976175) (xy 417.276299 -318.951568) (xy 417.238178 -318.920443) (xy 417.205543 -318.883606)
			(xy 417.17924 -318.84201) (xy 417.159949 -318.796734) (xy 417.148172 -318.74895) (xy 417.144212 -318.699896)
			(xy 415.85515 -318.699896) (xy 415.854655 -318.724503) (xy 415.84676 -318.77308) (xy 415.831176 -318.819761)
			(xy 415.808305 -318.863338) (xy 415.77874 -318.902682) (xy 415.743247 -318.936774) (xy 415.702744 -318.96473)
			(xy 415.658282 -318.985828) (xy 415.611011 -318.99952) (xy 415.562156 -319.005452) (xy 415.512981 -319.003471)
			(xy 415.464762 -318.993627) (xy 415.418746 -318.976175) (xy 415.376125 -318.951568) (xy 415.338004 -318.920443)
			(xy 415.305369 -318.883606) (xy 415.279066 -318.84201) (xy 415.259775 -318.796734) (xy 415.247998 -318.74895)
			(xy 415.244038 -318.699896) (xy 398.755108 -318.699896) (xy 398.754613 -318.724503) (xy 398.746718 -318.77308)
			(xy 398.731134 -318.819761) (xy 398.708263 -318.863338) (xy 398.678698 -318.902682) (xy 398.643205 -318.936774)
			(xy 398.602702 -318.96473) (xy 398.55824 -318.985828) (xy 398.510969 -318.99952) (xy 398.462114 -319.005452)
			(xy 398.412939 -319.003471) (xy 398.36472 -318.993627) (xy 398.318704 -318.976175) (xy 398.276083 -318.951568)
			(xy 398.237962 -318.920443) (xy 398.205327 -318.883606) (xy 398.179024 -318.84201) (xy 398.159733 -318.796734)
			(xy 398.147956 -318.74895) (xy 398.143996 -318.699896) (xy 396.855188 -318.699896) (xy 396.854693 -318.724503)
			(xy 396.846798 -318.77308) (xy 396.831214 -318.819761) (xy 396.808343 -318.863338) (xy 396.778778 -318.902682)
			(xy 396.743285 -318.936774) (xy 396.702782 -318.96473) (xy 396.65832 -318.985828) (xy 396.611049 -318.99952)
			(xy 396.562194 -319.005452) (xy 396.513019 -319.003471) (xy 396.4648 -318.993627) (xy 396.418784 -318.976175)
			(xy 396.376163 -318.951568) (xy 396.338042 -318.920443) (xy 396.305407 -318.883606) (xy 396.279104 -318.84201)
			(xy 396.259813 -318.796734) (xy 396.248036 -318.74895) (xy 396.244076 -318.699896) (xy 394.955268 -318.699896)
			(xy 394.954773 -318.724503) (xy 394.946878 -318.77308) (xy 394.931294 -318.819761) (xy 394.908423 -318.863338)
			(xy 394.878858 -318.902682) (xy 394.843365 -318.936774) (xy 394.802862 -318.96473) (xy 394.7584 -318.985828)
			(xy 394.711129 -318.99952) (xy 394.662274 -319.005452) (xy 394.613099 -319.003471) (xy 394.56488 -318.993627)
			(xy 394.518864 -318.976175) (xy 394.476243 -318.951568) (xy 394.438122 -318.920443) (xy 394.405487 -318.883606)
			(xy 394.379184 -318.84201) (xy 394.359893 -318.796734) (xy 394.348116 -318.74895) (xy 394.344156 -318.699896)
			(xy 393.055094 -318.699896) (xy 393.054599 -318.724503) (xy 393.046704 -318.77308) (xy 393.03112 -318.819761)
			(xy 393.008249 -318.863338) (xy 392.978684 -318.902682) (xy 392.943191 -318.936774) (xy 392.902688 -318.96473)
			(xy 392.858226 -318.985828) (xy 392.810955 -318.99952) (xy 392.7621 -319.005452) (xy 392.712925 -319.003471)
			(xy 392.664706 -318.993627) (xy 392.61869 -318.976175) (xy 392.576069 -318.951568) (xy 392.537948 -318.920443)
			(xy 392.505313 -318.883606) (xy 392.47901 -318.84201) (xy 392.459719 -318.796734) (xy 392.447942 -318.74895)
			(xy 392.443982 -318.699896) (xy 391.155174 -318.699896) (xy 391.154679 -318.724503) (xy 391.146784 -318.77308)
			(xy 391.1312 -318.819761) (xy 391.108329 -318.863338) (xy 391.078764 -318.902682) (xy 391.043271 -318.936774)
			(xy 391.002768 -318.96473) (xy 390.958306 -318.985828) (xy 390.911035 -318.99952) (xy 390.86218 -319.005452)
			(xy 390.813005 -319.003471) (xy 390.764786 -318.993627) (xy 390.71877 -318.976175) (xy 390.676149 -318.951568)
			(xy 390.638028 -318.920443) (xy 390.605393 -318.883606) (xy 390.57909 -318.84201) (xy 390.559799 -318.796734)
			(xy 390.548022 -318.74895) (xy 390.544062 -318.699896) (xy 389.255254 -318.699896) (xy 389.254759 -318.724503)
			(xy 389.246864 -318.77308) (xy 389.23128 -318.819761) (xy 389.208409 -318.863338) (xy 389.178844 -318.902682)
			(xy 389.143351 -318.936774) (xy 389.102848 -318.96473) (xy 389.058386 -318.985828) (xy 389.011115 -318.99952)
			(xy 388.96226 -319.005452) (xy 388.913085 -319.003471) (xy 388.864866 -318.993627) (xy 388.81885 -318.976175)
			(xy 388.776229 -318.951568) (xy 388.738108 -318.920443) (xy 388.705473 -318.883606) (xy 388.67917 -318.84201)
			(xy 388.659879 -318.796734) (xy 388.648102 -318.74895) (xy 388.644142 -318.699896) (xy 387.355334 -318.699896)
			(xy 387.354839 -318.724503) (xy 387.346944 -318.77308) (xy 387.33136 -318.819761) (xy 387.308489 -318.863338)
			(xy 387.278924 -318.902682) (xy 387.243431 -318.936774) (xy 387.202928 -318.96473) (xy 387.158466 -318.985828)
			(xy 387.111195 -318.99952) (xy 387.06234 -319.005452) (xy 387.013165 -319.003471) (xy 386.964946 -318.993627)
			(xy 386.91893 -318.976175) (xy 386.876309 -318.951568) (xy 386.838188 -318.920443) (xy 386.805553 -318.883606)
			(xy 386.77925 -318.84201) (xy 386.759959 -318.796734) (xy 386.748182 -318.74895) (xy 386.744222 -318.699896)
			(xy 379.626683 -318.699896) (xy 379.699893 -318.756463) (xy 379.81243 -318.853497) (xy 379.919597 -318.956432)
			(xy 380.021084 -319.064971) (xy 380.116598 -319.1788) (xy 380.205865 -319.297593) (xy 380.288626 -319.421005)
			(xy 380.364644 -319.548683) (xy 380.433699 -319.680256) (xy 380.495592 -319.815347) (xy 380.550145 -319.953564)
			(xy 380.5972 -320.094511) (xy 380.636622 -320.237781) (xy 380.668296 -320.38296) (xy 380.692132 -320.529629)
			(xy 380.708061 -320.677367) (xy 380.716037 -320.825747) (xy 380.716536 -320.900044) (xy 435.182527 -320.900044)
			(xy 435.186516 -320.751504) (xy 435.198473 -320.603391) (xy 435.218363 -320.456134) (xy 435.246128 -320.310158)
			(xy 435.281689 -320.165881) (xy 435.324943 -320.023722) (xy 435.375765 -319.884089) (xy 435.434009 -319.747386)
			(xy 435.499507 -319.614006) (xy 435.57207 -319.484334) (xy 435.651488 -319.358744) (xy 435.737533 -319.237597)
			(xy 435.829957 -319.121244) (xy 435.928493 -319.01002) (xy 436.032857 -318.904245) (xy 436.142749 -318.804225)
			(xy 436.25785 -318.710247) (xy 436.37783 -318.622583) (xy 436.502343 -318.541486) (xy 436.631029 -318.467189)
			(xy 436.763518 -318.399907) (xy 436.899427 -318.339833) (xy 437.038365 -318.287141) (xy 437.179931 -318.241982)
			(xy 437.323717 -318.204487) (xy 437.469308 -318.174765) (xy 437.616284 -318.1529) (xy 437.764223 -318.138956)
			(xy 437.912696 -318.132972) (xy 438.061277 -318.134967) (xy 438.209536 -318.144935) (xy 438.357047 -318.162846)
			(xy 438.503383 -318.188649) (xy 438.648124 -318.222269) (xy 438.790851 -318.263611) (xy 438.931154 -318.312554)
			(xy 439.068627 -318.368957) (xy 439.202874 -318.432658) (xy 439.333509 -318.503474) (xy 439.460154 -318.581199)
			(xy 439.582444 -318.66561) (xy 439.700027 -318.756463) (xy 439.812564 -318.853497) (xy 439.919731 -318.956432)
			(xy 440.021218 -319.064971) (xy 440.116732 -319.1788) (xy 440.205999 -319.297593) (xy 440.28876 -319.421005)
			(xy 440.364778 -319.548683) (xy 440.433833 -319.680256) (xy 440.495726 -319.815347) (xy 440.550279 -319.953564)
			(xy 440.597334 -320.094511) (xy 440.636756 -320.237781) (xy 440.66843 -320.38296) (xy 440.692266 -320.529629)
			(xy 440.708195 -320.677367) (xy 440.716171 -320.825747) (xy 440.71667 -320.900044) (xy 440.716171 -320.974341)
			(xy 440.708195 -321.122721) (xy 440.692266 -321.270459) (xy 440.66843 -321.417128) (xy 440.636756 -321.562307)
			(xy 440.597334 -321.705577) (xy 440.550279 -321.846524) (xy 440.495726 -321.984741) (xy 440.433833 -322.119832)
			(xy 440.364778 -322.251405) (xy 440.28876 -322.379083) (xy 440.205999 -322.502495) (xy 440.116732 -322.621288)
			(xy 440.021218 -322.735117) (xy 439.919731 -322.843656) (xy 439.812564 -322.946591) (xy 439.700027 -323.043625)
			(xy 439.582444 -323.134478) (xy 439.460154 -323.218889) (xy 439.333509 -323.296614) (xy 439.202874 -323.36743)
			(xy 439.068627 -323.431131) (xy 438.931154 -323.487534) (xy 438.790851 -323.536477) (xy 438.648124 -323.577819)
			(xy 438.503383 -323.611439) (xy 438.357047 -323.637242) (xy 438.209536 -323.655153) (xy 438.061277 -323.665121)
			(xy 437.912696 -323.667116) (xy 437.764223 -323.661132) (xy 437.616284 -323.647188) (xy 437.469308 -323.625323)
			(xy 437.323717 -323.595601) (xy 437.179931 -323.558106) (xy 437.038365 -323.512947) (xy 436.899427 -323.460255)
			(xy 436.763518 -323.400181) (xy 436.631029 -323.332899) (xy 436.502343 -323.258602) (xy 436.37783 -323.177505)
			(xy 436.25785 -323.089841) (xy 436.142749 -322.995863) (xy 436.032857 -322.895843) (xy 435.928493 -322.790068)
			(xy 435.829957 -322.678844) (xy 435.737533 -322.562491) (xy 435.651488 -322.441344) (xy 435.57207 -322.315754)
			(xy 435.499507 -322.186082) (xy 435.434009 -322.052702) (xy 435.375765 -321.915999) (xy 435.324943 -321.776366)
			(xy 435.281689 -321.634207) (xy 435.246128 -321.48993) (xy 435.218363 -321.343954) (xy 435.198473 -321.196697)
			(xy 435.186516 -321.048584) (xy 435.182527 -320.900044) (xy 380.716536 -320.900044) (xy 380.716037 -320.974341)
			(xy 380.708061 -321.122721) (xy 380.692132 -321.270459) (xy 380.668296 -321.417128) (xy 380.636622 -321.562307)
			(xy 380.5972 -321.705577) (xy 380.550145 -321.846524) (xy 380.495592 -321.984741) (xy 380.433699 -322.119832)
			(xy 380.364644 -322.251405) (xy 380.288626 -322.379083) (xy 380.205865 -322.502495) (xy 380.116598 -322.621288)
			(xy 380.021084 -322.735117) (xy 379.919597 -322.843656) (xy 379.81243 -322.946591) (xy 379.699893 -323.043625)
			(xy 379.58231 -323.134478) (xy 379.46002 -323.218889) (xy 379.333375 -323.296614) (xy 379.20274 -323.36743)
			(xy 379.068493 -323.431131) (xy 378.93102 -323.487534) (xy 378.790717 -323.536477) (xy 378.64799 -323.577819)
			(xy 378.503249 -323.611439) (xy 378.356913 -323.637242) (xy 378.209402 -323.655153) (xy 378.061143 -323.665121)
			(xy 377.912562 -323.667116) (xy 377.764089 -323.661132) (xy 377.61615 -323.647188) (xy 377.469174 -323.625323)
			(xy 377.323583 -323.595601) (xy 377.179797 -323.558106) (xy 377.038231 -323.512947) (xy 376.899293 -323.460255)
			(xy 376.763384 -323.400181) (xy 376.630895 -323.332899) (xy 376.502209 -323.258602) (xy 376.377696 -323.177505)
			(xy 376.257716 -323.089841) (xy 376.142615 -322.995863) (xy 376.032723 -322.895843) (xy 375.928359 -322.790068)
			(xy 375.829823 -322.678844) (xy 375.737399 -322.562491) (xy 375.651354 -322.441344) (xy 375.571936 -322.315754)
			(xy 375.499373 -322.186082) (xy 375.433875 -322.052702) (xy 375.375631 -321.915999) (xy 375.324809 -321.776366)
			(xy 375.281555 -321.634207) (xy 375.245994 -321.48993) (xy 375.218229 -321.343954) (xy 375.198339 -321.196697)
			(xy 375.186382 -321.048584) (xy 375.182393 -320.900044) (xy 324.616572 -320.900044) (xy 324.616073 -320.974341)
			(xy 324.608097 -321.122721) (xy 324.592168 -321.270459) (xy 324.568332 -321.417128) (xy 324.536658 -321.562307)
			(xy 324.497236 -321.705577) (xy 324.450181 -321.846524) (xy 324.395628 -321.984741) (xy 324.333735 -322.119832)
			(xy 324.26468 -322.251405) (xy 324.188662 -322.379083) (xy 324.105901 -322.502495) (xy 324.016634 -322.621288)
			(xy 323.92112 -322.735117) (xy 323.819633 -322.843656) (xy 323.712466 -322.946591) (xy 323.599929 -323.043625)
			(xy 323.482346 -323.134478) (xy 323.360056 -323.218889) (xy 323.233411 -323.296614) (xy 323.102776 -323.36743)
			(xy 322.968529 -323.431131) (xy 322.831056 -323.487534) (xy 322.690753 -323.536477) (xy 322.548026 -323.577819)
			(xy 322.403285 -323.611439) (xy 322.256949 -323.637242) (xy 322.109438 -323.655153) (xy 321.961179 -323.665121)
			(xy 321.812598 -323.667116) (xy 321.664125 -323.661132) (xy 321.516186 -323.647188) (xy 321.36921 -323.625323)
			(xy 321.223619 -323.595601) (xy 321.079833 -323.558106) (xy 320.938267 -323.512947) (xy 320.799329 -323.460255)
			(xy 320.66342 -323.400181) (xy 320.530931 -323.332899) (xy 320.402245 -323.258602) (xy 320.277732 -323.177505)
			(xy 320.157752 -323.089841) (xy 320.042651 -322.995863) (xy 319.932759 -322.895843) (xy 319.828395 -322.790068)
			(xy 319.729859 -322.678844) (xy 319.637435 -322.562491) (xy 319.55139 -322.441344) (xy 319.471972 -322.315754)
			(xy 319.399409 -322.186082) (xy 319.333911 -322.052702) (xy 319.275667 -321.915999) (xy 319.224845 -321.776366)
			(xy 319.181591 -321.634207) (xy 319.14603 -321.48993) (xy 319.118265 -321.343954) (xy 319.098375 -321.196697)
			(xy 319.086418 -321.048584) (xy 319.082429 -320.900044) (xy 264.616692 -320.900044) (xy 264.616193 -320.974341)
			(xy 264.608217 -321.122721) (xy 264.592288 -321.270459) (xy 264.568452 -321.417128) (xy 264.536778 -321.562307)
			(xy 264.497356 -321.705577) (xy 264.450301 -321.846524) (xy 264.395748 -321.984741) (xy 264.333855 -322.119832)
			(xy 264.2648 -322.251405) (xy 264.188782 -322.379083) (xy 264.106021 -322.502495) (xy 264.016754 -322.621288)
			(xy 263.92124 -322.735117) (xy 263.819753 -322.843656) (xy 263.712586 -322.946591) (xy 263.600049 -323.043625)
			(xy 263.482466 -323.134478) (xy 263.360176 -323.218889) (xy 263.233531 -323.296614) (xy 263.102896 -323.36743)
			(xy 262.968649 -323.431131) (xy 262.831176 -323.487534) (xy 262.690873 -323.536477) (xy 262.548146 -323.577819)
			(xy 262.403405 -323.611439) (xy 262.257069 -323.637242) (xy 262.109558 -323.655153) (xy 261.961299 -323.665121)
			(xy 261.812718 -323.667116) (xy 261.664245 -323.661132) (xy 261.516306 -323.647188) (xy 261.36933 -323.625323)
			(xy 261.223739 -323.595601) (xy 261.079953 -323.558106) (xy 260.938387 -323.512947) (xy 260.799449 -323.460255)
			(xy 260.66354 -323.400181) (xy 260.531051 -323.332899) (xy 260.402365 -323.258602) (xy 260.277852 -323.177505)
			(xy 260.157872 -323.089841) (xy 260.042771 -322.995863) (xy 259.932879 -322.895843) (xy 259.828515 -322.790068)
			(xy 259.729979 -322.678844) (xy 259.637555 -322.562491) (xy 259.55151 -322.441344) (xy 259.472092 -322.315754)
			(xy 259.399529 -322.186082) (xy 259.334031 -322.052702) (xy 259.275787 -321.915999) (xy 259.224965 -321.776366)
			(xy 259.181711 -321.634207) (xy 259.14615 -321.48993) (xy 259.118385 -321.343954) (xy 259.098495 -321.196697)
			(xy 259.086538 -321.048584) (xy 259.082549 -320.900044) (xy 208.516474 -320.900044) (xy 208.515975 -320.974341)
			(xy 208.507999 -321.122721) (xy 208.49207 -321.270459) (xy 208.468234 -321.417128) (xy 208.43656 -321.562307)
			(xy 208.397138 -321.705577) (xy 208.350083 -321.846524) (xy 208.29553 -321.984741) (xy 208.233637 -322.119832)
			(xy 208.164582 -322.251405) (xy 208.088564 -322.379083) (xy 208.005803 -322.502495) (xy 207.916536 -322.621288)
			(xy 207.821022 -322.735117) (xy 207.719535 -322.843656) (xy 207.612368 -322.946591) (xy 207.499831 -323.043625)
			(xy 207.382248 -323.134478) (xy 207.259958 -323.218889) (xy 207.133313 -323.296614) (xy 207.002678 -323.36743)
			(xy 206.868431 -323.431131) (xy 206.730958 -323.487534) (xy 206.590655 -323.536477) (xy 206.447928 -323.577819)
			(xy 206.303187 -323.611439) (xy 206.156851 -323.637242) (xy 206.00934 -323.655153) (xy 205.861081 -323.665121)
			(xy 205.7125 -323.667116) (xy 205.564027 -323.661132) (xy 205.416088 -323.647188) (xy 205.269112 -323.625323)
			(xy 205.123521 -323.595601) (xy 204.979735 -323.558106) (xy 204.838169 -323.512947) (xy 204.699231 -323.460255)
			(xy 204.563322 -323.400181) (xy 204.430833 -323.332899) (xy 204.302147 -323.258602) (xy 204.177634 -323.177505)
			(xy 204.057654 -323.089841) (xy 203.942553 -322.995863) (xy 203.832661 -322.895843) (xy 203.728297 -322.790068)
			(xy 203.629761 -322.678844) (xy 203.537337 -322.562491) (xy 203.451292 -322.441344) (xy 203.371874 -322.315754)
			(xy 203.299311 -322.186082) (xy 203.233813 -322.052702) (xy 203.175569 -321.915999) (xy 203.124747 -321.776366)
			(xy 203.081493 -321.634207) (xy 203.045932 -321.48993) (xy 203.018167 -321.343954) (xy 202.998277 -321.196697)
			(xy 202.98632 -321.048584) (xy 202.982331 -320.900044) (xy 148.516594 -320.900044) (xy 148.516095 -320.974341)
			(xy 148.508119 -321.122721) (xy 148.49219 -321.270459) (xy 148.468354 -321.417128) (xy 148.43668 -321.562307)
			(xy 148.397258 -321.705577) (xy 148.350203 -321.846524) (xy 148.29565 -321.984741) (xy 148.233757 -322.119832)
			(xy 148.164702 -322.251405) (xy 148.088684 -322.379083) (xy 148.005923 -322.502495) (xy 147.916656 -322.621288)
			(xy 147.821142 -322.735117) (xy 147.719655 -322.843656) (xy 147.612488 -322.946591) (xy 147.499951 -323.043625)
			(xy 147.382368 -323.134478) (xy 147.260078 -323.218889) (xy 147.133433 -323.296614) (xy 147.002798 -323.36743)
			(xy 146.868551 -323.431131) (xy 146.731078 -323.487534) (xy 146.590775 -323.536477) (xy 146.448048 -323.577819)
			(xy 146.303307 -323.611439) (xy 146.156971 -323.637242) (xy 146.00946 -323.655153) (xy 145.861201 -323.665121)
			(xy 145.71262 -323.667116) (xy 145.564147 -323.661132) (xy 145.416208 -323.647188) (xy 145.269232 -323.625323)
			(xy 145.123641 -323.595601) (xy 144.979855 -323.558106) (xy 144.838289 -323.512947) (xy 144.699351 -323.460255)
			(xy 144.563442 -323.400181) (xy 144.430953 -323.332899) (xy 144.302267 -323.258602) (xy 144.177754 -323.177505)
			(xy 144.057774 -323.089841) (xy 143.942673 -322.995863) (xy 143.832781 -322.895843) (xy 143.728417 -322.790068)
			(xy 143.629881 -322.678844) (xy 143.537457 -322.562491) (xy 143.451412 -322.441344) (xy 143.371994 -322.315754)
			(xy 143.299431 -322.186082) (xy 143.233933 -322.052702) (xy 143.175689 -321.915999) (xy 143.124867 -321.776366)
			(xy 143.081613 -321.634207) (xy 143.046052 -321.48993) (xy 143.018287 -321.343954) (xy 142.998397 -321.196697)
			(xy 142.98644 -321.048584) (xy 142.982451 -320.900044) (xy 92.41663 -320.900044) (xy 92.416131 -320.974341)
			(xy 92.408155 -321.122721) (xy 92.392226 -321.270459) (xy 92.36839 -321.417128) (xy 92.336716 -321.562307)
			(xy 92.297294 -321.705577) (xy 92.250239 -321.846524) (xy 92.195686 -321.984741) (xy 92.133793 -322.119832)
			(xy 92.064738 -322.251405) (xy 91.98872 -322.379083) (xy 91.905959 -322.502495) (xy 91.816692 -322.621288)
			(xy 91.721178 -322.735117) (xy 91.619691 -322.843656) (xy 91.512524 -322.946591) (xy 91.399987 -323.043625)
			(xy 91.282404 -323.134478) (xy 91.160114 -323.218889) (xy 91.033469 -323.296614) (xy 90.902834 -323.36743)
			(xy 90.768587 -323.431131) (xy 90.631114 -323.487534) (xy 90.490811 -323.536477) (xy 90.348084 -323.577819)
			(xy 90.203343 -323.611439) (xy 90.057007 -323.637242) (xy 89.909496 -323.655153) (xy 89.761237 -323.665121)
			(xy 89.612656 -323.667116) (xy 89.464183 -323.661132) (xy 89.316244 -323.647188) (xy 89.169268 -323.625323)
			(xy 89.023677 -323.595601) (xy 88.879891 -323.558106) (xy 88.738325 -323.512947) (xy 88.599387 -323.460255)
			(xy 88.463478 -323.400181) (xy 88.330989 -323.332899) (xy 88.202303 -323.258602) (xy 88.07779 -323.177505)
			(xy 87.95781 -323.089841) (xy 87.842709 -322.995863) (xy 87.732817 -322.895843) (xy 87.628453 -322.790068)
			(xy 87.529917 -322.678844) (xy 87.437493 -322.562491) (xy 87.351448 -322.441344) (xy 87.27203 -322.315754)
			(xy 87.199467 -322.186082) (xy 87.133969 -322.052702) (xy 87.075725 -321.915999) (xy 87.024903 -321.776366)
			(xy 86.981649 -321.634207) (xy 86.946088 -321.48993) (xy 86.918323 -321.343954) (xy 86.898433 -321.196697)
			(xy 86.886476 -321.048584) (xy 86.882487 -320.900044) (xy 32.416496 -320.900044) (xy 32.415997 -320.974341)
			(xy 32.408021 -321.122721) (xy 32.392092 -321.270459) (xy 32.368256 -321.417128) (xy 32.336582 -321.562307)
			(xy 32.29716 -321.705577) (xy 32.250105 -321.846524) (xy 32.195552 -321.984741) (xy 32.133659 -322.119832)
			(xy 32.064604 -322.251405) (xy 31.988586 -322.379083) (xy 31.905825 -322.502495) (xy 31.816558 -322.621288)
			(xy 31.721044 -322.735117) (xy 31.619557 -322.843656) (xy 31.51239 -322.946591) (xy 31.399853 -323.043625)
			(xy 31.28227 -323.134478) (xy 31.15998 -323.218889) (xy 31.033335 -323.296614) (xy 30.9027 -323.36743)
			(xy 30.768453 -323.431131) (xy 30.63098 -323.487534) (xy 30.490677 -323.536477) (xy 30.34795 -323.577819)
			(xy 30.203209 -323.611439) (xy 30.056873 -323.637242) (xy 29.909362 -323.655153) (xy 29.761103 -323.665121)
			(xy 29.612522 -323.667116) (xy 29.464049 -323.661132) (xy 29.31611 -323.647188) (xy 29.169134 -323.625323)
			(xy 29.023543 -323.595601) (xy 28.879757 -323.558106) (xy 28.738191 -323.512947) (xy 28.599253 -323.460255)
			(xy 28.463344 -323.400181) (xy 28.330855 -323.332899) (xy 28.202169 -323.258602) (xy 28.077656 -323.177505)
			(xy 27.957676 -323.089841) (xy 27.842575 -322.995863) (xy 27.732683 -322.895843) (xy 27.628319 -322.790068)
			(xy 27.529783 -322.678844) (xy 27.437359 -322.562491) (xy 27.351314 -322.441344) (xy 27.271896 -322.315754)
			(xy 27.199333 -322.186082) (xy 27.133835 -322.052702) (xy 27.075591 -321.915999) (xy 27.024769 -321.776366)
			(xy 26.981515 -321.634207) (xy 26.945954 -321.48993) (xy 26.918189 -321.343954) (xy 26.898299 -321.196697)
			(xy 26.886342 -321.048584) (xy 26.882353 -320.900044) (xy 0.508 -320.900044) (xy 0.508 -330.416662)
			(xy 97.355152 -330.416662) (xy 97.355152 -329.553062) (xy 97.355642 -329.523078) (xy 97.36347 -329.463622)
			(xy 97.378991 -329.405697) (xy 97.40194 -329.350293) (xy 97.431924 -329.298359) (xy 97.46843 -329.250783)
			(xy 97.510835 -329.208378) (xy 97.558411 -329.171872) (xy 97.610345 -329.141888) (xy 97.665749 -329.118939)
			(xy 97.723674 -329.103418) (xy 97.78313 -329.09559) (xy 97.843098 -329.09559) (xy 97.902554 -329.103418)
			(xy 97.960479 -329.118939) (xy 98.015883 -329.141888) (xy 98.067817 -329.171872) (xy 98.115393 -329.208378)
			(xy 98.157798 -329.250783) (xy 98.194304 -329.298359) (xy 98.224288 -329.350293) (xy 98.247237 -329.405697)
			(xy 98.262758 -329.463622) (xy 98.270586 -329.523078) (xy 98.271076 -329.553062) (xy 98.271076 -330.416662)
			(xy 98.270586 -330.446646) (xy 98.262758 -330.506102) (xy 98.247237 -330.564027) (xy 98.224288 -330.619431)
			(xy 98.194304 -330.671365) (xy 98.157798 -330.718941) (xy 98.115393 -330.761346) (xy 98.067817 -330.797852)
			(xy 98.015883 -330.827836) (xy 97.960479 -330.850785) (xy 97.902554 -330.866306) (xy 97.843098 -330.874134)
			(xy 97.78313 -330.874134) (xy 97.723674 -330.866306) (xy 97.665749 -330.850785) (xy 97.610345 -330.827836)
			(xy 97.558411 -330.797852) (xy 97.510835 -330.761346) (xy 97.46843 -330.718941) (xy 97.431924 -330.671365)
			(xy 97.40194 -330.619431) (xy 97.378991 -330.564027) (xy 97.36347 -330.506102) (xy 97.355642 -330.446646)
			(xy 97.355152 -330.416662) (xy 0.508 -330.416662) (xy 0.508 -331.53223) (xy 114.955828 -331.53223)
			(xy 114.955828 -330.66863) (xy 114.956318 -330.638646) (xy 114.964146 -330.57919) (xy 114.979667 -330.521265)
			(xy 115.002616 -330.465861) (xy 115.0326 -330.413927) (xy 115.069106 -330.366351) (xy 115.111511 -330.323946)
			(xy 115.159087 -330.28744) (xy 115.211021 -330.257456) (xy 115.266425 -330.234507) (xy 115.32435 -330.218986)
			(xy 115.383806 -330.211158) (xy 115.443774 -330.211158) (xy 115.50323 -330.218986) (xy 115.561155 -330.234507)
			(xy 115.616559 -330.257456) (xy 115.668493 -330.28744) (xy 115.716069 -330.323946) (xy 115.758474 -330.366351)
			(xy 115.79498 -330.413927) (xy 115.824964 -330.465861) (xy 115.847913 -330.521265) (xy 115.863434 -330.57919)
			(xy 115.871262 -330.638646) (xy 115.871752 -330.66863) (xy 115.871752 -331.53223) (xy 115.871262 -331.562214)
			(xy 115.863434 -331.62167) (xy 115.847913 -331.679595) (xy 115.824964 -331.734999) (xy 115.79498 -331.786933)
			(xy 115.758474 -331.834509) (xy 115.716069 -331.876914) (xy 115.668493 -331.91342) (xy 115.616559 -331.943404)
			(xy 115.561155 -331.966353) (xy 115.50323 -331.981874) (xy 115.443774 -331.989702) (xy 115.383806 -331.989702)
			(xy 115.32435 -331.981874) (xy 115.266425 -331.966353) (xy 115.211021 -331.943404) (xy 115.159087 -331.91342)
			(xy 115.111511 -331.876914) (xy 115.069106 -331.834509) (xy 115.0326 -331.786933) (xy 115.002616 -331.734999)
			(xy 114.979667 -331.679595) (xy 114.964146 -331.62167) (xy 114.956318 -331.562214) (xy 114.955828 -331.53223)
			(xy 0.508 -331.53223) (xy 0.508 -333.950056) (xy 93.5736 -333.950056) (xy 93.5736 -333.086456) (xy 93.57409 -333.056488)
			(xy 93.581913 -332.997066) (xy 93.597426 -332.939173) (xy 93.620362 -332.8838) (xy 93.650329 -332.831894)
			(xy 93.686816 -332.784344) (xy 93.729196 -332.741964) (xy 93.776746 -332.705477) (xy 93.828652 -332.67551)
			(xy 93.884025 -332.652574) (xy 93.941918 -332.637061) (xy 94.00134 -332.629238) (xy 94.061276 -332.629238)
			(xy 94.120698 -332.637061) (xy 94.178591 -332.652574) (xy 94.233964 -332.67551) (xy 94.28587 -332.705477)
			(xy 94.33342 -332.741964) (xy 94.3758 -332.784344) (xy 94.412287 -332.831894) (xy 94.442254 -332.8838)
			(xy 94.46519 -332.939173) (xy 94.46736 -332.947271) (xy 365.368753 -332.947271) (xy 365.368753 -332.887329)
			(xy 365.376578 -332.827899) (xy 365.392093 -332.77) (xy 365.415033 -332.71462) (xy 365.445006 -332.66271)
			(xy 365.481498 -332.615155) (xy 365.523886 -332.572772) (xy 365.571443 -332.536283) (xy 365.623356 -332.506315)
			(xy 365.678737 -332.48338) (xy 365.736639 -332.46787) (xy 365.796069 -332.460051) (xy 365.82604 -332.459584)
			(xy 366.68964 -332.459584) (xy 366.719605 -332.460093) (xy 366.779023 -332.46792) (xy 366.836911 -332.483435)
			(xy 366.892278 -332.506374) (xy 366.944178 -332.536342) (xy 366.991723 -332.572828) (xy 367.034098 -332.615207)
			(xy 367.07058 -332.662755) (xy 367.100544 -332.714658) (xy 367.123478 -332.770027) (xy 367.138988 -332.827916)
			(xy 367.14681 -332.887335) (xy 367.14681 -332.947265) (xy 367.138988 -333.006684) (xy 367.123478 -333.064573)
			(xy 367.100544 -333.119942) (xy 367.07058 -333.171845) (xy 367.034098 -333.219393) (xy 366.991723 -333.261772)
			(xy 366.944178 -333.298258) (xy 366.892278 -333.328226) (xy 366.836911 -333.351165) (xy 366.779023 -333.36668)
			(xy 366.719605 -333.374507) (xy 366.68964 -333.375) (xy 365.82604 -333.375) (xy 365.796069 -333.374549)
			(xy 365.736639 -333.36673) (xy 365.678737 -333.35122) (xy 365.623356 -333.328285) (xy 365.571443 -333.298317)
			(xy 365.523886 -333.261828) (xy 365.481498 -333.219445) (xy 365.445006 -333.17189) (xy 365.415033 -333.11998)
			(xy 365.392093 -333.0646) (xy 365.376578 -333.006701) (xy 365.368753 -332.947271) (xy 94.46736 -332.947271)
			(xy 94.480703 -332.997066) (xy 94.488526 -333.056488) (xy 94.489016 -333.086456) (xy 94.489016 -333.950056)
			(xy 94.488526 -333.980024) (xy 94.480703 -334.039446) (xy 94.46519 -334.097339) (xy 94.442254 -334.152712)
			(xy 94.412287 -334.204618) (xy 94.3758 -334.252168) (xy 94.33342 -334.294548) (xy 94.28587 -334.331035)
			(xy 94.233964 -334.361002) (xy 94.178591 -334.383938) (xy 94.120698 -334.399451) (xy 94.061276 -334.407274)
			(xy 94.00134 -334.407274) (xy 93.941918 -334.399451) (xy 93.884025 -334.383938) (xy 93.828652 -334.361002)
			(xy 93.776746 -334.331035) (xy 93.729196 -334.294548) (xy 93.686816 -334.252168) (xy 93.650329 -334.204618)
			(xy 93.620362 -334.152712) (xy 93.597426 -334.097339) (xy 93.581913 -334.039446) (xy 93.57409 -333.980024)
			(xy 93.5736 -333.950056) (xy 0.508 -333.950056) (xy 0.508 -337.266026) (xy 234.403392 -337.266026)
			(xy 234.403392 -336.402426) (xy 234.403882 -336.372458) (xy 234.411705 -336.313036) (xy 234.427218 -336.255143)
			(xy 234.450154 -336.19977) (xy 234.480121 -336.147864) (xy 234.516608 -336.100314) (xy 234.558988 -336.057934)
			(xy 234.606538 -336.021447) (xy 234.658444 -335.99148) (xy 234.713817 -335.968544) (xy 234.77171 -335.953031)
			(xy 234.831132 -335.945208) (xy 234.891068 -335.945208) (xy 234.95049 -335.953031) (xy 235.008383 -335.968544)
			(xy 235.063756 -335.99148) (xy 235.115662 -336.021447) (xy 235.163212 -336.057934) (xy 235.205592 -336.100314)
			(xy 235.242079 -336.147864) (xy 235.272046 -336.19977) (xy 235.294982 -336.255143) (xy 235.310495 -336.313036)
			(xy 235.318318 -336.372458) (xy 235.318808 -336.402426) (xy 235.318808 -337.266026) (xy 235.318318 -337.295994)
			(xy 235.310495 -337.355416) (xy 235.294982 -337.413309) (xy 235.272046 -337.468682) (xy 235.242079 -337.520588)
			(xy 235.205592 -337.568138) (xy 235.163212 -337.610518) (xy 235.115662 -337.647005) (xy 235.063756 -337.676972)
			(xy 235.008383 -337.699908) (xy 234.95049 -337.715421) (xy 234.891068 -337.723244) (xy 234.831132 -337.723244)
			(xy 234.77171 -337.715421) (xy 234.713817 -337.699908) (xy 234.658444 -337.676972) (xy 234.606538 -337.647005)
			(xy 234.558988 -337.610518) (xy 234.516608 -337.568138) (xy 234.480121 -337.520588) (xy 234.450154 -337.468682)
			(xy 234.427218 -337.413309) (xy 234.411705 -337.355416) (xy 234.403882 -337.295994) (xy 234.403392 -337.266026)
			(xy 0.508 -337.266026) (xy 0.508 -342.466769) (xy 18.951172 -342.466769) (xy 18.951172 -342.412231)
			(xy 18.958934 -342.358247) (xy 18.974299 -342.305917) (xy 18.996956 -342.256307) (xy 19.026441 -342.210426)
			(xy 19.062157 -342.169208) (xy 19.103374 -342.133493) (xy 19.149255 -342.104007) (xy 19.198865 -342.08135)
			(xy 19.251195 -342.065985) (xy 19.305179 -342.058223) (xy 19.332448 -342.057736) (xy 20.196048 -342.057736)
			(xy 20.223319 -342.058203) (xy 20.277306 -342.065965) (xy 20.329638 -342.081331) (xy 20.379252 -342.103989)
			(xy 20.425135 -342.133476) (xy 20.466355 -342.169193) (xy 20.502073 -342.210413) (xy 20.53156 -342.256297)
			(xy 20.554218 -342.30591) (xy 20.569584 -342.358242) (xy 20.577347 -342.412229) (xy 20.577347 -342.466771)
			(xy 20.577347 -342.466772) (xy 22.0601 -342.466772) (xy 22.0601 -342.412228) (xy 22.067862 -342.358241)
			(xy 22.083229 -342.305907) (xy 22.105887 -342.256293) (xy 22.135375 -342.210409) (xy 22.171094 -342.169188)
			(xy 22.212315 -342.133471) (xy 22.2582 -342.103983) (xy 22.307815 -342.081326) (xy 22.360148 -342.06596)
			(xy 22.414136 -342.058199) (xy 22.441408 -342.057736) (xy 23.305008 -342.057736) (xy 23.332277 -342.058227)
			(xy 23.386259 -342.06599) (xy 23.438588 -342.081355) (xy 23.488197 -342.104012) (xy 23.534076 -342.133498)
			(xy 23.575293 -342.169213) (xy 23.611007 -342.21043) (xy 23.640492 -342.256311) (xy 23.663147 -342.30592)
			(xy 23.678512 -342.358249) (xy 23.686274 -342.412231) (xy 23.686274 -342.466768) (xy 25.169122 -342.466768)
			(xy 25.169122 -342.412232) (xy 25.176883 -342.358251) (xy 25.192247 -342.305924) (xy 25.214901 -342.256315)
			(xy 25.244384 -342.210436) (xy 25.280096 -342.169219) (xy 25.32131 -342.133503) (xy 25.367187 -342.104016)
			(xy 25.416794 -342.081358) (xy 25.46912 -342.06599) (xy 25.5231 -342.058225) (xy 25.550368 -342.057736)
			(xy 26.413968 -342.057736) (xy 26.44124 -342.058201) (xy 26.49523 -342.06596) (xy 26.547567 -342.081323)
			(xy 26.597184 -342.103979) (xy 26.643071 -342.133465) (xy 26.684295 -342.169183) (xy 26.720015 -342.210403)
			(xy 26.749506 -342.256288) (xy 26.772166 -342.305903) (xy 26.787533 -342.358238) (xy 26.795296 -342.412228)
			(xy 26.795296 -342.466772) (xy 28.278 -342.466772) (xy 28.278 -342.412228) (xy 28.285762 -342.358238)
			(xy 28.30113 -342.305903) (xy 28.32379 -342.256288) (xy 28.35328 -342.210402) (xy 28.389001 -342.169181)
			(xy 28.430225 -342.133464) (xy 28.476112 -342.103977) (xy 28.525729 -342.08132) (xy 28.578065 -342.065957)
			(xy 28.632056 -342.058198) (xy 28.659328 -342.057736) (xy 29.522928 -342.057736) (xy 29.550196 -342.058228)
			(xy 29.604176 -342.065993) (xy 29.656502 -342.081361) (xy 29.706109 -342.104019) (xy 29.751986 -342.133505)
			(xy 29.7932 -342.16922) (xy 29.828912 -342.210437) (xy 29.858395 -342.256316) (xy 29.881049 -342.305924)
			(xy 29.896413 -342.358251) (xy 29.904174 -342.412232) (xy 29.904174 -342.466768) (xy 29.904174 -342.466769)
			(xy 31.387022 -342.466769) (xy 31.387022 -342.412231) (xy 31.394784 -342.358248) (xy 31.410149 -342.305919)
			(xy 31.432804 -342.25631) (xy 31.462289 -342.210429) (xy 31.498003 -342.169212) (xy 31.53922 -342.133496)
			(xy 31.585099 -342.10401) (xy 31.634708 -342.081353) (xy 31.687036 -342.065986) (xy 31.741019 -342.058223)
			(xy 31.768288 -342.057736) (xy 32.631888 -342.057736) (xy 32.659159 -342.058203) (xy 32.713147 -342.065963)
			(xy 32.765481 -342.081329) (xy 32.815096 -342.103985) (xy 32.86098 -342.133472) (xy 32.902202 -342.16919)
			(xy 32.93792 -342.21041) (xy 32.967409 -342.256294) (xy 32.990067 -342.305908) (xy 33.005434 -342.358241)
			(xy 33.013196 -342.412229) (xy 33.013196 -342.466771) (xy 33.013196 -342.466773) (xy 34.4959 -342.466773)
			(xy 34.4959 -342.412227) (xy 34.503663 -342.358235) (xy 34.519032 -342.305899) (xy 34.541693 -342.256282)
			(xy 34.571185 -342.210396) (xy 34.606908 -342.169174) (xy 34.648134 -342.133456) (xy 34.694024 -342.10397)
			(xy 34.743644 -342.081315) (xy 34.795982 -342.065953) (xy 34.849975 -342.058196) (xy 34.877248 -342.057736)
			(xy 35.740848 -342.057736) (xy 35.768115 -342.05823) (xy 35.822093 -342.065997) (xy 35.874417 -342.081366)
			(xy 35.92402 -342.104025) (xy 35.969895 -342.133512) (xy 36.011107 -342.169227) (xy 36.046817 -342.210443)
			(xy 36.076298 -342.256322) (xy 36.098951 -342.305928) (xy 36.114313 -342.358254) (xy 36.122074 -342.412233)
			(xy 36.122074 -342.466767) (xy 36.122073 -342.466772) (xy 37.6049 -342.466772) (xy 37.6049 -342.412228)
			(xy 37.612662 -342.358241) (xy 37.628029 -342.305907) (xy 37.650687 -342.256293) (xy 37.680175 -342.210409)
			(xy 37.715894 -342.169188) (xy 37.757115 -342.133471) (xy 37.803 -342.103983) (xy 37.852615 -342.081326)
			(xy 37.904948 -342.06596) (xy 37.958936 -342.058199) (xy 37.986208 -342.057736) (xy 38.849808 -342.057736)
			(xy 38.877077 -342.058227) (xy 38.931059 -342.06599) (xy 38.983388 -342.081355) (xy 39.032997 -342.104012)
			(xy 39.078876 -342.133498) (xy 39.120093 -342.169213) (xy 39.155807 -342.21043) (xy 39.185292 -342.256311)
			(xy 39.207947 -342.30592) (xy 39.223312 -342.358249) (xy 39.231074 -342.412231) (xy 39.231074 -342.466768)
			(xy 40.713922 -342.466768) (xy 40.713922 -342.412232) (xy 40.721683 -342.358251) (xy 40.737047 -342.305924)
			(xy 40.759701 -342.256315) (xy 40.789184 -342.210436) (xy 40.824896 -342.169219) (xy 40.86611 -342.133503)
			(xy 40.911987 -342.104016) (xy 40.961594 -342.081358) (xy 41.01392 -342.06599) (xy 41.0679 -342.058225)
			(xy 41.095168 -342.057736) (xy 41.958768 -342.057736) (xy 41.98604 -342.058201) (xy 42.04003 -342.06596)
			(xy 42.092367 -342.081323) (xy 42.141984 -342.103979) (xy 42.187871 -342.133465) (xy 42.229095 -342.169183)
			(xy 42.264815 -342.210403) (xy 42.294306 -342.256288) (xy 42.316966 -342.305903) (xy 42.332333 -342.358238)
			(xy 42.340096 -342.412228) (xy 42.340096 -342.466772) (xy 43.8228 -342.466772) (xy 43.8228 -342.412228)
			(xy 43.830562 -342.358238) (xy 43.84593 -342.305903) (xy 43.86859 -342.256288) (xy 43.89808 -342.210402)
			(xy 43.933801 -342.169181) (xy 43.975025 -342.133464) (xy 44.020912 -342.103977) (xy 44.070529 -342.08132)
			(xy 44.122865 -342.065957) (xy 44.176856 -342.058198) (xy 44.204128 -342.057736) (xy 45.067728 -342.057736)
			(xy 45.094996 -342.058228) (xy 45.148976 -342.065993) (xy 45.201302 -342.081361) (xy 45.250909 -342.104019)
			(xy 45.296786 -342.133505) (xy 45.338 -342.16922) (xy 45.373712 -342.210437) (xy 45.403195 -342.256316)
			(xy 45.425849 -342.305924) (xy 45.441213 -342.358251) (xy 45.448974 -342.412232) (xy 45.448974 -342.466768)
			(xy 45.448974 -342.466769) (xy 46.931822 -342.466769) (xy 46.931822 -342.412231) (xy 46.939584 -342.358248)
			(xy 46.954949 -342.305919) (xy 46.977604 -342.25631) (xy 47.007089 -342.210429) (xy 47.042803 -342.169212)
			(xy 47.08402 -342.133496) (xy 47.129899 -342.10401) (xy 47.179508 -342.081353) (xy 47.231836 -342.065986)
			(xy 47.285819 -342.058223) (xy 47.313088 -342.057736) (xy 48.176688 -342.057736) (xy 48.203959 -342.058203)
			(xy 48.257947 -342.065963) (xy 48.310281 -342.081329) (xy 48.359896 -342.103985) (xy 48.40578 -342.133472)
			(xy 48.447002 -342.16919) (xy 48.48272 -342.21041) (xy 48.512209 -342.256294) (xy 48.534867 -342.305908)
			(xy 48.550234 -342.358241) (xy 48.557996 -342.412229) (xy 48.557996 -342.466771) (xy 48.557996 -342.466773)
			(xy 50.0407 -342.466773) (xy 50.0407 -342.412227) (xy 50.048463 -342.358235) (xy 50.063832 -342.305899)
			(xy 50.086493 -342.256282) (xy 50.115985 -342.210396) (xy 50.151708 -342.169174) (xy 50.192934 -342.133456)
			(xy 50.238824 -342.10397) (xy 50.288444 -342.081315) (xy 50.340782 -342.065953) (xy 50.394775 -342.058196)
			(xy 50.422048 -342.057736) (xy 51.285648 -342.057736) (xy 51.312915 -342.05823) (xy 51.366893 -342.065997)
			(xy 51.419217 -342.081366) (xy 51.46882 -342.104025) (xy 51.514695 -342.133512) (xy 51.555907 -342.169227)
			(xy 51.591617 -342.210443) (xy 51.621098 -342.256322) (xy 51.643751 -342.305928) (xy 51.659113 -342.358254)
			(xy 51.666874 -342.412233) (xy 51.666874 -342.466767) (xy 51.666873 -342.466773) (xy 60.9909 -342.466773)
			(xy 60.9909 -342.412227) (xy 60.998663 -342.358236) (xy 61.014031 -342.3059) (xy 61.036692 -342.256284)
			(xy 61.066184 -342.210398) (xy 61.101906 -342.169176) (xy 61.143131 -342.133459) (xy 61.18902 -342.103972)
			(xy 61.238639 -342.081317) (xy 61.290977 -342.065954) (xy 61.344969 -342.058197) (xy 61.372242 -342.057736)
			(xy 62.235842 -342.057736) (xy 62.263109 -342.058229) (xy 62.317088 -342.065996) (xy 62.369412 -342.081365)
			(xy 62.419017 -342.104023) (xy 62.464892 -342.13351) (xy 62.506105 -342.169225) (xy 62.541815 -342.210441)
			(xy 62.571297 -342.25632) (xy 62.59395 -342.305927) (xy 62.609313 -342.358253) (xy 62.617074 -342.412233)
			(xy 62.617074 -342.466767) (xy 62.617073 -342.466771) (xy 64.099899 -342.466771) (xy 64.099899 -342.412229)
			(xy 64.107662 -342.358241) (xy 64.123028 -342.305908) (xy 64.145686 -342.256295) (xy 64.175174 -342.210411)
			(xy 64.210892 -342.16919) (xy 64.252112 -342.133473) (xy 64.297997 -342.103985) (xy 64.34761 -342.081327)
			(xy 64.399943 -342.065961) (xy 64.453931 -342.058199) (xy 64.481202 -342.057736) (xy 65.344802 -342.057736)
			(xy 65.372071 -342.058227) (xy 65.426054 -342.065988) (xy 65.478383 -342.081354) (xy 65.527993 -342.10401)
			(xy 65.573873 -342.133496) (xy 65.615091 -342.169211) (xy 65.650805 -342.210428) (xy 65.680291 -342.256309)
			(xy 65.702947 -342.305919) (xy 65.718312 -342.358248) (xy 65.726074 -342.412231) (xy 65.726074 -342.466768)
			(xy 67.208922 -342.466768) (xy 67.208922 -342.412232) (xy 67.216683 -342.358252) (xy 67.232047 -342.305925)
			(xy 67.2547 -342.256317) (xy 67.284183 -342.210438) (xy 67.319894 -342.169221) (xy 67.361107 -342.133505)
			(xy 67.406984 -342.104018) (xy 67.456589 -342.08136) (xy 67.508914 -342.065991) (xy 67.562894 -342.058225)
			(xy 67.590162 -342.057736) (xy 68.453762 -342.057736) (xy 68.481035 -342.058201) (xy 68.535025 -342.065959)
			(xy 68.587362 -342.081321) (xy 68.63698 -342.103977) (xy 68.682868 -342.133463) (xy 68.724093 -342.16918)
			(xy 68.759814 -342.210401) (xy 68.789305 -342.256287) (xy 68.811965 -342.305902) (xy 68.827333 -342.358237)
			(xy 68.835096 -342.412227) (xy 68.835096 -342.466772) (xy 70.3178 -342.466772) (xy 70.3178 -342.412228)
			(xy 70.325562 -342.358239) (xy 70.34093 -342.305904) (xy 70.363589 -342.256289) (xy 70.393079 -342.210404)
			(xy 70.428799 -342.169183) (xy 70.470022 -342.133466) (xy 70.515909 -342.103979) (xy 70.565525 -342.081322)
			(xy 70.61786 -342.065958) (xy 70.67185 -342.058198) (xy 70.699122 -342.057736) (xy 71.562722 -342.057736)
			(xy 71.58999 -342.058228) (xy 71.643971 -342.065992) (xy 71.696298 -342.081359) (xy 71.745905 -342.104017)
			(xy 71.791783 -342.133503) (xy 71.832998 -342.169218) (xy 71.86871 -342.210435) (xy 71.898194 -342.256314)
			(xy 71.920848 -342.305923) (xy 71.936213 -342.35825) (xy 71.943974 -342.412232) (xy 71.943974 -342.466768)
			(xy 71.943974 -342.466769) (xy 73.426822 -342.466769) (xy 73.426822 -342.412231) (xy 73.434584 -342.358249)
			(xy 73.449948 -342.305921) (xy 73.472603 -342.256311) (xy 73.502087 -342.210431) (xy 73.537801 -342.169214)
			(xy 73.579017 -342.133498) (xy 73.624896 -342.104012) (xy 73.674504 -342.081354) (xy 73.726831 -342.065987)
			(xy 73.780813 -342.058224) (xy 73.808082 -342.057736) (xy 74.671682 -342.057736) (xy 74.698954 -342.058202)
			(xy 74.752942 -342.065962) (xy 74.805277 -342.081327) (xy 74.854892 -342.103983) (xy 74.900778 -342.13347)
			(xy 74.942 -342.169188) (xy 74.977719 -342.210408) (xy 75.007208 -342.256292) (xy 75.029867 -342.305906)
			(xy 75.045234 -342.35824) (xy 75.052996 -342.412228) (xy 75.052996 -342.466772) (xy 75.052996 -342.466773)
			(xy 76.5357 -342.466773) (xy 76.5357 -342.412227) (xy 76.543463 -342.358236) (xy 76.558831 -342.3059)
			(xy 76.581492 -342.256284) (xy 76.610984 -342.210398) (xy 76.646706 -342.169176) (xy 76.687931 -342.133459)
			(xy 76.73382 -342.103972) (xy 76.783439 -342.081317) (xy 76.835777 -342.065954) (xy 76.889769 -342.058197)
			(xy 76.917042 -342.057736) (xy 77.780642 -342.057736) (xy 77.807909 -342.058229) (xy 77.861888 -342.065996)
			(xy 77.914212 -342.081365) (xy 77.963817 -342.104023) (xy 78.009692 -342.13351) (xy 78.050905 -342.169225)
			(xy 78.086615 -342.210441) (xy 78.116097 -342.25632) (xy 78.13875 -342.305927) (xy 78.154113 -342.358253)
			(xy 78.161874 -342.412233) (xy 78.161874 -342.466767) (xy 78.161873 -342.466771) (xy 79.644699 -342.466771)
			(xy 79.644699 -342.412229) (xy 79.652462 -342.358241) (xy 79.667828 -342.305908) (xy 79.690486 -342.256295)
			(xy 79.719974 -342.210411) (xy 79.755692 -342.16919) (xy 79.796912 -342.133473) (xy 79.842797 -342.103985)
			(xy 79.89241 -342.081327) (xy 79.944743 -342.065961) (xy 79.998731 -342.058199) (xy 80.026002 -342.057736)
			(xy 80.889602 -342.057736) (xy 80.916871 -342.058227) (xy 80.970854 -342.065988) (xy 81.023183 -342.081354)
			(xy 81.072793 -342.10401) (xy 81.118673 -342.133496) (xy 81.159891 -342.169211) (xy 81.195605 -342.210428)
			(xy 81.225091 -342.256309) (xy 81.247747 -342.305919) (xy 81.263112 -342.358248) (xy 81.270874 -342.412231)
			(xy 81.270874 -342.466768) (xy 82.753722 -342.466768) (xy 82.753722 -342.412232) (xy 82.761483 -342.358252)
			(xy 82.776847 -342.305925) (xy 82.7995 -342.256317) (xy 82.828983 -342.210438) (xy 82.864694 -342.169221)
			(xy 82.905907 -342.133505) (xy 82.951784 -342.104018) (xy 83.001389 -342.08136) (xy 83.053714 -342.065991)
			(xy 83.107694 -342.058225) (xy 83.134962 -342.057736) (xy 83.998562 -342.057736) (xy 84.025835 -342.058201)
			(xy 84.079825 -342.065959) (xy 84.132162 -342.081321) (xy 84.18178 -342.103977) (xy 84.227668 -342.133463)
			(xy 84.268893 -342.16918) (xy 84.304614 -342.210401) (xy 84.334105 -342.256287) (xy 84.356765 -342.305902)
			(xy 84.372133 -342.358237) (xy 84.379896 -342.412227) (xy 84.379896 -342.466772) (xy 85.8626 -342.466772)
			(xy 85.8626 -342.412228) (xy 85.870362 -342.358239) (xy 85.88573 -342.305904) (xy 85.908389 -342.256289)
			(xy 85.937879 -342.210404) (xy 85.973599 -342.169183) (xy 86.014822 -342.133466) (xy 86.060709 -342.103979)
			(xy 86.110325 -342.081322) (xy 86.16266 -342.065958) (xy 86.21665 -342.058198) (xy 86.243922 -342.057736)
			(xy 87.107522 -342.057736) (xy 87.13479 -342.058228) (xy 87.188771 -342.065992) (xy 87.241098 -342.081359)
			(xy 87.290705 -342.104017) (xy 87.336583 -342.133503) (xy 87.377798 -342.169218) (xy 87.41351 -342.210435)
			(xy 87.442994 -342.256314) (xy 87.465648 -342.305923) (xy 87.481013 -342.35825) (xy 87.488774 -342.412232)
			(xy 87.488774 -342.466768) (xy 87.488774 -342.466769) (xy 88.971622 -342.466769) (xy 88.971622 -342.412231)
			(xy 88.979384 -342.358249) (xy 88.994748 -342.305921) (xy 89.017403 -342.256311) (xy 89.046887 -342.210431)
			(xy 89.082601 -342.169214) (xy 89.123817 -342.133498) (xy 89.169696 -342.104012) (xy 89.219304 -342.081354)
			(xy 89.271631 -342.065987) (xy 89.325613 -342.058224) (xy 89.352882 -342.057736) (xy 90.216482 -342.057736)
			(xy 90.243754 -342.058202) (xy 90.297742 -342.065962) (xy 90.350077 -342.081327) (xy 90.399692 -342.103983)
			(xy 90.445578 -342.13347) (xy 90.4868 -342.169188) (xy 90.522519 -342.210408) (xy 90.552008 -342.256292)
			(xy 90.574667 -342.305906) (xy 90.590034 -342.35824) (xy 90.597796 -342.412228) (xy 90.597796 -342.466772)
			(xy 90.597796 -342.466773) (xy 92.0805 -342.466773) (xy 92.0805 -342.412227) (xy 92.088263 -342.358236)
			(xy 92.103631 -342.3059) (xy 92.126292 -342.256284) (xy 92.155784 -342.210398) (xy 92.191506 -342.169176)
			(xy 92.232731 -342.133459) (xy 92.27862 -342.103972) (xy 92.328239 -342.081317) (xy 92.380577 -342.065954)
			(xy 92.434569 -342.058197) (xy 92.461842 -342.057736) (xy 93.325442 -342.057736) (xy 93.352709 -342.058229)
			(xy 93.406688 -342.065996) (xy 93.459012 -342.081365) (xy 93.508617 -342.104023) (xy 93.554492 -342.13351)
			(xy 93.595705 -342.169225) (xy 93.631415 -342.210441) (xy 93.660897 -342.25632) (xy 93.68355 -342.305927)
			(xy 93.698913 -342.358253) (xy 93.706674 -342.412233) (xy 93.706674 -342.466767) (xy 93.698913 -342.520747)
			(xy 93.68355 -342.573073) (xy 93.660897 -342.62268) (xy 93.631415 -342.668559) (xy 93.60914 -342.694268)
			(xy 102.35157 -342.694268) (xy 102.35157 -342.634332) (xy 102.359393 -342.574909) (xy 102.374905 -342.517016)
			(xy 102.397841 -342.461642) (xy 102.427809 -342.409736) (xy 102.464294 -342.362185) (xy 102.506675 -342.319804)
			(xy 102.554224 -342.283316) (xy 102.60613 -342.253347) (xy 102.661502 -342.23041) (xy 102.719395 -342.214896)
			(xy 102.778818 -342.207071) (xy 102.808786 -342.20658) (xy 103.672386 -342.20658) (xy 103.702355 -342.207072)
			(xy 103.76178 -342.214894) (xy 103.819676 -342.230405) (xy 103.875051 -342.253341) (xy 103.926959 -342.283309)
			(xy 103.974512 -342.319796) (xy 104.016895 -342.362178) (xy 104.053383 -342.409729) (xy 104.083352 -342.461636)
			(xy 104.085479 -342.466772) (xy 111.4808 -342.466772) (xy 111.4808 -342.412228) (xy 111.488562 -342.358241)
			(xy 111.503929 -342.305907) (xy 111.526587 -342.256293) (xy 111.556075 -342.210409) (xy 111.591794 -342.169188)
			(xy 111.633015 -342.133471) (xy 111.6789 -342.103983) (xy 111.728515 -342.081326) (xy 111.780848 -342.06596)
			(xy 111.834836 -342.058199) (xy 111.862108 -342.057736) (xy 112.725708 -342.057736) (xy 112.752977 -342.058227)
			(xy 112.806959 -342.06599) (xy 112.859288 -342.081355) (xy 112.908897 -342.104012) (xy 112.954776 -342.133498)
			(xy 112.995993 -342.169213) (xy 113.031707 -342.21043) (xy 113.061192 -342.256311) (xy 113.083847 -342.30592)
			(xy 113.099212 -342.358249) (xy 113.106974 -342.412231) (xy 113.106974 -342.466768) (xy 114.589822 -342.466768)
			(xy 114.589822 -342.412232) (xy 114.597583 -342.358251) (xy 114.612947 -342.305924) (xy 114.635601 -342.256315)
			(xy 114.665084 -342.210436) (xy 114.700796 -342.169219) (xy 114.74201 -342.133503) (xy 114.787887 -342.104016)
			(xy 114.837494 -342.081358) (xy 114.88982 -342.06599) (xy 114.9438 -342.058225) (xy 114.971068 -342.057736)
			(xy 115.834668 -342.057736) (xy 115.86194 -342.058201) (xy 115.91593 -342.06596) (xy 115.968267 -342.081323)
			(xy 116.017884 -342.103979) (xy 116.063771 -342.133465) (xy 116.104995 -342.169183) (xy 116.140715 -342.210403)
			(xy 116.170206 -342.256288) (xy 116.192866 -342.305903) (xy 116.208233 -342.358238) (xy 116.215996 -342.412228)
			(xy 116.215996 -342.466772) (xy 117.6987 -342.466772) (xy 117.6987 -342.412228) (xy 117.706462 -342.358238)
			(xy 117.72183 -342.305903) (xy 117.74449 -342.256288) (xy 117.77398 -342.210402) (xy 117.809701 -342.169181)
			(xy 117.850925 -342.133464) (xy 117.896812 -342.103977) (xy 117.946429 -342.08132) (xy 117.998765 -342.065957)
			(xy 118.052756 -342.058198) (xy 118.080028 -342.057736) (xy 118.943628 -342.057736) (xy 118.970896 -342.058228)
			(xy 119.024876 -342.065993) (xy 119.077202 -342.081361) (xy 119.126809 -342.104019) (xy 119.172686 -342.133505)
			(xy 119.2139 -342.16922) (xy 119.249612 -342.210437) (xy 119.279095 -342.256316) (xy 119.301749 -342.305924)
			(xy 119.317113 -342.358251) (xy 119.324874 -342.412232) (xy 119.324874 -342.466768) (xy 119.324874 -342.466769)
			(xy 120.807722 -342.466769) (xy 120.807722 -342.412231) (xy 120.815484 -342.358248) (xy 120.830849 -342.305919)
			(xy 120.853504 -342.25631) (xy 120.882989 -342.210429) (xy 120.918703 -342.169212) (xy 120.95992 -342.133496)
			(xy 121.005799 -342.10401) (xy 121.055408 -342.081353) (xy 121.107736 -342.065986) (xy 121.161719 -342.058223)
			(xy 121.188988 -342.057736) (xy 122.052588 -342.057736) (xy 122.079859 -342.058203) (xy 122.133847 -342.065963)
			(xy 122.186181 -342.081329) (xy 122.235796 -342.103985) (xy 122.28168 -342.133472) (xy 122.322902 -342.16919)
			(xy 122.35862 -342.21041) (xy 122.388109 -342.256294) (xy 122.410767 -342.305908) (xy 122.426134 -342.358241)
			(xy 122.433896 -342.412229) (xy 122.433896 -342.466771) (xy 122.433896 -342.466773) (xy 123.9166 -342.466773)
			(xy 123.9166 -342.412227) (xy 123.924363 -342.358235) (xy 123.939732 -342.305899) (xy 123.962393 -342.256282)
			(xy 123.991885 -342.210396) (xy 124.027608 -342.169174) (xy 124.068834 -342.133456) (xy 124.114724 -342.10397)
			(xy 124.164344 -342.081315) (xy 124.216682 -342.065953) (xy 124.270675 -342.058196) (xy 124.297948 -342.057736)
			(xy 125.161548 -342.057736) (xy 125.188815 -342.05823) (xy 125.242793 -342.065997) (xy 125.295117 -342.081366)
			(xy 125.34472 -342.104025) (xy 125.390595 -342.133512) (xy 125.431807 -342.169227) (xy 125.467517 -342.210443)
			(xy 125.496998 -342.256322) (xy 125.519651 -342.305928) (xy 125.535013 -342.358254) (xy 125.542774 -342.412233)
			(xy 125.542774 -342.466767) (xy 125.542773 -342.466772) (xy 127.0256 -342.466772) (xy 127.0256 -342.412228)
			(xy 127.033362 -342.358241) (xy 127.048729 -342.305907) (xy 127.071387 -342.256293) (xy 127.100875 -342.210409)
			(xy 127.136594 -342.169188) (xy 127.177815 -342.133471) (xy 127.2237 -342.103983) (xy 127.273315 -342.081326)
			(xy 127.325648 -342.06596) (xy 127.379636 -342.058199) (xy 127.406908 -342.057736) (xy 128.270508 -342.057736)
			(xy 128.297777 -342.058227) (xy 128.351759 -342.06599) (xy 128.404088 -342.081355) (xy 128.453697 -342.104012)
			(xy 128.499576 -342.133498) (xy 128.540793 -342.169213) (xy 128.576507 -342.21043) (xy 128.605992 -342.256311)
			(xy 128.628647 -342.30592) (xy 128.644012 -342.358249) (xy 128.651774 -342.412231) (xy 128.651774 -342.466768)
			(xy 130.134622 -342.466768) (xy 130.134622 -342.412232) (xy 130.142383 -342.358251) (xy 130.157747 -342.305924)
			(xy 130.180401 -342.256315) (xy 130.209884 -342.210436) (xy 130.245596 -342.169219) (xy 130.28681 -342.133503)
			(xy 130.332687 -342.104016) (xy 130.382294 -342.081358) (xy 130.43462 -342.06599) (xy 130.4886 -342.058225)
			(xy 130.515868 -342.057736) (xy 131.379468 -342.057736) (xy 131.40674 -342.058201) (xy 131.46073 -342.06596)
			(xy 131.513067 -342.081323) (xy 131.562684 -342.103979) (xy 131.608571 -342.133465) (xy 131.649795 -342.169183)
			(xy 131.685515 -342.210403) (xy 131.715006 -342.256288) (xy 131.737666 -342.305903) (xy 131.753033 -342.358238)
			(xy 131.760796 -342.412228) (xy 131.760796 -342.466772) (xy 133.2435 -342.466772) (xy 133.2435 -342.412228)
			(xy 133.251262 -342.358238) (xy 133.26663 -342.305903) (xy 133.28929 -342.256288) (xy 133.31878 -342.210402)
			(xy 133.354501 -342.169181) (xy 133.395725 -342.133464) (xy 133.441612 -342.103977) (xy 133.491229 -342.08132)
			(xy 133.543565 -342.065957) (xy 133.597556 -342.058198) (xy 133.624828 -342.057736) (xy 134.488428 -342.057736)
			(xy 134.515696 -342.058228) (xy 134.569676 -342.065993) (xy 134.622002 -342.081361) (xy 134.671609 -342.104019)
			(xy 134.717486 -342.133505) (xy 134.7587 -342.16922) (xy 134.794412 -342.210437) (xy 134.823895 -342.256316)
			(xy 134.846549 -342.305924) (xy 134.861913 -342.358251) (xy 134.869674 -342.412232) (xy 134.869674 -342.466768)
			(xy 134.869674 -342.466769) (xy 136.352522 -342.466769) (xy 136.352522 -342.412231) (xy 136.360284 -342.358248)
			(xy 136.375649 -342.305919) (xy 136.398304 -342.25631) (xy 136.427789 -342.210429) (xy 136.463503 -342.169212)
			(xy 136.50472 -342.133496) (xy 136.550599 -342.10401) (xy 136.600208 -342.081353) (xy 136.652536 -342.065986)
			(xy 136.706519 -342.058223) (xy 136.733788 -342.057736) (xy 137.597388 -342.057736) (xy 137.624659 -342.058203)
			(xy 137.678647 -342.065963) (xy 137.730981 -342.081329) (xy 137.780596 -342.103985) (xy 137.82648 -342.133472)
			(xy 137.867702 -342.16919) (xy 137.90342 -342.21041) (xy 137.932909 -342.256294) (xy 137.955567 -342.305908)
			(xy 137.970934 -342.358241) (xy 137.978696 -342.412229) (xy 137.978696 -342.466771) (xy 137.978696 -342.466773)
			(xy 139.4614 -342.466773) (xy 139.4614 -342.412227) (xy 139.469163 -342.358235) (xy 139.484532 -342.305899)
			(xy 139.507193 -342.256282) (xy 139.536685 -342.210396) (xy 139.572408 -342.169174) (xy 139.613634 -342.133456)
			(xy 139.659524 -342.10397) (xy 139.709144 -342.081315) (xy 139.761482 -342.065953) (xy 139.815475 -342.058196)
			(xy 139.842748 -342.057736) (xy 140.706348 -342.057736) (xy 140.733615 -342.05823) (xy 140.787593 -342.065997)
			(xy 140.839917 -342.081366) (xy 140.88952 -342.104025) (xy 140.935395 -342.133512) (xy 140.976607 -342.169227)
			(xy 141.012317 -342.210443) (xy 141.041798 -342.256322) (xy 141.064451 -342.305928) (xy 141.079813 -342.358254)
			(xy 141.087574 -342.412233) (xy 141.087574 -342.466767) (xy 141.087573 -342.466772) (xy 142.5704 -342.466772)
			(xy 142.5704 -342.412228) (xy 142.578162 -342.358241) (xy 142.593529 -342.305907) (xy 142.616187 -342.256293)
			(xy 142.645675 -342.210409) (xy 142.681394 -342.169188) (xy 142.722615 -342.133471) (xy 142.7685 -342.103983)
			(xy 142.818115 -342.081326) (xy 142.870448 -342.06596) (xy 142.924436 -342.058199) (xy 142.951708 -342.057736)
			(xy 143.815308 -342.057736) (xy 143.842577 -342.058227) (xy 143.896559 -342.06599) (xy 143.948888 -342.081355)
			(xy 143.998497 -342.104012) (xy 144.044376 -342.133498) (xy 144.085593 -342.169213) (xy 144.121307 -342.21043)
			(xy 144.150792 -342.256311) (xy 144.173447 -342.30592) (xy 144.188812 -342.358249) (xy 144.196574 -342.412231)
			(xy 144.196574 -342.466768) (xy 164.913822 -342.466768) (xy 164.913822 -342.412232) (xy 164.921583 -342.35825)
			(xy 164.936947 -342.305923) (xy 164.959602 -342.256314) (xy 164.989085 -342.210434) (xy 165.024797 -342.169217)
			(xy 165.066012 -342.133502) (xy 165.11189 -342.104015) (xy 165.161496 -342.081357) (xy 165.213823 -342.065989)
			(xy 165.267804 -342.058224) (xy 165.295072 -342.057736) (xy 166.158672 -342.057736) (xy 166.185944 -342.058202)
			(xy 166.239934 -342.06596) (xy 166.29227 -342.081324) (xy 166.341886 -342.10398) (xy 166.387773 -342.133467)
			(xy 166.428996 -342.169184) (xy 166.464716 -342.210405) (xy 166.494207 -342.256289) (xy 166.516866 -342.305904)
			(xy 166.532234 -342.358239) (xy 166.539996 -342.412228) (xy 166.539996 -342.466772) (xy 166.539996 -342.466773)
			(xy 168.0227 -342.466773) (xy 168.0227 -342.412227) (xy 168.030463 -342.358237) (xy 168.045831 -342.305902)
			(xy 168.068491 -342.256286) (xy 168.097981 -342.210401) (xy 168.133702 -342.16918) (xy 168.174927 -342.133462)
			(xy 168.220815 -342.103975) (xy 168.270432 -342.081319) (xy 168.322769 -342.065956) (xy 168.376759 -342.058197)
			(xy 168.404032 -342.057736) (xy 169.267632 -342.057736) (xy 169.2949 -342.058229) (xy 169.34888 -342.065994)
			(xy 169.401205 -342.081362) (xy 169.450811 -342.10402) (xy 169.496688 -342.133506) (xy 169.537901 -342.169222)
			(xy 169.573613 -342.210438) (xy 169.603095 -342.256317) (xy 169.625749 -342.305925) (xy 169.641113 -342.358252)
			(xy 169.648874 -342.412232) (xy 169.648874 -342.466768) (xy 169.648874 -342.466769) (xy 171.131722 -342.466769)
			(xy 171.131722 -342.412231) (xy 171.139484 -342.358248) (xy 171.154849 -342.305918) (xy 171.177505 -342.256309)
			(xy 171.20699 -342.210428) (xy 171.242705 -342.16921) (xy 171.283921 -342.133495) (xy 171.329802 -342.104009)
			(xy 171.379411 -342.081352) (xy 171.43174 -342.065986) (xy 171.485723 -342.058223) (xy 171.512992 -342.057736)
			(xy 172.376592 -342.057736) (xy 172.403863 -342.058203) (xy 172.457851 -342.065964) (xy 172.510184 -342.08133)
			(xy 172.559798 -342.103987) (xy 172.605682 -342.133474) (xy 172.646903 -342.169191) (xy 172.682621 -342.210411)
			(xy 172.71211 -342.256295) (xy 172.734768 -342.305908) (xy 172.750134 -342.358241) (xy 172.757896 -342.412229)
			(xy 172.757896 -342.466767) (xy 174.240722 -342.466767) (xy 174.240722 -342.412233) (xy 174.248483 -342.358253)
			(xy 174.263846 -342.305927) (xy 174.286499 -342.25632) (xy 174.31598 -342.210441) (xy 174.35169 -342.169224)
			(xy 174.392902 -342.133509) (xy 174.438778 -342.104022) (xy 174.488382 -342.081363) (xy 174.540706 -342.065993)
			(xy 174.594685 -342.058226) (xy 174.621952 -342.057736) (xy 175.485552 -342.057736) (xy 175.512825 -342.0582)
			(xy 175.566817 -342.065957) (xy 175.619155 -342.081319) (xy 175.668774 -342.103974) (xy 175.714663 -342.13346)
			(xy 175.755889 -342.169177) (xy 175.791612 -342.210398) (xy 175.821103 -342.256284) (xy 175.843764 -342.3059)
			(xy 175.859133 -342.358236) (xy 175.866896 -342.412227) (xy 175.866896 -342.466772) (xy 177.3496 -342.466772)
			(xy 177.3496 -342.412228) (xy 177.357362 -342.35824) (xy 177.372729 -342.305906) (xy 177.395388 -342.256292)
			(xy 177.424876 -342.210407) (xy 177.460595 -342.169187) (xy 177.501817 -342.133469) (xy 177.547703 -342.103982)
			(xy 177.597317 -342.081325) (xy 177.649652 -342.065959) (xy 177.70364 -342.058199) (xy 177.730912 -342.057736)
			(xy 178.594512 -342.057736) (xy 178.621781 -342.058227) (xy 178.675763 -342.06599) (xy 178.728091 -342.081357)
			(xy 178.777699 -342.104013) (xy 178.823578 -342.133499) (xy 178.864794 -342.169214) (xy 178.900508 -342.210432)
			(xy 178.929992 -342.256312) (xy 178.952648 -342.305921) (xy 178.968012 -342.358249) (xy 178.975774 -342.412231)
			(xy 178.975774 -342.466768) (xy 180.458622 -342.466768) (xy 180.458622 -342.412232) (xy 180.466383 -342.35825)
			(xy 180.481747 -342.305923) (xy 180.504402 -342.256314) (xy 180.533885 -342.210434) (xy 180.569597 -342.169217)
			(xy 180.610812 -342.133502) (xy 180.65669 -342.104015) (xy 180.706296 -342.081357) (xy 180.758623 -342.065989)
			(xy 180.812604 -342.058224) (xy 180.839872 -342.057736) (xy 181.703472 -342.057736) (xy 181.730744 -342.058202)
			(xy 181.784734 -342.06596) (xy 181.83707 -342.081324) (xy 181.886686 -342.10398) (xy 181.932573 -342.133467)
			(xy 181.973796 -342.169184) (xy 182.009516 -342.210405) (xy 182.039007 -342.256289) (xy 182.061666 -342.305904)
			(xy 182.077034 -342.358239) (xy 182.084796 -342.412228) (xy 182.084796 -342.466772) (xy 182.084796 -342.466773)
			(xy 183.5675 -342.466773) (xy 183.5675 -342.412227) (xy 183.575263 -342.358237) (xy 183.590631 -342.305902)
			(xy 183.613291 -342.256286) (xy 183.642781 -342.210401) (xy 183.678502 -342.16918) (xy 183.719727 -342.133462)
			(xy 183.765615 -342.103975) (xy 183.815232 -342.081319) (xy 183.867569 -342.065956) (xy 183.921559 -342.058197)
			(xy 183.948832 -342.057736) (xy 184.812432 -342.057736) (xy 184.8397 -342.058229) (xy 184.89368 -342.065994)
			(xy 184.946005 -342.081362) (xy 184.995611 -342.10402) (xy 185.041488 -342.133506) (xy 185.082701 -342.169222)
			(xy 185.118413 -342.210438) (xy 185.147895 -342.256317) (xy 185.170549 -342.305925) (xy 185.185913 -342.358252)
			(xy 185.193674 -342.412232) (xy 185.193674 -342.466768) (xy 185.193674 -342.466769) (xy 186.676522 -342.466769)
			(xy 186.676522 -342.412231) (xy 186.684284 -342.358248) (xy 186.699649 -342.305918) (xy 186.722305 -342.256309)
			(xy 186.75179 -342.210428) (xy 186.787505 -342.16921) (xy 186.828721 -342.133495) (xy 186.874602 -342.104009)
			(xy 186.924211 -342.081352) (xy 186.97654 -342.065986) (xy 187.030523 -342.058223) (xy 187.057792 -342.057736)
			(xy 187.921392 -342.057736) (xy 187.948663 -342.058203) (xy 188.002651 -342.065964) (xy 188.054984 -342.08133)
			(xy 188.104598 -342.103987) (xy 188.150482 -342.133474) (xy 188.191703 -342.169191) (xy 188.227421 -342.210411)
			(xy 188.25691 -342.256295) (xy 188.279568 -342.305908) (xy 188.294934 -342.358241) (xy 188.302696 -342.412229)
			(xy 188.302696 -342.466767) (xy 189.785522 -342.466767) (xy 189.785522 -342.412233) (xy 189.793283 -342.358253)
			(xy 189.808646 -342.305927) (xy 189.831299 -342.25632) (xy 189.86078 -342.210441) (xy 189.89649 -342.169224)
			(xy 189.937702 -342.133509) (xy 189.983578 -342.104022) (xy 190.033182 -342.081363) (xy 190.085506 -342.065993)
			(xy 190.139485 -342.058226) (xy 190.166752 -342.057736) (xy 191.030352 -342.057736) (xy 191.057625 -342.0582)
			(xy 191.111617 -342.065957) (xy 191.163955 -342.081319) (xy 191.213574 -342.103974) (xy 191.259463 -342.13346)
			(xy 191.300689 -342.169177) (xy 191.336412 -342.210398) (xy 191.365903 -342.256284) (xy 191.388564 -342.3059)
			(xy 191.403933 -342.358236) (xy 191.411696 -342.412227) (xy 191.411696 -342.466772) (xy 192.8944 -342.466772)
			(xy 192.8944 -342.412228) (xy 192.902162 -342.35824) (xy 192.917529 -342.305906) (xy 192.940188 -342.256292)
			(xy 192.969676 -342.210407) (xy 193.005395 -342.169187) (xy 193.046617 -342.133469) (xy 193.092503 -342.103982)
			(xy 193.142117 -342.081325) (xy 193.194452 -342.065959) (xy 193.24844 -342.058199) (xy 193.275712 -342.057736)
			(xy 194.139312 -342.057736) (xy 194.166581 -342.058227) (xy 194.220563 -342.06599) (xy 194.272891 -342.081357)
			(xy 194.322499 -342.104013) (xy 194.368378 -342.133499) (xy 194.409594 -342.169214) (xy 194.445308 -342.210432)
			(xy 194.474792 -342.256312) (xy 194.497448 -342.305921) (xy 194.512812 -342.358249) (xy 194.520574 -342.412231)
			(xy 194.520574 -342.466768) (xy 196.003422 -342.466768) (xy 196.003422 -342.412232) (xy 196.011183 -342.35825)
			(xy 196.026547 -342.305923) (xy 196.049202 -342.256314) (xy 196.078685 -342.210434) (xy 196.114397 -342.169217)
			(xy 196.155612 -342.133502) (xy 196.20149 -342.104015) (xy 196.251096 -342.081357) (xy 196.303423 -342.065989)
			(xy 196.357404 -342.058224) (xy 196.384672 -342.057736) (xy 197.248272 -342.057736) (xy 197.275544 -342.058202)
			(xy 197.28821 -342.060022) (xy 255.91262 -342.060022) (xy 255.91262 -341.196422) (xy 255.91311 -341.166438)
			(xy 255.920938 -341.106982) (xy 255.936459 -341.049057) (xy 255.959408 -340.993653) (xy 255.989392 -340.941719)
			(xy 256.025898 -340.894143) (xy 256.068303 -340.851738) (xy 256.115879 -340.815232) (xy 256.167813 -340.785248)
			(xy 256.223217 -340.762299) (xy 256.281142 -340.746778) (xy 256.340598 -340.73895) (xy 256.400566 -340.73895)
			(xy 256.460022 -340.746778) (xy 256.517947 -340.762299) (xy 256.573351 -340.785248) (xy 256.625285 -340.815232)
			(xy 256.672861 -340.851738) (xy 256.715266 -340.894143) (xy 256.751772 -340.941719) (xy 256.781756 -340.993653)
			(xy 256.804705 -341.049057) (xy 256.820226 -341.106982) (xy 256.828054 -341.166438) (xy 256.828544 -341.196422)
			(xy 256.828544 -342.060022) (xy 256.828054 -342.090006) (xy 256.820226 -342.149462) (xy 256.804705 -342.207387)
			(xy 256.781756 -342.262791) (xy 256.751772 -342.314725) (xy 256.715266 -342.362301) (xy 256.672861 -342.404706)
			(xy 256.625285 -342.441212) (xy 256.581015 -342.466771) (xy 267.515799 -342.466771) (xy 267.515799 -342.412229)
			(xy 267.523562 -342.358241) (xy 267.538928 -342.305908) (xy 267.561586 -342.256295) (xy 267.591074 -342.210411)
			(xy 267.626792 -342.16919) (xy 267.668012 -342.133473) (xy 267.713897 -342.103985) (xy 267.76351 -342.081327)
			(xy 267.815843 -342.065961) (xy 267.869831 -342.058199) (xy 267.897102 -342.057736) (xy 268.760702 -342.057736)
			(xy 268.787971 -342.058227) (xy 268.841954 -342.065988) (xy 268.894283 -342.081354) (xy 268.943893 -342.10401)
			(xy 268.989773 -342.133496) (xy 269.030991 -342.169211) (xy 269.066705 -342.210428) (xy 269.096191 -342.256309)
			(xy 269.118847 -342.305919) (xy 269.134212 -342.358248) (xy 269.141974 -342.412231) (xy 269.141974 -342.466768)
			(xy 270.624822 -342.466768) (xy 270.624822 -342.412232) (xy 270.632583 -342.358252) (xy 270.647947 -342.305925)
			(xy 270.6706 -342.256317) (xy 270.700083 -342.210438) (xy 270.735794 -342.169221) (xy 270.777007 -342.133505)
			(xy 270.822884 -342.104018) (xy 270.872489 -342.08136) (xy 270.924814 -342.065991) (xy 270.978794 -342.058225)
			(xy 271.006062 -342.057736) (xy 271.869662 -342.057736) (xy 271.896935 -342.058201) (xy 271.950925 -342.065959)
			(xy 272.003262 -342.081321) (xy 272.05288 -342.103977) (xy 272.098768 -342.133463) (xy 272.139993 -342.16918)
			(xy 272.175714 -342.210401) (xy 272.205205 -342.256287) (xy 272.227865 -342.305902) (xy 272.243233 -342.358237)
			(xy 272.250996 -342.412227) (xy 272.250996 -342.466772) (xy 273.7337 -342.466772) (xy 273.7337 -342.412228)
			(xy 273.741462 -342.358239) (xy 273.75683 -342.305904) (xy 273.779489 -342.256289) (xy 273.808979 -342.210404)
			(xy 273.844699 -342.169183) (xy 273.885922 -342.133466) (xy 273.931809 -342.103979) (xy 273.981425 -342.081322)
			(xy 274.03376 -342.065958) (xy 274.08775 -342.058198) (xy 274.115022 -342.057736) (xy 274.978622 -342.057736)
			(xy 275.00589 -342.058228) (xy 275.059871 -342.065992) (xy 275.112198 -342.081359) (xy 275.161805 -342.104017)
			(xy 275.207683 -342.133503) (xy 275.248898 -342.169218) (xy 275.28461 -342.210435) (xy 275.314094 -342.256314)
			(xy 275.336748 -342.305923) (xy 275.352113 -342.35825) (xy 275.359874 -342.412232) (xy 275.359874 -342.466768)
			(xy 275.359874 -342.466769) (xy 276.842722 -342.466769) (xy 276.842722 -342.412231) (xy 276.850484 -342.358249)
			(xy 276.865848 -342.305921) (xy 276.888503 -342.256311) (xy 276.917987 -342.210431) (xy 276.953701 -342.169214)
			(xy 276.994917 -342.133498) (xy 277.040796 -342.104012) (xy 277.090404 -342.081354) (xy 277.142731 -342.065987)
			(xy 277.196713 -342.058224) (xy 277.223982 -342.057736) (xy 278.087582 -342.057736) (xy 278.114854 -342.058202)
			(xy 278.168842 -342.065962) (xy 278.221177 -342.081327) (xy 278.270792 -342.103983) (xy 278.316678 -342.13347)
			(xy 278.3579 -342.169188) (xy 278.393619 -342.210408) (xy 278.423108 -342.256292) (xy 278.445767 -342.305906)
			(xy 278.461134 -342.35824) (xy 278.468896 -342.412228) (xy 278.468896 -342.466772) (xy 278.468896 -342.466773)
			(xy 279.9516 -342.466773) (xy 279.9516 -342.412227) (xy 279.959363 -342.358236) (xy 279.974731 -342.3059)
			(xy 279.997392 -342.256284) (xy 280.026884 -342.210398) (xy 280.062606 -342.169176) (xy 280.103831 -342.133459)
			(xy 280.14972 -342.103972) (xy 280.199339 -342.081317) (xy 280.251677 -342.065954) (xy 280.305669 -342.058197)
			(xy 280.332942 -342.057736) (xy 281.196542 -342.057736) (xy 281.223809 -342.058229) (xy 281.277788 -342.065996)
			(xy 281.330112 -342.081365) (xy 281.379717 -342.104023) (xy 281.425592 -342.13351) (xy 281.466805 -342.169225)
			(xy 281.502515 -342.210441) (xy 281.531997 -342.25632) (xy 281.55465 -342.305927) (xy 281.570013 -342.358253)
			(xy 281.577774 -342.412233) (xy 281.577774 -342.466767) (xy 281.577773 -342.466771) (xy 283.060599 -342.466771)
			(xy 283.060599 -342.412229) (xy 283.068362 -342.358241) (xy 283.083728 -342.305908) (xy 283.106386 -342.256295)
			(xy 283.135874 -342.210411) (xy 283.171592 -342.16919) (xy 283.212812 -342.133473) (xy 283.258697 -342.103985)
			(xy 283.30831 -342.081327) (xy 283.360643 -342.065961) (xy 283.414631 -342.058199) (xy 283.441902 -342.057736)
			(xy 284.305502 -342.057736) (xy 284.332771 -342.058227) (xy 284.386754 -342.065988) (xy 284.439083 -342.081354)
			(xy 284.488693 -342.10401) (xy 284.534573 -342.133496) (xy 284.575791 -342.169211) (xy 284.611505 -342.210428)
			(xy 284.640991 -342.256309) (xy 284.663647 -342.305919) (xy 284.679012 -342.358248) (xy 284.686774 -342.412231)
			(xy 284.686774 -342.466768) (xy 286.169622 -342.466768) (xy 286.169622 -342.412232) (xy 286.177383 -342.358252)
			(xy 286.192747 -342.305925) (xy 286.2154 -342.256317) (xy 286.244883 -342.210438) (xy 286.280594 -342.169221)
			(xy 286.321807 -342.133505) (xy 286.367684 -342.104018) (xy 286.417289 -342.08136) (xy 286.469614 -342.065991)
			(xy 286.523594 -342.058225) (xy 286.550862 -342.057736) (xy 287.414462 -342.057736) (xy 287.441735 -342.058201)
			(xy 287.495725 -342.065959) (xy 287.548062 -342.081321) (xy 287.59768 -342.103977) (xy 287.643568 -342.133463)
			(xy 287.684793 -342.16918) (xy 287.720514 -342.210401) (xy 287.750005 -342.256287) (xy 287.772665 -342.305902)
			(xy 287.788033 -342.358237) (xy 287.795796 -342.412227) (xy 287.795796 -342.466772) (xy 289.2785 -342.466772)
			(xy 289.2785 -342.412228) (xy 289.286262 -342.358239) (xy 289.30163 -342.305904) (xy 289.324289 -342.256289)
			(xy 289.353779 -342.210404) (xy 289.389499 -342.169183) (xy 289.430722 -342.133466) (xy 289.476609 -342.103979)
			(xy 289.526225 -342.081322) (xy 289.57856 -342.065958) (xy 289.63255 -342.058198) (xy 289.659822 -342.057736)
			(xy 290.523422 -342.057736) (xy 290.55069 -342.058228) (xy 290.604671 -342.065992) (xy 290.656998 -342.081359)
			(xy 290.706605 -342.104017) (xy 290.752483 -342.133503) (xy 290.793698 -342.169218) (xy 290.82941 -342.210435)
			(xy 290.858894 -342.256314) (xy 290.881548 -342.305923) (xy 290.896913 -342.35825) (xy 290.904674 -342.412232)
			(xy 290.904674 -342.466768) (xy 290.904674 -342.466769) (xy 292.387522 -342.466769) (xy 292.387522 -342.412231)
			(xy 292.395284 -342.358249) (xy 292.410648 -342.305921) (xy 292.433303 -342.256311) (xy 292.462787 -342.210431)
			(xy 292.498501 -342.169214) (xy 292.539717 -342.133498) (xy 292.585596 -342.104012) (xy 292.635204 -342.081354)
			(xy 292.687531 -342.065987) (xy 292.741513 -342.058224) (xy 292.768782 -342.057736) (xy 293.632382 -342.057736)
			(xy 293.659654 -342.058202) (xy 293.713642 -342.065962) (xy 293.765977 -342.081327) (xy 293.815592 -342.103983)
			(xy 293.861478 -342.13347) (xy 293.9027 -342.169188) (xy 293.938419 -342.210408) (xy 293.967908 -342.256292)
			(xy 293.990567 -342.305906) (xy 294.005934 -342.35824) (xy 294.013696 -342.412228) (xy 294.013696 -342.466772)
			(xy 294.013696 -342.466773) (xy 295.4964 -342.466773) (xy 295.4964 -342.412227) (xy 295.504163 -342.358236)
			(xy 295.519531 -342.3059) (xy 295.542192 -342.256284) (xy 295.571684 -342.210398) (xy 295.607406 -342.169176)
			(xy 295.648631 -342.133459) (xy 295.69452 -342.103972) (xy 295.744139 -342.081317) (xy 295.796477 -342.065954)
			(xy 295.850469 -342.058197) (xy 295.877742 -342.057736) (xy 296.741342 -342.057736) (xy 296.768609 -342.058229)
			(xy 296.822588 -342.065996) (xy 296.874912 -342.081365) (xy 296.924517 -342.104023) (xy 296.970392 -342.13351)
			(xy 297.011605 -342.169225) (xy 297.047315 -342.210441) (xy 297.076797 -342.25632) (xy 297.09945 -342.305927)
			(xy 297.114813 -342.358253) (xy 297.122574 -342.412233) (xy 297.122574 -342.466767) (xy 297.122573 -342.466771)
			(xy 298.605399 -342.466771) (xy 298.605399 -342.412229) (xy 298.613162 -342.358241) (xy 298.628528 -342.305908)
			(xy 298.651186 -342.256295) (xy 298.680674 -342.210411) (xy 298.716392 -342.16919) (xy 298.757612 -342.133473)
			(xy 298.803497 -342.103985) (xy 298.85311 -342.081327) (xy 298.905443 -342.065961) (xy 298.959431 -342.058199)
			(xy 298.986702 -342.057736) (xy 299.850302 -342.057736) (xy 299.877571 -342.058227) (xy 299.931554 -342.065988)
			(xy 299.983883 -342.081354) (xy 300.033493 -342.10401) (xy 300.079373 -342.133496) (xy 300.120591 -342.169211)
			(xy 300.156305 -342.210428) (xy 300.185791 -342.256309) (xy 300.208447 -342.305919) (xy 300.223812 -342.358248)
			(xy 300.231574 -342.412231) (xy 300.231574 -342.466769) (xy 300.231574 -342.466771) (xy 312.1215 -342.466771)
			(xy 312.1215 -342.412229) (xy 312.129262 -342.358241) (xy 312.144628 -342.305908) (xy 312.167286 -342.256294)
			(xy 312.196774 -342.21041) (xy 312.232493 -342.16919) (xy 312.273713 -342.133472) (xy 312.319598 -342.103984)
			(xy 312.369212 -342.081327) (xy 312.421545 -342.065961) (xy 312.475533 -342.058199) (xy 312.502804 -342.057736)
			(xy 313.366404 -342.057736) (xy 313.393673 -342.058227) (xy 313.447656 -342.065989) (xy 313.499985 -342.081354)
			(xy 313.549594 -342.104011) (xy 313.595474 -342.133497) (xy 313.636691 -342.169212) (xy 313.672406 -342.210429)
			(xy 313.701891 -342.256309) (xy 313.724547 -342.305919) (xy 313.739912 -342.358248) (xy 313.747674 -342.412231)
			(xy 313.747674 -342.466768) (xy 315.230522 -342.466768) (xy 315.230522 -342.412232) (xy 315.238283 -342.358251)
			(xy 315.253647 -342.305924) (xy 315.2763 -342.256316) (xy 315.305783 -342.210437) (xy 315.341495 -342.16922)
			(xy 315.382708 -342.133505) (xy 315.428585 -342.104018) (xy 315.478191 -342.081359) (xy 315.530516 -342.065991)
			(xy 315.584496 -342.058225) (xy 315.611764 -342.057736) (xy 316.475364 -342.057736) (xy 316.502637 -342.058201)
			(xy 316.556627 -342.065959) (xy 316.608964 -342.081322) (xy 316.658581 -342.103977) (xy 316.704469 -342.133464)
			(xy 316.745693 -342.169181) (xy 316.781414 -342.210402) (xy 316.810905 -342.256287) (xy 316.833565 -342.305902)
			(xy 316.848933 -342.358238) (xy 316.856696 -342.412228) (xy 316.856696 -342.466772) (xy 318.3394 -342.466772)
			(xy 318.3394 -342.412228) (xy 318.347162 -342.358239) (xy 318.36253 -342.305904) (xy 318.385189 -342.256289)
			(xy 318.414679 -342.210404) (xy 318.4504 -342.169183) (xy 318.491623 -342.133465) (xy 318.53751 -342.103978)
			(xy 318.587126 -342.081322) (xy 318.639462 -342.065957) (xy 318.693452 -342.058198) (xy 318.720724 -342.057736)
			(xy 319.584324 -342.057736) (xy 319.611592 -342.058228) (xy 319.665573 -342.065992) (xy 319.717899 -342.08136)
			(xy 319.767506 -342.104017) (xy 319.813384 -342.133504) (xy 319.854598 -342.169219) (xy 319.890311 -342.210435)
			(xy 319.919794 -342.256315) (xy 319.942449 -342.305923) (xy 319.957813 -342.358251) (xy 319.965574 -342.412232)
			(xy 319.965574 -342.466768) (xy 319.965574 -342.466769) (xy 321.448422 -342.466769) (xy 321.448422 -342.412231)
			(xy 321.456184 -342.358249) (xy 321.471548 -342.30592) (xy 321.494203 -342.256311) (xy 321.523688 -342.21043)
			(xy 321.559402 -342.169213) (xy 321.600618 -342.133498) (xy 321.646497 -342.104011) (xy 321.696105 -342.081354)
			(xy 321.748433 -342.065987) (xy 321.802415 -342.058224) (xy 321.829684 -342.057736) (xy 322.693284 -342.057736)
			(xy 322.720556 -342.058202) (xy 322.774544 -342.065963) (xy 322.826878 -342.081327) (xy 322.876493 -342.103984)
			(xy 322.922379 -342.133471) (xy 322.9636 -342.169188) (xy 322.999319 -342.210409) (xy 323.028808 -342.256293)
			(xy 323.051467 -342.305907) (xy 323.066834 -342.35824) (xy 323.074596 -342.412228) (xy 323.074596 -342.466772)
			(xy 323.074596 -342.466773) (xy 324.5573 -342.466773) (xy 324.5573 -342.412227) (xy 324.565063 -342.358236)
			(xy 324.580432 -342.305899) (xy 324.603092 -342.256283) (xy 324.632584 -342.210397) (xy 324.668307 -342.169176)
			(xy 324.709532 -342.133458) (xy 324.755422 -342.103971) (xy 324.805041 -342.081316) (xy 324.857379 -342.065954)
			(xy 324.911371 -342.058196) (xy 324.938644 -342.057736) (xy 325.802244 -342.057736) (xy 325.829511 -342.058229)
			(xy 325.88349 -342.065996) (xy 325.935814 -342.081365) (xy 325.985418 -342.104024) (xy 326.031293 -342.133511)
			(xy 326.072505 -342.169226) (xy 326.108216 -342.210442) (xy 326.137697 -342.256321) (xy 326.16035 -342.305928)
			(xy 326.175713 -342.358253) (xy 326.183474 -342.412233) (xy 326.183474 -342.466767) (xy 326.183473 -342.466771)
			(xy 327.6663 -342.466771) (xy 327.6663 -342.412229) (xy 327.674062 -342.358241) (xy 327.689428 -342.305908)
			(xy 327.712086 -342.256294) (xy 327.741574 -342.21041) (xy 327.777293 -342.16919) (xy 327.818513 -342.133472)
			(xy 327.864398 -342.103984) (xy 327.914012 -342.081327) (xy 327.966345 -342.065961) (xy 328.020333 -342.058199)
			(xy 328.047604 -342.057736) (xy 328.911204 -342.057736) (xy 328.938473 -342.058227) (xy 328.992456 -342.065989)
			(xy 329.044785 -342.081354) (xy 329.094394 -342.104011) (xy 329.140274 -342.133497) (xy 329.181491 -342.169212)
			(xy 329.217206 -342.210429) (xy 329.246691 -342.256309) (xy 329.269347 -342.305919) (xy 329.284712 -342.358248)
			(xy 329.292474 -342.412231) (xy 329.292474 -342.466768) (xy 330.775322 -342.466768) (xy 330.775322 -342.412232)
			(xy 330.783083 -342.358251) (xy 330.798447 -342.305924) (xy 330.8211 -342.256316) (xy 330.850583 -342.210437)
			(xy 330.886295 -342.16922) (xy 330.927508 -342.133505) (xy 330.973385 -342.104018) (xy 331.022991 -342.081359)
			(xy 331.075316 -342.065991) (xy 331.129296 -342.058225) (xy 331.156564 -342.057736) (xy 332.020164 -342.057736)
			(xy 332.047437 -342.058201) (xy 332.101427 -342.065959) (xy 332.153764 -342.081322) (xy 332.203381 -342.103977)
			(xy 332.249269 -342.133464) (xy 332.290493 -342.169181) (xy 332.326214 -342.210402) (xy 332.355705 -342.256287)
			(xy 332.378365 -342.305902) (xy 332.393733 -342.358238) (xy 332.401496 -342.412228) (xy 332.401496 -342.466772)
			(xy 333.8842 -342.466772) (xy 333.8842 -342.412228) (xy 333.891962 -342.358239) (xy 333.90733 -342.305904)
			(xy 333.929989 -342.256289) (xy 333.959479 -342.210404) (xy 333.9952 -342.169183) (xy 334.036423 -342.133465)
			(xy 334.08231 -342.103978) (xy 334.131926 -342.081322) (xy 334.184262 -342.065957) (xy 334.238252 -342.058198)
			(xy 334.265524 -342.057736) (xy 335.129124 -342.057736) (xy 335.156392 -342.058228) (xy 335.210373 -342.065992)
			(xy 335.262699 -342.08136) (xy 335.312306 -342.104017) (xy 335.358184 -342.133504) (xy 335.399398 -342.169219)
			(xy 335.435111 -342.210435) (xy 335.464594 -342.256315) (xy 335.487249 -342.305923) (xy 335.502613 -342.358251)
			(xy 335.510374 -342.412232) (xy 335.510374 -342.466768) (xy 335.510374 -342.466769) (xy 336.993222 -342.466769)
			(xy 336.993222 -342.412231) (xy 337.000984 -342.358249) (xy 337.016348 -342.30592) (xy 337.039003 -342.256311)
			(xy 337.068488 -342.21043) (xy 337.104202 -342.169213) (xy 337.145418 -342.133498) (xy 337.191297 -342.104011)
			(xy 337.240905 -342.081354) (xy 337.293233 -342.065987) (xy 337.347215 -342.058224) (xy 337.374484 -342.057736)
			(xy 338.238084 -342.057736) (xy 338.265356 -342.058202) (xy 338.319344 -342.065963) (xy 338.371678 -342.081327)
			(xy 338.421293 -342.103984) (xy 338.467179 -342.133471) (xy 338.5084 -342.169188) (xy 338.544119 -342.210409)
			(xy 338.573608 -342.256293) (xy 338.596267 -342.305907) (xy 338.611634 -342.35824) (xy 338.619396 -342.412228)
			(xy 338.619396 -342.466772) (xy 338.619396 -342.466773) (xy 340.1021 -342.466773) (xy 340.1021 -342.412227)
			(xy 340.109863 -342.358236) (xy 340.125232 -342.305899) (xy 340.147892 -342.256283) (xy 340.177384 -342.210397)
			(xy 340.213107 -342.169176) (xy 340.254332 -342.133458) (xy 340.300222 -342.103971) (xy 340.349841 -342.081316)
			(xy 340.402179 -342.065954) (xy 340.456171 -342.058196) (xy 340.483444 -342.057736) (xy 341.347044 -342.057736)
			(xy 341.374311 -342.058229) (xy 341.42829 -342.065996) (xy 341.480614 -342.081365) (xy 341.530218 -342.104024)
			(xy 341.576093 -342.133511) (xy 341.617305 -342.169226) (xy 341.653016 -342.210442) (xy 341.682497 -342.256321)
			(xy 341.70515 -342.305928) (xy 341.720513 -342.358253) (xy 341.728274 -342.412233) (xy 341.728274 -342.466767)
			(xy 341.728273 -342.466771) (xy 343.2111 -342.466771) (xy 343.2111 -342.412229) (xy 343.218862 -342.358241)
			(xy 343.234228 -342.305908) (xy 343.256886 -342.256294) (xy 343.286374 -342.21041) (xy 343.322093 -342.16919)
			(xy 343.363313 -342.133472) (xy 343.409198 -342.103984) (xy 343.458812 -342.081327) (xy 343.511145 -342.065961)
			(xy 343.565133 -342.058199) (xy 343.592404 -342.057736) (xy 344.456004 -342.057736) (xy 344.483273 -342.058227)
			(xy 344.537256 -342.065989) (xy 344.589585 -342.081354) (xy 344.639194 -342.104011) (xy 344.685074 -342.133497)
			(xy 344.726291 -342.169212) (xy 344.762006 -342.210429) (xy 344.791491 -342.256309) (xy 344.814147 -342.305919)
			(xy 344.829512 -342.358248) (xy 344.837274 -342.412231) (xy 344.837274 -342.466769) (xy 370.806722 -342.466769)
			(xy 370.806722 -342.412231) (xy 370.814484 -342.358249) (xy 370.829848 -342.305921) (xy 370.852503 -342.256312)
			(xy 370.881987 -342.210432) (xy 370.9177 -342.169214) (xy 370.958916 -342.133499) (xy 371.004794 -342.104012)
			(xy 371.054402 -342.081355) (xy 371.10673 -342.065988) (xy 371.160711 -342.058224) (xy 371.18798 -342.057736)
			(xy 372.05158 -342.057736) (xy 372.078852 -342.058202) (xy 372.132841 -342.065962) (xy 372.185175 -342.081326)
			(xy 372.234791 -342.103983) (xy 372.280677 -342.13347) (xy 372.321899 -342.169187) (xy 372.357618 -342.210407)
			(xy 372.387108 -342.256292) (xy 372.409767 -342.305906) (xy 372.425134 -342.35824) (xy 372.432896 -342.412228)
			(xy 372.432896 -342.466772) (xy 372.432896 -342.466773) (xy 373.9156 -342.466773) (xy 373.9156 -342.412227)
			(xy 373.923363 -342.358236) (xy 373.938731 -342.3059) (xy 373.961392 -342.256284) (xy 373.990883 -342.210398)
			(xy 374.026605 -342.169177) (xy 374.06783 -342.133459) (xy 374.113719 -342.103973) (xy 374.163338 -342.081317)
			(xy 374.215676 -342.065954) (xy 374.269667 -342.058197) (xy 374.29694 -342.057736) (xy 375.16054 -342.057736)
			(xy 375.187807 -342.058229) (xy 375.241786 -342.065995) (xy 375.294111 -342.081364) (xy 375.343716 -342.104022)
			(xy 375.389591 -342.133509) (xy 375.430804 -342.169224) (xy 375.466515 -342.210441) (xy 375.495997 -342.256319)
			(xy 375.51865 -342.305927) (xy 375.534013 -342.358253) (xy 375.541774 -342.412233) (xy 375.541774 -342.466767)
			(xy 375.541774 -342.46677) (xy 377.024622 -342.46677) (xy 377.024622 -342.41223) (xy 377.032384 -342.358247)
			(xy 377.04775 -342.305917) (xy 377.070406 -342.256306) (xy 377.099892 -342.210425) (xy 377.135607 -342.169207)
			(xy 377.176825 -342.133492) (xy 377.222706 -342.104006) (xy 377.272317 -342.08135) (xy 377.324647 -342.065984)
			(xy 377.37863 -342.058222) (xy 377.4059 -342.057736) (xy 378.2695 -342.057736) (xy 378.296769 -342.058226)
			(xy 378.350753 -342.065988) (xy 378.403082 -342.081353) (xy 378.452692 -342.104009) (xy 378.498572 -342.133495)
			(xy 378.53979 -342.16921) (xy 378.575505 -342.210428) (xy 378.604991 -342.256308) (xy 378.627647 -342.305918)
			(xy 378.643012 -342.358247) (xy 378.650774 -342.412231) (xy 378.650774 -342.466768) (xy 380.133622 -342.466768)
			(xy 380.133622 -342.412232) (xy 380.141383 -342.358252) (xy 380.156746 -342.305925) (xy 380.1794 -342.256318)
			(xy 380.208882 -342.210438) (xy 380.244593 -342.169222) (xy 380.285806 -342.133506) (xy 380.331682 -342.104019)
			(xy 380.381288 -342.08136) (xy 380.433613 -342.065991) (xy 380.487592 -342.058225) (xy 380.51486 -342.057736)
			(xy 381.37846 -342.057736) (xy 381.405733 -342.058201) (xy 381.459724 -342.065958) (xy 381.512061 -342.081321)
			(xy 381.561679 -342.103976) (xy 381.607567 -342.133463) (xy 381.648792 -342.16918) (xy 381.684513 -342.210401)
			(xy 381.714005 -342.256286) (xy 381.736665 -342.305902) (xy 381.752033 -342.358237) (xy 381.759796 -342.412227)
			(xy 381.759796 -342.466772) (xy 383.2425 -342.466772) (xy 383.2425 -342.412228) (xy 383.250262 -342.358239)
			(xy 383.26563 -342.305904) (xy 383.288289 -342.25629) (xy 383.317778 -342.210405) (xy 383.353498 -342.169184)
			(xy 383.394721 -342.133466) (xy 383.440607 -342.103979) (xy 383.490223 -342.081323) (xy 383.542559 -342.065958)
			(xy 383.596548 -342.058198) (xy 383.62382 -342.057736) (xy 384.48742 -342.057736) (xy 384.514688 -342.058228)
			(xy 384.568669 -342.065992) (xy 384.620996 -342.081359) (xy 384.670604 -342.104016) (xy 384.716482 -342.133502)
			(xy 384.757697 -342.169217) (xy 384.79341 -342.210434) (xy 384.822894 -342.256314) (xy 384.845548 -342.305922)
			(xy 384.860913 -342.35825) (xy 384.868674 -342.412232) (xy 384.868674 -342.466768) (xy 384.868674 -342.466769)
			(xy 386.351522 -342.466769) (xy 386.351522 -342.412231) (xy 386.359284 -342.358249) (xy 386.374648 -342.305921)
			(xy 386.397303 -342.256312) (xy 386.426787 -342.210432) (xy 386.4625 -342.169214) (xy 386.503716 -342.133499)
			(xy 386.549594 -342.104012) (xy 386.599202 -342.081355) (xy 386.65153 -342.065988) (xy 386.705511 -342.058224)
			(xy 386.73278 -342.057736) (xy 387.59638 -342.057736) (xy 387.623652 -342.058202) (xy 387.677641 -342.065962)
			(xy 387.729975 -342.081326) (xy 387.779591 -342.103983) (xy 387.825477 -342.13347) (xy 387.866699 -342.169187)
			(xy 387.902418 -342.210407) (xy 387.931908 -342.256292) (xy 387.954567 -342.305906) (xy 387.969934 -342.35824)
			(xy 387.977696 -342.412228) (xy 387.977696 -342.466772) (xy 387.977696 -342.466773) (xy 389.4604 -342.466773)
			(xy 389.4604 -342.412227) (xy 389.468163 -342.358236) (xy 389.483531 -342.3059) (xy 389.506192 -342.256284)
			(xy 389.535683 -342.210398) (xy 389.571405 -342.169177) (xy 389.61263 -342.133459) (xy 389.658519 -342.103973)
			(xy 389.708138 -342.081317) (xy 389.760476 -342.065954) (xy 389.814467 -342.058197) (xy 389.84174 -342.057736)
			(xy 390.70534 -342.057736) (xy 390.732607 -342.058229) (xy 390.786586 -342.065995) (xy 390.838911 -342.081364)
			(xy 390.888516 -342.104022) (xy 390.934391 -342.133509) (xy 390.975604 -342.169224) (xy 391.011315 -342.210441)
			(xy 391.040797 -342.256319) (xy 391.06345 -342.305927) (xy 391.078813 -342.358253) (xy 391.086574 -342.412233)
			(xy 391.086574 -342.466767) (xy 391.086574 -342.46677) (xy 392.569422 -342.46677) (xy 392.569422 -342.41223)
			(xy 392.577184 -342.358247) (xy 392.59255 -342.305917) (xy 392.615206 -342.256306) (xy 392.644692 -342.210425)
			(xy 392.680407 -342.169207) (xy 392.721625 -342.133492) (xy 392.767506 -342.104006) (xy 392.817117 -342.08135)
			(xy 392.869447 -342.065984) (xy 392.92343 -342.058222) (xy 392.9507 -342.057736) (xy 393.8143 -342.057736)
			(xy 393.841569 -342.058226) (xy 393.895553 -342.065988) (xy 393.947882 -342.081353) (xy 393.997492 -342.104009)
			(xy 394.043372 -342.133495) (xy 394.08459 -342.16921) (xy 394.120305 -342.210428) (xy 394.149791 -342.256308)
			(xy 394.172447 -342.305918) (xy 394.187812 -342.358247) (xy 394.195574 -342.412231) (xy 394.195574 -342.466768)
			(xy 395.678422 -342.466768) (xy 395.678422 -342.412232) (xy 395.686183 -342.358252) (xy 395.701546 -342.305925)
			(xy 395.7242 -342.256318) (xy 395.753682 -342.210438) (xy 395.789393 -342.169222) (xy 395.830606 -342.133506)
			(xy 395.876482 -342.104019) (xy 395.926088 -342.08136) (xy 395.978413 -342.065991) (xy 396.032392 -342.058225)
			(xy 396.05966 -342.057736) (xy 396.92326 -342.057736) (xy 396.950533 -342.058201) (xy 397.004524 -342.065958)
			(xy 397.056861 -342.081321) (xy 397.106479 -342.103976) (xy 397.152367 -342.133463) (xy 397.193592 -342.16918)
			(xy 397.229313 -342.210401) (xy 397.258805 -342.256286) (xy 397.281465 -342.305902) (xy 397.296833 -342.358237)
			(xy 397.304596 -342.412227) (xy 397.304596 -342.466772) (xy 398.7873 -342.466772) (xy 398.7873 -342.412228)
			(xy 398.795062 -342.358239) (xy 398.81043 -342.305904) (xy 398.833089 -342.25629) (xy 398.862578 -342.210405)
			(xy 398.898298 -342.169184) (xy 398.939521 -342.133466) (xy 398.985407 -342.103979) (xy 399.035023 -342.081323)
			(xy 399.087359 -342.065958) (xy 399.141348 -342.058198) (xy 399.16862 -342.057736) (xy 400.03222 -342.057736)
			(xy 400.059488 -342.058228) (xy 400.113469 -342.065992) (xy 400.165796 -342.081359) (xy 400.215404 -342.104016)
			(xy 400.261282 -342.133502) (xy 400.302497 -342.169217) (xy 400.33821 -342.210434) (xy 400.367694 -342.256314)
			(xy 400.390348 -342.305922) (xy 400.405713 -342.35825) (xy 400.413474 -342.412232) (xy 400.413474 -342.466768)
			(xy 400.413474 -342.466769) (xy 401.896322 -342.466769) (xy 401.896322 -342.412231) (xy 401.904084 -342.358249)
			(xy 401.919448 -342.305921) (xy 401.942103 -342.256312) (xy 401.971587 -342.210432) (xy 402.0073 -342.169214)
			(xy 402.048516 -342.133499) (xy 402.094394 -342.104012) (xy 402.144002 -342.081355) (xy 402.19633 -342.065988)
			(xy 402.250311 -342.058224) (xy 402.27758 -342.057736) (xy 403.14118 -342.057736) (xy 403.168452 -342.058202)
			(xy 403.222441 -342.065962) (xy 403.274775 -342.081326) (xy 403.324391 -342.103983) (xy 403.370277 -342.13347)
			(xy 403.411499 -342.169187) (xy 403.447218 -342.210407) (xy 403.476708 -342.256292) (xy 403.499367 -342.305906)
			(xy 403.514734 -342.35824) (xy 403.522496 -342.412228) (xy 403.522496 -342.466769) (xy 408.913822 -342.466769)
			(xy 408.913822 -342.412231) (xy 408.921584 -342.358248) (xy 408.936949 -342.305918) (xy 408.959605 -342.256309)
			(xy 408.98909 -342.210428) (xy 409.024805 -342.16921) (xy 409.066021 -342.133495) (xy 409.111902 -342.104009)
			(xy 409.161511 -342.081352) (xy 409.21384 -342.065986) (xy 409.267823 -342.058223) (xy 409.295092 -342.057736)
			(xy 410.158692 -342.057736) (xy 410.185963 -342.058203) (xy 410.239951 -342.065964) (xy 410.292284 -342.08133)
			(xy 410.341898 -342.103987) (xy 410.387782 -342.133474) (xy 410.429003 -342.169191) (xy 410.464721 -342.210411)
			(xy 410.49421 -342.256295) (xy 410.516868 -342.305908) (xy 410.532234 -342.358241) (xy 410.539996 -342.412229)
			(xy 410.539996 -342.466767) (xy 412.022822 -342.466767) (xy 412.022822 -342.412233) (xy 412.030583 -342.358253)
			(xy 412.045946 -342.305927) (xy 412.068599 -342.25632) (xy 412.09808 -342.210441) (xy 412.13379 -342.169224)
			(xy 412.175002 -342.133509) (xy 412.220878 -342.104022) (xy 412.270482 -342.081363) (xy 412.322806 -342.065993)
			(xy 412.376785 -342.058226) (xy 412.404052 -342.057736) (xy 413.267652 -342.057736) (xy 413.294925 -342.0582)
			(xy 413.348917 -342.065957) (xy 413.401255 -342.081319) (xy 413.450874 -342.103974) (xy 413.496763 -342.13346)
			(xy 413.537989 -342.169177) (xy 413.573712 -342.210398) (xy 413.603203 -342.256284) (xy 413.625864 -342.3059)
			(xy 413.641233 -342.358236) (xy 413.648996 -342.412227) (xy 413.648996 -342.466772) (xy 415.1317 -342.466772)
			(xy 415.1317 -342.412228) (xy 415.139462 -342.35824) (xy 415.154829 -342.305906) (xy 415.177488 -342.256292)
			(xy 415.206976 -342.210407) (xy 415.242695 -342.169187) (xy 415.283917 -342.133469) (xy 415.329803 -342.103982)
			(xy 415.379417 -342.081325) (xy 415.431752 -342.065959) (xy 415.48574 -342.058199) (xy 415.513012 -342.057736)
			(xy 416.376612 -342.057736) (xy 416.403881 -342.058227) (xy 416.457863 -342.06599) (xy 416.510191 -342.081357)
			(xy 416.559799 -342.104013) (xy 416.605678 -342.133499) (xy 416.646894 -342.169214) (xy 416.682608 -342.210432)
			(xy 416.712092 -342.256312) (xy 416.734748 -342.305921) (xy 416.750112 -342.358249) (xy 416.757874 -342.412231)
			(xy 416.757874 -342.466768) (xy 418.240722 -342.466768) (xy 418.240722 -342.412232) (xy 418.248483 -342.35825)
			(xy 418.263847 -342.305923) (xy 418.286502 -342.256314) (xy 418.315985 -342.210434) (xy 418.351697 -342.169217)
			(xy 418.392912 -342.133502) (xy 418.43879 -342.104015) (xy 418.488396 -342.081357) (xy 418.540723 -342.065989)
			(xy 418.594704 -342.058224) (xy 418.621972 -342.057736) (xy 419.485572 -342.057736) (xy 419.512844 -342.058202)
			(xy 419.566834 -342.06596) (xy 419.61917 -342.081324) (xy 419.668786 -342.10398) (xy 419.714673 -342.133467)
			(xy 419.755896 -342.169184) (xy 419.791616 -342.210405) (xy 419.821107 -342.256289) (xy 419.843766 -342.305904)
			(xy 419.859134 -342.358239) (xy 419.866896 -342.412228) (xy 419.866896 -342.466772) (xy 419.866896 -342.466773)
			(xy 421.3496 -342.466773) (xy 421.3496 -342.412227) (xy 421.357363 -342.358237) (xy 421.372731 -342.305902)
			(xy 421.395391 -342.256286) (xy 421.424881 -342.210401) (xy 421.460602 -342.16918) (xy 421.501827 -342.133462)
			(xy 421.547715 -342.103975) (xy 421.597332 -342.081319) (xy 421.649669 -342.065956) (xy 421.703659 -342.058197)
			(xy 421.730932 -342.057736) (xy 422.594532 -342.057736) (xy 422.6218 -342.058229) (xy 422.67578 -342.065994)
			(xy 422.728105 -342.081362) (xy 422.777711 -342.10402) (xy 422.823588 -342.133506) (xy 422.864801 -342.169222)
			(xy 422.900513 -342.210438) (xy 422.929995 -342.256317) (xy 422.952649 -342.305925) (xy 422.968013 -342.358252)
			(xy 422.975774 -342.412232) (xy 422.975774 -342.466768) (xy 422.975774 -342.466769) (xy 424.458622 -342.466769)
			(xy 424.458622 -342.412231) (xy 424.466384 -342.358248) (xy 424.481749 -342.305918) (xy 424.504405 -342.256309)
			(xy 424.53389 -342.210428) (xy 424.569605 -342.16921) (xy 424.610821 -342.133495) (xy 424.656702 -342.104009)
			(xy 424.706311 -342.081352) (xy 424.75864 -342.065986) (xy 424.812623 -342.058223) (xy 424.839892 -342.057736)
			(xy 425.703492 -342.057736) (xy 425.730763 -342.058203) (xy 425.784751 -342.065964) (xy 425.837084 -342.08133)
			(xy 425.886698 -342.103987) (xy 425.932582 -342.133474) (xy 425.973803 -342.169191) (xy 426.009521 -342.210411)
			(xy 426.03901 -342.256295) (xy 426.061668 -342.305908) (xy 426.077034 -342.358241) (xy 426.084796 -342.412229)
			(xy 426.084796 -342.466767) (xy 427.567622 -342.466767) (xy 427.567622 -342.412233) (xy 427.575383 -342.358253)
			(xy 427.590746 -342.305927) (xy 427.613399 -342.25632) (xy 427.64288 -342.210441) (xy 427.67859 -342.169224)
			(xy 427.719802 -342.133509) (xy 427.765678 -342.104022) (xy 427.815282 -342.081363) (xy 427.867606 -342.065993)
			(xy 427.921585 -342.058226) (xy 427.948852 -342.057736) (xy 428.812452 -342.057736) (xy 428.839725 -342.0582)
			(xy 428.893717 -342.065957) (xy 428.946055 -342.081319) (xy 428.995674 -342.103974) (xy 429.041563 -342.13346)
			(xy 429.082789 -342.169177) (xy 429.118512 -342.210398) (xy 429.148003 -342.256284) (xy 429.170664 -342.3059)
			(xy 429.186033 -342.358236) (xy 429.193796 -342.412227) (xy 429.193796 -342.466772) (xy 430.6765 -342.466772)
			(xy 430.6765 -342.412228) (xy 430.684262 -342.35824) (xy 430.699629 -342.305906) (xy 430.722288 -342.256292)
			(xy 430.751776 -342.210407) (xy 430.787495 -342.169187) (xy 430.828717 -342.133469) (xy 430.874603 -342.103982)
			(xy 430.924217 -342.081325) (xy 430.976552 -342.065959) (xy 431.03054 -342.058199) (xy 431.057812 -342.057736)
			(xy 431.921412 -342.057736) (xy 431.948681 -342.058227) (xy 432.002663 -342.06599) (xy 432.054991 -342.081357)
			(xy 432.104599 -342.104013) (xy 432.150478 -342.133499) (xy 432.191694 -342.169214) (xy 432.227408 -342.210432)
			(xy 432.256892 -342.256312) (xy 432.279548 -342.305921) (xy 432.294912 -342.358249) (xy 432.302674 -342.412231)
			(xy 432.302674 -342.466768) (xy 433.785522 -342.466768) (xy 433.785522 -342.412232) (xy 433.793283 -342.35825)
			(xy 433.808647 -342.305923) (xy 433.831302 -342.256314) (xy 433.860785 -342.210434) (xy 433.896497 -342.169217)
			(xy 433.937712 -342.133502) (xy 433.98359 -342.104015) (xy 434.033196 -342.081357) (xy 434.085523 -342.065989)
			(xy 434.139504 -342.058224) (xy 434.166772 -342.057736) (xy 435.030372 -342.057736) (xy 435.057644 -342.058202)
			(xy 435.111634 -342.06596) (xy 435.16397 -342.081324) (xy 435.213586 -342.10398) (xy 435.259473 -342.133467)
			(xy 435.300696 -342.169184) (xy 435.336416 -342.210405) (xy 435.365907 -342.256289) (xy 435.388566 -342.305904)
			(xy 435.403934 -342.358239) (xy 435.411696 -342.412228) (xy 435.411696 -342.466772) (xy 435.411696 -342.466773)
			(xy 436.8944 -342.466773) (xy 436.8944 -342.412227) (xy 436.902163 -342.358237) (xy 436.917531 -342.305902)
			(xy 436.940191 -342.256286) (xy 436.969681 -342.210401) (xy 437.005402 -342.16918) (xy 437.046627 -342.133462)
			(xy 437.092515 -342.103975) (xy 437.142132 -342.081319) (xy 437.194469 -342.065956) (xy 437.248459 -342.058197)
			(xy 437.275732 -342.057736) (xy 438.139332 -342.057736) (xy 438.1666 -342.058229) (xy 438.22058 -342.065994)
			(xy 438.272905 -342.081362) (xy 438.322511 -342.10402) (xy 438.368388 -342.133506) (xy 438.409601 -342.169222)
			(xy 438.445313 -342.210438) (xy 438.474795 -342.256317) (xy 438.497449 -342.305925) (xy 438.512813 -342.358252)
			(xy 438.520574 -342.412232) (xy 438.520574 -342.466768) (xy 438.520574 -342.466769) (xy 440.003422 -342.466769)
			(xy 440.003422 -342.412231) (xy 440.011184 -342.358248) (xy 440.026549 -342.305918) (xy 440.049205 -342.256309)
			(xy 440.07869 -342.210428) (xy 440.114405 -342.16921) (xy 440.155621 -342.133495) (xy 440.201502 -342.104009)
			(xy 440.251111 -342.081352) (xy 440.30344 -342.065986) (xy 440.357423 -342.058223) (xy 440.384692 -342.057736)
			(xy 441.248292 -342.057736) (xy 441.275563 -342.058203) (xy 441.329551 -342.065964) (xy 441.381884 -342.08133)
			(xy 441.431498 -342.103987) (xy 441.477382 -342.133474) (xy 441.518603 -342.169191) (xy 441.554321 -342.210411)
			(xy 441.58381 -342.256295) (xy 441.606468 -342.305908) (xy 441.621834 -342.358241) (xy 441.629596 -342.412229)
			(xy 441.629596 -342.466771) (xy 441.621834 -342.520759) (xy 441.606468 -342.573092) (xy 441.58381 -342.622705)
			(xy 441.554321 -342.668589) (xy 441.518603 -342.709809) (xy 441.477382 -342.745526) (xy 441.431498 -342.775013)
			(xy 441.381884 -342.79767) (xy 441.329551 -342.813036) (xy 441.275563 -342.820797) (xy 441.248292 -342.82126)
			(xy 440.384692 -342.82126) (xy 440.357423 -342.820777) (xy 440.30344 -342.813014) (xy 440.251111 -342.797648)
			(xy 440.201502 -342.774991) (xy 440.155621 -342.745505) (xy 440.114405 -342.70979) (xy 440.07869 -342.668572)
			(xy 440.049205 -342.622691) (xy 440.026549 -342.573082) (xy 440.011184 -342.520752) (xy 440.003422 -342.466769)
			(xy 438.520574 -342.466769) (xy 438.512813 -342.520748) (xy 438.497449 -342.573075) (xy 438.474795 -342.622683)
			(xy 438.445313 -342.668562) (xy 438.409601 -342.709778) (xy 438.368388 -342.745494) (xy 438.322511 -342.77498)
			(xy 438.272905 -342.797638) (xy 438.22058 -342.813006) (xy 438.1666 -342.820771) (xy 438.139332 -342.82126)
			(xy 437.275732 -342.82126) (xy 437.248459 -342.820803) (xy 437.194469 -342.813044) (xy 437.142132 -342.797681)
			(xy 437.092515 -342.775025) (xy 437.046627 -342.745538) (xy 437.005402 -342.70982) (xy 436.969681 -342.668599)
			(xy 436.940191 -342.622714) (xy 436.917531 -342.573098) (xy 436.902163 -342.520763) (xy 436.8944 -342.466773)
			(xy 435.411696 -342.466773) (xy 435.403934 -342.520761) (xy 435.388566 -342.573096) (xy 435.365907 -342.622711)
			(xy 435.336416 -342.668595) (xy 435.300696 -342.709816) (xy 435.259473 -342.745533) (xy 435.213586 -342.77502)
			(xy 435.16397 -342.797676) (xy 435.111634 -342.81304) (xy 435.057644 -342.820798) (xy 435.030372 -342.82126)
			(xy 434.166772 -342.82126) (xy 434.139504 -342.820776) (xy 434.085523 -342.813011) (xy 434.033196 -342.797643)
			(xy 433.98359 -342.774985) (xy 433.937712 -342.745498) (xy 433.896497 -342.709783) (xy 433.860785 -342.668566)
			(xy 433.831302 -342.622686) (xy 433.808647 -342.573077) (xy 433.793283 -342.52075) (xy 433.785522 -342.466768)
			(xy 432.302674 -342.466768) (xy 432.302674 -342.466769) (xy 432.294912 -342.520751) (xy 432.279548 -342.573079)
			(xy 432.256892 -342.622688) (xy 432.227408 -342.668568) (xy 432.191694 -342.709786) (xy 432.150478 -342.745501)
			(xy 432.104599 -342.774987) (xy 432.054991 -342.797643) (xy 432.002663 -342.81301) (xy 431.948681 -342.820773)
			(xy 431.921412 -342.82126) (xy 431.057812 -342.82126) (xy 431.03054 -342.820801) (xy 430.976552 -342.813041)
			(xy 430.924217 -342.797675) (xy 430.874603 -342.775018) (xy 430.828717 -342.745531) (xy 430.787495 -342.709813)
			(xy 430.751776 -342.668593) (xy 430.722288 -342.622708) (xy 430.699629 -342.573094) (xy 430.684262 -342.52076)
			(xy 430.6765 -342.466772) (xy 429.193796 -342.466772) (xy 429.193796 -342.466773) (xy 429.186033 -342.520764)
			(xy 429.170664 -342.5731) (xy 429.148003 -342.622716) (xy 429.118512 -342.668602) (xy 429.082789 -342.709823)
			(xy 429.041563 -342.74554) (xy 428.995674 -342.775026) (xy 428.946055 -342.797681) (xy 428.893717 -342.813043)
			(xy 428.839725 -342.8208) (xy 428.812452 -342.82126) (xy 427.948852 -342.82126) (xy 427.921585 -342.820774)
			(xy 427.867606 -342.813007) (xy 427.815282 -342.797637) (xy 427.765678 -342.774978) (xy 427.719802 -342.745491)
			(xy 427.67859 -342.709776) (xy 427.64288 -342.668559) (xy 427.613399 -342.62268) (xy 427.590746 -342.573073)
			(xy 427.575383 -342.520747) (xy 427.567622 -342.466767) (xy 426.084796 -342.466767) (xy 426.084796 -342.466771)
			(xy 426.077034 -342.520759) (xy 426.061668 -342.573092) (xy 426.03901 -342.622705) (xy 426.009521 -342.668589)
			(xy 425.973803 -342.709809) (xy 425.932582 -342.745526) (xy 425.886698 -342.775013) (xy 425.837084 -342.79767)
			(xy 425.784751 -342.813036) (xy 425.730763 -342.820797) (xy 425.703492 -342.82126) (xy 424.839892 -342.82126)
			(xy 424.812623 -342.820777) (xy 424.75864 -342.813014) (xy 424.706311 -342.797648) (xy 424.656702 -342.774991)
			(xy 424.610821 -342.745505) (xy 424.569605 -342.70979) (xy 424.53389 -342.668572) (xy 424.504405 -342.622691)
			(xy 424.481749 -342.573082) (xy 424.466384 -342.520752) (xy 424.458622 -342.466769) (xy 422.975774 -342.466769)
			(xy 422.968013 -342.520748) (xy 422.952649 -342.573075) (xy 422.929995 -342.622683) (xy 422.900513 -342.668562)
			(xy 422.864801 -342.709778) (xy 422.823588 -342.745494) (xy 422.777711 -342.77498) (xy 422.728105 -342.797638)
			(xy 422.67578 -342.813006) (xy 422.6218 -342.820771) (xy 422.594532 -342.82126) (xy 421.730932 -342.82126)
			(xy 421.703659 -342.820803) (xy 421.649669 -342.813044) (xy 421.597332 -342.797681) (xy 421.547715 -342.775025)
			(xy 421.501827 -342.745538) (xy 421.460602 -342.70982) (xy 421.424881 -342.668599) (xy 421.395391 -342.622714)
			(xy 421.372731 -342.573098) (xy 421.357363 -342.520763) (xy 421.3496 -342.466773) (xy 419.866896 -342.466773)
			(xy 419.859134 -342.520761) (xy 419.843766 -342.573096) (xy 419.821107 -342.622711) (xy 419.791616 -342.668595)
			(xy 419.755896 -342.709816) (xy 419.714673 -342.745533) (xy 419.668786 -342.77502) (xy 419.61917 -342.797676)
			(xy 419.566834 -342.81304) (xy 419.512844 -342.820798) (xy 419.485572 -342.82126) (xy 418.621972 -342.82126)
			(xy 418.594704 -342.820776) (xy 418.540723 -342.813011) (xy 418.488396 -342.797643) (xy 418.43879 -342.774985)
			(xy 418.392912 -342.745498) (xy 418.351697 -342.709783) (xy 418.315985 -342.668566) (xy 418.286502 -342.622686)
			(xy 418.263847 -342.573077) (xy 418.248483 -342.52075) (xy 418.240722 -342.466768) (xy 416.757874 -342.466768)
			(xy 416.757874 -342.466769) (xy 416.750112 -342.520751) (xy 416.734748 -342.573079) (xy 416.712092 -342.622688)
			(xy 416.682608 -342.668568) (xy 416.646894 -342.709786) (xy 416.605678 -342.745501) (xy 416.559799 -342.774987)
			(xy 416.510191 -342.797643) (xy 416.457863 -342.81301) (xy 416.403881 -342.820773) (xy 416.376612 -342.82126)
			(xy 415.513012 -342.82126) (xy 415.48574 -342.820801) (xy 415.431752 -342.813041) (xy 415.379417 -342.797675)
			(xy 415.329803 -342.775018) (xy 415.283917 -342.745531) (xy 415.242695 -342.709813) (xy 415.206976 -342.668593)
			(xy 415.177488 -342.622708) (xy 415.154829 -342.573094) (xy 415.139462 -342.52076) (xy 415.1317 -342.466772)
			(xy 413.648996 -342.466772) (xy 413.648996 -342.466773) (xy 413.641233 -342.520764) (xy 413.625864 -342.5731)
			(xy 413.603203 -342.622716) (xy 413.573712 -342.668602) (xy 413.537989 -342.709823) (xy 413.496763 -342.74554)
			(xy 413.450874 -342.775026) (xy 413.401255 -342.797681) (xy 413.348917 -342.813043) (xy 413.294925 -342.8208)
			(xy 413.267652 -342.82126) (xy 412.404052 -342.82126) (xy 412.376785 -342.820774) (xy 412.322806 -342.813007)
			(xy 412.270482 -342.797637) (xy 412.220878 -342.774978) (xy 412.175002 -342.745491) (xy 412.13379 -342.709776)
			(xy 412.09808 -342.668559) (xy 412.068599 -342.62268) (xy 412.045946 -342.573073) (xy 412.030583 -342.520747)
			(xy 412.022822 -342.466767) (xy 410.539996 -342.466767) (xy 410.539996 -342.466771) (xy 410.532234 -342.520759)
			(xy 410.516868 -342.573092) (xy 410.49421 -342.622705) (xy 410.464721 -342.668589) (xy 410.429003 -342.709809)
			(xy 410.387782 -342.745526) (xy 410.341898 -342.775013) (xy 410.292284 -342.79767) (xy 410.239951 -342.813036)
			(xy 410.185963 -342.820797) (xy 410.158692 -342.82126) (xy 409.295092 -342.82126) (xy 409.267823 -342.820777)
			(xy 409.21384 -342.813014) (xy 409.161511 -342.797648) (xy 409.111902 -342.774991) (xy 409.066021 -342.745505)
			(xy 409.024805 -342.70979) (xy 408.98909 -342.668572) (xy 408.959605 -342.622691) (xy 408.936949 -342.573082)
			(xy 408.921584 -342.520752) (xy 408.913822 -342.466769) (xy 403.522496 -342.466769) (xy 403.522496 -342.466772)
			(xy 403.514734 -342.52076) (xy 403.499367 -342.573094) (xy 403.476708 -342.622708) (xy 403.447218 -342.668593)
			(xy 403.411499 -342.709813) (xy 403.370277 -342.74553) (xy 403.324391 -342.775017) (xy 403.274775 -342.797674)
			(xy 403.222441 -342.813038) (xy 403.168452 -342.820798) (xy 403.14118 -342.82126) (xy 402.27758 -342.82126)
			(xy 402.250311 -342.820776) (xy 402.19633 -342.813012) (xy 402.144002 -342.797645) (xy 402.094394 -342.774988)
			(xy 402.048516 -342.745501) (xy 402.0073 -342.709786) (xy 401.971587 -342.668568) (xy 401.942103 -342.622688)
			(xy 401.919448 -342.573079) (xy 401.904084 -342.520751) (xy 401.896322 -342.466769) (xy 400.413474 -342.466769)
			(xy 400.405713 -342.52075) (xy 400.390348 -342.573078) (xy 400.367694 -342.622686) (xy 400.33821 -342.668566)
			(xy 400.302497 -342.709783) (xy 400.261282 -342.745498) (xy 400.215404 -342.774984) (xy 400.165796 -342.797641)
			(xy 400.113469 -342.813008) (xy 400.059488 -342.820772) (xy 400.03222 -342.82126) (xy 399.16862 -342.82126)
			(xy 399.141348 -342.820802) (xy 399.087359 -342.813042) (xy 399.035023 -342.797677) (xy 398.985407 -342.775021)
			(xy 398.939521 -342.745534) (xy 398.898298 -342.709816) (xy 398.862578 -342.668595) (xy 398.833089 -342.62271)
			(xy 398.81043 -342.573096) (xy 398.795062 -342.520761) (xy 398.7873 -342.466772) (xy 397.304596 -342.466772)
			(xy 397.304596 -342.466773) (xy 397.296833 -342.520763) (xy 397.281465 -342.573098) (xy 397.258805 -342.622714)
			(xy 397.229313 -342.668599) (xy 397.193592 -342.70982) (xy 397.152367 -342.745537) (xy 397.106479 -342.775024)
			(xy 397.056861 -342.797679) (xy 397.004524 -342.813042) (xy 396.950533 -342.820799) (xy 396.92326 -342.82126)
			(xy 396.05966 -342.82126) (xy 396.032392 -342.820775) (xy 395.978413 -342.813009) (xy 395.926088 -342.79764)
			(xy 395.876482 -342.774981) (xy 395.830606 -342.745494) (xy 395.789393 -342.709778) (xy 395.753682 -342.668562)
			(xy 395.7242 -342.622682) (xy 395.701546 -342.573075) (xy 395.686183 -342.520748) (xy 395.678422 -342.466768)
			(xy 394.195574 -342.466768) (xy 394.195574 -342.466769) (xy 394.187812 -342.520753) (xy 394.172447 -342.573082)
			(xy 394.149791 -342.622692) (xy 394.120305 -342.668572) (xy 394.08459 -342.70979) (xy 394.043372 -342.745505)
			(xy 393.997492 -342.774991) (xy 393.947882 -342.797647) (xy 393.895553 -342.813012) (xy 393.841569 -342.820774)
			(xy 393.8143 -342.82126) (xy 392.9507 -342.82126) (xy 392.92343 -342.820778) (xy 392.869447 -342.813016)
			(xy 392.817117 -342.79765) (xy 392.767506 -342.774994) (xy 392.721625 -342.745508) (xy 392.680407 -342.709793)
			(xy 392.644692 -342.668575) (xy 392.615206 -342.622694) (xy 392.59255 -342.573083) (xy 392.577184 -342.520753)
			(xy 392.569422 -342.46677) (xy 391.086574 -342.46677) (xy 391.078813 -342.520747) (xy 391.06345 -342.573073)
			(xy 391.040797 -342.622681) (xy 391.011315 -342.668559) (xy 390.975604 -342.709776) (xy 390.934391 -342.745491)
			(xy 390.888516 -342.774978) (xy 390.838911 -342.797636) (xy 390.786586 -342.813005) (xy 390.732607 -342.820771)
			(xy 390.70534 -342.82126) (xy 389.84174 -342.82126) (xy 389.814467 -342.820803) (xy 389.760476 -342.813046)
			(xy 389.708138 -342.797683) (xy 389.658519 -342.775027) (xy 389.61263 -342.745541) (xy 389.571405 -342.709823)
			(xy 389.535683 -342.668602) (xy 389.506192 -342.622716) (xy 389.483531 -342.5731) (xy 389.468163 -342.520764)
			(xy 389.4604 -342.466773) (xy 387.977696 -342.466773) (xy 387.969934 -342.52076) (xy 387.954567 -342.573094)
			(xy 387.931908 -342.622708) (xy 387.902418 -342.668593) (xy 387.866699 -342.709813) (xy 387.825477 -342.74553)
			(xy 387.779591 -342.775017) (xy 387.729975 -342.797674) (xy 387.677641 -342.813038) (xy 387.623652 -342.820798)
			(xy 387.59638 -342.82126) (xy 386.73278 -342.82126) (xy 386.705511 -342.820776) (xy 386.65153 -342.813012)
			(xy 386.599202 -342.797645) (xy 386.549594 -342.774988) (xy 386.503716 -342.745501) (xy 386.4625 -342.709786)
			(xy 386.426787 -342.668568) (xy 386.397303 -342.622688) (xy 386.374648 -342.573079) (xy 386.359284 -342.520751)
			(xy 386.351522 -342.466769) (xy 384.868674 -342.466769) (xy 384.860913 -342.52075) (xy 384.845548 -342.573078)
			(xy 384.822894 -342.622686) (xy 384.79341 -342.668566) (xy 384.757697 -342.709783) (xy 384.716482 -342.745498)
			(xy 384.670604 -342.774984) (xy 384.620996 -342.797641) (xy 384.568669 -342.813008) (xy 384.514688 -342.820772)
			(xy 384.48742 -342.82126) (xy 383.62382 -342.82126) (xy 383.596548 -342.820802) (xy 383.542559 -342.813042)
			(xy 383.490223 -342.797677) (xy 383.440607 -342.775021) (xy 383.394721 -342.745534) (xy 383.353498 -342.709816)
			(xy 383.317778 -342.668595) (xy 383.288289 -342.62271) (xy 383.26563 -342.573096) (xy 383.250262 -342.520761)
			(xy 383.2425 -342.466772) (xy 381.759796 -342.466772) (xy 381.759796 -342.466773) (xy 381.752033 -342.520763)
			(xy 381.736665 -342.573098) (xy 381.714005 -342.622714) (xy 381.684513 -342.668599) (xy 381.648792 -342.70982)
			(xy 381.607567 -342.745537) (xy 381.561679 -342.775024) (xy 381.512061 -342.797679) (xy 381.459724 -342.813042)
			(xy 381.405733 -342.820799) (xy 381.37846 -342.82126) (xy 380.51486 -342.82126) (xy 380.487592 -342.820775)
			(xy 380.433613 -342.813009) (xy 380.381288 -342.79764) (xy 380.331682 -342.774981) (xy 380.285806 -342.745494)
			(xy 380.244593 -342.709778) (xy 380.208882 -342.668562) (xy 380.1794 -342.622682) (xy 380.156746 -342.573075)
			(xy 380.141383 -342.520748) (xy 380.133622 -342.466768) (xy 378.650774 -342.466768) (xy 378.650774 -342.466769)
			(xy 378.643012 -342.520753) (xy 378.627647 -342.573082) (xy 378.604991 -342.622692) (xy 378.575505 -342.668572)
			(xy 378.53979 -342.70979) (xy 378.498572 -342.745505) (xy 378.452692 -342.774991) (xy 378.403082 -342.797647)
			(xy 378.350753 -342.813012) (xy 378.296769 -342.820774) (xy 378.2695 -342.82126) (xy 377.4059 -342.82126)
			(xy 377.37863 -342.820778) (xy 377.324647 -342.813016) (xy 377.272317 -342.79765) (xy 377.222706 -342.774994)
			(xy 377.176825 -342.745508) (xy 377.135607 -342.709793) (xy 377.099892 -342.668575) (xy 377.070406 -342.622694)
			(xy 377.04775 -342.573083) (xy 377.032384 -342.520753) (xy 377.024622 -342.46677) (xy 375.541774 -342.46677)
			(xy 375.534013 -342.520747) (xy 375.51865 -342.573073) (xy 375.495997 -342.622681) (xy 375.466515 -342.668559)
			(xy 375.430804 -342.709776) (xy 375.389591 -342.745491) (xy 375.343716 -342.774978) (xy 375.294111 -342.797636)
			(xy 375.241786 -342.813005) (xy 375.187807 -342.820771) (xy 375.16054 -342.82126) (xy 374.29694 -342.82126)
			(xy 374.269667 -342.820803) (xy 374.215676 -342.813046) (xy 374.163338 -342.797683) (xy 374.113719 -342.775027)
			(xy 374.06783 -342.745541) (xy 374.026605 -342.709823) (xy 373.990883 -342.668602) (xy 373.961392 -342.622716)
			(xy 373.938731 -342.5731) (xy 373.923363 -342.520764) (xy 373.9156 -342.466773) (xy 372.432896 -342.466773)
			(xy 372.425134 -342.52076) (xy 372.409767 -342.573094) (xy 372.387108 -342.622708) (xy 372.357618 -342.668593)
			(xy 372.321899 -342.709813) (xy 372.280677 -342.74553) (xy 372.234791 -342.775017) (xy 372.185175 -342.797674)
			(xy 372.132841 -342.813038) (xy 372.078852 -342.820798) (xy 372.05158 -342.82126) (xy 371.18798 -342.82126)
			(xy 371.160711 -342.820776) (xy 371.10673 -342.813012) (xy 371.054402 -342.797645) (xy 371.004794 -342.774988)
			(xy 370.958916 -342.745501) (xy 370.9177 -342.709786) (xy 370.881987 -342.668568) (xy 370.852503 -342.622688)
			(xy 370.829848 -342.573079) (xy 370.814484 -342.520751) (xy 370.806722 -342.466769) (xy 344.837274 -342.466769)
			(xy 344.829512 -342.520752) (xy 344.814147 -342.573081) (xy 344.791491 -342.622691) (xy 344.762006 -342.668571)
			(xy 344.726291 -342.709788) (xy 344.685074 -342.745503) (xy 344.639194 -342.774989) (xy 344.589585 -342.797646)
			(xy 344.537256 -342.813011) (xy 344.483273 -342.820773) (xy 344.456004 -342.82126) (xy 343.592404 -342.82126)
			(xy 343.565133 -342.820801) (xy 343.511145 -342.813039) (xy 343.458812 -342.797673) (xy 343.409198 -342.775016)
			(xy 343.363313 -342.745528) (xy 343.322093 -342.70981) (xy 343.286374 -342.66859) (xy 343.256886 -342.622706)
			(xy 343.234228 -342.573092) (xy 343.218862 -342.520759) (xy 343.2111 -342.466771) (xy 341.728273 -342.466771)
			(xy 341.720513 -342.520747) (xy 341.70515 -342.573072) (xy 341.682497 -342.622679) (xy 341.653016 -342.668558)
			(xy 341.617305 -342.709774) (xy 341.576093 -342.745489) (xy 341.530218 -342.774976) (xy 341.480614 -342.797635)
			(xy 341.42829 -342.813004) (xy 341.374311 -342.820771) (xy 341.347044 -342.82126) (xy 340.483444 -342.82126)
			(xy 340.456171 -342.820804) (xy 340.402179 -342.813046) (xy 340.349841 -342.797684) (xy 340.300222 -342.775029)
			(xy 340.254332 -342.745542) (xy 340.213107 -342.709824) (xy 340.177384 -342.668603) (xy 340.147892 -342.622717)
			(xy 340.125232 -342.573101) (xy 340.109863 -342.520764) (xy 340.1021 -342.466773) (xy 338.619396 -342.466773)
			(xy 338.611634 -342.52076) (xy 338.596267 -342.573093) (xy 338.573608 -342.622707) (xy 338.544119 -342.668591)
			(xy 338.5084 -342.709812) (xy 338.467179 -342.745529) (xy 338.421293 -342.775016) (xy 338.371678 -342.797673)
			(xy 338.319344 -342.813037) (xy 338.265356 -342.820798) (xy 338.238084 -342.82126) (xy 337.374484 -342.82126)
			(xy 337.347215 -342.820776) (xy 337.293233 -342.813013) (xy 337.240905 -342.797646) (xy 337.191297 -342.774989)
			(xy 337.145418 -342.745502) (xy 337.104202 -342.709787) (xy 337.068488 -342.66857) (xy 337.039003 -342.622689)
			(xy 337.016348 -342.57308) (xy 337.000984 -342.520751) (xy 336.993222 -342.466769) (xy 335.510374 -342.466769)
			(xy 335.502613 -342.520749) (xy 335.487249 -342.573077) (xy 335.464594 -342.622685) (xy 335.435111 -342.668565)
			(xy 335.399398 -342.709781) (xy 335.358184 -342.745496) (xy 335.312306 -342.774983) (xy 335.262699 -342.79764)
			(xy 335.210373 -342.813008) (xy 335.156392 -342.820772) (xy 335.129124 -342.82126) (xy 334.265524 -342.82126)
			(xy 334.238252 -342.820802) (xy 334.184262 -342.813043) (xy 334.131926 -342.797678) (xy 334.08231 -342.775022)
			(xy 334.036423 -342.745535) (xy 333.9952 -342.709817) (xy 333.959479 -342.668596) (xy 333.929989 -342.622711)
			(xy 333.90733 -342.573096) (xy 333.891962 -342.520761) (xy 333.8842 -342.466772) (xy 332.401496 -342.466772)
			(xy 332.393733 -342.520762) (xy 332.378365 -342.573098) (xy 332.355705 -342.622713) (xy 332.326214 -342.668598)
			(xy 332.290493 -342.709819) (xy 332.249269 -342.745536) (xy 332.203381 -342.775023) (xy 332.153764 -342.797678)
			(xy 332.101427 -342.813041) (xy 332.047437 -342.820799) (xy 332.020164 -342.82126) (xy 331.156564 -342.82126)
			(xy 331.129296 -342.820775) (xy 331.075316 -342.813009) (xy 331.022991 -342.797641) (xy 330.973385 -342.774982)
			(xy 330.927508 -342.745495) (xy 330.886295 -342.70978) (xy 330.850583 -342.668563) (xy 330.8211 -342.622684)
			(xy 330.798447 -342.573076) (xy 330.783083 -342.520749) (xy 330.775322 -342.466768) (xy 329.292474 -342.466768)
			(xy 329.292474 -342.466769) (xy 329.284712 -342.520752) (xy 329.269347 -342.573081) (xy 329.246691 -342.622691)
			(xy 329.217206 -342.668571) (xy 329.181491 -342.709788) (xy 329.140274 -342.745503) (xy 329.094394 -342.774989)
			(xy 329.044785 -342.797646) (xy 328.992456 -342.813011) (xy 328.938473 -342.820773) (xy 328.911204 -342.82126)
			(xy 328.047604 -342.82126) (xy 328.020333 -342.820801) (xy 327.966345 -342.813039) (xy 327.914012 -342.797673)
			(xy 327.864398 -342.775016) (xy 327.818513 -342.745528) (xy 327.777293 -342.70981) (xy 327.741574 -342.66859)
			(xy 327.712086 -342.622706) (xy 327.689428 -342.573092) (xy 327.674062 -342.520759) (xy 327.6663 -342.466771)
			(xy 326.183473 -342.466771) (xy 326.175713 -342.520747) (xy 326.16035 -342.573072) (xy 326.137697 -342.622679)
			(xy 326.108216 -342.668558) (xy 326.072505 -342.709774) (xy 326.031293 -342.745489) (xy 325.985418 -342.774976)
			(xy 325.935814 -342.797635) (xy 325.88349 -342.813004) (xy 325.829511 -342.820771) (xy 325.802244 -342.82126)
			(xy 324.938644 -342.82126) (xy 324.911371 -342.820804) (xy 324.857379 -342.813046) (xy 324.805041 -342.797684)
			(xy 324.755422 -342.775029) (xy 324.709532 -342.745542) (xy 324.668307 -342.709824) (xy 324.632584 -342.668603)
			(xy 324.603092 -342.622717) (xy 324.580432 -342.573101) (xy 324.565063 -342.520764) (xy 324.5573 -342.466773)
			(xy 323.074596 -342.466773) (xy 323.066834 -342.52076) (xy 323.051467 -342.573093) (xy 323.028808 -342.622707)
			(xy 322.999319 -342.668591) (xy 322.9636 -342.709812) (xy 322.922379 -342.745529) (xy 322.876493 -342.775016)
			(xy 322.826878 -342.797673) (xy 322.774544 -342.813037) (xy 322.720556 -342.820798) (xy 322.693284 -342.82126)
			(xy 321.829684 -342.82126) (xy 321.802415 -342.820776) (xy 321.748433 -342.813013) (xy 321.696105 -342.797646)
			(xy 321.646497 -342.774989) (xy 321.600618 -342.745502) (xy 321.559402 -342.709787) (xy 321.523688 -342.66857)
			(xy 321.494203 -342.622689) (xy 321.471548 -342.57308) (xy 321.456184 -342.520751) (xy 321.448422 -342.466769)
			(xy 319.965574 -342.466769) (xy 319.957813 -342.520749) (xy 319.942449 -342.573077) (xy 319.919794 -342.622685)
			(xy 319.890311 -342.668565) (xy 319.854598 -342.709781) (xy 319.813384 -342.745496) (xy 319.767506 -342.774983)
			(xy 319.717899 -342.79764) (xy 319.665573 -342.813008) (xy 319.611592 -342.820772) (xy 319.584324 -342.82126)
			(xy 318.720724 -342.82126) (xy 318.693452 -342.820802) (xy 318.639462 -342.813043) (xy 318.587126 -342.797678)
			(xy 318.53751 -342.775022) (xy 318.491623 -342.745535) (xy 318.4504 -342.709817) (xy 318.414679 -342.668596)
			(xy 318.385189 -342.622711) (xy 318.36253 -342.573096) (xy 318.347162 -342.520761) (xy 318.3394 -342.466772)
			(xy 316.856696 -342.466772) (xy 316.848933 -342.520762) (xy 316.833565 -342.573098) (xy 316.810905 -342.622713)
			(xy 316.781414 -342.668598) (xy 316.745693 -342.709819) (xy 316.704469 -342.745536) (xy 316.658581 -342.775023)
			(xy 316.608964 -342.797678) (xy 316.556627 -342.813041) (xy 316.502637 -342.820799) (xy 316.475364 -342.82126)
			(xy 315.611764 -342.82126) (xy 315.584496 -342.820775) (xy 315.530516 -342.813009) (xy 315.478191 -342.797641)
			(xy 315.428585 -342.774982) (xy 315.382708 -342.745495) (xy 315.341495 -342.70978) (xy 315.305783 -342.668563)
			(xy 315.2763 -342.622684) (xy 315.253647 -342.573076) (xy 315.238283 -342.520749) (xy 315.230522 -342.466768)
			(xy 313.747674 -342.466768) (xy 313.747674 -342.466769) (xy 313.739912 -342.520752) (xy 313.724547 -342.573081)
			(xy 313.701891 -342.622691) (xy 313.672406 -342.668571) (xy 313.636691 -342.709788) (xy 313.595474 -342.745503)
			(xy 313.549594 -342.774989) (xy 313.499985 -342.797646) (xy 313.447656 -342.813011) (xy 313.393673 -342.820773)
			(xy 313.366404 -342.82126) (xy 312.502804 -342.82126) (xy 312.475533 -342.820801) (xy 312.421545 -342.813039)
			(xy 312.369212 -342.797673) (xy 312.319598 -342.775016) (xy 312.273713 -342.745528) (xy 312.232493 -342.70981)
			(xy 312.196774 -342.66859) (xy 312.167286 -342.622706) (xy 312.144628 -342.573092) (xy 312.129262 -342.520759)
			(xy 312.1215 -342.466771) (xy 300.231574 -342.466771) (xy 300.223812 -342.520752) (xy 300.208447 -342.573081)
			(xy 300.185791 -342.622691) (xy 300.156305 -342.668572) (xy 300.120591 -342.709789) (xy 300.079373 -342.745504)
			(xy 300.033493 -342.77499) (xy 299.983883 -342.797646) (xy 299.931554 -342.813012) (xy 299.877571 -342.820773)
			(xy 299.850302 -342.82126) (xy 298.986702 -342.82126) (xy 298.959431 -342.820801) (xy 298.905443 -342.813039)
			(xy 298.85311 -342.797673) (xy 298.803497 -342.775015) (xy 298.757612 -342.745527) (xy 298.716392 -342.70981)
			(xy 298.680674 -342.668589) (xy 298.651186 -342.622705) (xy 298.628528 -342.573092) (xy 298.613162 -342.520759)
			(xy 298.605399 -342.466771) (xy 297.122573 -342.466771) (xy 297.114813 -342.520747) (xy 297.09945 -342.573073)
			(xy 297.076797 -342.62268) (xy 297.047315 -342.668559) (xy 297.011605 -342.709775) (xy 296.970392 -342.74549)
			(xy 296.924517 -342.774977) (xy 296.874912 -342.797635) (xy 296.822588 -342.813004) (xy 296.768609 -342.820771)
			(xy 296.741342 -342.82126) (xy 295.877742 -342.82126) (xy 295.850469 -342.820803) (xy 295.796477 -342.813046)
			(xy 295.744139 -342.797683) (xy 295.694521 -342.775028) (xy 295.648631 -342.745541) (xy 295.607406 -342.709824)
			(xy 295.571684 -342.668602) (xy 295.542192 -342.622716) (xy 295.519531 -342.5731) (xy 295.504163 -342.520764)
			(xy 295.4964 -342.466773) (xy 294.013696 -342.466773) (xy 294.005934 -342.52076) (xy 293.990567 -342.573094)
			(xy 293.967908 -342.622708) (xy 293.938419 -342.668592) (xy 293.9027 -342.709812) (xy 293.861478 -342.74553)
			(xy 293.815592 -342.775017) (xy 293.765977 -342.797673) (xy 293.713642 -342.813038) (xy 293.659654 -342.820798)
			(xy 293.632382 -342.82126) (xy 292.768782 -342.82126) (xy 292.741513 -342.820776) (xy 292.687531 -342.813013)
			(xy 292.635204 -342.797646) (xy 292.585596 -342.774988) (xy 292.539717 -342.745502) (xy 292.498501 -342.709786)
			(xy 292.462787 -342.668569) (xy 292.433303 -342.622689) (xy 292.410648 -342.573079) (xy 292.395284 -342.520751)
			(xy 292.387522 -342.466769) (xy 290.904674 -342.466769) (xy 290.896913 -342.52075) (xy 290.881548 -342.573077)
			(xy 290.858894 -342.622686) (xy 290.82941 -342.668565) (xy 290.793698 -342.709782) (xy 290.752483 -342.745497)
			(xy 290.706605 -342.774983) (xy 290.656998 -342.797641) (xy 290.604671 -342.813008) (xy 290.55069 -342.820772)
			(xy 290.523422 -342.82126) (xy 289.659822 -342.82126) (xy 289.63255 -342.820802) (xy 289.57856 -342.813042)
			(xy 289.526225 -342.797678) (xy 289.476609 -342.775021) (xy 289.430722 -342.745534) (xy 289.389499 -342.709817)
			(xy 289.353779 -342.668596) (xy 289.324289 -342.622711) (xy 289.30163 -342.573096) (xy 289.286262 -342.520761)
			(xy 289.2785 -342.466772) (xy 287.795796 -342.466772) (xy 287.795796 -342.466773) (xy 287.788033 -342.520763)
			(xy 287.772665 -342.573098) (xy 287.750005 -342.622713) (xy 287.720514 -342.668599) (xy 287.684793 -342.70982)
			(xy 287.643568 -342.745537) (xy 287.59768 -342.775023) (xy 287.548062 -342.797679) (xy 287.495725 -342.813041)
			(xy 287.441735 -342.820799) (xy 287.414462 -342.82126) (xy 286.550862 -342.82126) (xy 286.523594 -342.820775)
			(xy 286.469614 -342.813009) (xy 286.417289 -342.79764) (xy 286.367684 -342.774982) (xy 286.321807 -342.745495)
			(xy 286.280594 -342.709779) (xy 286.244883 -342.668562) (xy 286.2154 -342.622683) (xy 286.192747 -342.573075)
			(xy 286.177383 -342.520748) (xy 286.169622 -342.466768) (xy 284.686774 -342.466768) (xy 284.686774 -342.466769)
			(xy 284.679012 -342.520752) (xy 284.663647 -342.573081) (xy 284.640991 -342.622691) (xy 284.611505 -342.668572)
			(xy 284.575791 -342.709789) (xy 284.534573 -342.745504) (xy 284.488693 -342.77499) (xy 284.439083 -342.797646)
			(xy 284.386754 -342.813012) (xy 284.332771 -342.820773) (xy 284.305502 -342.82126) (xy 283.441902 -342.82126)
			(xy 283.414631 -342.820801) (xy 283.360643 -342.813039) (xy 283.30831 -342.797673) (xy 283.258697 -342.775015)
			(xy 283.212812 -342.745527) (xy 283.171592 -342.70981) (xy 283.135874 -342.668589) (xy 283.106386 -342.622705)
			(xy 283.083728 -342.573092) (xy 283.068362 -342.520759) (xy 283.060599 -342.466771) (xy 281.577773 -342.466771)
			(xy 281.570013 -342.520747) (xy 281.55465 -342.573073) (xy 281.531997 -342.62268) (xy 281.502515 -342.668559)
			(xy 281.466805 -342.709775) (xy 281.425592 -342.74549) (xy 281.379717 -342.774977) (xy 281.330112 -342.797635)
			(xy 281.277788 -342.813004) (xy 281.223809 -342.820771) (xy 281.196542 -342.82126) (xy 280.332942 -342.82126)
			(xy 280.305669 -342.820803) (xy 280.251677 -342.813046) (xy 280.199339 -342.797683) (xy 280.149721 -342.775028)
			(xy 280.103831 -342.745541) (xy 280.062606 -342.709824) (xy 280.026884 -342.668602) (xy 279.997392 -342.622716)
			(xy 279.974731 -342.5731) (xy 279.959363 -342.520764) (xy 279.9516 -342.466773) (xy 278.468896 -342.466773)
			(xy 278.461134 -342.52076) (xy 278.445767 -342.573094) (xy 278.423108 -342.622708) (xy 278.393619 -342.668592)
			(xy 278.3579 -342.709812) (xy 278.316678 -342.74553) (xy 278.270792 -342.775017) (xy 278.221177 -342.797673)
			(xy 278.168842 -342.813038) (xy 278.114854 -342.820798) (xy 278.087582 -342.82126) (xy 277.223982 -342.82126)
			(xy 277.196713 -342.820776) (xy 277.142731 -342.813013) (xy 277.090404 -342.797646) (xy 277.040796 -342.774988)
			(xy 276.994917 -342.745502) (xy 276.953701 -342.709786) (xy 276.917987 -342.668569) (xy 276.888503 -342.622689)
			(xy 276.865848 -342.573079) (xy 276.850484 -342.520751) (xy 276.842722 -342.466769) (xy 275.359874 -342.466769)
			(xy 275.352113 -342.52075) (xy 275.336748 -342.573077) (xy 275.314094 -342.622686) (xy 275.28461 -342.668565)
			(xy 275.248898 -342.709782) (xy 275.207683 -342.745497) (xy 275.161805 -342.774983) (xy 275.112198 -342.797641)
			(xy 275.059871 -342.813008) (xy 275.00589 -342.820772) (xy 274.978622 -342.82126) (xy 274.115022 -342.82126)
			(xy 274.08775 -342.820802) (xy 274.03376 -342.813042) (xy 273.981425 -342.797678) (xy 273.931809 -342.775021)
			(xy 273.885922 -342.745534) (xy 273.844699 -342.709817) (xy 273.808979 -342.668596) (xy 273.779489 -342.622711)
			(xy 273.75683 -342.573096) (xy 273.741462 -342.520761) (xy 273.7337 -342.466772) (xy 272.250996 -342.466772)
			(xy 272.250996 -342.466773) (xy 272.243233 -342.520763) (xy 272.227865 -342.573098) (xy 272.205205 -342.622713)
			(xy 272.175714 -342.668599) (xy 272.139993 -342.70982) (xy 272.098768 -342.745537) (xy 272.05288 -342.775023)
			(xy 272.003262 -342.797679) (xy 271.950925 -342.813041) (xy 271.896935 -342.820799) (xy 271.869662 -342.82126)
			(xy 271.006062 -342.82126) (xy 270.978794 -342.820775) (xy 270.924814 -342.813009) (xy 270.872489 -342.79764)
			(xy 270.822884 -342.774982) (xy 270.777007 -342.745495) (xy 270.735794 -342.709779) (xy 270.700083 -342.668562)
			(xy 270.6706 -342.622683) (xy 270.647947 -342.573075) (xy 270.632583 -342.520748) (xy 270.624822 -342.466768)
			(xy 269.141974 -342.466768) (xy 269.141974 -342.466769) (xy 269.134212 -342.520752) (xy 269.118847 -342.573081)
			(xy 269.096191 -342.622691) (xy 269.066705 -342.668572) (xy 269.030991 -342.709789) (xy 268.989773 -342.745504)
			(xy 268.943893 -342.77499) (xy 268.894283 -342.797646) (xy 268.841954 -342.813012) (xy 268.787971 -342.820773)
			(xy 268.760702 -342.82126) (xy 267.897102 -342.82126) (xy 267.869831 -342.820801) (xy 267.815843 -342.813039)
			(xy 267.76351 -342.797673) (xy 267.713897 -342.775015) (xy 267.668012 -342.745527) (xy 267.626792 -342.70981)
			(xy 267.591074 -342.668589) (xy 267.561586 -342.622705) (xy 267.538928 -342.573092) (xy 267.523562 -342.520759)
			(xy 267.515799 -342.466771) (xy 256.581015 -342.466771) (xy 256.573351 -342.471196) (xy 256.517947 -342.494145)
			(xy 256.460022 -342.509666) (xy 256.400566 -342.517494) (xy 256.340598 -342.517494) (xy 256.281142 -342.509666)
			(xy 256.223217 -342.494145) (xy 256.167813 -342.471196) (xy 256.115879 -342.441212) (xy 256.068303 -342.404706)
			(xy 256.025898 -342.362301) (xy 255.989392 -342.314725) (xy 255.959408 -342.262791) (xy 255.936459 -342.207387)
			(xy 255.920938 -342.149462) (xy 255.91311 -342.090006) (xy 255.91262 -342.060022) (xy 197.28821 -342.060022)
			(xy 197.329534 -342.06596) (xy 197.38187 -342.081324) (xy 197.431486 -342.10398) (xy 197.477373 -342.133467)
			(xy 197.518596 -342.169184) (xy 197.554316 -342.210405) (xy 197.583807 -342.256289) (xy 197.606466 -342.305904)
			(xy 197.621834 -342.358239) (xy 197.629596 -342.412228) (xy 197.629596 -342.466772) (xy 197.621834 -342.520761)
			(xy 197.606466 -342.573096) (xy 197.583807 -342.622711) (xy 197.554316 -342.668595) (xy 197.518596 -342.709816)
			(xy 197.477373 -342.745533) (xy 197.431486 -342.77502) (xy 197.38187 -342.797676) (xy 197.329534 -342.81304)
			(xy 197.275544 -342.820798) (xy 197.248272 -342.82126) (xy 196.384672 -342.82126) (xy 196.357404 -342.820776)
			(xy 196.303423 -342.813011) (xy 196.251096 -342.797643) (xy 196.20149 -342.774985) (xy 196.155612 -342.745498)
			(xy 196.114397 -342.709783) (xy 196.078685 -342.668566) (xy 196.049202 -342.622686) (xy 196.026547 -342.573077)
			(xy 196.011183 -342.52075) (xy 196.003422 -342.466768) (xy 194.520574 -342.466768) (xy 194.520574 -342.466769)
			(xy 194.512812 -342.520751) (xy 194.497448 -342.573079) (xy 194.474792 -342.622688) (xy 194.445308 -342.668568)
			(xy 194.409594 -342.709786) (xy 194.368378 -342.745501) (xy 194.322499 -342.774987) (xy 194.272891 -342.797643)
			(xy 194.220563 -342.81301) (xy 194.166581 -342.820773) (xy 194.139312 -342.82126) (xy 193.275712 -342.82126)
			(xy 193.24844 -342.820801) (xy 193.194452 -342.813041) (xy 193.142117 -342.797675) (xy 193.092503 -342.775018)
			(xy 193.046617 -342.745531) (xy 193.005395 -342.709813) (xy 192.969676 -342.668593) (xy 192.940188 -342.622708)
			(xy 192.917529 -342.573094) (xy 192.902162 -342.52076) (xy 192.8944 -342.466772) (xy 191.411696 -342.466772)
			(xy 191.411696 -342.466773) (xy 191.403933 -342.520764) (xy 191.388564 -342.5731) (xy 191.365903 -342.622716)
			(xy 191.336412 -342.668602) (xy 191.300689 -342.709823) (xy 191.259463 -342.74554) (xy 191.213574 -342.775026)
			(xy 191.163955 -342.797681) (xy 191.111617 -342.813043) (xy 191.057625 -342.8208) (xy 191.030352 -342.82126)
			(xy 190.166752 -342.82126) (xy 190.139485 -342.820774) (xy 190.085506 -342.813007) (xy 190.033182 -342.797637)
			(xy 189.983578 -342.774978) (xy 189.937702 -342.745491) (xy 189.89649 -342.709776) (xy 189.86078 -342.668559)
			(xy 189.831299 -342.62268) (xy 189.808646 -342.573073) (xy 189.793283 -342.520747) (xy 189.785522 -342.466767)
			(xy 188.302696 -342.466767) (xy 188.302696 -342.466771) (xy 188.294934 -342.520759) (xy 188.279568 -342.573092)
			(xy 188.25691 -342.622705) (xy 188.227421 -342.668589) (xy 188.191703 -342.709809) (xy 188.150482 -342.745526)
			(xy 188.104598 -342.775013) (xy 188.054984 -342.79767) (xy 188.002651 -342.813036) (xy 187.948663 -342.820797)
			(xy 187.921392 -342.82126) (xy 187.057792 -342.82126) (xy 187.030523 -342.820777) (xy 186.97654 -342.813014)
			(xy 186.924211 -342.797648) (xy 186.874602 -342.774991) (xy 186.828721 -342.745505) (xy 186.787505 -342.70979)
			(xy 186.75179 -342.668572) (xy 186.722305 -342.622691) (xy 186.699649 -342.573082) (xy 186.684284 -342.520752)
			(xy 186.676522 -342.466769) (xy 185.193674 -342.466769) (xy 185.185913 -342.520748) (xy 185.170549 -342.573075)
			(xy 185.147895 -342.622683) (xy 185.118413 -342.668562) (xy 185.082701 -342.709778) (xy 185.041488 -342.745494)
			(xy 184.995611 -342.77498) (xy 184.946005 -342.797638) (xy 184.89368 -342.813006) (xy 184.8397 -342.820771)
			(xy 184.812432 -342.82126) (xy 183.948832 -342.82126) (xy 183.921559 -342.820803) (xy 183.867569 -342.813044)
			(xy 183.815232 -342.797681) (xy 183.765615 -342.775025) (xy 183.719727 -342.745538) (xy 183.678502 -342.70982)
			(xy 183.642781 -342.668599) (xy 183.613291 -342.622714) (xy 183.590631 -342.573098) (xy 183.575263 -342.520763)
			(xy 183.5675 -342.466773) (xy 182.084796 -342.466773) (xy 182.077034 -342.520761) (xy 182.061666 -342.573096)
			(xy 182.039007 -342.622711) (xy 182.009516 -342.668595) (xy 181.973796 -342.709816) (xy 181.932573 -342.745533)
			(xy 181.886686 -342.77502) (xy 181.83707 -342.797676) (xy 181.784734 -342.81304) (xy 181.730744 -342.820798)
			(xy 181.703472 -342.82126) (xy 180.839872 -342.82126) (xy 180.812604 -342.820776) (xy 180.758623 -342.813011)
			(xy 180.706296 -342.797643) (xy 180.65669 -342.774985) (xy 180.610812 -342.745498) (xy 180.569597 -342.709783)
			(xy 180.533885 -342.668566) (xy 180.504402 -342.622686) (xy 180.481747 -342.573077) (xy 180.466383 -342.52075)
			(xy 180.458622 -342.466768) (xy 178.975774 -342.466768) (xy 178.975774 -342.466769) (xy 178.968012 -342.520751)
			(xy 178.952648 -342.573079) (xy 178.929992 -342.622688) (xy 178.900508 -342.668568) (xy 178.864794 -342.709786)
			(xy 178.823578 -342.745501) (xy 178.777699 -342.774987) (xy 178.728091 -342.797643) (xy 178.675763 -342.81301)
			(xy 178.621781 -342.820773) (xy 178.594512 -342.82126) (xy 177.730912 -342.82126) (xy 177.70364 -342.820801)
			(xy 177.649652 -342.813041) (xy 177.597317 -342.797675) (xy 177.547703 -342.775018) (xy 177.501817 -342.745531)
			(xy 177.460595 -342.709813) (xy 177.424876 -342.668593) (xy 177.395388 -342.622708) (xy 177.372729 -342.573094)
			(xy 177.357362 -342.52076) (xy 177.3496 -342.466772) (xy 175.866896 -342.466772) (xy 175.866896 -342.466773)
			(xy 175.859133 -342.520764) (xy 175.843764 -342.5731) (xy 175.821103 -342.622716) (xy 175.791612 -342.668602)
			(xy 175.755889 -342.709823) (xy 175.714663 -342.74554) (xy 175.668774 -342.775026) (xy 175.619155 -342.797681)
			(xy 175.566817 -342.813043) (xy 175.512825 -342.8208) (xy 175.485552 -342.82126) (xy 174.621952 -342.82126)
			(xy 174.594685 -342.820774) (xy 174.540706 -342.813007) (xy 174.488382 -342.797637) (xy 174.438778 -342.774978)
			(xy 174.392902 -342.745491) (xy 174.35169 -342.709776) (xy 174.31598 -342.668559) (xy 174.286499 -342.62268)
			(xy 174.263846 -342.573073) (xy 174.248483 -342.520747) (xy 174.240722 -342.466767) (xy 172.757896 -342.466767)
			(xy 172.757896 -342.466771) (xy 172.750134 -342.520759) (xy 172.734768 -342.573092) (xy 172.71211 -342.622705)
			(xy 172.682621 -342.668589) (xy 172.646903 -342.709809) (xy 172.605682 -342.745526) (xy 172.559798 -342.775013)
			(xy 172.510184 -342.79767) (xy 172.457851 -342.813036) (xy 172.403863 -342.820797) (xy 172.376592 -342.82126)
			(xy 171.512992 -342.82126) (xy 171.485723 -342.820777) (xy 171.43174 -342.813014) (xy 171.379411 -342.797648)
			(xy 171.329802 -342.774991) (xy 171.283921 -342.745505) (xy 171.242705 -342.70979) (xy 171.20699 -342.668572)
			(xy 171.177505 -342.622691) (xy 171.154849 -342.573082) (xy 171.139484 -342.520752) (xy 171.131722 -342.466769)
			(xy 169.648874 -342.466769) (xy 169.641113 -342.520748) (xy 169.625749 -342.573075) (xy 169.603095 -342.622683)
			(xy 169.573613 -342.668562) (xy 169.537901 -342.709778) (xy 169.496688 -342.745494) (xy 169.450811 -342.77498)
			(xy 169.401205 -342.797638) (xy 169.34888 -342.813006) (xy 169.2949 -342.820771) (xy 169.267632 -342.82126)
			(xy 168.404032 -342.82126) (xy 168.376759 -342.820803) (xy 168.322769 -342.813044) (xy 168.270432 -342.797681)
			(xy 168.220815 -342.775025) (xy 168.174927 -342.745538) (xy 168.133702 -342.70982) (xy 168.097981 -342.668599)
			(xy 168.068491 -342.622714) (xy 168.045831 -342.573098) (xy 168.030463 -342.520763) (xy 168.0227 -342.466773)
			(xy 166.539996 -342.466773) (xy 166.532234 -342.520761) (xy 166.516866 -342.573096) (xy 166.494207 -342.622711)
			(xy 166.464716 -342.668595) (xy 166.428996 -342.709816) (xy 166.387773 -342.745533) (xy 166.341886 -342.77502)
			(xy 166.29227 -342.797676) (xy 166.239934 -342.81304) (xy 166.185944 -342.820798) (xy 166.158672 -342.82126)
			(xy 165.295072 -342.82126) (xy 165.267804 -342.820776) (xy 165.213823 -342.813011) (xy 165.161496 -342.797643)
			(xy 165.11189 -342.774985) (xy 165.066012 -342.745498) (xy 165.024797 -342.709783) (xy 164.989085 -342.668566)
			(xy 164.959602 -342.622686) (xy 164.936947 -342.573077) (xy 164.921583 -342.52075) (xy 164.913822 -342.466768)
			(xy 144.196574 -342.466768) (xy 144.196574 -342.466769) (xy 144.188812 -342.520751) (xy 144.173447 -342.57308)
			(xy 144.150792 -342.622689) (xy 144.121307 -342.66857) (xy 144.085593 -342.709787) (xy 144.044376 -342.745502)
			(xy 143.998497 -342.774988) (xy 143.948888 -342.797645) (xy 143.896559 -342.81301) (xy 143.842577 -342.820773)
			(xy 143.815308 -342.82126) (xy 142.951708 -342.82126) (xy 142.924436 -342.820801) (xy 142.870448 -342.81304)
			(xy 142.818115 -342.797674) (xy 142.7685 -342.775017) (xy 142.722615 -342.745529) (xy 142.681394 -342.709812)
			(xy 142.645675 -342.668591) (xy 142.616187 -342.622707) (xy 142.593529 -342.573093) (xy 142.578162 -342.520759)
			(xy 142.5704 -342.466772) (xy 141.087573 -342.466772) (xy 141.079813 -342.520746) (xy 141.064451 -342.573072)
			(xy 141.041798 -342.622678) (xy 141.012317 -342.668557) (xy 140.976607 -342.709773) (xy 140.935395 -342.745488)
			(xy 140.88952 -342.774975) (xy 140.839917 -342.797634) (xy 140.787593 -342.813003) (xy 140.733615 -342.82077)
			(xy 140.706348 -342.82126) (xy 139.842748 -342.82126) (xy 139.815475 -342.820804) (xy 139.761482 -342.813047)
			(xy 139.709144 -342.797685) (xy 139.659524 -342.77503) (xy 139.613634 -342.745544) (xy 139.572408 -342.709826)
			(xy 139.536685 -342.668604) (xy 139.507193 -342.622718) (xy 139.484532 -342.573101) (xy 139.469163 -342.520765)
			(xy 139.4614 -342.466773) (xy 137.978696 -342.466773) (xy 137.970934 -342.520759) (xy 137.955567 -342.573092)
			(xy 137.932909 -342.622706) (xy 137.90342 -342.66859) (xy 137.867702 -342.70981) (xy 137.82648 -342.745528)
			(xy 137.780596 -342.775015) (xy 137.730981 -342.797671) (xy 137.678647 -342.813037) (xy 137.624659 -342.820797)
			(xy 137.597388 -342.82126) (xy 136.733788 -342.82126) (xy 136.706519 -342.820777) (xy 136.652536 -342.813014)
			(xy 136.600208 -342.797647) (xy 136.550599 -342.77499) (xy 136.50472 -342.745504) (xy 136.463503 -342.709788)
			(xy 136.427789 -342.668571) (xy 136.398304 -342.62269) (xy 136.375649 -342.573081) (xy 136.360284 -342.520752)
			(xy 136.352522 -342.466769) (xy 134.869674 -342.466769) (xy 134.861913 -342.520749) (xy 134.846549 -342.573076)
			(xy 134.823895 -342.622684) (xy 134.794412 -342.668563) (xy 134.7587 -342.70978) (xy 134.717486 -342.745495)
			(xy 134.671609 -342.774981) (xy 134.622002 -342.797639) (xy 134.569676 -342.813007) (xy 134.515696 -342.820772)
			(xy 134.488428 -342.82126) (xy 133.624828 -342.82126) (xy 133.597556 -342.820802) (xy 133.543565 -342.813043)
			(xy 133.491229 -342.79768) (xy 133.441612 -342.775023) (xy 133.395725 -342.745536) (xy 133.354501 -342.709819)
			(xy 133.31878 -342.668598) (xy 133.28929 -342.622712) (xy 133.26663 -342.573097) (xy 133.251262 -342.520762)
			(xy 133.2435 -342.466772) (xy 131.760796 -342.466772) (xy 131.753033 -342.520762) (xy 131.737666 -342.573097)
			(xy 131.715006 -342.622712) (xy 131.685515 -342.668597) (xy 131.649795 -342.709817) (xy 131.608571 -342.745535)
			(xy 131.562684 -342.775021) (xy 131.513067 -342.797677) (xy 131.46073 -342.81304) (xy 131.40674 -342.820799)
			(xy 131.379468 -342.82126) (xy 130.515868 -342.82126) (xy 130.4886 -342.820775) (xy 130.43462 -342.81301)
			(xy 130.382294 -342.797642) (xy 130.332687 -342.774984) (xy 130.28681 -342.745497) (xy 130.245596 -342.709781)
			(xy 130.209884 -342.668564) (xy 130.180401 -342.622685) (xy 130.157747 -342.573076) (xy 130.142383 -342.520749)
			(xy 130.134622 -342.466768) (xy 128.651774 -342.466768) (xy 128.651774 -342.466769) (xy 128.644012 -342.520751)
			(xy 128.628647 -342.57308) (xy 128.605992 -342.622689) (xy 128.576507 -342.66857) (xy 128.540793 -342.709787)
			(xy 128.499576 -342.745502) (xy 128.453697 -342.774988) (xy 128.404088 -342.797645) (xy 128.351759 -342.81301)
			(xy 128.297777 -342.820773) (xy 128.270508 -342.82126) (xy 127.406908 -342.82126) (xy 127.379636 -342.820801)
			(xy 127.325648 -342.81304) (xy 127.273315 -342.797674) (xy 127.2237 -342.775017) (xy 127.177815 -342.745529)
			(xy 127.136594 -342.709812) (xy 127.100875 -342.668591) (xy 127.071387 -342.622707) (xy 127.048729 -342.573093)
			(xy 127.033362 -342.520759) (xy 127.0256 -342.466772) (xy 125.542773 -342.466772) (xy 125.535013 -342.520746)
			(xy 125.519651 -342.573072) (xy 125.496998 -342.622678) (xy 125.467517 -342.668557) (xy 125.431807 -342.709773)
			(xy 125.390595 -342.745488) (xy 125.34472 -342.774975) (xy 125.295117 -342.797634) (xy 125.242793 -342.813003)
			(xy 125.188815 -342.82077) (xy 125.161548 -342.82126) (xy 124.297948 -342.82126) (xy 124.270675 -342.820804)
			(xy 124.216682 -342.813047) (xy 124.164344 -342.797685) (xy 124.114724 -342.77503) (xy 124.068834 -342.745544)
			(xy 124.027608 -342.709826) (xy 123.991885 -342.668604) (xy 123.962393 -342.622718) (xy 123.939732 -342.573101)
			(xy 123.924363 -342.520765) (xy 123.9166 -342.466773) (xy 122.433896 -342.466773) (xy 122.426134 -342.520759)
			(xy 122.410767 -342.573092) (xy 122.388109 -342.622706) (xy 122.35862 -342.66859) (xy 122.322902 -342.70981)
			(xy 122.28168 -342.745528) (xy 122.235796 -342.775015) (xy 122.186181 -342.797671) (xy 122.133847 -342.813037)
			(xy 122.079859 -342.820797) (xy 122.052588 -342.82126) (xy 121.188988 -342.82126) (xy 121.161719 -342.820777)
			(xy 121.107736 -342.813014) (xy 121.055408 -342.797647) (xy 121.005799 -342.77499) (xy 120.95992 -342.745504)
			(xy 120.918703 -342.709788) (xy 120.882989 -342.668571) (xy 120.853504 -342.62269) (xy 120.830849 -342.573081)
			(xy 120.815484 -342.520752) (xy 120.807722 -342.466769) (xy 119.324874 -342.466769) (xy 119.317113 -342.520749)
			(xy 119.301749 -342.573076) (xy 119.279095 -342.622684) (xy 119.249612 -342.668563) (xy 119.2139 -342.70978)
			(xy 119.172686 -342.745495) (xy 119.126809 -342.774981) (xy 119.077202 -342.797639) (xy 119.024876 -342.813007)
			(xy 118.970896 -342.820772) (xy 118.943628 -342.82126) (xy 118.080028 -342.82126) (xy 118.052756 -342.820802)
			(xy 117.998765 -342.813043) (xy 117.946429 -342.79768) (xy 117.896812 -342.775023) (xy 117.850925 -342.745536)
			(xy 117.809701 -342.709819) (xy 117.77398 -342.668598) (xy 117.74449 -342.622712) (xy 117.72183 -342.573097)
			(xy 117.706462 -342.520762) (xy 117.6987 -342.466772) (xy 116.215996 -342.466772) (xy 116.208233 -342.520762)
			(xy 116.192866 -342.573097) (xy 116.170206 -342.622712) (xy 116.140715 -342.668597) (xy 116.104995 -342.709817)
			(xy 116.063771 -342.745535) (xy 116.017884 -342.775021) (xy 115.968267 -342.797677) (xy 115.91593 -342.81304)
			(xy 115.86194 -342.820799) (xy 115.834668 -342.82126) (xy 114.971068 -342.82126) (xy 114.9438 -342.820775)
			(xy 114.88982 -342.81301) (xy 114.837494 -342.797642) (xy 114.787887 -342.774984) (xy 114.74201 -342.745497)
			(xy 114.700796 -342.709781) (xy 114.665084 -342.668564) (xy 114.635601 -342.622685) (xy 114.612947 -342.573076)
			(xy 114.597583 -342.520749) (xy 114.589822 -342.466768) (xy 113.106974 -342.466768) (xy 113.106974 -342.466769)
			(xy 113.099212 -342.520751) (xy 113.083847 -342.57308) (xy 113.061192 -342.622689) (xy 113.031707 -342.66857)
			(xy 112.995993 -342.709787) (xy 112.954776 -342.745502) (xy 112.908897 -342.774988) (xy 112.859288 -342.797645)
			(xy 112.806959 -342.81301) (xy 112.752977 -342.820773) (xy 112.725708 -342.82126) (xy 111.862108 -342.82126)
			(xy 111.834836 -342.820801) (xy 111.780848 -342.81304) (xy 111.728515 -342.797674) (xy 111.6789 -342.775017)
			(xy 111.633015 -342.745529) (xy 111.591794 -342.709812) (xy 111.556075 -342.668591) (xy 111.526587 -342.622707)
			(xy 111.503929 -342.573093) (xy 111.488562 -342.520759) (xy 111.4808 -342.466772) (xy 104.085479 -342.466772)
			(xy 104.10629 -342.517011) (xy 104.121803 -342.574906) (xy 104.129627 -342.634331) (xy 104.129627 -342.694269)
			(xy 104.121803 -342.753694) (xy 104.10629 -342.811589) (xy 104.083352 -342.866964) (xy 104.053383 -342.918871)
			(xy 104.016895 -342.966422) (xy 103.974512 -343.008804) (xy 103.926959 -343.045291) (xy 103.875051 -343.075259)
			(xy 103.819676 -343.098195) (xy 103.76178 -343.113706) (xy 103.702355 -343.121528) (xy 103.672386 -343.121996)
			(xy 102.808786 -343.121996) (xy 102.778818 -343.121529) (xy 102.719395 -343.113704) (xy 102.661502 -343.09819)
			(xy 102.60613 -343.075253) (xy 102.554224 -343.045284) (xy 102.506675 -343.008796) (xy 102.464294 -342.966415)
			(xy 102.427809 -342.918864) (xy 102.397841 -342.866958) (xy 102.374905 -342.811584) (xy 102.359393 -342.753691)
			(xy 102.35157 -342.694268) (xy 93.60914 -342.694268) (xy 93.595705 -342.709775) (xy 93.554492 -342.74549)
			(xy 93.508617 -342.774977) (xy 93.459012 -342.797635) (xy 93.406688 -342.813004) (xy 93.352709 -342.820771)
			(xy 93.325442 -342.82126) (xy 92.461842 -342.82126) (xy 92.434569 -342.820803) (xy 92.380577 -342.813046)
			(xy 92.328239 -342.797683) (xy 92.278621 -342.775028) (xy 92.232731 -342.745541) (xy 92.191506 -342.709824)
			(xy 92.155784 -342.668602) (xy 92.126292 -342.622716) (xy 92.103631 -342.5731) (xy 92.088263 -342.520764)
			(xy 92.0805 -342.466773) (xy 90.597796 -342.466773) (xy 90.590034 -342.52076) (xy 90.574667 -342.573094)
			(xy 90.552008 -342.622708) (xy 90.522519 -342.668592) (xy 90.4868 -342.709812) (xy 90.445578 -342.74553)
			(xy 90.399692 -342.775017) (xy 90.350077 -342.797673) (xy 90.297742 -342.813038) (xy 90.243754 -342.820798)
			(xy 90.216482 -342.82126) (xy 89.352882 -342.82126) (xy 89.325613 -342.820776) (xy 89.271631 -342.813013)
			(xy 89.219304 -342.797646) (xy 89.169696 -342.774988) (xy 89.123817 -342.745502) (xy 89.082601 -342.709786)
			(xy 89.046887 -342.668569) (xy 89.017403 -342.622689) (xy 88.994748 -342.573079) (xy 88.979384 -342.520751)
			(xy 88.971622 -342.466769) (xy 87.488774 -342.466769) (xy 87.481013 -342.52075) (xy 87.465648 -342.573077)
			(xy 87.442994 -342.622686) (xy 87.41351 -342.668565) (xy 87.377798 -342.709782) (xy 87.336583 -342.745497)
			(xy 87.290705 -342.774983) (xy 87.241098 -342.797641) (xy 87.188771 -342.813008) (xy 87.13479 -342.820772)
			(xy 87.107522 -342.82126) (xy 86.243922 -342.82126) (xy 86.21665 -342.820802) (xy 86.16266 -342.813042)
			(xy 86.110325 -342.797678) (xy 86.060709 -342.775021) (xy 86.014822 -342.745534) (xy 85.973599 -342.709817)
			(xy 85.937879 -342.668596) (xy 85.908389 -342.622711) (xy 85.88573 -342.573096) (xy 85.870362 -342.520761)
			(xy 85.8626 -342.466772) (xy 84.379896 -342.466772) (xy 84.379896 -342.466773) (xy 84.372133 -342.520763)
			(xy 84.356765 -342.573098) (xy 84.334105 -342.622713) (xy 84.304614 -342.668599) (xy 84.268893 -342.70982)
			(xy 84.227668 -342.745537) (xy 84.18178 -342.775023) (xy 84.132162 -342.797679) (xy 84.079825 -342.813041)
			(xy 84.025835 -342.820799) (xy 83.998562 -342.82126) (xy 83.134962 -342.82126) (xy 83.107694 -342.820775)
			(xy 83.053714 -342.813009) (xy 83.001389 -342.79764) (xy 82.951784 -342.774982) (xy 82.905907 -342.745495)
			(xy 82.864694 -342.709779) (xy 82.828983 -342.668562) (xy 82.7995 -342.622683) (xy 82.776847 -342.573075)
			(xy 82.761483 -342.520748) (xy 82.753722 -342.466768) (xy 81.270874 -342.466768) (xy 81.270874 -342.466769)
			(xy 81.263112 -342.520752) (xy 81.247747 -342.573081) (xy 81.225091 -342.622691) (xy 81.195605 -342.668572)
			(xy 81.159891 -342.709789) (xy 81.118673 -342.745504) (xy 81.072793 -342.77499) (xy 81.023183 -342.797646)
			(xy 80.970854 -342.813012) (xy 80.916871 -342.820773) (xy 80.889602 -342.82126) (xy 80.026002 -342.82126)
			(xy 79.998731 -342.820801) (xy 79.944743 -342.813039) (xy 79.89241 -342.797673) (xy 79.842797 -342.775015)
			(xy 79.796912 -342.745527) (xy 79.755692 -342.70981) (xy 79.719974 -342.668589) (xy 79.690486 -342.622705)
			(xy 79.667828 -342.573092) (xy 79.652462 -342.520759) (xy 79.644699 -342.466771) (xy 78.161873 -342.466771)
			(xy 78.154113 -342.520747) (xy 78.13875 -342.573073) (xy 78.116097 -342.62268) (xy 78.086615 -342.668559)
			(xy 78.050905 -342.709775) (xy 78.009692 -342.74549) (xy 77.963817 -342.774977) (xy 77.914212 -342.797635)
			(xy 77.861888 -342.813004) (xy 77.807909 -342.820771) (xy 77.780642 -342.82126) (xy 76.917042 -342.82126)
			(xy 76.889769 -342.820803) (xy 76.835777 -342.813046) (xy 76.783439 -342.797683) (xy 76.733821 -342.775028)
			(xy 76.687931 -342.745541) (xy 76.646706 -342.709824) (xy 76.610984 -342.668602) (xy 76.581492 -342.622716)
			(xy 76.558831 -342.5731) (xy 76.543463 -342.520764) (xy 76.5357 -342.466773) (xy 75.052996 -342.466773)
			(xy 75.045234 -342.52076) (xy 75.029867 -342.573094) (xy 75.007208 -342.622708) (xy 74.977719 -342.668592)
			(xy 74.942 -342.709812) (xy 74.900778 -342.74553) (xy 74.854892 -342.775017) (xy 74.805277 -342.797673)
			(xy 74.752942 -342.813038) (xy 74.698954 -342.820798) (xy 74.671682 -342.82126) (xy 73.808082 -342.82126)
			(xy 73.780813 -342.820776) (xy 73.726831 -342.813013) (xy 73.674504 -342.797646) (xy 73.624896 -342.774988)
			(xy 73.579017 -342.745502) (xy 73.537801 -342.709786) (xy 73.502087 -342.668569) (xy 73.472603 -342.622689)
			(xy 73.449948 -342.573079) (xy 73.434584 -342.520751) (xy 73.426822 -342.466769) (xy 71.943974 -342.466769)
			(xy 71.936213 -342.52075) (xy 71.920848 -342.573077) (xy 71.898194 -342.622686) (xy 71.86871 -342.668565)
			(xy 71.832998 -342.709782) (xy 71.791783 -342.745497) (xy 71.745905 -342.774983) (xy 71.696298 -342.797641)
			(xy 71.643971 -342.813008) (xy 71.58999 -342.820772) (xy 71.562722 -342.82126) (xy 70.699122 -342.82126)
			(xy 70.67185 -342.820802) (xy 70.61786 -342.813042) (xy 70.565525 -342.797678) (xy 70.515909 -342.775021)
			(xy 70.470022 -342.745534) (xy 70.428799 -342.709817) (xy 70.393079 -342.668596) (xy 70.363589 -342.622711)
			(xy 70.34093 -342.573096) (xy 70.325562 -342.520761) (xy 70.3178 -342.466772) (xy 68.835096 -342.466772)
			(xy 68.835096 -342.466773) (xy 68.827333 -342.520763) (xy 68.811965 -342.573098) (xy 68.789305 -342.622713)
			(xy 68.759814 -342.668599) (xy 68.724093 -342.70982) (xy 68.682868 -342.745537) (xy 68.63698 -342.775023)
			(xy 68.587362 -342.797679) (xy 68.535025 -342.813041) (xy 68.481035 -342.820799) (xy 68.453762 -342.82126)
			(xy 67.590162 -342.82126) (xy 67.562894 -342.820775) (xy 67.508914 -342.813009) (xy 67.456589 -342.79764)
			(xy 67.406984 -342.774982) (xy 67.361107 -342.745495) (xy 67.319894 -342.709779) (xy 67.284183 -342.668562)
			(xy 67.2547 -342.622683) (xy 67.232047 -342.573075) (xy 67.216683 -342.520748) (xy 67.208922 -342.466768)
			(xy 65.726074 -342.466768) (xy 65.726074 -342.466769) (xy 65.718312 -342.520752) (xy 65.702947 -342.573081)
			(xy 65.680291 -342.622691) (xy 65.650805 -342.668572) (xy 65.615091 -342.709789) (xy 65.573873 -342.745504)
			(xy 65.527993 -342.77499) (xy 65.478383 -342.797646) (xy 65.426054 -342.813012) (xy 65.372071 -342.820773)
			(xy 65.344802 -342.82126) (xy 64.481202 -342.82126) (xy 64.453931 -342.820801) (xy 64.399943 -342.813039)
			(xy 64.34761 -342.797673) (xy 64.297997 -342.775015) (xy 64.252112 -342.745527) (xy 64.210892 -342.70981)
			(xy 64.175174 -342.668589) (xy 64.145686 -342.622705) (xy 64.123028 -342.573092) (xy 64.107662 -342.520759)
			(xy 64.099899 -342.466771) (xy 62.617073 -342.466771) (xy 62.609313 -342.520747) (xy 62.59395 -342.573073)
			(xy 62.571297 -342.62268) (xy 62.541815 -342.668559) (xy 62.506105 -342.709775) (xy 62.464892 -342.74549)
			(xy 62.419017 -342.774977) (xy 62.369412 -342.797635) (xy 62.317088 -342.813004) (xy 62.263109 -342.820771)
			(xy 62.235842 -342.82126) (xy 61.372242 -342.82126) (xy 61.344969 -342.820803) (xy 61.290977 -342.813046)
			(xy 61.238639 -342.797683) (xy 61.189021 -342.775028) (xy 61.143131 -342.745541) (xy 61.101906 -342.709824)
			(xy 61.066184 -342.668602) (xy 61.036692 -342.622716) (xy 61.014031 -342.5731) (xy 60.998663 -342.520764)
			(xy 60.9909 -342.466773) (xy 51.666873 -342.466773) (xy 51.659113 -342.520746) (xy 51.643751 -342.573072)
			(xy 51.621098 -342.622678) (xy 51.591617 -342.668557) (xy 51.555907 -342.709773) (xy 51.514695 -342.745488)
			(xy 51.46882 -342.774975) (xy 51.419217 -342.797634) (xy 51.366893 -342.813003) (xy 51.312915 -342.82077)
			(xy 51.285648 -342.82126) (xy 50.422048 -342.82126) (xy 50.394775 -342.820804) (xy 50.340782 -342.813047)
			(xy 50.288444 -342.797685) (xy 50.238824 -342.77503) (xy 50.192934 -342.745544) (xy 50.151708 -342.709826)
			(xy 50.115985 -342.668604) (xy 50.086493 -342.622718) (xy 50.063832 -342.573101) (xy 50.048463 -342.520765)
			(xy 50.0407 -342.466773) (xy 48.557996 -342.466773) (xy 48.550234 -342.520759) (xy 48.534867 -342.573092)
			(xy 48.512209 -342.622706) (xy 48.48272 -342.66859) (xy 48.447002 -342.70981) (xy 48.40578 -342.745528)
			(xy 48.359896 -342.775015) (xy 48.310281 -342.797671) (xy 48.257947 -342.813037) (xy 48.203959 -342.820797)
			(xy 48.176688 -342.82126) (xy 47.313088 -342.82126) (xy 47.285819 -342.820777) (xy 47.231836 -342.813014)
			(xy 47.179508 -342.797647) (xy 47.129899 -342.77499) (xy 47.08402 -342.745504) (xy 47.042803 -342.709788)
			(xy 47.007089 -342.668571) (xy 46.977604 -342.62269) (xy 46.954949 -342.573081) (xy 46.939584 -342.520752)
			(xy 46.931822 -342.466769) (xy 45.448974 -342.466769) (xy 45.441213 -342.520749) (xy 45.425849 -342.573076)
			(xy 45.403195 -342.622684) (xy 45.373712 -342.668563) (xy 45.338 -342.70978) (xy 45.296786 -342.745495)
			(xy 45.250909 -342.774981) (xy 45.201302 -342.797639) (xy 45.148976 -342.813007) (xy 45.094996 -342.820772)
			(xy 45.067728 -342.82126) (xy 44.204128 -342.82126) (xy 44.176856 -342.820802) (xy 44.122865 -342.813043)
			(xy 44.070529 -342.79768) (xy 44.020912 -342.775023) (xy 43.975025 -342.745536) (xy 43.933801 -342.709819)
			(xy 43.89808 -342.668598) (xy 43.86859 -342.622712) (xy 43.84593 -342.573097) (xy 43.830562 -342.520762)
			(xy 43.8228 -342.466772) (xy 42.340096 -342.466772) (xy 42.332333 -342.520762) (xy 42.316966 -342.573097)
			(xy 42.294306 -342.622712) (xy 42.264815 -342.668597) (xy 42.229095 -342.709817) (xy 42.187871 -342.745535)
			(xy 42.141984 -342.775021) (xy 42.092367 -342.797677) (xy 42.04003 -342.81304) (xy 41.98604 -342.820799)
			(xy 41.958768 -342.82126) (xy 41.095168 -342.82126) (xy 41.0679 -342.820775) (xy 41.01392 -342.81301)
			(xy 40.961594 -342.797642) (xy 40.911987 -342.774984) (xy 40.86611 -342.745497) (xy 40.824896 -342.709781)
			(xy 40.789184 -342.668564) (xy 40.759701 -342.622685) (xy 40.737047 -342.573076) (xy 40.721683 -342.520749)
			(xy 40.713922 -342.466768) (xy 39.231074 -342.466768) (xy 39.231074 -342.466769) (xy 39.223312 -342.520751)
			(xy 39.207947 -342.57308) (xy 39.185292 -342.622689) (xy 39.155807 -342.66857) (xy 39.120093 -342.709787)
			(xy 39.078876 -342.745502) (xy 39.032997 -342.774988) (xy 38.983388 -342.797645) (xy 38.931059 -342.81301)
			(xy 38.877077 -342.820773) (xy 38.849808 -342.82126) (xy 37.986208 -342.82126) (xy 37.958936 -342.820801)
			(xy 37.904948 -342.81304) (xy 37.852615 -342.797674) (xy 37.803 -342.775017) (xy 37.757115 -342.745529)
			(xy 37.715894 -342.709812) (xy 37.680175 -342.668591) (xy 37.650687 -342.622707) (xy 37.628029 -342.573093)
			(xy 37.612662 -342.520759) (xy 37.6049 -342.466772) (xy 36.122073 -342.466772) (xy 36.114313 -342.520746)
			(xy 36.098951 -342.573072) (xy 36.076298 -342.622678) (xy 36.046817 -342.668557) (xy 36.011107 -342.709773)
			(xy 35.969895 -342.745488) (xy 35.92402 -342.774975) (xy 35.874417 -342.797634) (xy 35.822093 -342.813003)
			(xy 35.768115 -342.82077) (xy 35.740848 -342.82126) (xy 34.877248 -342.82126) (xy 34.849975 -342.820804)
			(xy 34.795982 -342.813047) (xy 34.743644 -342.797685) (xy 34.694024 -342.77503) (xy 34.648134 -342.745544)
			(xy 34.606908 -342.709826) (xy 34.571185 -342.668604) (xy 34.541693 -342.622718) (xy 34.519032 -342.573101)
			(xy 34.503663 -342.520765) (xy 34.4959 -342.466773) (xy 33.013196 -342.466773) (xy 33.005434 -342.520759)
			(xy 32.990067 -342.573092) (xy 32.967409 -342.622706) (xy 32.93792 -342.66859) (xy 32.902202 -342.70981)
			(xy 32.86098 -342.745528) (xy 32.815096 -342.775015) (xy 32.765481 -342.797671) (xy 32.713147 -342.813037)
			(xy 32.659159 -342.820797) (xy 32.631888 -342.82126) (xy 31.768288 -342.82126) (xy 31.741019 -342.820777)
			(xy 31.687036 -342.813014) (xy 31.634708 -342.797647) (xy 31.585099 -342.77499) (xy 31.53922 -342.745504)
			(xy 31.498003 -342.709788) (xy 31.462289 -342.668571) (xy 31.432804 -342.62269) (xy 31.410149 -342.573081)
			(xy 31.394784 -342.520752) (xy 31.387022 -342.466769) (xy 29.904174 -342.466769) (xy 29.896413 -342.520749)
			(xy 29.881049 -342.573076) (xy 29.858395 -342.622684) (xy 29.828912 -342.668563) (xy 29.7932 -342.70978)
			(xy 29.751986 -342.745495) (xy 29.706109 -342.774981) (xy 29.656502 -342.797639) (xy 29.604176 -342.813007)
			(xy 29.550196 -342.820772) (xy 29.522928 -342.82126) (xy 28.659328 -342.82126) (xy 28.632056 -342.820802)
			(xy 28.578065 -342.813043) (xy 28.525729 -342.79768) (xy 28.476112 -342.775023) (xy 28.430225 -342.745536)
			(xy 28.389001 -342.709819) (xy 28.35328 -342.668598) (xy 28.32379 -342.622712) (xy 28.30113 -342.573097)
			(xy 28.285762 -342.520762) (xy 28.278 -342.466772) (xy 26.795296 -342.466772) (xy 26.787533 -342.520762)
			(xy 26.772166 -342.573097) (xy 26.749506 -342.622712) (xy 26.720015 -342.668597) (xy 26.684295 -342.709817)
			(xy 26.643071 -342.745535) (xy 26.597184 -342.775021) (xy 26.547567 -342.797677) (xy 26.49523 -342.81304)
			(xy 26.44124 -342.820799) (xy 26.413968 -342.82126) (xy 25.550368 -342.82126) (xy 25.5231 -342.820775)
			(xy 25.46912 -342.81301) (xy 25.416794 -342.797642) (xy 25.367187 -342.774984) (xy 25.32131 -342.745497)
			(xy 25.280096 -342.709781) (xy 25.244384 -342.668564) (xy 25.214901 -342.622685) (xy 25.192247 -342.573076)
			(xy 25.176883 -342.520749) (xy 25.169122 -342.466768) (xy 23.686274 -342.466768) (xy 23.686274 -342.466769)
			(xy 23.678512 -342.520751) (xy 23.663147 -342.57308) (xy 23.640492 -342.622689) (xy 23.611007 -342.66857)
			(xy 23.575293 -342.709787) (xy 23.534076 -342.745502) (xy 23.488197 -342.774988) (xy 23.438588 -342.797645)
			(xy 23.386259 -342.81301) (xy 23.332277 -342.820773) (xy 23.305008 -342.82126) (xy 22.441408 -342.82126)
			(xy 22.414136 -342.820801) (xy 22.360148 -342.81304) (xy 22.307815 -342.797674) (xy 22.2582 -342.775017)
			(xy 22.212315 -342.745529) (xy 22.171094 -342.709812) (xy 22.135375 -342.668591) (xy 22.105887 -342.622707)
			(xy 22.083229 -342.573093) (xy 22.067862 -342.520759) (xy 22.0601 -342.466772) (xy 20.577347 -342.466772)
			(xy 20.569584 -342.520758) (xy 20.554218 -342.57309) (xy 20.53156 -342.622703) (xy 20.502073 -342.668587)
			(xy 20.466355 -342.709807) (xy 20.425135 -342.745524) (xy 20.379252 -342.775011) (xy 20.329638 -342.797669)
			(xy 20.277306 -342.813035) (xy 20.223319 -342.820797) (xy 20.196048 -342.82126) (xy 19.332448 -342.82126)
			(xy 19.305179 -342.820777) (xy 19.251195 -342.813015) (xy 19.198865 -342.79765) (xy 19.149255 -342.774993)
			(xy 19.103374 -342.745507) (xy 19.062157 -342.709792) (xy 19.026441 -342.668574) (xy 18.996956 -342.622693)
			(xy 18.974299 -342.573083) (xy 18.958934 -342.520753) (xy 18.951172 -342.466769) (xy 0.508 -342.466769)
			(xy 0.508 -345.49242) (xy 18.95117 -345.49242) (xy 18.95117 -345.43788) (xy 18.958932 -345.383896)
			(xy 18.974298 -345.331567) (xy 18.996954 -345.281956) (xy 19.02644 -345.236075) (xy 19.062155 -345.194857)
			(xy 19.103373 -345.159141) (xy 19.149254 -345.129655) (xy 19.198865 -345.106998) (xy 19.251194 -345.091633)
			(xy 19.305178 -345.083871) (xy 19.332448 -345.083384) (xy 20.196048 -345.083384) (xy 20.223319 -345.083855)
			(xy 20.277305 -345.091617) (xy 20.329638 -345.106983) (xy 20.379251 -345.12964) (xy 20.425134 -345.159128)
			(xy 20.466354 -345.194845) (xy 20.502071 -345.236064) (xy 20.531559 -345.281948) (xy 20.554216 -345.33156)
			(xy 20.569582 -345.383893) (xy 20.577345 -345.437879) (xy 20.577345 -345.49242) (xy 22.06013 -345.49242)
			(xy 22.06013 -345.43788) (xy 22.067892 -345.383896) (xy 22.083258 -345.331567) (xy 22.105914 -345.281956)
			(xy 22.1354 -345.236075) (xy 22.171115 -345.194857) (xy 22.212333 -345.159141) (xy 22.258214 -345.129655)
			(xy 22.307825 -345.106998) (xy 22.360154 -345.091633) (xy 22.414138 -345.083871) (xy 22.441408 -345.083384)
			(xy 23.305008 -345.083384) (xy 23.332279 -345.083855) (xy 23.386265 -345.091617) (xy 23.438598 -345.106983)
			(xy 23.488211 -345.12964) (xy 23.534094 -345.159128) (xy 23.575314 -345.194845) (xy 23.611031 -345.236064)
			(xy 23.640519 -345.281948) (xy 23.663176 -345.33156) (xy 23.678542 -345.383893) (xy 23.686305 -345.437879)
			(xy 23.686305 -345.492365) (xy 25.16917 -345.492365) (xy 25.16917 -345.437835) (xy 25.17693 -345.383861)
			(xy 25.192292 -345.33154) (xy 25.214943 -345.281938) (xy 25.244422 -345.236064) (xy 25.28013 -345.194853)
			(xy 25.321339 -345.159142) (xy 25.36721 -345.129658) (xy 25.41681 -345.107003) (xy 25.46913 -345.091637)
			(xy 25.523103 -345.083872) (xy 25.550368 -345.083384) (xy 26.413968 -345.083384) (xy 26.441244 -345.083753)
			(xy 26.495241 -345.091513) (xy 26.547583 -345.106878) (xy 26.597207 -345.129537) (xy 26.6431 -345.159027)
			(xy 26.684329 -345.194749) (xy 26.720054 -345.235975) (xy 26.749548 -345.281865) (xy 26.772211 -345.331487)
			(xy 26.78758 -345.383828) (xy 26.795344 -345.437824) (xy 26.795344 -345.492369) (xy 28.278047 -345.492369)
			(xy 28.278047 -345.437831) (xy 28.285809 -345.383848) (xy 28.301175 -345.33152) (xy 28.323832 -345.281911)
			(xy 28.353319 -345.236031) (xy 28.389035 -345.194815) (xy 28.430253 -345.159102) (xy 28.476135 -345.129619)
			(xy 28.525746 -345.106965) (xy 28.578076 -345.091603) (xy 28.632059 -345.083845) (xy 28.659328 -345.083384)
			(xy 29.522928 -345.083384) (xy 29.550199 -345.08378) (xy 29.604186 -345.091546) (xy 29.656519 -345.106916)
			(xy 29.706132 -345.129576) (xy 29.752014 -345.159067) (xy 29.793234 -345.194786) (xy 29.82895 -345.236008)
			(xy 29.858437 -345.281893) (xy 29.881094 -345.331507) (xy 29.89646 -345.383841) (xy 29.904222 -345.437829)
			(xy 29.904222 -345.492366) (xy 31.38707 -345.492366) (xy 31.38707 -345.437834) (xy 31.394831 -345.383858)
			(xy 31.410194 -345.331536) (xy 31.432846 -345.281933) (xy 31.462327 -345.236058) (xy 31.498037 -345.194846)
			(xy 31.539248 -345.159135) (xy 31.585122 -345.129652) (xy 31.634725 -345.106998) (xy 31.687047 -345.091633)
			(xy 31.741022 -345.083871) (xy 31.768288 -345.083384) (xy 32.631888 -345.083384) (xy 32.659163 -345.083755)
			(xy 32.713157 -345.091516) (xy 32.765498 -345.106884) (xy 32.815119 -345.129543) (xy 32.861009 -345.159034)
			(xy 32.902236 -345.194756) (xy 32.937959 -345.235981) (xy 32.967451 -345.281871) (xy 32.990112 -345.331491)
			(xy 33.005481 -345.383831) (xy 33.013244 -345.437825) (xy 33.013244 -345.49237) (xy 34.495948 -345.49237)
			(xy 34.495948 -345.43783) (xy 34.50371 -345.383846) (xy 34.519077 -345.331515) (xy 34.541735 -345.281905)
			(xy 34.571224 -345.236024) (xy 34.606942 -345.194808) (xy 34.648163 -345.159095) (xy 34.694047 -345.129612)
			(xy 34.74366 -345.10696) (xy 34.795992 -345.0916) (xy 34.849978 -345.083844) (xy 34.877248 -345.083384)
			(xy 35.740848 -345.083384) (xy 35.768118 -345.083782) (xy 35.822103 -345.09155) (xy 35.874433 -345.106921)
			(xy 35.924044 -345.129583) (xy 35.969924 -345.159074) (xy 36.011141 -345.194793) (xy 36.046855 -345.236015)
			(xy 36.07634 -345.281899) (xy 36.098995 -345.331512) (xy 36.11436 -345.383844) (xy 36.122122 -345.43783)
			(xy 36.122122 -345.492368) (xy 37.604947 -345.492368) (xy 37.604947 -345.437832) (xy 37.612709 -345.383851)
			(xy 37.628074 -345.331524) (xy 37.650729 -345.281916) (xy 37.680214 -345.236038) (xy 37.715928 -345.194822)
			(xy 37.757144 -345.159109) (xy 37.803023 -345.129625) (xy 37.852631 -345.106971) (xy 37.904959 -345.091607)
			(xy 37.95894 -345.083847) (xy 37.986208 -345.083384) (xy 38.849808 -345.083384) (xy 38.87708 -345.083779)
			(xy 38.93107 -345.091543) (xy 38.983404 -345.106911) (xy 39.03302 -345.12957) (xy 39.078905 -345.15906)
			(xy 39.120127 -345.194779) (xy 39.155845 -345.236001) (xy 39.185334 -345.281888) (xy 39.207992 -345.331503)
			(xy 39.223359 -345.383838) (xy 39.231121 -345.437828) (xy 39.231121 -345.492365) (xy 40.71397 -345.492365)
			(xy 40.71397 -345.437835) (xy 40.72173 -345.383861) (xy 40.737092 -345.33154) (xy 40.759743 -345.281938)
			(xy 40.789222 -345.236064) (xy 40.82493 -345.194853) (xy 40.866139 -345.159142) (xy 40.91201 -345.129658)
			(xy 40.96161 -345.107003) (xy 41.01393 -345.091637) (xy 41.067903 -345.083872) (xy 41.095168 -345.083384)
			(xy 41.958768 -345.083384) (xy 41.986044 -345.083753) (xy 42.040041 -345.091513) (xy 42.092383 -345.106878)
			(xy 42.142007 -345.129537) (xy 42.1879 -345.159027) (xy 42.229129 -345.194749) (xy 42.264854 -345.235975)
			(xy 42.294348 -345.281865) (xy 42.317011 -345.331487) (xy 42.33238 -345.383828) (xy 42.340144 -345.437824)
			(xy 42.340144 -345.492369) (xy 43.822847 -345.492369) (xy 43.822847 -345.437831) (xy 43.830609 -345.383848)
			(xy 43.845975 -345.33152) (xy 43.868632 -345.281911) (xy 43.898119 -345.236031) (xy 43.933835 -345.194815)
			(xy 43.975053 -345.159102) (xy 44.020935 -345.129619) (xy 44.070546 -345.106965) (xy 44.122876 -345.091603)
			(xy 44.176859 -345.083845) (xy 44.204128 -345.083384) (xy 45.067728 -345.083384) (xy 45.094999 -345.08378)
			(xy 45.148986 -345.091546) (xy 45.201319 -345.106916) (xy 45.250932 -345.129576) (xy 45.296814 -345.159067)
			(xy 45.338034 -345.194786) (xy 45.37375 -345.236008) (xy 45.403237 -345.281893) (xy 45.425894 -345.331507)
			(xy 45.44126 -345.383841) (xy 45.449022 -345.437829) (xy 45.449022 -345.492366) (xy 46.93187 -345.492366)
			(xy 46.93187 -345.437834) (xy 46.939631 -345.383858) (xy 46.954994 -345.331536) (xy 46.977646 -345.281933)
			(xy 47.007127 -345.236058) (xy 47.042837 -345.194846) (xy 47.084048 -345.159135) (xy 47.129922 -345.129652)
			(xy 47.179525 -345.106998) (xy 47.231847 -345.091633) (xy 47.285822 -345.083871) (xy 47.313088 -345.083384)
			(xy 48.176688 -345.083384) (xy 48.203963 -345.083755) (xy 48.257957 -345.091516) (xy 48.310298 -345.106884)
			(xy 48.359919 -345.129543) (xy 48.405809 -345.159034) (xy 48.447036 -345.194756) (xy 48.482759 -345.235981)
			(xy 48.512251 -345.281871) (xy 48.534912 -345.331491) (xy 48.550281 -345.383831) (xy 48.558044 -345.437825)
			(xy 48.558044 -345.49237) (xy 50.040748 -345.49237) (xy 50.040748 -345.43783) (xy 50.04851 -345.383846)
			(xy 50.063877 -345.331515) (xy 50.086535 -345.281905) (xy 50.116024 -345.236024) (xy 50.151742 -345.194808)
			(xy 50.192963 -345.159095) (xy 50.238847 -345.129612) (xy 50.28846 -345.10696) (xy 50.340792 -345.0916)
			(xy 50.394778 -345.083844) (xy 50.422048 -345.083384) (xy 51.285648 -345.083384) (xy 51.312918 -345.083782)
			(xy 51.366903 -345.09155) (xy 51.419233 -345.106921) (xy 51.468844 -345.129583) (xy 51.514724 -345.159074)
			(xy 51.555941 -345.194793) (xy 51.591655 -345.236015) (xy 51.62114 -345.281899) (xy 51.643795 -345.331512)
			(xy 51.65916 -345.383844) (xy 51.666922 -345.43783) (xy 51.666922 -345.49237) (xy 60.990948 -345.49237)
			(xy 60.990948 -345.43783) (xy 60.99871 -345.383846) (xy 61.014076 -345.331517) (xy 61.036734 -345.281907)
			(xy 61.066222 -345.236026) (xy 61.10194 -345.19481) (xy 61.14316 -345.159097) (xy 61.189044 -345.129614)
			(xy 61.238656 -345.106962) (xy 61.290987 -345.091601) (xy 61.344972 -345.083845) (xy 61.372242 -345.083384)
			(xy 62.235842 -345.083384) (xy 62.263113 -345.083781) (xy 62.317098 -345.091549) (xy 62.369429 -345.10692)
			(xy 62.41904 -345.129581) (xy 62.464921 -345.159072) (xy 62.506139 -345.194791) (xy 62.541854 -345.236013)
			(xy 62.571339 -345.281897) (xy 62.593995 -345.33151) (xy 62.60936 -345.383843) (xy 62.617122 -345.437829)
			(xy 62.617122 -345.492368) (xy 64.099947 -345.492368) (xy 64.099947 -345.437832) (xy 64.107709 -345.383852)
			(xy 64.123073 -345.331525) (xy 64.145728 -345.281918) (xy 64.175212 -345.23604) (xy 64.210926 -345.194824)
			(xy 64.252141 -345.159111) (xy 64.29802 -345.129627) (xy 64.347627 -345.106972) (xy 64.399954 -345.091608)
			(xy 64.453934 -345.083847) (xy 64.481202 -345.083384) (xy 65.344802 -345.083384) (xy 65.372075 -345.083779)
			(xy 65.426064 -345.091542) (xy 65.4784 -345.106909) (xy 65.528016 -345.129568) (xy 65.573902 -345.159057)
			(xy 65.615124 -345.194777) (xy 65.650844 -345.236) (xy 65.680333 -345.281886) (xy 65.702992 -345.331502)
			(xy 65.718359 -345.383838) (xy 65.726121 -345.437827) (xy 65.726121 -345.492364) (xy 67.20897 -345.492364)
			(xy 67.20897 -345.437836) (xy 67.21673 -345.383862) (xy 67.232092 -345.331542) (xy 67.254742 -345.28194)
			(xy 67.284221 -345.236066) (xy 67.319928 -345.194855) (xy 67.361136 -345.159144) (xy 67.407007 -345.12966)
			(xy 67.456606 -345.107005) (xy 67.508925 -345.091638) (xy 67.562898 -345.083873) (xy 67.590162 -345.083384)
			(xy 68.453762 -345.083384) (xy 68.481038 -345.083753) (xy 68.535036 -345.091512) (xy 68.587379 -345.106877)
			(xy 68.637003 -345.129535) (xy 68.682897 -345.159025) (xy 68.724127 -345.194747) (xy 68.759852 -345.235973)
			(xy 68.789347 -345.281864) (xy 68.81201 -345.331485) (xy 68.82738 -345.383827) (xy 68.835144 -345.437824)
			(xy 68.835144 -345.492369) (xy 70.317847 -345.492369) (xy 70.317847 -345.437831) (xy 70.325609 -345.383849)
			(xy 70.340975 -345.331521) (xy 70.363631 -345.281912) (xy 70.393117 -345.236033) (xy 70.428833 -345.194817)
			(xy 70.470051 -345.159104) (xy 70.515932 -345.129621) (xy 70.565541 -345.106967) (xy 70.617871 -345.091605)
			(xy 70.671853 -345.083846) (xy 70.699122 -345.083384) (xy 71.562722 -345.083384) (xy 71.589994 -345.08378)
			(xy 71.643981 -345.091545) (xy 71.696315 -345.106914) (xy 71.745928 -345.129574) (xy 71.791812 -345.159064)
			(xy 71.833032 -345.194784) (xy 71.868749 -345.236006) (xy 71.898236 -345.281891) (xy 71.920893 -345.331506)
			(xy 71.936259 -345.38384) (xy 71.944022 -345.437828) (xy 71.944022 -345.492365) (xy 73.42687 -345.492365)
			(xy 73.42687 -345.437835) (xy 73.434631 -345.383859) (xy 73.449993 -345.331537) (xy 73.472645 -345.281934)
			(xy 73.502126 -345.23606) (xy 73.537835 -345.194848) (xy 73.579045 -345.159137) (xy 73.624919 -345.129654)
			(xy 73.674521 -345.106999) (xy 73.726842 -345.091634) (xy 73.780817 -345.083872) (xy 73.808082 -345.083384)
			(xy 74.671682 -345.083384) (xy 74.698957 -345.083754) (xy 74.752952 -345.091515) (xy 74.805294 -345.106882)
			(xy 74.854915 -345.129541) (xy 74.900806 -345.159032) (xy 74.942034 -345.194754) (xy 74.977757 -345.235979)
			(xy 75.00725 -345.281869) (xy 75.029912 -345.33149) (xy 75.045281 -345.38383) (xy 75.053044 -345.437825)
			(xy 75.053044 -345.49237) (xy 76.535748 -345.49237) (xy 76.535748 -345.43783) (xy 76.54351 -345.383846)
			(xy 76.558876 -345.331517) (xy 76.581534 -345.281907) (xy 76.611022 -345.236026) (xy 76.64674 -345.19481)
			(xy 76.68796 -345.159097) (xy 76.733844 -345.129614) (xy 76.783456 -345.106962) (xy 76.835787 -345.091601)
			(xy 76.889772 -345.083845) (xy 76.917042 -345.083384) (xy 77.780642 -345.083384) (xy 77.807913 -345.083781)
			(xy 77.861898 -345.091549) (xy 77.914229 -345.10692) (xy 77.96384 -345.129581) (xy 78.009721 -345.159072)
			(xy 78.050939 -345.194791) (xy 78.086654 -345.236013) (xy 78.116139 -345.281897) (xy 78.138795 -345.33151)
			(xy 78.15416 -345.383843) (xy 78.161922 -345.437829) (xy 78.161922 -345.492368) (xy 79.644747 -345.492368)
			(xy 79.644747 -345.437832) (xy 79.652509 -345.383852) (xy 79.667873 -345.331525) (xy 79.690528 -345.281918)
			(xy 79.720012 -345.23604) (xy 79.755726 -345.194824) (xy 79.796941 -345.159111) (xy 79.84282 -345.129627)
			(xy 79.892427 -345.106972) (xy 79.944754 -345.091608) (xy 79.998734 -345.083847) (xy 80.026002 -345.083384)
			(xy 80.889602 -345.083384) (xy 80.916875 -345.083779) (xy 80.970864 -345.091542) (xy 81.0232 -345.106909)
			(xy 81.072816 -345.129568) (xy 81.118702 -345.159057) (xy 81.159924 -345.194777) (xy 81.195644 -345.236)
			(xy 81.225133 -345.281886) (xy 81.247792 -345.331502) (xy 81.263159 -345.383838) (xy 81.270921 -345.437827)
			(xy 81.270921 -345.492364) (xy 82.75377 -345.492364) (xy 82.75377 -345.437836) (xy 82.76153 -345.383862)
			(xy 82.776892 -345.331542) (xy 82.799542 -345.28194) (xy 82.829021 -345.236066) (xy 82.864728 -345.194855)
			(xy 82.905936 -345.159144) (xy 82.951807 -345.12966) (xy 83.001406 -345.107005) (xy 83.053725 -345.091638)
			(xy 83.107698 -345.083873) (xy 83.134962 -345.083384) (xy 83.998562 -345.083384) (xy 84.025838 -345.083753)
			(xy 84.079836 -345.091512) (xy 84.132179 -345.106877) (xy 84.181803 -345.129535) (xy 84.227697 -345.159025)
			(xy 84.268927 -345.194747) (xy 84.304652 -345.235973) (xy 84.334147 -345.281864) (xy 84.35681 -345.331485)
			(xy 84.37218 -345.383827) (xy 84.379944 -345.437824) (xy 84.379944 -345.492369) (xy 85.862647 -345.492369)
			(xy 85.862647 -345.437831) (xy 85.870409 -345.383849) (xy 85.885775 -345.331521) (xy 85.908431 -345.281912)
			(xy 85.937917 -345.236033) (xy 85.973633 -345.194817) (xy 86.014851 -345.159104) (xy 86.060732 -345.129621)
			(xy 86.110341 -345.106967) (xy 86.162671 -345.091605) (xy 86.216653 -345.083846) (xy 86.243922 -345.083384)
			(xy 87.107522 -345.083384) (xy 87.134794 -345.08378) (xy 87.188781 -345.091545) (xy 87.241115 -345.106914)
			(xy 87.290728 -345.129574) (xy 87.336612 -345.159064) (xy 87.377832 -345.194784) (xy 87.413549 -345.236006)
			(xy 87.443036 -345.281891) (xy 87.465693 -345.331506) (xy 87.481059 -345.38384) (xy 87.488822 -345.437828)
			(xy 87.488822 -345.492365) (xy 88.97167 -345.492365) (xy 88.97167 -345.437835) (xy 88.979431 -345.383859)
			(xy 88.994793 -345.331537) (xy 89.017445 -345.281934) (xy 89.046926 -345.23606) (xy 89.082635 -345.194848)
			(xy 89.123845 -345.159137) (xy 89.169719 -345.129654) (xy 89.219321 -345.106999) (xy 89.271642 -345.091634)
			(xy 89.325617 -345.083872) (xy 89.352882 -345.083384) (xy 90.216482 -345.083384) (xy 90.243757 -345.083754)
			(xy 90.297752 -345.091515) (xy 90.350094 -345.106882) (xy 90.399715 -345.129541) (xy 90.445606 -345.159032)
			(xy 90.486834 -345.194754) (xy 90.522557 -345.235979) (xy 90.55205 -345.281869) (xy 90.574712 -345.33149)
			(xy 90.590081 -345.38383) (xy 90.597844 -345.437825) (xy 90.597844 -345.49237) (xy 92.080548 -345.49237)
			(xy 92.080548 -345.43783) (xy 92.08831 -345.383846) (xy 92.103676 -345.331517) (xy 92.126334 -345.281907)
			(xy 92.155822 -345.236026) (xy 92.19154 -345.19481) (xy 92.23276 -345.159097) (xy 92.278644 -345.129614)
			(xy 92.328256 -345.106962) (xy 92.380587 -345.091601) (xy 92.434572 -345.083845) (xy 92.461842 -345.083384)
			(xy 93.325442 -345.083384) (xy 93.352713 -345.083781) (xy 93.406698 -345.091549) (xy 93.459029 -345.10692)
			(xy 93.50864 -345.129581) (xy 93.554521 -345.159072) (xy 93.595739 -345.194791) (xy 93.631454 -345.236013)
			(xy 93.660939 -345.281897) (xy 93.683595 -345.33151) (xy 93.69896 -345.383843) (xy 93.706722 -345.437829)
			(xy 93.706722 -345.492368) (xy 111.480847 -345.492368) (xy 111.480847 -345.437832) (xy 111.488609 -345.383851)
			(xy 111.503974 -345.331524) (xy 111.526629 -345.281916) (xy 111.556114 -345.236038) (xy 111.591828 -345.194822)
			(xy 111.633044 -345.159109) (xy 111.678923 -345.129625) (xy 111.728531 -345.106971) (xy 111.780859 -345.091607)
			(xy 111.83484 -345.083847) (xy 111.862108 -345.083384) (xy 112.725708 -345.083384) (xy 112.75298 -345.083779)
			(xy 112.80697 -345.091543) (xy 112.859304 -345.106911) (xy 112.90892 -345.12957) (xy 112.954805 -345.15906)
			(xy 112.996027 -345.194779) (xy 113.031745 -345.236001) (xy 113.061234 -345.281888) (xy 113.083892 -345.331503)
			(xy 113.099259 -345.383838) (xy 113.107021 -345.437828) (xy 113.107021 -345.492365) (xy 114.58987 -345.492365)
			(xy 114.58987 -345.437835) (xy 114.59763 -345.383861) (xy 114.612992 -345.33154) (xy 114.635643 -345.281938)
			(xy 114.665122 -345.236064) (xy 114.70083 -345.194853) (xy 114.742039 -345.159142) (xy 114.78791 -345.129658)
			(xy 114.83751 -345.107003) (xy 114.88983 -345.091637) (xy 114.943803 -345.083872) (xy 114.971068 -345.083384)
			(xy 115.834668 -345.083384) (xy 115.861944 -345.083753) (xy 115.915941 -345.091513) (xy 115.968283 -345.106878)
			(xy 116.017907 -345.129537) (xy 116.0638 -345.159027) (xy 116.105029 -345.194749) (xy 116.140754 -345.235975)
			(xy 116.170248 -345.281865) (xy 116.192911 -345.331487) (xy 116.20828 -345.383828) (xy 116.216044 -345.437824)
			(xy 116.216044 -345.492369) (xy 117.698747 -345.492369) (xy 117.698747 -345.437831) (xy 117.706509 -345.383848)
			(xy 117.721875 -345.33152) (xy 117.744532 -345.281911) (xy 117.774019 -345.236031) (xy 117.809735 -345.194815)
			(xy 117.850953 -345.159102) (xy 117.896835 -345.129619) (xy 117.946446 -345.106965) (xy 117.998776 -345.091603)
			(xy 118.052759 -345.083845) (xy 118.080028 -345.083384) (xy 118.943628 -345.083384) (xy 118.970899 -345.08378)
			(xy 119.024886 -345.091546) (xy 119.077219 -345.106916) (xy 119.126832 -345.129576) (xy 119.172714 -345.159067)
			(xy 119.213934 -345.194786) (xy 119.24965 -345.236008) (xy 119.279137 -345.281893) (xy 119.301794 -345.331507)
			(xy 119.31716 -345.383841) (xy 119.324922 -345.437829) (xy 119.324922 -345.492366) (xy 120.80777 -345.492366)
			(xy 120.80777 -345.437834) (xy 120.815531 -345.383858) (xy 120.830894 -345.331536) (xy 120.853546 -345.281933)
			(xy 120.883027 -345.236058) (xy 120.918737 -345.194846) (xy 120.959948 -345.159135) (xy 121.005822 -345.129652)
			(xy 121.055425 -345.106998) (xy 121.107747 -345.091633) (xy 121.161722 -345.083871) (xy 121.188988 -345.083384)
			(xy 122.052588 -345.083384) (xy 122.079863 -345.083755) (xy 122.133857 -345.091516) (xy 122.186198 -345.106884)
			(xy 122.235819 -345.129543) (xy 122.281709 -345.159034) (xy 122.322936 -345.194756) (xy 122.358659 -345.235981)
			(xy 122.388151 -345.281871) (xy 122.410812 -345.331491) (xy 122.426181 -345.383831) (xy 122.433944 -345.437825)
			(xy 122.433944 -345.49237) (xy 123.916648 -345.49237) (xy 123.916648 -345.43783) (xy 123.92441 -345.383846)
			(xy 123.939777 -345.331515) (xy 123.962435 -345.281905) (xy 123.991924 -345.236024) (xy 124.027642 -345.194808)
			(xy 124.068863 -345.159095) (xy 124.114747 -345.129612) (xy 124.16436 -345.10696) (xy 124.216692 -345.0916)
			(xy 124.270678 -345.083844) (xy 124.297948 -345.083384) (xy 125.161548 -345.083384) (xy 125.188818 -345.083782)
			(xy 125.242803 -345.09155) (xy 125.295133 -345.106921) (xy 125.344744 -345.129583) (xy 125.390624 -345.159074)
			(xy 125.431841 -345.194793) (xy 125.467555 -345.236015) (xy 125.49704 -345.281899) (xy 125.519695 -345.331512)
			(xy 125.53506 -345.383844) (xy 125.542822 -345.43783) (xy 125.542822 -345.492368) (xy 127.025647 -345.492368)
			(xy 127.025647 -345.437832) (xy 127.033409 -345.383851) (xy 127.048774 -345.331524) (xy 127.071429 -345.281916)
			(xy 127.100914 -345.236038) (xy 127.136628 -345.194822) (xy 127.177844 -345.159109) (xy 127.223723 -345.129625)
			(xy 127.273331 -345.106971) (xy 127.325659 -345.091607) (xy 127.37964 -345.083847) (xy 127.406908 -345.083384)
			(xy 128.270508 -345.083384) (xy 128.29778 -345.083779) (xy 128.35177 -345.091543) (xy 128.404104 -345.106911)
			(xy 128.45372 -345.12957) (xy 128.499605 -345.15906) (xy 128.540827 -345.194779) (xy 128.576545 -345.236001)
			(xy 128.606034 -345.281888) (xy 128.628692 -345.331503) (xy 128.644059 -345.383838) (xy 128.651821 -345.437828)
			(xy 128.651821 -345.492365) (xy 130.13467 -345.492365) (xy 130.13467 -345.437835) (xy 130.14243 -345.383861)
			(xy 130.157792 -345.33154) (xy 130.180443 -345.281938) (xy 130.209922 -345.236064) (xy 130.24563 -345.194853)
			(xy 130.286839 -345.159142) (xy 130.33271 -345.129658) (xy 130.38231 -345.107003) (xy 130.43463 -345.091637)
			(xy 130.488603 -345.083872) (xy 130.515868 -345.083384) (xy 131.379468 -345.083384) (xy 131.406744 -345.083753)
			(xy 131.460741 -345.091513) (xy 131.513083 -345.106878) (xy 131.562707 -345.129537) (xy 131.6086 -345.159027)
			(xy 131.649829 -345.194749) (xy 131.685554 -345.235975) (xy 131.715048 -345.281865) (xy 131.737711 -345.331487)
			(xy 131.75308 -345.383828) (xy 131.760844 -345.437824) (xy 131.760844 -345.492369) (xy 133.243547 -345.492369)
			(xy 133.243547 -345.437831) (xy 133.251309 -345.383848) (xy 133.266675 -345.33152) (xy 133.289332 -345.281911)
			(xy 133.318819 -345.236031) (xy 133.354535 -345.194815) (xy 133.395753 -345.159102) (xy 133.441635 -345.129619)
			(xy 133.491246 -345.106965) (xy 133.543576 -345.091603) (xy 133.597559 -345.083845) (xy 133.624828 -345.083384)
			(xy 134.488428 -345.083384) (xy 134.515699 -345.08378) (xy 134.569686 -345.091546) (xy 134.622019 -345.106916)
			(xy 134.671632 -345.129576) (xy 134.717514 -345.159067) (xy 134.758734 -345.194786) (xy 134.79445 -345.236008)
			(xy 134.823937 -345.281893) (xy 134.846594 -345.331507) (xy 134.86196 -345.383841) (xy 134.869722 -345.437829)
			(xy 134.869722 -345.492366) (xy 136.35257 -345.492366) (xy 136.35257 -345.437834) (xy 136.360331 -345.383858)
			(xy 136.375694 -345.331536) (xy 136.398346 -345.281933) (xy 136.427827 -345.236058) (xy 136.463537 -345.194846)
			(xy 136.504748 -345.159135) (xy 136.550622 -345.129652) (xy 136.600225 -345.106998) (xy 136.652547 -345.091633)
			(xy 136.706522 -345.083871) (xy 136.733788 -345.083384) (xy 137.597388 -345.083384) (xy 137.624663 -345.083755)
			(xy 137.678657 -345.091516) (xy 137.730998 -345.106884) (xy 137.780619 -345.129543) (xy 137.826509 -345.159034)
			(xy 137.867736 -345.194756) (xy 137.903459 -345.235981) (xy 137.932951 -345.281871) (xy 137.955612 -345.331491)
			(xy 137.970981 -345.383831) (xy 137.978744 -345.437825) (xy 137.978744 -345.49237) (xy 139.461448 -345.49237)
			(xy 139.461448 -345.43783) (xy 139.46921 -345.383846) (xy 139.484577 -345.331515) (xy 139.507235 -345.281905)
			(xy 139.536724 -345.236024) (xy 139.572442 -345.194808) (xy 139.613663 -345.159095) (xy 139.659547 -345.129612)
			(xy 139.70916 -345.10696) (xy 139.761492 -345.0916) (xy 139.815478 -345.083844) (xy 139.842748 -345.083384)
			(xy 140.706348 -345.083384) (xy 140.733618 -345.083782) (xy 140.787603 -345.09155) (xy 140.839933 -345.106921)
			(xy 140.889544 -345.129583) (xy 140.935424 -345.159074) (xy 140.976641 -345.194793) (xy 141.012355 -345.236015)
			(xy 141.04184 -345.281899) (xy 141.064495 -345.331512) (xy 141.07986 -345.383844) (xy 141.087622 -345.43783)
			(xy 141.087622 -345.492368) (xy 142.570447 -345.492368) (xy 142.570447 -345.437832) (xy 142.578209 -345.383851)
			(xy 142.593574 -345.331524) (xy 142.616229 -345.281916) (xy 142.645714 -345.236038) (xy 142.681428 -345.194822)
			(xy 142.722644 -345.159109) (xy 142.768523 -345.129625) (xy 142.818131 -345.106971) (xy 142.870459 -345.091607)
			(xy 142.92444 -345.083847) (xy 142.951708 -345.083384) (xy 143.815308 -345.083384) (xy 143.84258 -345.083779)
			(xy 143.89657 -345.091543) (xy 143.948904 -345.106911) (xy 143.99852 -345.12957) (xy 144.044405 -345.15906)
			(xy 144.085627 -345.194779) (xy 144.121345 -345.236001) (xy 144.150834 -345.281888) (xy 144.173492 -345.331503)
			(xy 144.188859 -345.383838) (xy 144.196621 -345.437828) (xy 144.196621 -345.492365) (xy 164.91387 -345.492365)
			(xy 164.91387 -345.437835) (xy 164.92163 -345.383861) (xy 164.936992 -345.33154) (xy 164.959644 -345.281937)
			(xy 164.989123 -345.236063) (xy 165.024831 -345.194851) (xy 165.066041 -345.15914) (xy 165.111913 -345.129657)
			(xy 165.161513 -345.107002) (xy 165.213833 -345.091636) (xy 165.267807 -345.083872) (xy 165.295072 -345.083384)
			(xy 166.158672 -345.083384) (xy 166.185948 -345.083754) (xy 166.239944 -345.091514) (xy 166.292286 -345.106879)
			(xy 166.341909 -345.129538) (xy 166.387802 -345.159028) (xy 166.42903 -345.19475) (xy 166.464755 -345.235976)
			(xy 166.494249 -345.281866) (xy 166.516911 -345.331487) (xy 166.532281 -345.383829) (xy 166.540044 -345.437824)
			(xy 166.540044 -345.492369) (xy 168.022747 -345.492369) (xy 168.022747 -345.437831) (xy 168.03051 -345.383848)
			(xy 168.045876 -345.331519) (xy 168.068533 -345.281909) (xy 168.09802 -345.23603) (xy 168.133736 -345.194814)
			(xy 168.174955 -345.159101) (xy 168.220838 -345.129617) (xy 168.270449 -345.106964) (xy 168.322779 -345.091603)
			(xy 168.376763 -345.083845) (xy 168.404032 -345.083384) (xy 169.267632 -345.083384) (xy 169.294903 -345.083781)
			(xy 169.34889 -345.091547) (xy 169.401222 -345.106917) (xy 169.450834 -345.129578) (xy 169.496716 -345.159068)
			(xy 169.537935 -345.194788) (xy 169.573651 -345.236009) (xy 169.603138 -345.281894) (xy 169.625794 -345.331508)
			(xy 169.64116 -345.383842) (xy 169.648922 -345.437829) (xy 169.648922 -345.492366) (xy 171.13177 -345.492366)
			(xy 171.13177 -345.437834) (xy 171.139531 -345.383858) (xy 171.154894 -345.331535) (xy 171.177547 -345.281932)
			(xy 171.207028 -345.236057) (xy 171.242738 -345.194844) (xy 171.28395 -345.159133) (xy 171.329825 -345.129651)
			(xy 171.379428 -345.106997) (xy 171.43175 -345.091633) (xy 171.485726 -345.083871) (xy 171.512992 -345.083384)
			(xy 172.376592 -345.083384) (xy 172.403867 -345.083755) (xy 172.457861 -345.091517) (xy 172.510201 -345.106885)
			(xy 172.559821 -345.129544) (xy 172.605711 -345.159035) (xy 172.646937 -345.194757) (xy 172.68266 -345.235982)
			(xy 172.712152 -345.281872) (xy 172.734813 -345.331492) (xy 172.750181 -345.383831) (xy 172.757944 -345.437825)
			(xy 172.757944 -345.492364) (xy 174.24077 -345.492364) (xy 174.24077 -345.437836) (xy 174.24853 -345.383863)
			(xy 174.263891 -345.331544) (xy 174.286541 -345.281943) (xy 174.316019 -345.23607) (xy 174.351724 -345.194858)
			(xy 174.392931 -345.159147) (xy 174.438801 -345.129664) (xy 174.488399 -345.107008) (xy 174.540716 -345.09164)
			(xy 174.594688 -345.083874) (xy 174.621952 -345.083384) (xy 175.485552 -345.083384) (xy 175.512829 -345.083752)
			(xy 175.566827 -345.09151) (xy 175.619172 -345.106874) (xy 175.668797 -345.129531) (xy 175.714692 -345.159021)
			(xy 175.755923 -345.194743) (xy 175.79165 -345.235969) (xy 175.821146 -345.281861) (xy 175.843809 -345.331483)
			(xy 175.85918 -345.383826) (xy 175.866944 -345.437824) (xy 175.866944 -345.492368) (xy 177.349647 -345.492368)
			(xy 177.349647 -345.437832) (xy 177.357409 -345.38385) (xy 177.372774 -345.331523) (xy 177.39543 -345.281915)
			(xy 177.424915 -345.236036) (xy 177.460629 -345.194821) (xy 177.501846 -345.159108) (xy 177.547726 -345.129624)
			(xy 177.597334 -345.10697) (xy 177.649662 -345.091606) (xy 177.703644 -345.083847) (xy 177.730912 -345.083384)
			(xy 178.594512 -345.083384) (xy 178.621784 -345.083779) (xy 178.675773 -345.091543) (xy 178.728107 -345.106912)
			(xy 178.777722 -345.129571) (xy 178.823607 -345.159061) (xy 178.864828 -345.194781) (xy 178.900546 -345.236003)
			(xy 178.930035 -345.281889) (xy 178.952693 -345.331504) (xy 178.968059 -345.383839) (xy 178.975821 -345.437828)
			(xy 178.975821 -345.492365) (xy 180.45867 -345.492365) (xy 180.45867 -345.437835) (xy 180.46643 -345.383861)
			(xy 180.481792 -345.33154) (xy 180.504444 -345.281937) (xy 180.533923 -345.236063) (xy 180.569631 -345.194851)
			(xy 180.610841 -345.15914) (xy 180.656713 -345.129657) (xy 180.706313 -345.107002) (xy 180.758633 -345.091636)
			(xy 180.812607 -345.083872) (xy 180.839872 -345.083384) (xy 181.703472 -345.083384) (xy 181.730748 -345.083754)
			(xy 181.784744 -345.091514) (xy 181.837086 -345.106879) (xy 181.886709 -345.129538) (xy 181.932602 -345.159028)
			(xy 181.97383 -345.19475) (xy 182.009555 -345.235976) (xy 182.039049 -345.281866) (xy 182.061711 -345.331487)
			(xy 182.077081 -345.383829) (xy 182.084844 -345.437824) (xy 182.084844 -345.492369) (xy 183.567547 -345.492369)
			(xy 183.567547 -345.437831) (xy 183.57531 -345.383848) (xy 183.590676 -345.331519) (xy 183.613333 -345.281909)
			(xy 183.64282 -345.23603) (xy 183.678536 -345.194814) (xy 183.719755 -345.159101) (xy 183.765638 -345.129617)
			(xy 183.815249 -345.106964) (xy 183.867579 -345.091603) (xy 183.921563 -345.083845) (xy 183.948832 -345.083384)
			(xy 184.812432 -345.083384) (xy 184.839703 -345.083781) (xy 184.89369 -345.091547) (xy 184.946022 -345.106917)
			(xy 184.995634 -345.129578) (xy 185.041516 -345.159068) (xy 185.082735 -345.194788) (xy 185.118451 -345.236009)
			(xy 185.147938 -345.281894) (xy 185.170594 -345.331508) (xy 185.18596 -345.383842) (xy 185.193722 -345.437829)
			(xy 185.193722 -345.492366) (xy 186.67657 -345.492366) (xy 186.67657 -345.437834) (xy 186.684331 -345.383858)
			(xy 186.699694 -345.331535) (xy 186.722347 -345.281932) (xy 186.751828 -345.236057) (xy 186.787538 -345.194844)
			(xy 186.82875 -345.159133) (xy 186.874625 -345.129651) (xy 186.924228 -345.106997) (xy 186.97655 -345.091633)
			(xy 187.030526 -345.083871) (xy 187.057792 -345.083384) (xy 187.921392 -345.083384) (xy 187.948667 -345.083755)
			(xy 188.002661 -345.091517) (xy 188.055001 -345.106885) (xy 188.104621 -345.129544) (xy 188.150511 -345.159035)
			(xy 188.191737 -345.194757) (xy 188.22746 -345.235982) (xy 188.256952 -345.281872) (xy 188.279613 -345.331492)
			(xy 188.294981 -345.383831) (xy 188.302744 -345.437825) (xy 188.302744 -345.492364) (xy 189.78557 -345.492364)
			(xy 189.78557 -345.437836) (xy 189.79333 -345.383863) (xy 189.808691 -345.331544) (xy 189.831341 -345.281943)
			(xy 189.860819 -345.23607) (xy 189.896524 -345.194858) (xy 189.937731 -345.159147) (xy 189.983601 -345.129664)
			(xy 190.033199 -345.107008) (xy 190.085516 -345.09164) (xy 190.139488 -345.083874) (xy 190.166752 -345.083384)
			(xy 191.030352 -345.083384) (xy 191.057629 -345.083752) (xy 191.111627 -345.09151) (xy 191.163972 -345.106874)
			(xy 191.213597 -345.129531) (xy 191.259492 -345.159021) (xy 191.300723 -345.194743) (xy 191.33645 -345.235969)
			(xy 191.365946 -345.281861) (xy 191.388609 -345.331483) (xy 191.40398 -345.383826) (xy 191.411744 -345.437824)
			(xy 191.411744 -345.492368) (xy 192.894447 -345.492368) (xy 192.894447 -345.437832) (xy 192.902209 -345.38385)
			(xy 192.917574 -345.331523) (xy 192.94023 -345.281915) (xy 192.969715 -345.236036) (xy 193.005429 -345.194821)
			(xy 193.046646 -345.159108) (xy 193.092526 -345.129624) (xy 193.142134 -345.10697) (xy 193.194462 -345.091606)
			(xy 193.248444 -345.083847) (xy 193.275712 -345.083384) (xy 194.139312 -345.083384) (xy 194.166584 -345.083779)
			(xy 194.220573 -345.091543) (xy 194.272907 -345.106912) (xy 194.322522 -345.129571) (xy 194.368407 -345.159061)
			(xy 194.409628 -345.194781) (xy 194.445346 -345.236003) (xy 194.474835 -345.281889) (xy 194.497493 -345.331504)
			(xy 194.512859 -345.383839) (xy 194.520621 -345.437828) (xy 194.520621 -345.492365) (xy 196.00347 -345.492365)
			(xy 196.00347 -345.437835) (xy 196.01123 -345.383861) (xy 196.026592 -345.33154) (xy 196.049244 -345.281937)
			(xy 196.078723 -345.236063) (xy 196.114431 -345.194851) (xy 196.155641 -345.15914) (xy 196.201513 -345.129657)
			(xy 196.251113 -345.107002) (xy 196.303433 -345.091636) (xy 196.357407 -345.083872) (xy 196.384672 -345.083384)
			(xy 197.248272 -345.083384) (xy 197.275548 -345.083754) (xy 197.329544 -345.091514) (xy 197.381886 -345.106879)
			(xy 197.431509 -345.129538) (xy 197.477402 -345.159028) (xy 197.51863 -345.19475) (xy 197.554355 -345.235976)
			(xy 197.583849 -345.281866) (xy 197.606511 -345.331487) (xy 197.621881 -345.383829) (xy 197.629644 -345.437824)
			(xy 197.629644 -345.492368) (xy 267.515847 -345.492368) (xy 267.515847 -345.437832) (xy 267.523609 -345.383852)
			(xy 267.538973 -345.331525) (xy 267.561628 -345.281918) (xy 267.591112 -345.23604) (xy 267.626826 -345.194824)
			(xy 267.668041 -345.159111) (xy 267.71392 -345.129627) (xy 267.763527 -345.106972) (xy 267.815854 -345.091608)
			(xy 267.869834 -345.083847) (xy 267.897102 -345.083384) (xy 268.760702 -345.083384) (xy 268.787975 -345.083779)
			(xy 268.841964 -345.091542) (xy 268.8943 -345.106909) (xy 268.943916 -345.129568) (xy 268.989802 -345.159057)
			(xy 269.031024 -345.194777) (xy 269.066744 -345.236) (xy 269.096233 -345.281886) (xy 269.118892 -345.331502)
			(xy 269.134259 -345.383838) (xy 269.142021 -345.437827) (xy 269.142021 -345.492364) (xy 270.62487 -345.492364)
			(xy 270.62487 -345.437836) (xy 270.63263 -345.383862) (xy 270.647992 -345.331542) (xy 270.670642 -345.28194)
			(xy 270.700121 -345.236066) (xy 270.735828 -345.194855) (xy 270.777036 -345.159144) (xy 270.822907 -345.12966)
			(xy 270.872506 -345.107005) (xy 270.924825 -345.091638) (xy 270.978798 -345.083873) (xy 271.006062 -345.083384)
			(xy 271.869662 -345.083384) (xy 271.896938 -345.083753) (xy 271.950936 -345.091512) (xy 272.003279 -345.106877)
			(xy 272.052903 -345.129535) (xy 272.098797 -345.159025) (xy 272.140027 -345.194747) (xy 272.175752 -345.235973)
			(xy 272.205247 -345.281864) (xy 272.22791 -345.331485) (xy 272.24328 -345.383827) (xy 272.251044 -345.437824)
			(xy 272.251044 -345.492369) (xy 273.733747 -345.492369) (xy 273.733747 -345.437831) (xy 273.741509 -345.383849)
			(xy 273.756875 -345.331521) (xy 273.779531 -345.281912) (xy 273.809017 -345.236033) (xy 273.844733 -345.194817)
			(xy 273.885951 -345.159104) (xy 273.931832 -345.129621) (xy 273.981441 -345.106967) (xy 274.033771 -345.091605)
			(xy 274.087753 -345.083846) (xy 274.115022 -345.083384) (xy 274.978622 -345.083384) (xy 275.005894 -345.08378)
			(xy 275.059881 -345.091545) (xy 275.112215 -345.106914) (xy 275.161828 -345.129574) (xy 275.207712 -345.159064)
			(xy 275.248932 -345.194784) (xy 275.284649 -345.236006) (xy 275.314136 -345.281891) (xy 275.336793 -345.331506)
			(xy 275.352159 -345.38384) (xy 275.359922 -345.437828) (xy 275.359922 -345.492365) (xy 276.84277 -345.492365)
			(xy 276.84277 -345.437835) (xy 276.850531 -345.383859) (xy 276.865893 -345.331537) (xy 276.888545 -345.281934)
			(xy 276.918026 -345.23606) (xy 276.953735 -345.194848) (xy 276.994945 -345.159137) (xy 277.040819 -345.129654)
			(xy 277.090421 -345.106999) (xy 277.142742 -345.091634) (xy 277.196717 -345.083872) (xy 277.223982 -345.083384)
			(xy 278.087582 -345.083384) (xy 278.114857 -345.083754) (xy 278.168852 -345.091515) (xy 278.221194 -345.106882)
			(xy 278.270815 -345.129541) (xy 278.316706 -345.159032) (xy 278.357934 -345.194754) (xy 278.393657 -345.235979)
			(xy 278.42315 -345.281869) (xy 278.445812 -345.33149) (xy 278.461181 -345.38383) (xy 278.468944 -345.437825)
			(xy 278.468944 -345.49237) (xy 279.951648 -345.49237) (xy 279.951648 -345.43783) (xy 279.95941 -345.383846)
			(xy 279.974776 -345.331517) (xy 279.997434 -345.281907) (xy 280.026922 -345.236026) (xy 280.06264 -345.19481)
			(xy 280.10386 -345.159097) (xy 280.149744 -345.129614) (xy 280.199356 -345.106962) (xy 280.251687 -345.091601)
			(xy 280.305672 -345.083845) (xy 280.332942 -345.083384) (xy 281.196542 -345.083384) (xy 281.223813 -345.083781)
			(xy 281.277798 -345.091549) (xy 281.330129 -345.10692) (xy 281.37974 -345.129581) (xy 281.425621 -345.159072)
			(xy 281.466839 -345.194791) (xy 281.502554 -345.236013) (xy 281.532039 -345.281897) (xy 281.554695 -345.33151)
			(xy 281.57006 -345.383843) (xy 281.577822 -345.437829) (xy 281.577822 -345.492368) (xy 283.060647 -345.492368)
			(xy 283.060647 -345.437832) (xy 283.068409 -345.383852) (xy 283.083773 -345.331525) (xy 283.106428 -345.281918)
			(xy 283.135912 -345.23604) (xy 283.171626 -345.194824) (xy 283.212841 -345.159111) (xy 283.25872 -345.129627)
			(xy 283.308327 -345.106972) (xy 283.360654 -345.091608) (xy 283.414634 -345.083847) (xy 283.441902 -345.083384)
			(xy 284.305502 -345.083384) (xy 284.332775 -345.083779) (xy 284.386764 -345.091542) (xy 284.4391 -345.106909)
			(xy 284.488716 -345.129568) (xy 284.534602 -345.159057) (xy 284.575824 -345.194777) (xy 284.611544 -345.236)
			(xy 284.641033 -345.281886) (xy 284.663692 -345.331502) (xy 284.679059 -345.383838) (xy 284.686821 -345.437827)
			(xy 284.686821 -345.492364) (xy 286.16967 -345.492364) (xy 286.16967 -345.437836) (xy 286.17743 -345.383862)
			(xy 286.192792 -345.331542) (xy 286.215442 -345.28194) (xy 286.244921 -345.236066) (xy 286.280628 -345.194855)
			(xy 286.321836 -345.159144) (xy 286.367707 -345.12966) (xy 286.417306 -345.107005) (xy 286.469625 -345.091638)
			(xy 286.523598 -345.083873) (xy 286.550862 -345.083384) (xy 287.414462 -345.083384) (xy 287.441738 -345.083753)
			(xy 287.495736 -345.091512) (xy 287.548079 -345.106877) (xy 287.597703 -345.129535) (xy 287.643597 -345.159025)
			(xy 287.684827 -345.194747) (xy 287.720552 -345.235973) (xy 287.750047 -345.281864) (xy 287.77271 -345.331485)
			(xy 287.78808 -345.383827) (xy 287.795844 -345.437824) (xy 287.795844 -345.492369) (xy 289.278547 -345.492369)
			(xy 289.278547 -345.437831) (xy 289.286309 -345.383849) (xy 289.301675 -345.331521) (xy 289.324331 -345.281912)
			(xy 289.353817 -345.236033) (xy 289.389533 -345.194817) (xy 289.430751 -345.159104) (xy 289.476632 -345.129621)
			(xy 289.526241 -345.106967) (xy 289.578571 -345.091605) (xy 289.632553 -345.083846) (xy 289.659822 -345.083384)
			(xy 290.523422 -345.083384) (xy 290.550694 -345.08378) (xy 290.604681 -345.091545) (xy 290.657015 -345.106914)
			(xy 290.706628 -345.129574) (xy 290.752512 -345.159064) (xy 290.793732 -345.194784) (xy 290.829449 -345.236006)
			(xy 290.858936 -345.281891) (xy 290.881593 -345.331506) (xy 290.896959 -345.38384) (xy 290.904722 -345.437828)
			(xy 290.904722 -345.492365) (xy 292.38757 -345.492365) (xy 292.38757 -345.437835) (xy 292.395331 -345.383859)
			(xy 292.410693 -345.331537) (xy 292.433345 -345.281934) (xy 292.462826 -345.23606) (xy 292.498535 -345.194848)
			(xy 292.539745 -345.159137) (xy 292.585619 -345.129654) (xy 292.635221 -345.106999) (xy 292.687542 -345.091634)
			(xy 292.741517 -345.083872) (xy 292.768782 -345.083384) (xy 293.632382 -345.083384) (xy 293.659657 -345.083754)
			(xy 293.713652 -345.091515) (xy 293.765994 -345.106882) (xy 293.815615 -345.129541) (xy 293.861506 -345.159032)
			(xy 293.902734 -345.194754) (xy 293.938457 -345.235979) (xy 293.96795 -345.281869) (xy 293.990612 -345.33149)
			(xy 294.005981 -345.38383) (xy 294.013744 -345.437825) (xy 294.013744 -345.49237) (xy 295.496448 -345.49237)
			(xy 295.496448 -345.43783) (xy 295.50421 -345.383846) (xy 295.519576 -345.331517) (xy 295.542234 -345.281907)
			(xy 295.571722 -345.236026) (xy 295.60744 -345.19481) (xy 295.64866 -345.159097) (xy 295.694544 -345.129614)
			(xy 295.744156 -345.106962) (xy 295.796487 -345.091601) (xy 295.850472 -345.083845) (xy 295.877742 -345.083384)
			(xy 296.741342 -345.083384) (xy 296.768613 -345.083781) (xy 296.822598 -345.091549) (xy 296.874929 -345.10692)
			(xy 296.92454 -345.129581) (xy 296.970421 -345.159072) (xy 297.011639 -345.194791) (xy 297.047354 -345.236013)
			(xy 297.076839 -345.281897) (xy 297.099495 -345.33151) (xy 297.11486 -345.383843) (xy 297.122622 -345.437829)
			(xy 297.122622 -345.492368) (xy 298.605447 -345.492368) (xy 298.605447 -345.437832) (xy 298.613209 -345.383852)
			(xy 298.628573 -345.331525) (xy 298.651228 -345.281918) (xy 298.680712 -345.23604) (xy 298.716426 -345.194824)
			(xy 298.757641 -345.159111) (xy 298.80352 -345.129627) (xy 298.853127 -345.106972) (xy 298.905454 -345.091608)
			(xy 298.959434 -345.083847) (xy 298.986702 -345.083384) (xy 299.850302 -345.083384) (xy 299.877575 -345.083779)
			(xy 299.931564 -345.091542) (xy 299.9839 -345.106909) (xy 300.033516 -345.129568) (xy 300.079402 -345.159057)
			(xy 300.120624 -345.194777) (xy 300.156344 -345.236) (xy 300.185833 -345.281886) (xy 300.208492 -345.331502)
			(xy 300.223859 -345.383838) (xy 300.231621 -345.437827) (xy 300.231621 -345.492368) (xy 312.121547 -345.492368)
			(xy 312.121547 -345.437832) (xy 312.129309 -345.383851) (xy 312.144673 -345.331525) (xy 312.167328 -345.281917)
			(xy 312.196813 -345.236039) (xy 312.232526 -345.194824) (xy 312.273742 -345.159111) (xy 312.319621 -345.129627)
			(xy 312.369228 -345.106972) (xy 312.421555 -345.091608) (xy 312.475536 -345.083847) (xy 312.502804 -345.083384)
			(xy 313.366404 -345.083384) (xy 313.393676 -345.083779) (xy 313.447666 -345.091542) (xy 313.500001 -345.106909)
			(xy 313.549617 -345.129569) (xy 313.595503 -345.159058) (xy 313.636725 -345.194778) (xy 313.672444 -345.236)
			(xy 313.701933 -345.281886) (xy 313.724592 -345.331502) (xy 313.739959 -345.383838) (xy 313.747721 -345.437828)
			(xy 313.747721 -345.492364) (xy 315.23057 -345.492364) (xy 315.23057 -345.437836) (xy 315.23833 -345.383862)
			(xy 315.253692 -345.331541) (xy 315.276343 -345.281939) (xy 315.305821 -345.236066) (xy 315.341529 -345.194854)
			(xy 315.382737 -345.159143) (xy 315.428608 -345.12966) (xy 315.478207 -345.107004) (xy 315.530526 -345.091638)
			(xy 315.5845 -345.083873) (xy 315.611764 -345.083384) (xy 316.475364 -345.083384) (xy 316.50264 -345.083753)
			(xy 316.556637 -345.091512) (xy 316.608981 -345.106877) (xy 316.658604 -345.129535) (xy 316.704498 -345.159026)
			(xy 316.745727 -345.194747) (xy 316.781453 -345.235973) (xy 316.810947 -345.281864) (xy 316.83361 -345.331486)
			(xy 316.84898 -345.383828) (xy 316.856744 -345.437824) (xy 316.856744 -345.492369) (xy 318.339447 -345.492369)
			(xy 318.339447 -345.437831) (xy 318.347209 -345.383849) (xy 318.362575 -345.33152) (xy 318.385231 -345.281912)
			(xy 318.414718 -345.236032) (xy 318.450434 -345.194817) (xy 318.491652 -345.159103) (xy 318.537533 -345.12962)
			(xy 318.587143 -345.106966) (xy 318.639472 -345.091604) (xy 318.693455 -345.083846) (xy 318.720724 -345.083384)
			(xy 319.584324 -345.083384) (xy 319.611596 -345.08378) (xy 319.665583 -345.091546) (xy 319.717916 -345.106915)
			(xy 319.767529 -345.129575) (xy 319.813413 -345.159065) (xy 319.854632 -345.194785) (xy 319.890349 -345.236007)
			(xy 319.919836 -345.281892) (xy 319.942494 -345.331507) (xy 319.95786 -345.38384) (xy 319.965622 -345.437828)
			(xy 319.965622 -345.492365) (xy 321.44847 -345.492365) (xy 321.44847 -345.437835) (xy 321.456231 -345.383859)
			(xy 321.471593 -345.331537) (xy 321.494246 -345.281934) (xy 321.523726 -345.236059) (xy 321.559436 -345.194847)
			(xy 321.600646 -345.159136) (xy 321.64652 -345.129653) (xy 321.696122 -345.106999) (xy 321.748443 -345.091634)
			(xy 321.802419 -345.083871) (xy 321.829684 -345.083384) (xy 322.693284 -345.083384) (xy 322.720559 -345.083755)
			(xy 322.774554 -345.091516) (xy 322.826895 -345.106882) (xy 322.876516 -345.129542) (xy 322.922407 -345.159033)
			(xy 322.963634 -345.194754) (xy 322.999358 -345.23598) (xy 323.02885 -345.28187) (xy 323.051512 -345.33149)
			(xy 323.066881 -345.38383) (xy 323.074644 -345.437825) (xy 323.074644 -345.49237) (xy 324.557348 -345.49237)
			(xy 324.557348 -345.43783) (xy 324.56511 -345.383846) (xy 324.580476 -345.331516) (xy 324.603135 -345.281906)
			(xy 324.632623 -345.236026) (xy 324.668341 -345.194809) (xy 324.709561 -345.159096) (xy 324.755445 -345.129613)
			(xy 324.805057 -345.106961) (xy 324.857389 -345.0916) (xy 324.911374 -345.083844) (xy 324.938644 -345.083384)
			(xy 325.802244 -345.083384) (xy 325.829515 -345.083782) (xy 325.8835 -345.091549) (xy 325.93583 -345.10692)
			(xy 325.985441 -345.129582) (xy 326.031322 -345.159072) (xy 326.072539 -345.194792) (xy 326.108254 -345.236013)
			(xy 326.137739 -345.281898) (xy 326.160395 -345.331511) (xy 326.17576 -345.383843) (xy 326.183522 -345.437829)
			(xy 326.183522 -345.492368) (xy 327.666347 -345.492368) (xy 327.666347 -345.437832) (xy 327.674109 -345.383851)
			(xy 327.689473 -345.331525) (xy 327.712128 -345.281917) (xy 327.741613 -345.236039) (xy 327.777326 -345.194824)
			(xy 327.818542 -345.159111) (xy 327.864421 -345.129627) (xy 327.914028 -345.106972) (xy 327.966355 -345.091608)
			(xy 328.020336 -345.083847) (xy 328.047604 -345.083384) (xy 328.911204 -345.083384) (xy 328.938476 -345.083779)
			(xy 328.992466 -345.091542) (xy 329.044801 -345.106909) (xy 329.094417 -345.129569) (xy 329.140303 -345.159058)
			(xy 329.181525 -345.194778) (xy 329.217244 -345.236) (xy 329.246733 -345.281886) (xy 329.269392 -345.331502)
			(xy 329.284759 -345.383838) (xy 329.292521 -345.437828) (xy 329.292521 -345.492364) (xy 330.77537 -345.492364)
			(xy 330.77537 -345.437836) (xy 330.78313 -345.383862) (xy 330.798492 -345.331541) (xy 330.821143 -345.281939)
			(xy 330.850621 -345.236066) (xy 330.886329 -345.194854) (xy 330.927537 -345.159143) (xy 330.973408 -345.12966)
			(xy 331.023007 -345.107004) (xy 331.075326 -345.091638) (xy 331.1293 -345.083873) (xy 331.156564 -345.083384)
			(xy 332.020164 -345.083384) (xy 332.04744 -345.083753) (xy 332.101437 -345.091512) (xy 332.153781 -345.106877)
			(xy 332.203404 -345.129535) (xy 332.249298 -345.159026) (xy 332.290527 -345.194747) (xy 332.326253 -345.235973)
			(xy 332.355747 -345.281864) (xy 332.37841 -345.331486) (xy 332.39378 -345.383828) (xy 332.401544 -345.437824)
			(xy 332.401544 -345.492369) (xy 333.884247 -345.492369) (xy 333.884247 -345.437831) (xy 333.892009 -345.383849)
			(xy 333.907375 -345.33152) (xy 333.930031 -345.281912) (xy 333.959518 -345.236032) (xy 333.995234 -345.194817)
			(xy 334.036452 -345.159103) (xy 334.082333 -345.12962) (xy 334.131943 -345.106966) (xy 334.184272 -345.091604)
			(xy 334.238255 -345.083846) (xy 334.265524 -345.083384) (xy 335.129124 -345.083384) (xy 335.156396 -345.08378)
			(xy 335.210383 -345.091546) (xy 335.262716 -345.106915) (xy 335.312329 -345.129575) (xy 335.358213 -345.159065)
			(xy 335.399432 -345.194785) (xy 335.435149 -345.236007) (xy 335.464636 -345.281892) (xy 335.487294 -345.331507)
			(xy 335.50266 -345.38384) (xy 335.510422 -345.437828) (xy 335.510422 -345.492365) (xy 336.99327 -345.492365)
			(xy 336.99327 -345.437835) (xy 337.001031 -345.383859) (xy 337.016393 -345.331537) (xy 337.039046 -345.281934)
			(xy 337.068526 -345.236059) (xy 337.104236 -345.194847) (xy 337.145446 -345.159136) (xy 337.19132 -345.129653)
			(xy 337.240922 -345.106999) (xy 337.293243 -345.091634) (xy 337.347219 -345.083871) (xy 337.374484 -345.083384)
			(xy 338.238084 -345.083384) (xy 338.265359 -345.083755) (xy 338.319354 -345.091516) (xy 338.371695 -345.106882)
			(xy 338.421316 -345.129542) (xy 338.467207 -345.159033) (xy 338.508434 -345.194754) (xy 338.544158 -345.23598)
			(xy 338.57365 -345.28187) (xy 338.596312 -345.33149) (xy 338.611681 -345.38383) (xy 338.619444 -345.437825)
			(xy 338.619444 -345.49237) (xy 340.102148 -345.49237) (xy 340.102148 -345.43783) (xy 340.10991 -345.383846)
			(xy 340.125276 -345.331516) (xy 340.147935 -345.281906) (xy 340.177423 -345.236026) (xy 340.213141 -345.194809)
			(xy 340.254361 -345.159096) (xy 340.300245 -345.129613) (xy 340.349857 -345.106961) (xy 340.402189 -345.0916)
			(xy 340.456174 -345.083844) (xy 340.483444 -345.083384) (xy 341.347044 -345.083384) (xy 341.374315 -345.083782)
			(xy 341.4283 -345.091549) (xy 341.48063 -345.10692) (xy 341.530241 -345.129582) (xy 341.576122 -345.159072)
			(xy 341.617339 -345.194792) (xy 341.653054 -345.236013) (xy 341.682539 -345.281898) (xy 341.705195 -345.331511)
			(xy 341.72056 -345.383843) (xy 341.728322 -345.437829) (xy 341.728322 -345.492368) (xy 343.211147 -345.492368)
			(xy 343.211147 -345.437832) (xy 343.218909 -345.383851) (xy 343.234273 -345.331525) (xy 343.256928 -345.281917)
			(xy 343.286413 -345.236039) (xy 343.322126 -345.194824) (xy 343.363342 -345.159111) (xy 343.409221 -345.129627)
			(xy 343.458828 -345.106972) (xy 343.511155 -345.091608) (xy 343.565136 -345.083847) (xy 343.592404 -345.083384)
			(xy 344.456004 -345.083384) (xy 344.483276 -345.083779) (xy 344.537266 -345.091542) (xy 344.589601 -345.106909)
			(xy 344.639217 -345.129569) (xy 344.685103 -345.159058) (xy 344.726325 -345.194778) (xy 344.762044 -345.236)
			(xy 344.791533 -345.281886) (xy 344.814192 -345.331502) (xy 344.829559 -345.383838) (xy 344.837321 -345.437828)
			(xy 344.837321 -345.492365) (xy 370.80677 -345.492365) (xy 370.80677 -345.437835) (xy 370.81453 -345.383859)
			(xy 370.829893 -345.331538) (xy 370.852545 -345.281935) (xy 370.882025 -345.236061) (xy 370.917734 -345.194848)
			(xy 370.958945 -345.159137) (xy 371.004817 -345.129655) (xy 371.054419 -345.107) (xy 371.10674 -345.091635)
			(xy 371.160715 -345.083872) (xy 371.18798 -345.083384) (xy 372.05158 -345.083384) (xy 372.078855 -345.083754)
			(xy 372.132851 -345.091515) (xy 372.185192 -345.106881) (xy 372.234814 -345.129541) (xy 372.280705 -345.159031)
			(xy 372.321933 -345.194753) (xy 372.357657 -345.235978) (xy 372.38715 -345.281869) (xy 372.409812 -345.331489)
			(xy 372.425181 -345.38383) (xy 372.432944 -345.437825) (xy 372.432944 -345.49237) (xy 373.915647 -345.49237)
			(xy 373.915647 -345.43783) (xy 373.92341 -345.383847) (xy 373.938776 -345.331517) (xy 373.961434 -345.281907)
			(xy 373.990922 -345.236027) (xy 374.026639 -345.194811) (xy 374.067859 -345.159098) (xy 374.113742 -345.129615)
			(xy 374.163355 -345.106962) (xy 374.215686 -345.091601) (xy 374.26967 -345.083845) (xy 374.29694 -345.083384)
			(xy 375.16054 -345.083384) (xy 375.187811 -345.083781) (xy 375.241797 -345.091549) (xy 375.294128 -345.106919)
			(xy 375.343739 -345.12958) (xy 375.38962 -345.159071) (xy 375.430838 -345.19479) (xy 375.466553 -345.236012)
			(xy 375.496039 -345.281896) (xy 375.518695 -345.33151) (xy 375.53406 -345.383843) (xy 375.541822 -345.437829)
			(xy 375.541822 -345.492366) (xy 377.02467 -345.492366) (xy 377.02467 -345.437834) (xy 377.032431 -345.383857)
			(xy 377.047795 -345.331534) (xy 377.070448 -345.281929) (xy 377.09993 -345.236054) (xy 377.135641 -345.194841)
			(xy 377.176854 -345.15913) (xy 377.222729 -345.129648) (xy 377.272334 -345.106995) (xy 377.324657 -345.091631)
			(xy 377.378634 -345.08387) (xy 377.4059 -345.083384) (xy 378.2695 -345.083384) (xy 378.296773 -345.083779)
			(xy 378.350763 -345.091541) (xy 378.403099 -345.106908) (xy 378.452715 -345.129567) (xy 378.498601 -345.159057)
			(xy 378.539824 -345.194776) (xy 378.575543 -345.235999) (xy 378.605033 -345.281885) (xy 378.627692 -345.331501)
			(xy 378.643059 -345.383837) (xy 378.650821 -345.437827) (xy 378.650821 -345.492364) (xy 380.13367 -345.492364)
			(xy 380.13367 -345.437836) (xy 380.14143 -345.383862) (xy 380.156791 -345.331542) (xy 380.179442 -345.281941)
			(xy 380.208921 -345.236067) (xy 380.244627 -345.194855) (xy 380.285835 -345.159145) (xy 380.331705 -345.129661)
			(xy 380.381305 -345.107005) (xy 380.433623 -345.091638) (xy 380.487596 -345.083873) (xy 380.51486 -345.083384)
			(xy 381.37846 -345.083384) (xy 381.405736 -345.083753) (xy 381.459734 -345.091511) (xy 381.512078 -345.106876)
			(xy 381.561702 -345.129534) (xy 381.607596 -345.159024) (xy 381.648826 -345.194746) (xy 381.684552 -345.235972)
			(xy 381.714047 -345.281863) (xy 381.73671 -345.331485) (xy 381.75208 -345.383827) (xy 381.759844 -345.437824)
			(xy 381.759844 -345.492369) (xy 383.242547 -345.492369) (xy 383.242547 -345.437831) (xy 383.250309 -345.383849)
			(xy 383.265675 -345.331521) (xy 383.288331 -345.281913) (xy 383.317817 -345.236034) (xy 383.353532 -345.194818)
			(xy 383.39475 -345.159105) (xy 383.44063 -345.129621) (xy 383.49024 -345.106968) (xy 383.542569 -345.091605)
			(xy 383.596551 -345.083846) (xy 383.62382 -345.083384) (xy 384.48742 -345.083384) (xy 384.514692 -345.08378)
			(xy 384.56868 -345.091545) (xy 384.621013 -345.106914) (xy 384.670627 -345.129574) (xy 384.716511 -345.159064)
			(xy 384.757731 -345.194783) (xy 384.793448 -345.236005) (xy 384.822936 -345.281891) (xy 384.845593 -345.331506)
			(xy 384.860959 -345.38384) (xy 384.868722 -345.437828) (xy 384.868722 -345.492365) (xy 386.35157 -345.492365)
			(xy 386.35157 -345.437835) (xy 386.35933 -345.383859) (xy 386.374693 -345.331538) (xy 386.397345 -345.281935)
			(xy 386.426825 -345.236061) (xy 386.462534 -345.194848) (xy 386.503745 -345.159137) (xy 386.549617 -345.129655)
			(xy 386.599219 -345.107) (xy 386.65154 -345.091635) (xy 386.705515 -345.083872) (xy 386.73278 -345.083384)
			(xy 387.59638 -345.083384) (xy 387.623655 -345.083754) (xy 387.677651 -345.091515) (xy 387.729992 -345.106881)
			(xy 387.779614 -345.129541) (xy 387.825505 -345.159031) (xy 387.866733 -345.194753) (xy 387.902457 -345.235978)
			(xy 387.93195 -345.281869) (xy 387.954612 -345.331489) (xy 387.969981 -345.38383) (xy 387.977744 -345.437825)
			(xy 387.977744 -345.49237) (xy 389.460447 -345.49237) (xy 389.460447 -345.43783) (xy 389.46821 -345.383847)
			(xy 389.483576 -345.331517) (xy 389.506234 -345.281907) (xy 389.535722 -345.236027) (xy 389.571439 -345.194811)
			(xy 389.612659 -345.159098) (xy 389.658542 -345.129615) (xy 389.708155 -345.106962) (xy 389.760486 -345.091601)
			(xy 389.81447 -345.083845) (xy 389.84174 -345.083384) (xy 390.70534 -345.083384) (xy 390.732611 -345.083781)
			(xy 390.786597 -345.091549) (xy 390.838928 -345.106919) (xy 390.888539 -345.12958) (xy 390.93442 -345.159071)
			(xy 390.975638 -345.19479) (xy 391.011353 -345.236012) (xy 391.040839 -345.281896) (xy 391.063495 -345.33151)
			(xy 391.07886 -345.383843) (xy 391.086622 -345.437829) (xy 391.086622 -345.492366) (xy 392.56947 -345.492366)
			(xy 392.56947 -345.437834) (xy 392.577231 -345.383857) (xy 392.592595 -345.331534) (xy 392.615248 -345.281929)
			(xy 392.64473 -345.236054) (xy 392.680441 -345.194841) (xy 392.721654 -345.15913) (xy 392.767529 -345.129648)
			(xy 392.817134 -345.106995) (xy 392.869457 -345.091631) (xy 392.923434 -345.08387) (xy 392.9507 -345.083384)
			(xy 393.8143 -345.083384) (xy 393.841573 -345.083779) (xy 393.895563 -345.091541) (xy 393.947899 -345.106908)
			(xy 393.997515 -345.129567) (xy 394.043401 -345.159057) (xy 394.084624 -345.194776) (xy 394.120343 -345.235999)
			(xy 394.149833 -345.281885) (xy 394.172492 -345.331501) (xy 394.187859 -345.383837) (xy 394.195621 -345.437827)
			(xy 394.195621 -345.492364) (xy 395.67847 -345.492364) (xy 395.67847 -345.437836) (xy 395.68623 -345.383862)
			(xy 395.701591 -345.331542) (xy 395.724242 -345.281941) (xy 395.753721 -345.236067) (xy 395.789427 -345.194855)
			(xy 395.830635 -345.159145) (xy 395.876505 -345.129661) (xy 395.926105 -345.107005) (xy 395.978423 -345.091638)
			(xy 396.032396 -345.083873) (xy 396.05966 -345.083384) (xy 396.92326 -345.083384) (xy 396.950536 -345.083753)
			(xy 397.004534 -345.091511) (xy 397.056878 -345.106876) (xy 397.106502 -345.129534) (xy 397.152396 -345.159024)
			(xy 397.193626 -345.194746) (xy 397.229352 -345.235972) (xy 397.258847 -345.281863) (xy 397.28151 -345.331485)
			(xy 397.29688 -345.383827) (xy 397.304644 -345.437824) (xy 397.304644 -345.492369) (xy 398.787347 -345.492369)
			(xy 398.787347 -345.437831) (xy 398.795109 -345.383849) (xy 398.810475 -345.331521) (xy 398.833131 -345.281913)
			(xy 398.862617 -345.236034) (xy 398.898332 -345.194818) (xy 398.93955 -345.159105) (xy 398.98543 -345.129621)
			(xy 399.03504 -345.106968) (xy 399.087369 -345.091605) (xy 399.141351 -345.083846) (xy 399.16862 -345.083384)
			(xy 400.03222 -345.083384) (xy 400.059492 -345.08378) (xy 400.11348 -345.091545) (xy 400.165813 -345.106914)
			(xy 400.215427 -345.129574) (xy 400.261311 -345.159064) (xy 400.302531 -345.194783) (xy 400.338248 -345.236005)
			(xy 400.367736 -345.281891) (xy 400.390393 -345.331506) (xy 400.405759 -345.38384) (xy 400.413522 -345.437828)
			(xy 400.413522 -345.492365) (xy 401.89637 -345.492365) (xy 401.89637 -345.437835) (xy 401.90413 -345.383859)
			(xy 401.919493 -345.331538) (xy 401.942145 -345.281935) (xy 401.971625 -345.236061) (xy 402.007334 -345.194848)
			(xy 402.048545 -345.159137) (xy 402.094417 -345.129655) (xy 402.144019 -345.107) (xy 402.19634 -345.091635)
			(xy 402.250315 -345.083872) (xy 402.27758 -345.083384) (xy 403.14118 -345.083384) (xy 403.168455 -345.083754)
			(xy 403.222451 -345.091515) (xy 403.274792 -345.106881) (xy 403.324414 -345.129541) (xy 403.370305 -345.159031)
			(xy 403.411533 -345.194753) (xy 403.447257 -345.235978) (xy 403.47675 -345.281869) (xy 403.499412 -345.331489)
			(xy 403.514781 -345.38383) (xy 403.522544 -345.437825) (xy 403.522544 -345.492366) (xy 408.91387 -345.492366)
			(xy 408.91387 -345.437834) (xy 408.921631 -345.383858) (xy 408.936994 -345.331535) (xy 408.959647 -345.281932)
			(xy 408.989128 -345.236057) (xy 409.024838 -345.194844) (xy 409.06605 -345.159133) (xy 409.111925 -345.129651)
			(xy 409.161528 -345.106997) (xy 409.21385 -345.091633) (xy 409.267826 -345.083871) (xy 409.295092 -345.083384)
			(xy 410.158692 -345.083384) (xy 410.185967 -345.083755) (xy 410.239961 -345.091517) (xy 410.292301 -345.106885)
			(xy 410.341921 -345.129544) (xy 410.387811 -345.159035) (xy 410.429037 -345.194757) (xy 410.46476 -345.235982)
			(xy 410.494252 -345.281872) (xy 410.516913 -345.331492) (xy 410.532281 -345.383831) (xy 410.540044 -345.437825)
			(xy 410.540044 -345.492364) (xy 412.02287 -345.492364) (xy 412.02287 -345.437836) (xy 412.03063 -345.383863)
			(xy 412.045991 -345.331544) (xy 412.068641 -345.281943) (xy 412.098119 -345.23607) (xy 412.133824 -345.194858)
			(xy 412.175031 -345.159147) (xy 412.220901 -345.129664) (xy 412.270499 -345.107008) (xy 412.322816 -345.09164)
			(xy 412.376788 -345.083874) (xy 412.404052 -345.083384) (xy 413.267652 -345.083384) (xy 413.294929 -345.083752)
			(xy 413.348927 -345.09151) (xy 413.401272 -345.106874) (xy 413.450897 -345.129531) (xy 413.496792 -345.159021)
			(xy 413.538023 -345.194743) (xy 413.57375 -345.235969) (xy 413.603246 -345.281861) (xy 413.625909 -345.331483)
			(xy 413.64128 -345.383826) (xy 413.649044 -345.437824) (xy 413.649044 -345.492368) (xy 415.131747 -345.492368)
			(xy 415.131747 -345.437832) (xy 415.139509 -345.38385) (xy 415.154874 -345.331523) (xy 415.17753 -345.281915)
			(xy 415.207015 -345.236036) (xy 415.242729 -345.194821) (xy 415.283946 -345.159108) (xy 415.329826 -345.129624)
			(xy 415.379434 -345.10697) (xy 415.431762 -345.091606) (xy 415.485744 -345.083847) (xy 415.513012 -345.083384)
			(xy 416.376612 -345.083384) (xy 416.403884 -345.083779) (xy 416.457873 -345.091543) (xy 416.510207 -345.106912)
			(xy 416.559822 -345.129571) (xy 416.605707 -345.159061) (xy 416.646928 -345.194781) (xy 416.682646 -345.236003)
			(xy 416.712135 -345.281889) (xy 416.734793 -345.331504) (xy 416.750159 -345.383839) (xy 416.757921 -345.437828)
			(xy 416.757921 -345.492365) (xy 418.24077 -345.492365) (xy 418.24077 -345.437835) (xy 418.24853 -345.383861)
			(xy 418.263892 -345.33154) (xy 418.286544 -345.281937) (xy 418.316023 -345.236063) (xy 418.351731 -345.194851)
			(xy 418.392941 -345.15914) (xy 418.438813 -345.129657) (xy 418.488413 -345.107002) (xy 418.540733 -345.091636)
			(xy 418.594707 -345.083872) (xy 418.621972 -345.083384) (xy 419.485572 -345.083384) (xy 419.512848 -345.083754)
			(xy 419.566844 -345.091514) (xy 419.619186 -345.106879) (xy 419.668809 -345.129538) (xy 419.714702 -345.159028)
			(xy 419.75593 -345.19475) (xy 419.791655 -345.235976) (xy 419.821149 -345.281866) (xy 419.843811 -345.331487)
			(xy 419.859181 -345.383829) (xy 419.866944 -345.437824) (xy 419.866944 -345.492369) (xy 421.349647 -345.492369)
			(xy 421.349647 -345.437831) (xy 421.35741 -345.383848) (xy 421.372776 -345.331519) (xy 421.395433 -345.281909)
			(xy 421.42492 -345.23603) (xy 421.460636 -345.194814) (xy 421.501855 -345.159101) (xy 421.547738 -345.129617)
			(xy 421.597349 -345.106964) (xy 421.649679 -345.091603) (xy 421.703663 -345.083845) (xy 421.730932 -345.083384)
			(xy 422.594532 -345.083384) (xy 422.621803 -345.083781) (xy 422.67579 -345.091547) (xy 422.728122 -345.106917)
			(xy 422.777734 -345.129578) (xy 422.823616 -345.159068) (xy 422.864835 -345.194788) (xy 422.900551 -345.236009)
			(xy 422.930038 -345.281894) (xy 422.952694 -345.331508) (xy 422.96806 -345.383842) (xy 422.975822 -345.437829)
			(xy 422.975822 -345.492366) (xy 424.45867 -345.492366) (xy 424.45867 -345.437834) (xy 424.466431 -345.383858)
			(xy 424.481794 -345.331535) (xy 424.504447 -345.281932) (xy 424.533928 -345.236057) (xy 424.569638 -345.194844)
			(xy 424.61085 -345.159133) (xy 424.656725 -345.129651) (xy 424.706328 -345.106997) (xy 424.75865 -345.091633)
			(xy 424.812626 -345.083871) (xy 424.839892 -345.083384) (xy 425.703492 -345.083384) (xy 425.730767 -345.083755)
			(xy 425.784761 -345.091517) (xy 425.837101 -345.106885) (xy 425.886721 -345.129544) (xy 425.932611 -345.159035)
			(xy 425.973837 -345.194757) (xy 426.00956 -345.235982) (xy 426.039052 -345.281872) (xy 426.061713 -345.331492)
			(xy 426.077081 -345.383831) (xy 426.084844 -345.437825) (xy 426.084844 -345.492364) (xy 427.56767 -345.492364)
			(xy 427.56767 -345.437836) (xy 427.57543 -345.383863) (xy 427.590791 -345.331544) (xy 427.613441 -345.281943)
			(xy 427.642919 -345.23607) (xy 427.678624 -345.194858) (xy 427.719831 -345.159147) (xy 427.765701 -345.129664)
			(xy 427.815299 -345.107008) (xy 427.867616 -345.09164) (xy 427.921588 -345.083874) (xy 427.948852 -345.083384)
			(xy 428.812452 -345.083384) (xy 428.839729 -345.083752) (xy 428.893727 -345.09151) (xy 428.946072 -345.106874)
			(xy 428.995697 -345.129531) (xy 429.041592 -345.159021) (xy 429.082823 -345.194743) (xy 429.11855 -345.235969)
			(xy 429.148046 -345.281861) (xy 429.170709 -345.331483) (xy 429.18608 -345.383826) (xy 429.193844 -345.437824)
			(xy 429.193844 -345.492368) (xy 430.676547 -345.492368) (xy 430.676547 -345.437832) (xy 430.684309 -345.38385)
			(xy 430.699674 -345.331523) (xy 430.72233 -345.281915) (xy 430.751815 -345.236036) (xy 430.787529 -345.194821)
			(xy 430.828746 -345.159108) (xy 430.874626 -345.129624) (xy 430.924234 -345.10697) (xy 430.976562 -345.091606)
			(xy 431.030544 -345.083847) (xy 431.057812 -345.083384) (xy 431.921412 -345.083384) (xy 431.948684 -345.083779)
			(xy 432.002673 -345.091543) (xy 432.055007 -345.106912) (xy 432.104622 -345.129571) (xy 432.150507 -345.159061)
			(xy 432.191728 -345.194781) (xy 432.227446 -345.236003) (xy 432.256935 -345.281889) (xy 432.279593 -345.331504)
			(xy 432.294959 -345.383839) (xy 432.302721 -345.437828) (xy 432.302721 -345.492365) (xy 433.78557 -345.492365)
			(xy 433.78557 -345.437835) (xy 433.79333 -345.383861) (xy 433.808692 -345.33154) (xy 433.831344 -345.281937)
			(xy 433.860823 -345.236063) (xy 433.896531 -345.194851) (xy 433.937741 -345.15914) (xy 433.983613 -345.129657)
			(xy 434.033213 -345.107002) (xy 434.085533 -345.091636) (xy 434.139507 -345.083872) (xy 434.166772 -345.083384)
			(xy 435.030372 -345.083384) (xy 435.057648 -345.083754) (xy 435.111644 -345.091514) (xy 435.163986 -345.106879)
			(xy 435.213609 -345.129538) (xy 435.259502 -345.159028) (xy 435.30073 -345.19475) (xy 435.336455 -345.235976)
			(xy 435.365949 -345.281866) (xy 435.388611 -345.331487) (xy 435.403981 -345.383829) (xy 435.411744 -345.437824)
			(xy 435.411744 -345.492369) (xy 436.894447 -345.492369) (xy 436.894447 -345.437831) (xy 436.90221 -345.383848)
			(xy 436.917576 -345.331519) (xy 436.940233 -345.281909) (xy 436.96972 -345.23603) (xy 437.005436 -345.194814)
			(xy 437.046655 -345.159101) (xy 437.092538 -345.129617) (xy 437.142149 -345.106964) (xy 437.194479 -345.091603)
			(xy 437.248463 -345.083845) (xy 437.275732 -345.083384) (xy 438.139332 -345.083384) (xy 438.166603 -345.083781)
			(xy 438.22059 -345.091547) (xy 438.272922 -345.106917) (xy 438.322534 -345.129578) (xy 438.368416 -345.159068)
			(xy 438.409635 -345.194788) (xy 438.445351 -345.236009) (xy 438.474838 -345.281894) (xy 438.497494 -345.331508)
			(xy 438.51286 -345.383842) (xy 438.520622 -345.437829) (xy 438.520622 -345.492366) (xy 440.00347 -345.492366)
			(xy 440.00347 -345.437834) (xy 440.011231 -345.383858) (xy 440.026594 -345.331535) (xy 440.049247 -345.281932)
			(xy 440.078728 -345.236057) (xy 440.114438 -345.194844) (xy 440.15565 -345.159133) (xy 440.201525 -345.129651)
			(xy 440.251128 -345.106997) (xy 440.30345 -345.091633) (xy 440.357426 -345.083871) (xy 440.384692 -345.083384)
			(xy 441.248292 -345.083384) (xy 441.275567 -345.083755) (xy 441.329561 -345.091517) (xy 441.381901 -345.106885)
			(xy 441.431521 -345.129544) (xy 441.477411 -345.159035) (xy 441.518637 -345.194757) (xy 441.55436 -345.235982)
			(xy 441.583852 -345.281872) (xy 441.606513 -345.331492) (xy 441.621881 -345.383831) (xy 441.629644 -345.437825)
			(xy 441.629644 -345.492375) (xy 441.621881 -345.546369) (xy 441.606513 -345.598708) (xy 441.583852 -345.648328)
			(xy 441.55436 -345.694218) (xy 441.518637 -345.735443) (xy 441.477411 -345.771165) (xy 441.431521 -345.800656)
			(xy 441.381901 -345.823315) (xy 441.329561 -345.838683) (xy 441.275567 -345.846445) (xy 441.248292 -345.846908)
			(xy 440.384692 -345.846908) (xy 440.357426 -345.846329) (xy 440.30345 -345.838567) (xy 440.251128 -345.823203)
			(xy 440.201525 -345.800549) (xy 440.15565 -345.771067) (xy 440.114438 -345.735356) (xy 440.078728 -345.694143)
			(xy 440.049247 -345.648268) (xy 440.026594 -345.598665) (xy 440.011231 -345.546342) (xy 440.00347 -345.492366)
			(xy 438.520622 -345.492366) (xy 438.520622 -345.492371) (xy 438.51286 -345.546358) (xy 438.497494 -345.598692)
			(xy 438.474838 -345.648306) (xy 438.445351 -345.694191) (xy 438.409635 -345.735412) (xy 438.368416 -345.771132)
			(xy 438.322534 -345.800622) (xy 438.272922 -345.823283) (xy 438.22059 -345.838653) (xy 438.166603 -345.846419)
			(xy 438.139332 -345.846908) (xy 437.275732 -345.846908) (xy 437.248463 -345.846355) (xy 437.194479 -345.838597)
			(xy 437.142149 -345.823236) (xy 437.092538 -345.800583) (xy 437.046655 -345.771099) (xy 437.005436 -345.735386)
			(xy 436.96972 -345.69417) (xy 436.940233 -345.648291) (xy 436.917576 -345.598681) (xy 436.90221 -345.546352)
			(xy 436.894447 -345.492369) (xy 435.411744 -345.492369) (xy 435.411744 -345.492376) (xy 435.403981 -345.546371)
			(xy 435.388611 -345.598713) (xy 435.365949 -345.648334) (xy 435.336455 -345.694224) (xy 435.30073 -345.73545)
			(xy 435.259502 -345.771172) (xy 435.213609 -345.800662) (xy 435.163986 -345.823321) (xy 435.111644 -345.838686)
			(xy 435.057648 -345.846446) (xy 435.030372 -345.846908) (xy 434.166772 -345.846908) (xy 434.139507 -345.846328)
			(xy 434.085533 -345.838564) (xy 434.033213 -345.823198) (xy 433.983613 -345.800543) (xy 433.937741 -345.77106)
			(xy 433.896531 -345.735349) (xy 433.860823 -345.694137) (xy 433.831344 -345.648263) (xy 433.808692 -345.59866)
			(xy 433.79333 -345.546339) (xy 433.78557 -345.492365) (xy 432.302721 -345.492365) (xy 432.302721 -345.492372)
			(xy 432.294959 -345.546361) (xy 432.279593 -345.598696) (xy 432.256935 -345.648311) (xy 432.227446 -345.694197)
			(xy 432.191728 -345.735419) (xy 432.150507 -345.771139) (xy 432.104622 -345.800629) (xy 432.055007 -345.823288)
			(xy 432.002673 -345.838657) (xy 431.948684 -345.846421) (xy 431.921412 -345.846908) (xy 431.057812 -345.846908)
			(xy 431.030544 -345.846353) (xy 430.976562 -345.838594) (xy 430.924234 -345.82323) (xy 430.874626 -345.800576)
			(xy 430.828746 -345.771092) (xy 430.787529 -345.735379) (xy 430.751815 -345.694164) (xy 430.72233 -345.648285)
			(xy 430.699674 -345.598677) (xy 430.684309 -345.54635) (xy 430.676547 -345.492368) (xy 429.193844 -345.492368)
			(xy 429.193844 -345.492376) (xy 429.18608 -345.546374) (xy 429.170709 -345.598717) (xy 429.148046 -345.648339)
			(xy 429.11855 -345.694231) (xy 429.082823 -345.735457) (xy 429.041592 -345.771179) (xy 428.995697 -345.800669)
			(xy 428.946072 -345.823326) (xy 428.893727 -345.83869) (xy 428.839729 -345.846448) (xy 428.812452 -345.846908)
			(xy 427.948852 -345.846908) (xy 427.921588 -345.846326) (xy 427.867616 -345.83856) (xy 427.815299 -345.823192)
			(xy 427.765701 -345.800536) (xy 427.719831 -345.771053) (xy 427.678624 -345.735342) (xy 427.642919 -345.69413)
			(xy 427.613441 -345.648257) (xy 427.590791 -345.598656) (xy 427.57543 -345.546337) (xy 427.56767 -345.492364)
			(xy 426.084844 -345.492364) (xy 426.084844 -345.492375) (xy 426.077081 -345.546369) (xy 426.061713 -345.598708)
			(xy 426.039052 -345.648328) (xy 426.00956 -345.694218) (xy 425.973837 -345.735443) (xy 425.932611 -345.771165)
			(xy 425.886721 -345.800656) (xy 425.837101 -345.823315) (xy 425.784761 -345.838683) (xy 425.730767 -345.846445)
			(xy 425.703492 -345.846908) (xy 424.839892 -345.846908) (xy 424.812626 -345.846329) (xy 424.75865 -345.838567)
			(xy 424.706328 -345.823203) (xy 424.656725 -345.800549) (xy 424.61085 -345.771067) (xy 424.569638 -345.735356)
			(xy 424.533928 -345.694143) (xy 424.504447 -345.648268) (xy 424.481794 -345.598665) (xy 424.466431 -345.546342)
			(xy 424.45867 -345.492366) (xy 422.975822 -345.492366) (xy 422.975822 -345.492371) (xy 422.96806 -345.546358)
			(xy 422.952694 -345.598692) (xy 422.930038 -345.648306) (xy 422.900551 -345.694191) (xy 422.864835 -345.735412)
			(xy 422.823616 -345.771132) (xy 422.777734 -345.800622) (xy 422.728122 -345.823283) (xy 422.67579 -345.838653)
			(xy 422.621803 -345.846419) (xy 422.594532 -345.846908) (xy 421.730932 -345.846908) (xy 421.703663 -345.846355)
			(xy 421.649679 -345.838597) (xy 421.597349 -345.823236) (xy 421.547738 -345.800583) (xy 421.501855 -345.771099)
			(xy 421.460636 -345.735386) (xy 421.42492 -345.69417) (xy 421.395433 -345.648291) (xy 421.372776 -345.598681)
			(xy 421.35741 -345.546352) (xy 421.349647 -345.492369) (xy 419.866944 -345.492369) (xy 419.866944 -345.492376)
			(xy 419.859181 -345.546371) (xy 419.843811 -345.598713) (xy 419.821149 -345.648334) (xy 419.791655 -345.694224)
			(xy 419.75593 -345.73545) (xy 419.714702 -345.771172) (xy 419.668809 -345.800662) (xy 419.619186 -345.823321)
			(xy 419.566844 -345.838686) (xy 419.512848 -345.846446) (xy 419.485572 -345.846908) (xy 418.621972 -345.846908)
			(xy 418.594707 -345.846328) (xy 418.540733 -345.838564) (xy 418.488413 -345.823198) (xy 418.438813 -345.800543)
			(xy 418.392941 -345.77106) (xy 418.351731 -345.735349) (xy 418.316023 -345.694137) (xy 418.286544 -345.648263)
			(xy 418.263892 -345.59866) (xy 418.24853 -345.546339) (xy 418.24077 -345.492365) (xy 416.757921 -345.492365)
			(xy 416.757921 -345.492372) (xy 416.750159 -345.546361) (xy 416.734793 -345.598696) (xy 416.712135 -345.648311)
			(xy 416.682646 -345.694197) (xy 416.646928 -345.735419) (xy 416.605707 -345.771139) (xy 416.559822 -345.800629)
			(xy 416.510207 -345.823288) (xy 416.457873 -345.838657) (xy 416.403884 -345.846421) (xy 416.376612 -345.846908)
			(xy 415.513012 -345.846908) (xy 415.485744 -345.846353) (xy 415.431762 -345.838594) (xy 415.379434 -345.82323)
			(xy 415.329826 -345.800576) (xy 415.283946 -345.771092) (xy 415.242729 -345.735379) (xy 415.207015 -345.694164)
			(xy 415.17753 -345.648285) (xy 415.154874 -345.598677) (xy 415.139509 -345.54635) (xy 415.131747 -345.492368)
			(xy 413.649044 -345.492368) (xy 413.649044 -345.492376) (xy 413.64128 -345.546374) (xy 413.625909 -345.598717)
			(xy 413.603246 -345.648339) (xy 413.57375 -345.694231) (xy 413.538023 -345.735457) (xy 413.496792 -345.771179)
			(xy 413.450897 -345.800669) (xy 413.401272 -345.823326) (xy 413.348927 -345.83869) (xy 413.294929 -345.846448)
			(xy 413.267652 -345.846908) (xy 412.404052 -345.846908) (xy 412.376788 -345.846326) (xy 412.322816 -345.83856)
			(xy 412.270499 -345.823192) (xy 412.220901 -345.800536) (xy 412.175031 -345.771053) (xy 412.133824 -345.735342)
			(xy 412.098119 -345.69413) (xy 412.068641 -345.648257) (xy 412.045991 -345.598656) (xy 412.03063 -345.546337)
			(xy 412.02287 -345.492364) (xy 410.540044 -345.492364) (xy 410.540044 -345.492375) (xy 410.532281 -345.546369)
			(xy 410.516913 -345.598708) (xy 410.494252 -345.648328) (xy 410.46476 -345.694218) (xy 410.429037 -345.735443)
			(xy 410.387811 -345.771165) (xy 410.341921 -345.800656) (xy 410.292301 -345.823315) (xy 410.239961 -345.838683)
			(xy 410.185967 -345.846445) (xy 410.158692 -345.846908) (xy 409.295092 -345.846908) (xy 409.267826 -345.846329)
			(xy 409.21385 -345.838567) (xy 409.161528 -345.823203) (xy 409.111925 -345.800549) (xy 409.06605 -345.771067)
			(xy 409.024838 -345.735356) (xy 408.989128 -345.694143) (xy 408.959647 -345.648268) (xy 408.936994 -345.598665)
			(xy 408.921631 -345.546342) (xy 408.91387 -345.492366) (xy 403.522544 -345.492366) (xy 403.522544 -345.492375)
			(xy 403.514781 -345.54637) (xy 403.499412 -345.598711) (xy 403.47675 -345.648331) (xy 403.447257 -345.694221)
			(xy 403.411533 -345.735447) (xy 403.370305 -345.771169) (xy 403.324414 -345.800659) (xy 403.274792 -345.823319)
			(xy 403.222451 -345.838685) (xy 403.168455 -345.846446) (xy 403.14118 -345.846908) (xy 402.27758 -345.846908)
			(xy 402.250315 -345.846328) (xy 402.19634 -345.838565) (xy 402.144019 -345.8232) (xy 402.094417 -345.800545)
			(xy 402.048545 -345.771063) (xy 402.007334 -345.735352) (xy 401.971625 -345.694139) (xy 401.942145 -345.648265)
			(xy 401.919493 -345.598662) (xy 401.90413 -345.546341) (xy 401.89637 -345.492365) (xy 400.413522 -345.492365)
			(xy 400.413522 -345.492372) (xy 400.405759 -345.54636) (xy 400.390393 -345.598694) (xy 400.367736 -345.648309)
			(xy 400.338248 -345.694195) (xy 400.302531 -345.735417) (xy 400.261311 -345.771136) (xy 400.215427 -345.800626)
			(xy 400.165813 -345.823286) (xy 400.11348 -345.838655) (xy 400.059492 -345.84642) (xy 400.03222 -345.846908)
			(xy 399.16862 -345.846908) (xy 399.141351 -345.846354) (xy 399.087369 -345.838595) (xy 399.03504 -345.823232)
			(xy 398.98543 -345.800579) (xy 398.93955 -345.771095) (xy 398.898332 -345.735382) (xy 398.862617 -345.694166)
			(xy 398.833131 -345.648287) (xy 398.810475 -345.598679) (xy 398.795109 -345.546351) (xy 398.787347 -345.492369)
			(xy 397.304644 -345.492369) (xy 397.304644 -345.492376) (xy 397.29688 -345.546373) (xy 397.28151 -345.598715)
			(xy 397.258847 -345.648337) (xy 397.229352 -345.694228) (xy 397.193626 -345.735454) (xy 397.152396 -345.771176)
			(xy 397.106502 -345.800666) (xy 397.056878 -345.823324) (xy 397.004534 -345.838689) (xy 396.950536 -345.846447)
			(xy 396.92326 -345.846908) (xy 396.05966 -345.846908) (xy 396.032396 -345.846327) (xy 395.978423 -345.838562)
			(xy 395.926105 -345.823195) (xy 395.876505 -345.800539) (xy 395.830635 -345.771055) (xy 395.789427 -345.735345)
			(xy 395.753721 -345.694133) (xy 395.724242 -345.648259) (xy 395.701591 -345.598658) (xy 395.68623 -345.546338)
			(xy 395.67847 -345.492364) (xy 394.195621 -345.492364) (xy 394.195621 -345.492373) (xy 394.187859 -345.546363)
			(xy 394.172492 -345.598699) (xy 394.149833 -345.648315) (xy 394.120343 -345.694201) (xy 394.084624 -345.735424)
			(xy 394.043401 -345.771143) (xy 393.997515 -345.800633) (xy 393.947899 -345.823292) (xy 393.895563 -345.838659)
			(xy 393.841573 -345.846421) (xy 393.8143 -345.846908) (xy 392.9507 -345.846908) (xy 392.923434 -345.84633)
			(xy 392.869457 -345.838569) (xy 392.817134 -345.823205) (xy 392.767529 -345.800552) (xy 392.721654 -345.77107)
			(xy 392.680441 -345.735359) (xy 392.64473 -345.694146) (xy 392.615248 -345.648271) (xy 392.592595 -345.598666)
			(xy 392.577231 -345.546343) (xy 392.56947 -345.492366) (xy 391.086622 -345.492366) (xy 391.086622 -345.492371)
			(xy 391.07886 -345.546357) (xy 391.063495 -345.59869) (xy 391.040839 -345.648304) (xy 391.011353 -345.694188)
			(xy 390.975638 -345.73541) (xy 390.93442 -345.771129) (xy 390.888539 -345.80062) (xy 390.838928 -345.823281)
			(xy 390.786597 -345.838651) (xy 390.732611 -345.846419) (xy 390.70534 -345.846908) (xy 389.84174 -345.846908)
			(xy 389.81447 -345.846355) (xy 389.760486 -345.838599) (xy 389.708155 -345.823238) (xy 389.658542 -345.800585)
			(xy 389.612659 -345.771102) (xy 389.571439 -345.735389) (xy 389.535722 -345.694173) (xy 389.506234 -345.648293)
			(xy 389.483576 -345.598683) (xy 389.46821 -345.546353) (xy 389.460447 -345.49237) (xy 387.977744 -345.49237)
			(xy 387.977744 -345.492375) (xy 387.969981 -345.54637) (xy 387.954612 -345.598711) (xy 387.93195 -345.648331)
			(xy 387.902457 -345.694221) (xy 387.866733 -345.735447) (xy 387.825505 -345.771169) (xy 387.779614 -345.800659)
			(xy 387.729992 -345.823319) (xy 387.677651 -345.838685) (xy 387.623655 -345.846446) (xy 387.59638 -345.846908)
			(xy 386.73278 -345.846908) (xy 386.705515 -345.846328) (xy 386.65154 -345.838565) (xy 386.599219 -345.8232)
			(xy 386.549617 -345.800545) (xy 386.503745 -345.771063) (xy 386.462534 -345.735352) (xy 386.426825 -345.694139)
			(xy 386.397345 -345.648265) (xy 386.374693 -345.598662) (xy 386.35933 -345.546341) (xy 386.35157 -345.492365)
			(xy 384.868722 -345.492365) (xy 384.868722 -345.492372) (xy 384.860959 -345.54636) (xy 384.845593 -345.598694)
			(xy 384.822936 -345.648309) (xy 384.793448 -345.694195) (xy 384.757731 -345.735417) (xy 384.716511 -345.771136)
			(xy 384.670627 -345.800626) (xy 384.621013 -345.823286) (xy 384.56868 -345.838655) (xy 384.514692 -345.84642)
			(xy 384.48742 -345.846908) (xy 383.62382 -345.846908) (xy 383.596551 -345.846354) (xy 383.542569 -345.838595)
			(xy 383.49024 -345.823232) (xy 383.44063 -345.800579) (xy 383.39475 -345.771095) (xy 383.353532 -345.735382)
			(xy 383.317817 -345.694166) (xy 383.288331 -345.648287) (xy 383.265675 -345.598679) (xy 383.250309 -345.546351)
			(xy 383.242547 -345.492369) (xy 381.759844 -345.492369) (xy 381.759844 -345.492376) (xy 381.75208 -345.546373)
			(xy 381.73671 -345.598715) (xy 381.714047 -345.648337) (xy 381.684552 -345.694228) (xy 381.648826 -345.735454)
			(xy 381.607596 -345.771176) (xy 381.561702 -345.800666) (xy 381.512078 -345.823324) (xy 381.459734 -345.838689)
			(xy 381.405736 -345.846447) (xy 381.37846 -345.846908) (xy 380.51486 -345.846908) (xy 380.487596 -345.846327)
			(xy 380.433623 -345.838562) (xy 380.381305 -345.823195) (xy 380.331705 -345.800539) (xy 380.285835 -345.771055)
			(xy 380.244627 -345.735345) (xy 380.208921 -345.694133) (xy 380.179442 -345.648259) (xy 380.156791 -345.598658)
			(xy 380.14143 -345.546338) (xy 380.13367 -345.492364) (xy 378.650821 -345.492364) (xy 378.650821 -345.492373)
			(xy 378.643059 -345.546363) (xy 378.627692 -345.598699) (xy 378.605033 -345.648315) (xy 378.575543 -345.694201)
			(xy 378.539824 -345.735424) (xy 378.498601 -345.771143) (xy 378.452715 -345.800633) (xy 378.403099 -345.823292)
			(xy 378.350763 -345.838659) (xy 378.296773 -345.846421) (xy 378.2695 -345.846908) (xy 377.4059 -345.846908)
			(xy 377.378634 -345.84633) (xy 377.324657 -345.838569) (xy 377.272334 -345.823205) (xy 377.222729 -345.800552)
			(xy 377.176854 -345.77107) (xy 377.135641 -345.735359) (xy 377.09993 -345.694146) (xy 377.070448 -345.648271)
			(xy 377.047795 -345.598666) (xy 377.032431 -345.546343) (xy 377.02467 -345.492366) (xy 375.541822 -345.492366)
			(xy 375.541822 -345.492371) (xy 375.53406 -345.546357) (xy 375.518695 -345.59869) (xy 375.496039 -345.648304)
			(xy 375.466553 -345.694188) (xy 375.430838 -345.73541) (xy 375.38962 -345.771129) (xy 375.343739 -345.80062)
			(xy 375.294128 -345.823281) (xy 375.241797 -345.838651) (xy 375.187811 -345.846419) (xy 375.16054 -345.846908)
			(xy 374.29694 -345.846908) (xy 374.26967 -345.846355) (xy 374.215686 -345.838599) (xy 374.163355 -345.823238)
			(xy 374.113742 -345.800585) (xy 374.067859 -345.771102) (xy 374.026639 -345.735389) (xy 373.990922 -345.694173)
			(xy 373.961434 -345.648293) (xy 373.938776 -345.598683) (xy 373.92341 -345.546353) (xy 373.915647 -345.49237)
			(xy 372.432944 -345.49237) (xy 372.432944 -345.492375) (xy 372.425181 -345.54637) (xy 372.409812 -345.598711)
			(xy 372.38715 -345.648331) (xy 372.357657 -345.694221) (xy 372.321933 -345.735447) (xy 372.280705 -345.771169)
			(xy 372.234814 -345.800659) (xy 372.185192 -345.823319) (xy 372.132851 -345.838685) (xy 372.078855 -345.846446)
			(xy 372.05158 -345.846908) (xy 371.18798 -345.846908) (xy 371.160715 -345.846328) (xy 371.10674 -345.838565)
			(xy 371.054419 -345.8232) (xy 371.004817 -345.800545) (xy 370.958945 -345.771063) (xy 370.917734 -345.735352)
			(xy 370.882025 -345.694139) (xy 370.852545 -345.648265) (xy 370.829893 -345.598662) (xy 370.81453 -345.546341)
			(xy 370.80677 -345.492365) (xy 344.837321 -345.492365) (xy 344.837321 -345.492372) (xy 344.829559 -345.546362)
			(xy 344.814192 -345.598698) (xy 344.791533 -345.648314) (xy 344.762044 -345.6942) (xy 344.726325 -345.735422)
			(xy 344.685103 -345.771142) (xy 344.639217 -345.800631) (xy 344.589601 -345.823291) (xy 344.537266 -345.838658)
			(xy 344.483276 -345.846421) (xy 344.456004 -345.846908) (xy 343.592404 -345.846908) (xy 343.565136 -345.846353)
			(xy 343.511155 -345.838592) (xy 343.458828 -345.823228) (xy 343.409221 -345.800573) (xy 343.363342 -345.771089)
			(xy 343.322126 -345.735376) (xy 343.286413 -345.694161) (xy 343.256928 -345.648283) (xy 343.234273 -345.598675)
			(xy 343.218909 -345.546349) (xy 343.211147 -345.492368) (xy 341.728322 -345.492368) (xy 341.728322 -345.492371)
			(xy 341.72056 -345.546357) (xy 341.705195 -345.598689) (xy 341.682539 -345.648302) (xy 341.653054 -345.694187)
			(xy 341.617339 -345.735408) (xy 341.576122 -345.771128) (xy 341.530241 -345.800618) (xy 341.48063 -345.82328)
			(xy 341.4283 -345.838651) (xy 341.374315 -345.846418) (xy 341.347044 -345.846908) (xy 340.483444 -345.846908)
			(xy 340.456174 -345.846356) (xy 340.402189 -345.8386) (xy 340.349857 -345.823239) (xy 340.300245 -345.800587)
			(xy 340.254361 -345.771104) (xy 340.213141 -345.735391) (xy 340.177423 -345.694174) (xy 340.147935 -345.648294)
			(xy 340.125276 -345.598684) (xy 340.10991 -345.546354) (xy 340.102148 -345.49237) (xy 338.619444 -345.49237)
			(xy 338.619444 -345.492375) (xy 338.611681 -345.54637) (xy 338.596312 -345.59871) (xy 338.57365 -345.64833)
			(xy 338.544158 -345.69422) (xy 338.508434 -345.735446) (xy 338.467207 -345.771167) (xy 338.421316 -345.800658)
			(xy 338.371695 -345.823318) (xy 338.319354 -345.838684) (xy 338.265359 -345.846445) (xy 338.238084 -345.846908)
			(xy 337.374484 -345.846908) (xy 337.347219 -345.846329) (xy 337.293243 -345.838566) (xy 337.240922 -345.823201)
			(xy 337.19132 -345.800547) (xy 337.145446 -345.771064) (xy 337.104236 -345.735353) (xy 337.068526 -345.694141)
			(xy 337.039046 -345.648266) (xy 337.016393 -345.598663) (xy 337.001031 -345.546341) (xy 336.99327 -345.492365)
			(xy 335.510422 -345.492365) (xy 335.510422 -345.492372) (xy 335.50266 -345.54636) (xy 335.487294 -345.598693)
			(xy 335.464636 -345.648308) (xy 335.435149 -345.694193) (xy 335.399432 -345.735415) (xy 335.358213 -345.771135)
			(xy 335.312329 -345.800625) (xy 335.262716 -345.823285) (xy 335.210383 -345.838654) (xy 335.156396 -345.84642)
			(xy 335.129124 -345.846908) (xy 334.265524 -345.846908) (xy 334.238255 -345.846354) (xy 334.184272 -345.838596)
			(xy 334.131943 -345.823234) (xy 334.082333 -345.80058) (xy 334.036452 -345.771097) (xy 333.995234 -345.735383)
			(xy 333.959518 -345.694168) (xy 333.930031 -345.648288) (xy 333.907375 -345.59868) (xy 333.892009 -345.546351)
			(xy 333.884247 -345.492369) (xy 332.401544 -345.492369) (xy 332.401544 -345.492376) (xy 332.39378 -345.546372)
			(xy 332.37841 -345.598714) (xy 332.355747 -345.648336) (xy 332.326253 -345.694227) (xy 332.290527 -345.735453)
			(xy 332.249298 -345.771174) (xy 332.203404 -345.800665) (xy 332.153781 -345.823323) (xy 332.101437 -345.838688)
			(xy 332.04744 -345.846447) (xy 332.020164 -345.846908) (xy 331.156564 -345.846908) (xy 331.1293 -345.846327)
			(xy 331.075326 -345.838562) (xy 331.023007 -345.823196) (xy 330.973408 -345.80054) (xy 330.927537 -345.771057)
			(xy 330.886329 -345.735346) (xy 330.850622 -345.694134) (xy 330.821143 -345.648261) (xy 330.798492 -345.598659)
			(xy 330.78313 -345.546338) (xy 330.77537 -345.492364) (xy 329.292521 -345.492364) (xy 329.292521 -345.492372)
			(xy 329.284759 -345.546362) (xy 329.269392 -345.598698) (xy 329.246733 -345.648314) (xy 329.217244 -345.6942)
			(xy 329.181525 -345.735422) (xy 329.140303 -345.771142) (xy 329.094417 -345.800631) (xy 329.044801 -345.823291)
			(xy 328.992466 -345.838658) (xy 328.938476 -345.846421) (xy 328.911204 -345.846908) (xy 328.047604 -345.846908)
			(xy 328.020336 -345.846353) (xy 327.966355 -345.838592) (xy 327.914028 -345.823228) (xy 327.864421 -345.800573)
			(xy 327.818542 -345.771089) (xy 327.777326 -345.735376) (xy 327.741613 -345.694161) (xy 327.712128 -345.648283)
			(xy 327.689473 -345.598675) (xy 327.674109 -345.546349) (xy 327.666347 -345.492368) (xy 326.183522 -345.492368)
			(xy 326.183522 -345.492371) (xy 326.17576 -345.546357) (xy 326.160395 -345.598689) (xy 326.137739 -345.648302)
			(xy 326.108254 -345.694187) (xy 326.072539 -345.735408) (xy 326.031322 -345.771128) (xy 325.985441 -345.800618)
			(xy 325.93583 -345.82328) (xy 325.8835 -345.838651) (xy 325.829515 -345.846418) (xy 325.802244 -345.846908)
			(xy 324.938644 -345.846908) (xy 324.911374 -345.846356) (xy 324.857389 -345.8386) (xy 324.805057 -345.823239)
			(xy 324.755445 -345.800587) (xy 324.709561 -345.771104) (xy 324.668341 -345.735391) (xy 324.632623 -345.694174)
			(xy 324.603135 -345.648294) (xy 324.580476 -345.598684) (xy 324.56511 -345.546354) (xy 324.557348 -345.49237)
			(xy 323.074644 -345.49237) (xy 323.074644 -345.492375) (xy 323.066881 -345.54637) (xy 323.051512 -345.59871)
			(xy 323.02885 -345.64833) (xy 322.999358 -345.69422) (xy 322.963634 -345.735446) (xy 322.922407 -345.771167)
			(xy 322.876516 -345.800658) (xy 322.826895 -345.823318) (xy 322.774554 -345.838684) (xy 322.720559 -345.846445)
			(xy 322.693284 -345.846908) (xy 321.829684 -345.846908) (xy 321.802419 -345.846329) (xy 321.748443 -345.838566)
			(xy 321.696122 -345.823201) (xy 321.64652 -345.800547) (xy 321.600646 -345.771064) (xy 321.559436 -345.735353)
			(xy 321.523726 -345.694141) (xy 321.494246 -345.648266) (xy 321.471593 -345.598663) (xy 321.456231 -345.546341)
			(xy 321.44847 -345.492365) (xy 319.965622 -345.492365) (xy 319.965622 -345.492372) (xy 319.95786 -345.54636)
			(xy 319.942494 -345.598693) (xy 319.919836 -345.648308) (xy 319.890349 -345.694193) (xy 319.854632 -345.735415)
			(xy 319.813413 -345.771135) (xy 319.767529 -345.800625) (xy 319.717916 -345.823285) (xy 319.665583 -345.838654)
			(xy 319.611596 -345.84642) (xy 319.584324 -345.846908) (xy 318.720724 -345.846908) (xy 318.693455 -345.846354)
			(xy 318.639472 -345.838596) (xy 318.587143 -345.823234) (xy 318.537533 -345.80058) (xy 318.491652 -345.771097)
			(xy 318.450434 -345.735383) (xy 318.414718 -345.694168) (xy 318.385231 -345.648288) (xy 318.362575 -345.59868)
			(xy 318.347209 -345.546351) (xy 318.339447 -345.492369) (xy 316.856744 -345.492369) (xy 316.856744 -345.492376)
			(xy 316.84898 -345.546372) (xy 316.83361 -345.598714) (xy 316.810947 -345.648336) (xy 316.781453 -345.694227)
			(xy 316.745727 -345.735453) (xy 316.704498 -345.771174) (xy 316.658604 -345.800665) (xy 316.608981 -345.823323)
			(xy 316.556637 -345.838688) (xy 316.50264 -345.846447) (xy 316.475364 -345.846908) (xy 315.611764 -345.846908)
			(xy 315.5845 -345.846327) (xy 315.530526 -345.838562) (xy 315.478207 -345.823196) (xy 315.428608 -345.80054)
			(xy 315.382737 -345.771057) (xy 315.341529 -345.735346) (xy 315.305822 -345.694134) (xy 315.276343 -345.648261)
			(xy 315.253692 -345.598659) (xy 315.23833 -345.546338) (xy 315.23057 -345.492364) (xy 313.747721 -345.492364)
			(xy 313.747721 -345.492372) (xy 313.739959 -345.546362) (xy 313.724592 -345.598698) (xy 313.701933 -345.648314)
			(xy 313.672444 -345.6942) (xy 313.636725 -345.735422) (xy 313.595503 -345.771142) (xy 313.549617 -345.800631)
			(xy 313.500001 -345.823291) (xy 313.447666 -345.838658) (xy 313.393676 -345.846421) (xy 313.366404 -345.846908)
			(xy 312.502804 -345.846908) (xy 312.475536 -345.846353) (xy 312.421555 -345.838592) (xy 312.369228 -345.823228)
			(xy 312.319621 -345.800573) (xy 312.273742 -345.771089) (xy 312.232526 -345.735376) (xy 312.196813 -345.694161)
			(xy 312.167328 -345.648283) (xy 312.144673 -345.598675) (xy 312.129309 -345.546349) (xy 312.121547 -345.492368)
			(xy 300.231621 -345.492368) (xy 300.231621 -345.492373) (xy 300.223859 -345.546362) (xy 300.208492 -345.598698)
			(xy 300.185833 -345.648314) (xy 300.156344 -345.6942) (xy 300.120624 -345.735423) (xy 300.079402 -345.771143)
			(xy 300.033516 -345.800632) (xy 299.9839 -345.823291) (xy 299.931564 -345.838658) (xy 299.877575 -345.846421)
			(xy 299.850302 -345.846908) (xy 298.986702 -345.846908) (xy 298.959434 -345.846353) (xy 298.905454 -345.838592)
			(xy 298.853127 -345.823228) (xy 298.80352 -345.800573) (xy 298.757641 -345.771089) (xy 298.716426 -345.735376)
			(xy 298.680712 -345.69416) (xy 298.651228 -345.648282) (xy 298.628573 -345.598675) (xy 298.613209 -345.546348)
			(xy 298.605447 -345.492368) (xy 297.122622 -345.492368) (xy 297.122622 -345.492371) (xy 297.11486 -345.546357)
			(xy 297.099495 -345.59869) (xy 297.076839 -345.648303) (xy 297.047354 -345.694187) (xy 297.011639 -345.735409)
			(xy 296.970421 -345.771128) (xy 296.92454 -345.800619) (xy 296.874929 -345.82328) (xy 296.822598 -345.838651)
			(xy 296.768613 -345.846419) (xy 296.741342 -345.846908) (xy 295.877742 -345.846908) (xy 295.850472 -345.846355)
			(xy 295.796487 -345.838599) (xy 295.744156 -345.823238) (xy 295.694543 -345.800586) (xy 295.64866 -345.771103)
			(xy 295.60744 -345.73539) (xy 295.571722 -345.694174) (xy 295.542234 -345.648293) (xy 295.519576 -345.598683)
			(xy 295.50421 -345.546354) (xy 295.496448 -345.49237) (xy 294.013744 -345.49237) (xy 294.013744 -345.492375)
			(xy 294.005981 -345.54637) (xy 293.990612 -345.59871) (xy 293.96795 -345.648331) (xy 293.938457 -345.694221)
			(xy 293.902734 -345.735446) (xy 293.861506 -345.771168) (xy 293.815615 -345.800659) (xy 293.765994 -345.823318)
			(xy 293.713652 -345.838685) (xy 293.659657 -345.846446) (xy 293.632382 -345.846908) (xy 292.768782 -345.846908)
			(xy 292.741517 -345.846328) (xy 292.687542 -345.838566) (xy 292.635221 -345.823201) (xy 292.585619 -345.800546)
			(xy 292.539745 -345.771063) (xy 292.498535 -345.735352) (xy 292.462826 -345.69414) (xy 292.433345 -345.648266)
			(xy 292.410693 -345.598663) (xy 292.395331 -345.546341) (xy 292.38757 -345.492365) (xy 290.904722 -345.492365)
			(xy 290.904722 -345.492372) (xy 290.896959 -345.54636) (xy 290.881593 -345.598694) (xy 290.858936 -345.648309)
			(xy 290.829449 -345.694194) (xy 290.793732 -345.735416) (xy 290.752512 -345.771136) (xy 290.706628 -345.800626)
			(xy 290.657015 -345.823286) (xy 290.604681 -345.838655) (xy 290.550694 -345.84642) (xy 290.523422 -345.846908)
			(xy 289.659822 -345.846908) (xy 289.632553 -345.846354) (xy 289.57857 -345.838595) (xy 289.526241 -345.823233)
			(xy 289.476632 -345.800579) (xy 289.430751 -345.771096) (xy 289.389533 -345.735383) (xy 289.353817 -345.694167)
			(xy 289.324331 -345.648288) (xy 289.301675 -345.598679) (xy 289.286309 -345.546351) (xy 289.278547 -345.492369)
			(xy 287.795844 -345.492369) (xy 287.795844 -345.492376) (xy 287.78808 -345.546373) (xy 287.77271 -345.598715)
			(xy 287.750047 -345.648336) (xy 287.720552 -345.694227) (xy 287.684827 -345.735453) (xy 287.643597 -345.771175)
			(xy 287.597703 -345.800665) (xy 287.548079 -345.823323) (xy 287.495736 -345.838688) (xy 287.441738 -345.846447)
			(xy 287.414462 -345.846908) (xy 286.550862 -345.846908) (xy 286.523598 -345.846327) (xy 286.469625 -345.838562)
			(xy 286.417306 -345.823195) (xy 286.367707 -345.80054) (xy 286.321836 -345.771056) (xy 286.280628 -345.735345)
			(xy 286.244921 -345.694134) (xy 286.215442 -345.64826) (xy 286.192792 -345.598658) (xy 286.17743 -345.546338)
			(xy 286.16967 -345.492364) (xy 284.686821 -345.492364) (xy 284.686821 -345.492373) (xy 284.679059 -345.546362)
			(xy 284.663692 -345.598698) (xy 284.641033 -345.648314) (xy 284.611544 -345.6942) (xy 284.575824 -345.735423)
			(xy 284.534602 -345.771143) (xy 284.488716 -345.800632) (xy 284.4391 -345.823291) (xy 284.386764 -345.838658)
			(xy 284.332775 -345.846421) (xy 284.305502 -345.846908) (xy 283.441902 -345.846908) (xy 283.414634 -345.846353)
			(xy 283.360654 -345.838592) (xy 283.308327 -345.823228) (xy 283.25872 -345.800573) (xy 283.212841 -345.771089)
			(xy 283.171626 -345.735376) (xy 283.135912 -345.69416) (xy 283.106428 -345.648282) (xy 283.083773 -345.598675)
			(xy 283.068409 -345.546348) (xy 283.060647 -345.492368) (xy 281.577822 -345.492368) (xy 281.577822 -345.492371)
			(xy 281.57006 -345.546357) (xy 281.554695 -345.59869) (xy 281.532039 -345.648303) (xy 281.502554 -345.694187)
			(xy 281.466839 -345.735409) (xy 281.425621 -345.771128) (xy 281.37974 -345.800619) (xy 281.330129 -345.82328)
			(xy 281.277798 -345.838651) (xy 281.223813 -345.846419) (xy 281.196542 -345.846908) (xy 280.332942 -345.846908)
			(xy 280.305672 -345.846355) (xy 280.251687 -345.838599) (xy 280.199356 -345.823238) (xy 280.149743 -345.800586)
			(xy 280.10386 -345.771103) (xy 280.06264 -345.73539) (xy 280.026922 -345.694174) (xy 279.997434 -345.648293)
			(xy 279.974776 -345.598683) (xy 279.95941 -345.546354) (xy 279.951648 -345.49237) (xy 278.468944 -345.49237)
			(xy 278.468944 -345.492375) (xy 278.461181 -345.54637) (xy 278.445812 -345.59871) (xy 278.42315 -345.648331)
			(xy 278.393657 -345.694221) (xy 278.357934 -345.735446) (xy 278.316706 -345.771168) (xy 278.270815 -345.800659)
			(xy 278.221194 -345.823318) (xy 278.168852 -345.838685) (xy 278.114857 -345.846446) (xy 278.087582 -345.846908)
			(xy 277.223982 -345.846908) (xy 277.196717 -345.846328) (xy 277.142742 -345.838566) (xy 277.090421 -345.823201)
			(xy 277.040819 -345.800546) (xy 276.994945 -345.771063) (xy 276.953735 -345.735352) (xy 276.918026 -345.69414)
			(xy 276.888545 -345.648266) (xy 276.865893 -345.598663) (xy 276.850531 -345.546341) (xy 276.84277 -345.492365)
			(xy 275.359922 -345.492365) (xy 275.359922 -345.492372) (xy 275.352159 -345.54636) (xy 275.336793 -345.598694)
			(xy 275.314136 -345.648309) (xy 275.284649 -345.694194) (xy 275.248932 -345.735416) (xy 275.207712 -345.771136)
			(xy 275.161828 -345.800626) (xy 275.112215 -345.823286) (xy 275.059881 -345.838655) (xy 275.005894 -345.84642)
			(xy 274.978622 -345.846908) (xy 274.115022 -345.846908) (xy 274.087753 -345.846354) (xy 274.03377 -345.838595)
			(xy 273.981441 -345.823233) (xy 273.931832 -345.800579) (xy 273.885951 -345.771096) (xy 273.844733 -345.735383)
			(xy 273.809017 -345.694167) (xy 273.779531 -345.648288) (xy 273.756875 -345.598679) (xy 273.741509 -345.546351)
			(xy 273.733747 -345.492369) (xy 272.251044 -345.492369) (xy 272.251044 -345.492376) (xy 272.24328 -345.546373)
			(xy 272.22791 -345.598715) (xy 272.205247 -345.648336) (xy 272.175752 -345.694227) (xy 272.140027 -345.735453)
			(xy 272.098797 -345.771175) (xy 272.052903 -345.800665) (xy 272.003279 -345.823323) (xy 271.950936 -345.838688)
			(xy 271.896938 -345.846447) (xy 271.869662 -345.846908) (xy 271.006062 -345.846908) (xy 270.978798 -345.846327)
			(xy 270.924825 -345.838562) (xy 270.872506 -345.823195) (xy 270.822907 -345.80054) (xy 270.777036 -345.771056)
			(xy 270.735828 -345.735345) (xy 270.700121 -345.694134) (xy 270.670642 -345.64826) (xy 270.647992 -345.598658)
			(xy 270.63263 -345.546338) (xy 270.62487 -345.492364) (xy 269.142021 -345.492364) (xy 269.142021 -345.492373)
			(xy 269.134259 -345.546362) (xy 269.118892 -345.598698) (xy 269.096233 -345.648314) (xy 269.066744 -345.6942)
			(xy 269.031024 -345.735423) (xy 268.989802 -345.771143) (xy 268.943916 -345.800632) (xy 268.8943 -345.823291)
			(xy 268.841964 -345.838658) (xy 268.787975 -345.846421) (xy 268.760702 -345.846908) (xy 267.897102 -345.846908)
			(xy 267.869834 -345.846353) (xy 267.815854 -345.838592) (xy 267.763527 -345.823228) (xy 267.71392 -345.800573)
			(xy 267.668041 -345.771089) (xy 267.626826 -345.735376) (xy 267.591112 -345.69416) (xy 267.561628 -345.648282)
			(xy 267.538973 -345.598675) (xy 267.523609 -345.546348) (xy 267.515847 -345.492368) (xy 197.629644 -345.492368)
			(xy 197.629644 -345.492376) (xy 197.621881 -345.546371) (xy 197.606511 -345.598713) (xy 197.583849 -345.648334)
			(xy 197.554355 -345.694224) (xy 197.51863 -345.73545) (xy 197.477402 -345.771172) (xy 197.431509 -345.800662)
			(xy 197.381886 -345.823321) (xy 197.329544 -345.838686) (xy 197.275548 -345.846446) (xy 197.248272 -345.846908)
			(xy 196.384672 -345.846908) (xy 196.357407 -345.846328) (xy 196.303433 -345.838564) (xy 196.251113 -345.823198)
			(xy 196.201513 -345.800543) (xy 196.155641 -345.77106) (xy 196.114431 -345.735349) (xy 196.078723 -345.694137)
			(xy 196.049244 -345.648263) (xy 196.026592 -345.59866) (xy 196.01123 -345.546339) (xy 196.00347 -345.492365)
			(xy 194.520621 -345.492365) (xy 194.520621 -345.492372) (xy 194.512859 -345.546361) (xy 194.497493 -345.598696)
			(xy 194.474835 -345.648311) (xy 194.445346 -345.694197) (xy 194.409628 -345.735419) (xy 194.368407 -345.771139)
			(xy 194.322522 -345.800629) (xy 194.272907 -345.823288) (xy 194.220573 -345.838657) (xy 194.166584 -345.846421)
			(xy 194.139312 -345.846908) (xy 193.275712 -345.846908) (xy 193.248444 -345.846353) (xy 193.194462 -345.838594)
			(xy 193.142134 -345.82323) (xy 193.092526 -345.800576) (xy 193.046646 -345.771092) (xy 193.005429 -345.735379)
			(xy 192.969715 -345.694164) (xy 192.94023 -345.648285) (xy 192.917574 -345.598677) (xy 192.902209 -345.54635)
			(xy 192.894447 -345.492368) (xy 191.411744 -345.492368) (xy 191.411744 -345.492376) (xy 191.40398 -345.546374)
			(xy 191.388609 -345.598717) (xy 191.365946 -345.648339) (xy 191.33645 -345.694231) (xy 191.300723 -345.735457)
			(xy 191.259492 -345.771179) (xy 191.213597 -345.800669) (xy 191.163972 -345.823326) (xy 191.111627 -345.83869)
			(xy 191.057629 -345.846448) (xy 191.030352 -345.846908) (xy 190.166752 -345.846908) (xy 190.139488 -345.846326)
			(xy 190.085516 -345.83856) (xy 190.033199 -345.823192) (xy 189.983601 -345.800536) (xy 189.937731 -345.771053)
			(xy 189.896524 -345.735342) (xy 189.860819 -345.69413) (xy 189.831341 -345.648257) (xy 189.808691 -345.598656)
			(xy 189.79333 -345.546337) (xy 189.78557 -345.492364) (xy 188.302744 -345.492364) (xy 188.302744 -345.492375)
			(xy 188.294981 -345.546369) (xy 188.279613 -345.598708) (xy 188.256952 -345.648328) (xy 188.22746 -345.694218)
			(xy 188.191737 -345.735443) (xy 188.150511 -345.771165) (xy 188.104621 -345.800656) (xy 188.055001 -345.823315)
			(xy 188.002661 -345.838683) (xy 187.948667 -345.846445) (xy 187.921392 -345.846908) (xy 187.057792 -345.846908)
			(xy 187.030526 -345.846329) (xy 186.97655 -345.838567) (xy 186.924228 -345.823203) (xy 186.874625 -345.800549)
			(xy 186.82875 -345.771067) (xy 186.787538 -345.735356) (xy 186.751828 -345.694143) (xy 186.722347 -345.648268)
			(xy 186.699694 -345.598665) (xy 186.684331 -345.546342) (xy 186.67657 -345.492366) (xy 185.193722 -345.492366)
			(xy 185.193722 -345.492371) (xy 185.18596 -345.546358) (xy 185.170594 -345.598692) (xy 185.147938 -345.648306)
			(xy 185.118451 -345.694191) (xy 185.082735 -345.735412) (xy 185.041516 -345.771132) (xy 184.995634 -345.800622)
			(xy 184.946022 -345.823283) (xy 184.89369 -345.838653) (xy 184.839703 -345.846419) (xy 184.812432 -345.846908)
			(xy 183.948832 -345.846908) (xy 183.921563 -345.846355) (xy 183.867579 -345.838597) (xy 183.815249 -345.823236)
			(xy 183.765638 -345.800583) (xy 183.719755 -345.771099) (xy 183.678536 -345.735386) (xy 183.64282 -345.69417)
			(xy 183.613333 -345.648291) (xy 183.590676 -345.598681) (xy 183.57531 -345.546352) (xy 183.567547 -345.492369)
			(xy 182.084844 -345.492369) (xy 182.084844 -345.492376) (xy 182.077081 -345.546371) (xy 182.061711 -345.598713)
			(xy 182.039049 -345.648334) (xy 182.009555 -345.694224) (xy 181.97383 -345.73545) (xy 181.932602 -345.771172)
			(xy 181.886709 -345.800662) (xy 181.837086 -345.823321) (xy 181.784744 -345.838686) (xy 181.730748 -345.846446)
			(xy 181.703472 -345.846908) (xy 180.839872 -345.846908) (xy 180.812607 -345.846328) (xy 180.758633 -345.838564)
			(xy 180.706313 -345.823198) (xy 180.656713 -345.800543) (xy 180.610841 -345.77106) (xy 180.569631 -345.735349)
			(xy 180.533923 -345.694137) (xy 180.504444 -345.648263) (xy 180.481792 -345.59866) (xy 180.46643 -345.546339)
			(xy 180.45867 -345.492365) (xy 178.975821 -345.492365) (xy 178.975821 -345.492372) (xy 178.968059 -345.546361)
			(xy 178.952693 -345.598696) (xy 178.930035 -345.648311) (xy 178.900546 -345.694197) (xy 178.864828 -345.735419)
			(xy 178.823607 -345.771139) (xy 178.777722 -345.800629) (xy 178.728107 -345.823288) (xy 178.675773 -345.838657)
			(xy 178.621784 -345.846421) (xy 178.594512 -345.846908) (xy 177.730912 -345.846908) (xy 177.703644 -345.846353)
			(xy 177.649662 -345.838594) (xy 177.597334 -345.82323) (xy 177.547726 -345.800576) (xy 177.501846 -345.771092)
			(xy 177.460629 -345.735379) (xy 177.424915 -345.694164) (xy 177.39543 -345.648285) (xy 177.372774 -345.598677)
			(xy 177.357409 -345.54635) (xy 177.349647 -345.492368) (xy 175.866944 -345.492368) (xy 175.866944 -345.492376)
			(xy 175.85918 -345.546374) (xy 175.843809 -345.598717) (xy 175.821146 -345.648339) (xy 175.79165 -345.694231)
			(xy 175.755923 -345.735457) (xy 175.714692 -345.771179) (xy 175.668797 -345.800669) (xy 175.619172 -345.823326)
			(xy 175.566827 -345.83869) (xy 175.512829 -345.846448) (xy 175.485552 -345.846908) (xy 174.621952 -345.846908)
			(xy 174.594688 -345.846326) (xy 174.540716 -345.83856) (xy 174.488399 -345.823192) (xy 174.438801 -345.800536)
			(xy 174.392931 -345.771053) (xy 174.351724 -345.735342) (xy 174.316019 -345.69413) (xy 174.286541 -345.648257)
			(xy 174.263891 -345.598656) (xy 174.24853 -345.546337) (xy 174.24077 -345.492364) (xy 172.757944 -345.492364)
			(xy 172.757944 -345.492375) (xy 172.750181 -345.546369) (xy 172.734813 -345.598708) (xy 172.712152 -345.648328)
			(xy 172.68266 -345.694218) (xy 172.646937 -345.735443) (xy 172.605711 -345.771165) (xy 172.559821 -345.800656)
			(xy 172.510201 -345.823315) (xy 172.457861 -345.838683) (xy 172.403867 -345.846445) (xy 172.376592 -345.846908)
			(xy 171.512992 -345.846908) (xy 171.485726 -345.846329) (xy 171.43175 -345.838567) (xy 171.379428 -345.823203)
			(xy 171.329825 -345.800549) (xy 171.28395 -345.771067) (xy 171.242738 -345.735356) (xy 171.207028 -345.694143)
			(xy 171.177547 -345.648268) (xy 171.154894 -345.598665) (xy 171.139531 -345.546342) (xy 171.13177 -345.492366)
			(xy 169.648922 -345.492366) (xy 169.648922 -345.492371) (xy 169.64116 -345.546358) (xy 169.625794 -345.598692)
			(xy 169.603138 -345.648306) (xy 169.573651 -345.694191) (xy 169.537935 -345.735412) (xy 169.496716 -345.771132)
			(xy 169.450834 -345.800622) (xy 169.401222 -345.823283) (xy 169.34889 -345.838653) (xy 169.294903 -345.846419)
			(xy 169.267632 -345.846908) (xy 168.404032 -345.846908) (xy 168.376763 -345.846355) (xy 168.322779 -345.838597)
			(xy 168.270449 -345.823236) (xy 168.220838 -345.800583) (xy 168.174955 -345.771099) (xy 168.133736 -345.735386)
			(xy 168.09802 -345.69417) (xy 168.068533 -345.648291) (xy 168.045876 -345.598681) (xy 168.03051 -345.546352)
			(xy 168.022747 -345.492369) (xy 166.540044 -345.492369) (xy 166.540044 -345.492376) (xy 166.532281 -345.546371)
			(xy 166.516911 -345.598713) (xy 166.494249 -345.648334) (xy 166.464755 -345.694224) (xy 166.42903 -345.73545)
			(xy 166.387802 -345.771172) (xy 166.341909 -345.800662) (xy 166.292286 -345.823321) (xy 166.239944 -345.838686)
			(xy 166.185948 -345.846446) (xy 166.158672 -345.846908) (xy 165.295072 -345.846908) (xy 165.267807 -345.846328)
			(xy 165.213833 -345.838564) (xy 165.161513 -345.823198) (xy 165.111913 -345.800543) (xy 165.066041 -345.77106)
			(xy 165.024831 -345.735349) (xy 164.989123 -345.694137) (xy 164.959644 -345.648263) (xy 164.936992 -345.59866)
			(xy 164.92163 -345.546339) (xy 164.91387 -345.492365) (xy 144.196621 -345.492365) (xy 144.196621 -345.492372)
			(xy 144.188859 -345.546362) (xy 144.173492 -345.598697) (xy 144.150834 -345.648312) (xy 144.121345 -345.694199)
			(xy 144.085627 -345.735421) (xy 144.044405 -345.77114) (xy 143.99852 -345.80063) (xy 143.948904 -345.82329)
			(xy 143.89657 -345.838657) (xy 143.84258 -345.846421) (xy 143.815308 -345.846908) (xy 142.951708 -345.846908)
			(xy 142.92444 -345.846353) (xy 142.870459 -345.838593) (xy 142.818131 -345.823229) (xy 142.768523 -345.800575)
			(xy 142.722644 -345.771091) (xy 142.681428 -345.735378) (xy 142.645714 -345.694162) (xy 142.616229 -345.648284)
			(xy 142.593574 -345.598676) (xy 142.578209 -345.546349) (xy 142.570447 -345.492368) (xy 141.087622 -345.492368)
			(xy 141.087622 -345.49237) (xy 141.07986 -345.546356) (xy 141.064495 -345.598688) (xy 141.04184 -345.648301)
			(xy 141.012355 -345.694185) (xy 140.976641 -345.735407) (xy 140.935424 -345.771126) (xy 140.889543 -345.800617)
			(xy 140.839933 -345.823279) (xy 140.787603 -345.83865) (xy 140.733618 -345.846418) (xy 140.706348 -345.846908)
			(xy 139.842748 -345.846908) (xy 139.815478 -345.846356) (xy 139.761492 -345.8386) (xy 139.70916 -345.82324)
			(xy 139.659547 -345.800588) (xy 139.613663 -345.771105) (xy 139.572442 -345.735392) (xy 139.536724 -345.694176)
			(xy 139.507235 -345.648295) (xy 139.484577 -345.598685) (xy 139.46921 -345.546354) (xy 139.461448 -345.49237)
			(xy 137.978744 -345.49237) (xy 137.978744 -345.492375) (xy 137.970981 -345.546369) (xy 137.955612 -345.598709)
			(xy 137.932951 -345.648329) (xy 137.903459 -345.694219) (xy 137.867736 -345.735444) (xy 137.826509 -345.771166)
			(xy 137.780619 -345.800657) (xy 137.730998 -345.823316) (xy 137.678658 -345.838684) (xy 137.624663 -345.846445)
			(xy 137.597388 -345.846908) (xy 136.733788 -345.846908) (xy 136.706522 -345.846329) (xy 136.652547 -345.838567)
			(xy 136.600225 -345.823202) (xy 136.550622 -345.800548) (xy 136.504748 -345.771065) (xy 136.463537 -345.735354)
			(xy 136.427827 -345.694142) (xy 136.398346 -345.648267) (xy 136.375694 -345.598664) (xy 136.360331 -345.546342)
			(xy 136.35257 -345.492366) (xy 134.869722 -345.492366) (xy 134.869722 -345.492371) (xy 134.86196 -345.546359)
			(xy 134.846594 -345.598693) (xy 134.823937 -345.648307) (xy 134.79445 -345.694192) (xy 134.758734 -345.735414)
			(xy 134.717514 -345.771133) (xy 134.671632 -345.800624) (xy 134.622019 -345.823284) (xy 134.569686 -345.838654)
			(xy 134.515699 -345.84642) (xy 134.488428 -345.846908) (xy 133.624828 -345.846908) (xy 133.597559 -345.846355)
			(xy 133.543576 -345.838597) (xy 133.491246 -345.823235) (xy 133.441635 -345.800581) (xy 133.395753 -345.771098)
			(xy 133.354535 -345.735385) (xy 133.318819 -345.694169) (xy 133.289332 -345.648289) (xy 133.266675 -345.59868)
			(xy 133.251309 -345.546352) (xy 133.243547 -345.492369) (xy 131.760844 -345.492369) (xy 131.760844 -345.492376)
			(xy 131.75308 -345.546372) (xy 131.737711 -345.598713) (xy 131.715048 -345.648335) (xy 131.685554 -345.694225)
			(xy 131.649829 -345.735451) (xy 131.6086 -345.771173) (xy 131.562707 -345.800663) (xy 131.513083 -345.823322)
			(xy 131.460741 -345.838687) (xy 131.406744 -345.846447) (xy 131.379468 -345.846908) (xy 130.515868 -345.846908)
			(xy 130.488603 -345.846328) (xy 130.43463 -345.838563) (xy 130.38231 -345.823197) (xy 130.33271 -345.800542)
			(xy 130.286839 -345.771058) (xy 130.24563 -345.735347) (xy 130.209922 -345.694136) (xy 130.180443 -345.648262)
			(xy 130.157792 -345.59866) (xy 130.14243 -345.546339) (xy 130.13467 -345.492365) (xy 128.651821 -345.492365)
			(xy 128.651821 -345.492372) (xy 128.644059 -345.546362) (xy 128.628692 -345.598697) (xy 128.606034 -345.648312)
			(xy 128.576545 -345.694199) (xy 128.540827 -345.735421) (xy 128.499605 -345.77114) (xy 128.45372 -345.80063)
			(xy 128.404104 -345.82329) (xy 128.35177 -345.838657) (xy 128.29778 -345.846421) (xy 128.270508 -345.846908)
			(xy 127.406908 -345.846908) (xy 127.37964 -345.846353) (xy 127.325659 -345.838593) (xy 127.273331 -345.823229)
			(xy 127.223723 -345.800575) (xy 127.177844 -345.771091) (xy 127.136628 -345.735378) (xy 127.100914 -345.694162)
			(xy 127.071429 -345.648284) (xy 127.048774 -345.598676) (xy 127.033409 -345.546349) (xy 127.025647 -345.492368)
			(xy 125.542822 -345.492368) (xy 125.542822 -345.49237) (xy 125.53506 -345.546356) (xy 125.519695 -345.598688)
			(xy 125.49704 -345.648301) (xy 125.467555 -345.694185) (xy 125.431841 -345.735407) (xy 125.390624 -345.771126)
			(xy 125.344743 -345.800617) (xy 125.295133 -345.823279) (xy 125.242803 -345.83865) (xy 125.188818 -345.846418)
			(xy 125.161548 -345.846908) (xy 124.297948 -345.846908) (xy 124.270678 -345.846356) (xy 124.216692 -345.8386)
			(xy 124.16436 -345.82324) (xy 124.114747 -345.800588) (xy 124.068863 -345.771105) (xy 124.027642 -345.735392)
			(xy 123.991924 -345.694176) (xy 123.962435 -345.648295) (xy 123.939777 -345.598685) (xy 123.92441 -345.546354)
			(xy 123.916648 -345.49237) (xy 122.433944 -345.49237) (xy 122.433944 -345.492375) (xy 122.426181 -345.546369)
			(xy 122.410812 -345.598709) (xy 122.388151 -345.648329) (xy 122.358659 -345.694219) (xy 122.322936 -345.735444)
			(xy 122.281709 -345.771166) (xy 122.235819 -345.800657) (xy 122.186198 -345.823316) (xy 122.133858 -345.838684)
			(xy 122.079863 -345.846445) (xy 122.052588 -345.846908) (xy 121.188988 -345.846908) (xy 121.161722 -345.846329)
			(xy 121.107747 -345.838567) (xy 121.055425 -345.823202) (xy 121.005822 -345.800548) (xy 120.959948 -345.771065)
			(xy 120.918737 -345.735354) (xy 120.883027 -345.694142) (xy 120.853546 -345.648267) (xy 120.830894 -345.598664)
			(xy 120.815531 -345.546342) (xy 120.80777 -345.492366) (xy 119.324922 -345.492366) (xy 119.324922 -345.492371)
			(xy 119.31716 -345.546359) (xy 119.301794 -345.598693) (xy 119.279137 -345.648307) (xy 119.24965 -345.694192)
			(xy 119.213934 -345.735414) (xy 119.172714 -345.771133) (xy 119.126832 -345.800624) (xy 119.077219 -345.823284)
			(xy 119.024886 -345.838654) (xy 118.970899 -345.84642) (xy 118.943628 -345.846908) (xy 118.080028 -345.846908)
			(xy 118.052759 -345.846355) (xy 117.998776 -345.838597) (xy 117.946446 -345.823235) (xy 117.896835 -345.800581)
			(xy 117.850953 -345.771098) (xy 117.809735 -345.735385) (xy 117.774019 -345.694169) (xy 117.744532 -345.648289)
			(xy 117.721875 -345.59868) (xy 117.706509 -345.546352) (xy 117.698747 -345.492369) (xy 116.216044 -345.492369)
			(xy 116.216044 -345.492376) (xy 116.20828 -345.546372) (xy 116.192911 -345.598713) (xy 116.170248 -345.648335)
			(xy 116.140754 -345.694225) (xy 116.105029 -345.735451) (xy 116.0638 -345.771173) (xy 116.017907 -345.800663)
			(xy 115.968283 -345.823322) (xy 115.915941 -345.838687) (xy 115.861944 -345.846447) (xy 115.834668 -345.846908)
			(xy 114.971068 -345.846908) (xy 114.943803 -345.846328) (xy 114.88983 -345.838563) (xy 114.83751 -345.823197)
			(xy 114.78791 -345.800542) (xy 114.742039 -345.771058) (xy 114.70083 -345.735347) (xy 114.665122 -345.694136)
			(xy 114.635643 -345.648262) (xy 114.612992 -345.59866) (xy 114.59763 -345.546339) (xy 114.58987 -345.492365)
			(xy 113.107021 -345.492365) (xy 113.107021 -345.492372) (xy 113.099259 -345.546362) (xy 113.083892 -345.598697)
			(xy 113.061234 -345.648312) (xy 113.031745 -345.694199) (xy 112.996027 -345.735421) (xy 112.954805 -345.77114)
			(xy 112.90892 -345.80063) (xy 112.859304 -345.82329) (xy 112.80697 -345.838657) (xy 112.75298 -345.846421)
			(xy 112.725708 -345.846908) (xy 111.862108 -345.846908) (xy 111.83484 -345.846353) (xy 111.780859 -345.838593)
			(xy 111.728531 -345.823229) (xy 111.678923 -345.800575) (xy 111.633044 -345.771091) (xy 111.591828 -345.735378)
			(xy 111.556114 -345.694162) (xy 111.526629 -345.648284) (xy 111.503974 -345.598676) (xy 111.488609 -345.546349)
			(xy 111.480847 -345.492368) (xy 93.706722 -345.492368) (xy 93.706722 -345.492371) (xy 93.69896 -345.546357)
			(xy 93.683595 -345.59869) (xy 93.660939 -345.648303) (xy 93.631454 -345.694187) (xy 93.595739 -345.735409)
			(xy 93.554521 -345.771128) (xy 93.50864 -345.800619) (xy 93.459029 -345.82328) (xy 93.406698 -345.838651)
			(xy 93.352713 -345.846419) (xy 93.325442 -345.846908) (xy 92.461842 -345.846908) (xy 92.434572 -345.846355)
			(xy 92.380587 -345.838599) (xy 92.328256 -345.823238) (xy 92.278643 -345.800586) (xy 92.23276 -345.771103)
			(xy 92.19154 -345.73539) (xy 92.155822 -345.694174) (xy 92.126334 -345.648293) (xy 92.103676 -345.598683)
			(xy 92.08831 -345.546354) (xy 92.080548 -345.49237) (xy 90.597844 -345.49237) (xy 90.597844 -345.492375)
			(xy 90.590081 -345.54637) (xy 90.574712 -345.59871) (xy 90.55205 -345.648331) (xy 90.522557 -345.694221)
			(xy 90.486834 -345.735446) (xy 90.445606 -345.771168) (xy 90.399715 -345.800659) (xy 90.350094 -345.823318)
			(xy 90.297752 -345.838685) (xy 90.243757 -345.846446) (xy 90.216482 -345.846908) (xy 89.352882 -345.846908)
			(xy 89.325617 -345.846328) (xy 89.271642 -345.838566) (xy 89.219321 -345.823201) (xy 89.169719 -345.800546)
			(xy 89.123845 -345.771063) (xy 89.082635 -345.735352) (xy 89.046926 -345.69414) (xy 89.017445 -345.648266)
			(xy 88.994793 -345.598663) (xy 88.979431 -345.546341) (xy 88.97167 -345.492365) (xy 87.488822 -345.492365)
			(xy 87.488822 -345.492372) (xy 87.481059 -345.54636) (xy 87.465693 -345.598694) (xy 87.443036 -345.648309)
			(xy 87.413549 -345.694194) (xy 87.377832 -345.735416) (xy 87.336612 -345.771136) (xy 87.290728 -345.800626)
			(xy 87.241115 -345.823286) (xy 87.188781 -345.838655) (xy 87.134794 -345.84642) (xy 87.107522 -345.846908)
			(xy 86.243922 -345.846908) (xy 86.216653 -345.846354) (xy 86.16267 -345.838595) (xy 86.110341 -345.823233)
			(xy 86.060732 -345.800579) (xy 86.014851 -345.771096) (xy 85.973633 -345.735383) (xy 85.937917 -345.694167)
			(xy 85.908431 -345.648288) (xy 85.885775 -345.598679) (xy 85.870409 -345.546351) (xy 85.862647 -345.492369)
			(xy 84.379944 -345.492369) (xy 84.379944 -345.492376) (xy 84.37218 -345.546373) (xy 84.35681 -345.598715)
			(xy 84.334147 -345.648336) (xy 84.304652 -345.694227) (xy 84.268927 -345.735453) (xy 84.227697 -345.771175)
			(xy 84.181803 -345.800665) (xy 84.132179 -345.823323) (xy 84.079836 -345.838688) (xy 84.025838 -345.846447)
			(xy 83.998562 -345.846908) (xy 83.134962 -345.846908) (xy 83.107698 -345.846327) (xy 83.053725 -345.838562)
			(xy 83.001406 -345.823195) (xy 82.951807 -345.80054) (xy 82.905936 -345.771056) (xy 82.864728 -345.735345)
			(xy 82.829021 -345.694134) (xy 82.799542 -345.64826) (xy 82.776892 -345.598658) (xy 82.76153 -345.546338)
			(xy 82.75377 -345.492364) (xy 81.270921 -345.492364) (xy 81.270921 -345.492373) (xy 81.263159 -345.546362)
			(xy 81.247792 -345.598698) (xy 81.225133 -345.648314) (xy 81.195644 -345.6942) (xy 81.159924 -345.735423)
			(xy 81.118702 -345.771143) (xy 81.072816 -345.800632) (xy 81.0232 -345.823291) (xy 80.970864 -345.838658)
			(xy 80.916875 -345.846421) (xy 80.889602 -345.846908) (xy 80.026002 -345.846908) (xy 79.998734 -345.846353)
			(xy 79.944754 -345.838592) (xy 79.892427 -345.823228) (xy 79.84282 -345.800573) (xy 79.796941 -345.771089)
			(xy 79.755726 -345.735376) (xy 79.720012 -345.69416) (xy 79.690528 -345.648282) (xy 79.667873 -345.598675)
			(xy 79.652509 -345.546348) (xy 79.644747 -345.492368) (xy 78.161922 -345.492368) (xy 78.161922 -345.492371)
			(xy 78.15416 -345.546357) (xy 78.138795 -345.59869) (xy 78.116139 -345.648303) (xy 78.086654 -345.694187)
			(xy 78.050939 -345.735409) (xy 78.009721 -345.771128) (xy 77.96384 -345.800619) (xy 77.914229 -345.82328)
			(xy 77.861898 -345.838651) (xy 77.807913 -345.846419) (xy 77.780642 -345.846908) (xy 76.917042 -345.846908)
			(xy 76.889772 -345.846355) (xy 76.835787 -345.838599) (xy 76.783456 -345.823238) (xy 76.733843 -345.800586)
			(xy 76.68796 -345.771103) (xy 76.64674 -345.73539) (xy 76.611022 -345.694174) (xy 76.581534 -345.648293)
			(xy 76.558876 -345.598683) (xy 76.54351 -345.546354) (xy 76.535748 -345.49237) (xy 75.053044 -345.49237)
			(xy 75.053044 -345.492375) (xy 75.045281 -345.54637) (xy 75.029912 -345.59871) (xy 75.00725 -345.648331)
			(xy 74.977757 -345.694221) (xy 74.942034 -345.735446) (xy 74.900806 -345.771168) (xy 74.854915 -345.800659)
			(xy 74.805294 -345.823318) (xy 74.752952 -345.838685) (xy 74.698957 -345.846446) (xy 74.671682 -345.846908)
			(xy 73.808082 -345.846908) (xy 73.780817 -345.846328) (xy 73.726842 -345.838566) (xy 73.674521 -345.823201)
			(xy 73.624919 -345.800546) (xy 73.579045 -345.771063) (xy 73.537835 -345.735352) (xy 73.502126 -345.69414)
			(xy 73.472645 -345.648266) (xy 73.449993 -345.598663) (xy 73.434631 -345.546341) (xy 73.42687 -345.492365)
			(xy 71.944022 -345.492365) (xy 71.944022 -345.492372) (xy 71.936259 -345.54636) (xy 71.920893 -345.598694)
			(xy 71.898236 -345.648309) (xy 71.868749 -345.694194) (xy 71.833032 -345.735416) (xy 71.791812 -345.771136)
			(xy 71.745928 -345.800626) (xy 71.696315 -345.823286) (xy 71.643981 -345.838655) (xy 71.589994 -345.84642)
			(xy 71.562722 -345.846908) (xy 70.699122 -345.846908) (xy 70.671853 -345.846354) (xy 70.61787 -345.838595)
			(xy 70.565541 -345.823233) (xy 70.515932 -345.800579) (xy 70.470051 -345.771096) (xy 70.428833 -345.735383)
			(xy 70.393117 -345.694167) (xy 70.363631 -345.648288) (xy 70.340975 -345.598679) (xy 70.325609 -345.546351)
			(xy 70.317847 -345.492369) (xy 68.835144 -345.492369) (xy 68.835144 -345.492376) (xy 68.82738 -345.546373)
			(xy 68.81201 -345.598715) (xy 68.789347 -345.648336) (xy 68.759852 -345.694227) (xy 68.724127 -345.735453)
			(xy 68.682897 -345.771175) (xy 68.637003 -345.800665) (xy 68.587379 -345.823323) (xy 68.535036 -345.838688)
			(xy 68.481038 -345.846447) (xy 68.453762 -345.846908) (xy 67.590162 -345.846908) (xy 67.562898 -345.846327)
			(xy 67.508925 -345.838562) (xy 67.456606 -345.823195) (xy 67.407007 -345.80054) (xy 67.361136 -345.771056)
			(xy 67.319928 -345.735345) (xy 67.284221 -345.694134) (xy 67.254742 -345.64826) (xy 67.232092 -345.598658)
			(xy 67.21673 -345.546338) (xy 67.20897 -345.492364) (xy 65.726121 -345.492364) (xy 65.726121 -345.492373)
			(xy 65.718359 -345.546362) (xy 65.702992 -345.598698) (xy 65.680333 -345.648314) (xy 65.650844 -345.6942)
			(xy 65.615124 -345.735423) (xy 65.573902 -345.771143) (xy 65.528016 -345.800632) (xy 65.4784 -345.823291)
			(xy 65.426064 -345.838658) (xy 65.372075 -345.846421) (xy 65.344802 -345.846908) (xy 64.481202 -345.846908)
			(xy 64.453934 -345.846353) (xy 64.399954 -345.838592) (xy 64.347627 -345.823228) (xy 64.29802 -345.800573)
			(xy 64.252141 -345.771089) (xy 64.210926 -345.735376) (xy 64.175212 -345.69416) (xy 64.145728 -345.648282)
			(xy 64.123073 -345.598675) (xy 64.107709 -345.546348) (xy 64.099947 -345.492368) (xy 62.617122 -345.492368)
			(xy 62.617122 -345.492371) (xy 62.60936 -345.546357) (xy 62.593995 -345.59869) (xy 62.571339 -345.648303)
			(xy 62.541854 -345.694187) (xy 62.506139 -345.735409) (xy 62.464921 -345.771128) (xy 62.41904 -345.800619)
			(xy 62.369429 -345.82328) (xy 62.317098 -345.838651) (xy 62.263113 -345.846419) (xy 62.235842 -345.846908)
			(xy 61.372242 -345.846908) (xy 61.344972 -345.846355) (xy 61.290987 -345.838599) (xy 61.238656 -345.823238)
			(xy 61.189043 -345.800586) (xy 61.14316 -345.771103) (xy 61.10194 -345.73539) (xy 61.066222 -345.694174)
			(xy 61.036734 -345.648293) (xy 61.014076 -345.598683) (xy 60.99871 -345.546354) (xy 60.990948 -345.49237)
			(xy 51.666922 -345.49237) (xy 51.65916 -345.546356) (xy 51.643795 -345.598688) (xy 51.62114 -345.648301)
			(xy 51.591655 -345.694185) (xy 51.555941 -345.735407) (xy 51.514724 -345.771126) (xy 51.468843 -345.800617)
			(xy 51.419233 -345.823279) (xy 51.366903 -345.83865) (xy 51.312918 -345.846418) (xy 51.285648 -345.846908)
			(xy 50.422048 -345.846908) (xy 50.394778 -345.846356) (xy 50.340792 -345.8386) (xy 50.28846 -345.82324)
			(xy 50.238847 -345.800588) (xy 50.192963 -345.771105) (xy 50.151742 -345.735392) (xy 50.116024 -345.694176)
			(xy 50.086535 -345.648295) (xy 50.063877 -345.598685) (xy 50.04851 -345.546354) (xy 50.040748 -345.49237)
			(xy 48.558044 -345.49237) (xy 48.558044 -345.492375) (xy 48.550281 -345.546369) (xy 48.534912 -345.598709)
			(xy 48.512251 -345.648329) (xy 48.482759 -345.694219) (xy 48.447036 -345.735444) (xy 48.405809 -345.771166)
			(xy 48.359919 -345.800657) (xy 48.310298 -345.823316) (xy 48.257958 -345.838684) (xy 48.203963 -345.846445)
			(xy 48.176688 -345.846908) (xy 47.313088 -345.846908) (xy 47.285822 -345.846329) (xy 47.231847 -345.838567)
			(xy 47.179525 -345.823202) (xy 47.129922 -345.800548) (xy 47.084048 -345.771065) (xy 47.042837 -345.735354)
			(xy 47.007127 -345.694142) (xy 46.977646 -345.648267) (xy 46.954994 -345.598664) (xy 46.939631 -345.546342)
			(xy 46.93187 -345.492366) (xy 45.449022 -345.492366) (xy 45.449022 -345.492371) (xy 45.44126 -345.546359)
			(xy 45.425894 -345.598693) (xy 45.403237 -345.648307) (xy 45.37375 -345.694192) (xy 45.338034 -345.735414)
			(xy 45.296814 -345.771133) (xy 45.250932 -345.800624) (xy 45.201319 -345.823284) (xy 45.148986 -345.838654)
			(xy 45.094999 -345.84642) (xy 45.067728 -345.846908) (xy 44.204128 -345.846908) (xy 44.176859 -345.846355)
			(xy 44.122876 -345.838597) (xy 44.070546 -345.823235) (xy 44.020935 -345.800581) (xy 43.975053 -345.771098)
			(xy 43.933835 -345.735385) (xy 43.898119 -345.694169) (xy 43.868632 -345.648289) (xy 43.845975 -345.59868)
			(xy 43.830609 -345.546352) (xy 43.822847 -345.492369) (xy 42.340144 -345.492369) (xy 42.340144 -345.492376)
			(xy 42.33238 -345.546372) (xy 42.317011 -345.598713) (xy 42.294348 -345.648335) (xy 42.264854 -345.694225)
			(xy 42.229129 -345.735451) (xy 42.1879 -345.771173) (xy 42.142007 -345.800663) (xy 42.092383 -345.823322)
			(xy 42.040041 -345.838687) (xy 41.986044 -345.846447) (xy 41.958768 -345.846908) (xy 41.095168 -345.846908)
			(xy 41.067903 -345.846328) (xy 41.01393 -345.838563) (xy 40.96161 -345.823197) (xy 40.91201 -345.800542)
			(xy 40.866139 -345.771058) (xy 40.82493 -345.735347) (xy 40.789222 -345.694136) (xy 40.759743 -345.648262)
			(xy 40.737092 -345.59866) (xy 40.72173 -345.546339) (xy 40.71397 -345.492365) (xy 39.231121 -345.492365)
			(xy 39.231121 -345.492372) (xy 39.223359 -345.546362) (xy 39.207992 -345.598697) (xy 39.185334 -345.648312)
			(xy 39.155845 -345.694199) (xy 39.120127 -345.735421) (xy 39.078905 -345.77114) (xy 39.03302 -345.80063)
			(xy 38.983404 -345.82329) (xy 38.93107 -345.838657) (xy 38.87708 -345.846421) (xy 38.849808 -345.846908)
			(xy 37.986208 -345.846908) (xy 37.95894 -345.846353) (xy 37.904959 -345.838593) (xy 37.852631 -345.823229)
			(xy 37.803023 -345.800575) (xy 37.757144 -345.771091) (xy 37.715928 -345.735378) (xy 37.680214 -345.694162)
			(xy 37.650729 -345.648284) (xy 37.628074 -345.598676) (xy 37.612709 -345.546349) (xy 37.604947 -345.492368)
			(xy 36.122122 -345.492368) (xy 36.122122 -345.49237) (xy 36.11436 -345.546356) (xy 36.098995 -345.598688)
			(xy 36.07634 -345.648301) (xy 36.046855 -345.694185) (xy 36.011141 -345.735407) (xy 35.969924 -345.771126)
			(xy 35.924043 -345.800617) (xy 35.874433 -345.823279) (xy 35.822103 -345.83865) (xy 35.768118 -345.846418)
			(xy 35.740848 -345.846908) (xy 34.877248 -345.846908) (xy 34.849978 -345.846356) (xy 34.795992 -345.8386)
			(xy 34.74366 -345.82324) (xy 34.694047 -345.800588) (xy 34.648163 -345.771105) (xy 34.606942 -345.735392)
			(xy 34.571224 -345.694176) (xy 34.541735 -345.648295) (xy 34.519077 -345.598685) (xy 34.50371 -345.546354)
			(xy 34.495948 -345.49237) (xy 33.013244 -345.49237) (xy 33.013244 -345.492375) (xy 33.005481 -345.546369)
			(xy 32.990112 -345.598709) (xy 32.967451 -345.648329) (xy 32.937959 -345.694219) (xy 32.902236 -345.735444)
			(xy 32.861009 -345.771166) (xy 32.815119 -345.800657) (xy 32.765498 -345.823316) (xy 32.713158 -345.838684)
			(xy 32.659163 -345.846445) (xy 32.631888 -345.846908) (xy 31.768288 -345.846908) (xy 31.741022 -345.846329)
			(xy 31.687047 -345.838567) (xy 31.634725 -345.823202) (xy 31.585122 -345.800548) (xy 31.539248 -345.771065)
			(xy 31.498037 -345.735354) (xy 31.462327 -345.694142) (xy 31.432846 -345.648267) (xy 31.410194 -345.598664)
			(xy 31.394831 -345.546342) (xy 31.38707 -345.492366) (xy 29.904222 -345.492366) (xy 29.904222 -345.492371)
			(xy 29.89646 -345.546359) (xy 29.881094 -345.598693) (xy 29.858437 -345.648307) (xy 29.82895 -345.694192)
			(xy 29.793234 -345.735414) (xy 29.752014 -345.771133) (xy 29.706132 -345.800624) (xy 29.656519 -345.823284)
			(xy 29.604186 -345.838654) (xy 29.550199 -345.84642) (xy 29.522928 -345.846908) (xy 28.659328 -345.846908)
			(xy 28.632059 -345.846355) (xy 28.578076 -345.838597) (xy 28.525746 -345.823235) (xy 28.476135 -345.800581)
			(xy 28.430253 -345.771098) (xy 28.389035 -345.735385) (xy 28.353319 -345.694169) (xy 28.323832 -345.648289)
			(xy 28.301175 -345.59868) (xy 28.285809 -345.546352) (xy 28.278047 -345.492369) (xy 26.795344 -345.492369)
			(xy 26.795344 -345.492376) (xy 26.78758 -345.546372) (xy 26.772211 -345.598713) (xy 26.749548 -345.648335)
			(xy 26.720054 -345.694225) (xy 26.684329 -345.735451) (xy 26.6431 -345.771173) (xy 26.597207 -345.800663)
			(xy 26.547583 -345.823322) (xy 26.495241 -345.838687) (xy 26.441244 -345.846447) (xy 26.413968 -345.846908)
			(xy 25.550368 -345.846908) (xy 25.523103 -345.846328) (xy 25.46913 -345.838563) (xy 25.41681 -345.823197)
			(xy 25.36721 -345.800542) (xy 25.321339 -345.771058) (xy 25.28013 -345.735347) (xy 25.244422 -345.694136)
			(xy 25.214943 -345.648262) (xy 25.192292 -345.59866) (xy 25.17693 -345.546339) (xy 25.16917 -345.492365)
			(xy 23.686305 -345.492365) (xy 23.686305 -345.492421) (xy 23.678542 -345.546407) (xy 23.663176 -345.59874)
			(xy 23.640519 -345.648352) (xy 23.611031 -345.694236) (xy 23.575314 -345.735455) (xy 23.534094 -345.771172)
			(xy 23.488211 -345.80066) (xy 23.438598 -345.823317) (xy 23.386265 -345.838683) (xy 23.332279 -345.846445)
			(xy 23.305008 -345.846908) (xy 22.441408 -345.846908) (xy 22.414138 -345.846429) (xy 22.360154 -345.838667)
			(xy 22.307825 -345.823302) (xy 22.258214 -345.800645) (xy 22.212333 -345.771159) (xy 22.171115 -345.735443)
			(xy 22.1354 -345.694225) (xy 22.105914 -345.648344) (xy 22.083258 -345.598733) (xy 22.067892 -345.546404)
			(xy 22.06013 -345.49242) (xy 20.577345 -345.49242) (xy 20.577345 -345.492421) (xy 20.569582 -345.546407)
			(xy 20.554216 -345.59874) (xy 20.531559 -345.648352) (xy 20.502071 -345.694236) (xy 20.466354 -345.735455)
			(xy 20.425134 -345.771172) (xy 20.379251 -345.80066) (xy 20.329638 -345.823317) (xy 20.277305 -345.838683)
			(xy 20.223319 -345.846445) (xy 20.196048 -345.846908) (xy 19.332448 -345.846908) (xy 19.305178 -345.846429)
			(xy 19.251194 -345.838667) (xy 19.198865 -345.823302) (xy 19.149254 -345.800645) (xy 19.103373 -345.771159)
			(xy 19.062155 -345.735443) (xy 19.02644 -345.694225) (xy 18.996954 -345.648344) (xy 18.974298 -345.598733)
			(xy 18.958932 -345.546404) (xy 18.95117 -345.49242) (xy 0.508 -345.49242) (xy 0.508 -348.976496)
			(xy 4.708641 -348.976496) (xy 4.708641 -348.847356) (xy 4.716591 -348.718461) (xy 4.732461 -348.590301)
			(xy 4.75619 -348.46336) (xy 4.787689 -348.338121) (xy 4.826838 -348.215058) (xy 4.873489 -348.094639)
			(xy 4.927464 -347.97732) (xy 4.988559 -347.863546) (xy 5.056542 -347.753749) (xy 5.131156 -347.648346)
			(xy 5.212117 -347.547736) (xy 5.299117 -347.452301) (xy 5.391828 -347.362402) (xy 5.489898 -347.278381)
			(xy 5.592953 -347.200557) (xy 5.700604 -347.129225) (xy 5.812443 -347.064655) (xy 5.928044 -347.007093)
			(xy 6.046969 -346.956756) (xy 6.168768 -346.913836) (xy 6.292978 -346.878495) (xy 6.419127 -346.850868)
			(xy 6.546739 -346.831059) (xy 6.675328 -346.819143) (xy 6.804406 -346.815167) (xy 6.933484 -346.819143)
			(xy 7.062073 -346.831059) (xy 7.189685 -346.850868) (xy 7.315834 -346.878495) (xy 7.440044 -346.913836)
			(xy 7.451736 -346.917956) (xy 245.50903 -346.917956) (xy 245.50903 -346.83326) (xy 245.517081 -346.748946)
			(xy 245.53311 -346.66578) (xy 245.556971 -346.584513) (xy 245.58845 -346.505883) (xy 245.627261 -346.430602)
			(xy 245.673051 -346.35935) (xy 245.725407 -346.292774) (xy 245.783855 -346.231476) (xy 245.847865 -346.176011)
			(xy 245.916857 -346.126882) (xy 245.990207 -346.084533) (xy 246.06725 -346.049349) (xy 246.147289 -346.021647)
			(xy 246.229598 -346.001679) (xy 246.313433 -345.989626) (xy 246.398034 -345.985596) (xy 246.482635 -345.989626)
			(xy 246.56647 -346.001679) (xy 246.648779 -346.021647) (xy 246.728818 -346.049349) (xy 246.805861 -346.084533)
			(xy 246.879211 -346.126882) (xy 246.948203 -346.176011) (xy 247.012213 -346.231476) (xy 247.070661 -346.292774)
			(xy 247.123017 -346.35935) (xy 247.168807 -346.430602) (xy 247.207618 -346.505883) (xy 247.239097 -346.584513)
			(xy 247.262958 -346.66578) (xy 247.278987 -346.748946) (xy 247.287038 -346.83326) (xy 247.287542 -346.875608)
			(xy 247.287038 -346.917956) (xy 247.278987 -347.00227) (xy 247.262958 -347.085436) (xy 247.239097 -347.166703)
			(xy 247.207618 -347.245333) (xy 247.168807 -347.320614) (xy 247.123017 -347.391866) (xy 247.070661 -347.458442)
			(xy 247.012213 -347.51974) (xy 246.948203 -347.575205) (xy 246.879211 -347.624334) (xy 246.805861 -347.666683)
			(xy 246.728818 -347.701867) (xy 246.648779 -347.729569) (xy 246.56647 -347.749537) (xy 246.482635 -347.76159)
			(xy 246.398034 -347.765621) (xy 246.313433 -347.76159) (xy 246.229598 -347.749537) (xy 246.147289 -347.729569)
			(xy 246.06725 -347.701867) (xy 245.990207 -347.666683) (xy 245.916857 -347.624334) (xy 245.847865 -347.575205)
			(xy 245.783855 -347.51974) (xy 245.725407 -347.458442) (xy 245.673051 -347.391866) (xy 245.627261 -347.320614)
			(xy 245.58845 -347.245333) (xy 245.556971 -347.166703) (xy 245.53311 -347.085436) (xy 245.517081 -347.00227)
			(xy 245.50903 -346.917956) (xy 7.451736 -346.917956) (xy 7.561843 -346.956756) (xy 7.680768 -347.007093)
			(xy 7.796369 -347.064655) (xy 7.908208 -347.129225) (xy 8.015859 -347.200557) (xy 8.118914 -347.278381)
			(xy 8.216984 -347.362402) (xy 8.309695 -347.452301) (xy 8.396695 -347.547736) (xy 8.477656 -347.648346)
			(xy 8.55227 -347.753749) (xy 8.620253 -347.863546) (xy 8.681348 -347.97732) (xy 8.735323 -348.094639)
			(xy 8.781974 -348.215058) (xy 8.821123 -348.338121) (xy 8.852622 -348.46336) (xy 8.876351 -348.590301)
			(xy 8.879169 -348.613059) (xy 18.951174 -348.613059) (xy 18.951174 -348.558521) (xy 18.958936 -348.504537)
			(xy 18.974301 -348.452208) (xy 18.996957 -348.402598) (xy 19.026443 -348.356717) (xy 19.062158 -348.315499)
			(xy 19.103375 -348.279784) (xy 19.149256 -348.250298) (xy 19.198866 -348.227642) (xy 19.251195 -348.212276)
			(xy 19.305179 -348.204515) (xy 19.332448 -348.204028) (xy 20.196048 -348.204028) (xy 20.223319 -348.204491)
			(xy 20.277306 -348.212253) (xy 20.329639 -348.227619) (xy 20.379253 -348.250277) (xy 20.425136 -348.279764)
			(xy 20.466357 -348.315482) (xy 20.502074 -348.356702) (xy 20.531562 -348.402586) (xy 20.55422 -348.452199)
			(xy 20.569586 -348.504532) (xy 20.577349 -348.558519) (xy 20.577349 -348.613061) (xy 20.577347 -348.613072)
			(xy 22.060092 -348.613072) (xy 22.060092 -348.558528) (xy 22.067854 -348.504539) (xy 22.083221 -348.452204)
			(xy 22.10588 -348.402589) (xy 22.135369 -348.356704) (xy 22.171088 -348.315483) (xy 22.21231 -348.279764)
			(xy 22.258196 -348.250276) (xy 22.307812 -348.227618) (xy 22.360147 -348.212252) (xy 22.414136 -348.204491)
			(xy 22.441408 -348.204028) (xy 23.305008 -348.204028) (xy 23.332276 -348.204535) (xy 23.386258 -348.212297)
			(xy 23.438585 -348.227663) (xy 23.488193 -348.250319) (xy 23.534071 -348.279804) (xy 23.575287 -348.315519)
			(xy 23.611 -348.356735) (xy 23.640485 -348.402614) (xy 23.66314 -348.452223) (xy 23.678504 -348.50455)
			(xy 23.686266 -348.558532) (xy 23.686266 -348.613068) (xy 23.686266 -348.613069) (xy 25.169114 -348.613069)
			(xy 25.169114 -348.558531) (xy 25.176875 -348.504549) (xy 25.19224 -348.452221) (xy 25.214894 -348.402611)
			(xy 25.244378 -348.356731) (xy 25.28009 -348.315513) (xy 25.321305 -348.279797) (xy 25.367183 -348.250309)
			(xy 25.416791 -348.227651) (xy 25.469118 -348.212282) (xy 25.523099 -348.204517) (xy 25.550368 -348.204028)
			(xy 26.413968 -348.204028) (xy 26.44124 -348.204509) (xy 26.495229 -348.212268) (xy 26.547564 -348.227631)
			(xy 26.59718 -348.250286) (xy 26.643066 -348.279772) (xy 26.684289 -348.315488) (xy 26.720009 -348.356708)
			(xy 26.749499 -348.402592) (xy 26.772158 -348.452206) (xy 26.787526 -348.50454) (xy 26.795288 -348.558528)
			(xy 26.795288 -348.613072) (xy 26.795288 -348.613073) (xy 28.277992 -348.613073) (xy 28.277992 -348.558527)
			(xy 28.285755 -348.504536) (xy 28.301123 -348.4522) (xy 28.323783 -348.402584) (xy 28.353274 -348.356697)
			(xy 28.388995 -348.315476) (xy 28.43022 -348.279757) (xy 28.476108 -348.25027) (xy 28.525726 -348.227613)
			(xy 28.578064 -348.212249) (xy 28.632055 -348.20449) (xy 28.659328 -348.204028) (xy 29.522928 -348.204028)
			(xy 29.550195 -348.204536) (xy 29.604175 -348.212301) (xy 29.656499 -348.227668) (xy 29.706105 -348.250326)
			(xy 29.751981 -348.279811) (xy 29.793194 -348.315526) (xy 29.828905 -348.356742) (xy 29.858388 -348.40262)
			(xy 29.881041 -348.452227) (xy 29.896405 -348.504553) (xy 29.904166 -348.558533) (xy 29.904166 -348.613067)
			(xy 29.904166 -348.61307) (xy 31.387014 -348.61307) (xy 31.387014 -348.55853) (xy 31.394776 -348.504546)
			(xy 31.410141 -348.452217) (xy 31.432797 -348.402606) (xy 31.462283 -348.356724) (xy 31.497997 -348.315506)
			(xy 31.539215 -348.27979) (xy 31.585095 -348.250303) (xy 31.634705 -348.227645) (xy 31.687035 -348.212279)
			(xy 31.741018 -348.204515) (xy 31.768288 -348.204028) (xy 32.631888 -348.204028) (xy 32.659159 -348.204511)
			(xy 32.713146 -348.212271) (xy 32.765478 -348.227636) (xy 32.815092 -348.250292) (xy 32.860976 -348.279779)
			(xy 32.902196 -348.315495) (xy 32.937914 -348.356715) (xy 32.967402 -348.402598) (xy 32.99006 -348.45221)
			(xy 33.005426 -348.504543) (xy 33.013189 -348.558529) (xy 33.013189 -348.613071) (xy 33.013189 -348.613074)
			(xy 34.495892 -348.613074) (xy 34.495892 -348.558526) (xy 34.503655 -348.504534) (xy 34.519024 -348.452196)
			(xy 34.541686 -348.402578) (xy 34.571179 -348.356691) (xy 34.606902 -348.315468) (xy 34.648129 -348.27975)
			(xy 34.69402 -348.250263) (xy 34.743641 -348.227608) (xy 34.795981 -348.212245) (xy 34.849974 -348.204488)
			(xy 34.877248 -348.204028) (xy 35.740848 -348.204028) (xy 35.768114 -348.204538) (xy 35.822091 -348.212305)
			(xy 35.874414 -348.227674) (xy 35.924017 -348.250332) (xy 35.96989 -348.279819) (xy 36.011101 -348.315533)
			(xy 36.04681 -348.356748) (xy 36.076291 -348.402626) (xy 36.098943 -348.452231) (xy 36.114306 -348.504556)
			(xy 36.122066 -348.558534) (xy 36.122066 -348.613066) (xy 36.122065 -348.613072) (xy 37.604892 -348.613072)
			(xy 37.604892 -348.558528) (xy 37.612654 -348.504539) (xy 37.628021 -348.452204) (xy 37.65068 -348.402589)
			(xy 37.680169 -348.356704) (xy 37.715888 -348.315483) (xy 37.75711 -348.279764) (xy 37.802996 -348.250276)
			(xy 37.852612 -348.227618) (xy 37.904947 -348.212252) (xy 37.958936 -348.204491) (xy 37.986208 -348.204028)
			(xy 38.849808 -348.204028) (xy 38.877076 -348.204535) (xy 38.931058 -348.212297) (xy 38.983385 -348.227663)
			(xy 39.032993 -348.250319) (xy 39.078871 -348.279804) (xy 39.120087 -348.315519) (xy 39.1558 -348.356735)
			(xy 39.185285 -348.402614) (xy 39.20794 -348.452223) (xy 39.223304 -348.50455) (xy 39.231066 -348.558532)
			(xy 39.231066 -348.613068) (xy 39.231066 -348.613069) (xy 40.713914 -348.613069) (xy 40.713914 -348.558531)
			(xy 40.721675 -348.504549) (xy 40.73704 -348.452221) (xy 40.759694 -348.402611) (xy 40.789178 -348.356731)
			(xy 40.82489 -348.315513) (xy 40.866105 -348.279797) (xy 40.911983 -348.250309) (xy 40.961591 -348.227651)
			(xy 41.013918 -348.212282) (xy 41.067899 -348.204517) (xy 41.095168 -348.204028) (xy 41.958768 -348.204028)
			(xy 41.98604 -348.204509) (xy 42.040029 -348.212268) (xy 42.092364 -348.227631) (xy 42.14198 -348.250286)
			(xy 42.187866 -348.279772) (xy 42.229089 -348.315488) (xy 42.264809 -348.356708) (xy 42.294299 -348.402592)
			(xy 42.316958 -348.452206) (xy 42.332326 -348.50454) (xy 42.340088 -348.558528) (xy 42.340088 -348.613072)
			(xy 42.340088 -348.613073) (xy 43.822792 -348.613073) (xy 43.822792 -348.558527) (xy 43.830555 -348.504536)
			(xy 43.845923 -348.4522) (xy 43.868583 -348.402584) (xy 43.898074 -348.356697) (xy 43.933795 -348.315476)
			(xy 43.97502 -348.279757) (xy 44.020908 -348.25027) (xy 44.070526 -348.227613) (xy 44.122864 -348.212249)
			(xy 44.176855 -348.20449) (xy 44.204128 -348.204028) (xy 45.067728 -348.204028) (xy 45.094995 -348.204536)
			(xy 45.148975 -348.212301) (xy 45.201299 -348.227668) (xy 45.250905 -348.250326) (xy 45.296781 -348.279811)
			(xy 45.337994 -348.315526) (xy 45.373705 -348.356742) (xy 45.403188 -348.40262) (xy 45.425841 -348.452227)
			(xy 45.441205 -348.504553) (xy 45.448966 -348.558533) (xy 45.448966 -348.613067) (xy 45.448966 -348.61307)
			(xy 46.931814 -348.61307) (xy 46.931814 -348.55853) (xy 46.939576 -348.504546) (xy 46.954941 -348.452217)
			(xy 46.977597 -348.402606) (xy 47.007083 -348.356724) (xy 47.042797 -348.315506) (xy 47.084015 -348.27979)
			(xy 47.129895 -348.250303) (xy 47.179505 -348.227645) (xy 47.231835 -348.212279) (xy 47.285818 -348.204515)
			(xy 47.313088 -348.204028) (xy 48.176688 -348.204028) (xy 48.203959 -348.204511) (xy 48.257946 -348.212271)
			(xy 48.310278 -348.227636) (xy 48.359892 -348.250292) (xy 48.405776 -348.279779) (xy 48.446996 -348.315495)
			(xy 48.482714 -348.356715) (xy 48.512202 -348.402598) (xy 48.53486 -348.45221) (xy 48.550226 -348.504543)
			(xy 48.557989 -348.558529) (xy 48.557989 -348.613071) (xy 48.557989 -348.613074) (xy 50.040692 -348.613074)
			(xy 50.040692 -348.558526) (xy 50.048455 -348.504534) (xy 50.063824 -348.452196) (xy 50.086486 -348.402578)
			(xy 50.115979 -348.356691) (xy 50.151702 -348.315468) (xy 50.192929 -348.27975) (xy 50.23882 -348.250263)
			(xy 50.288441 -348.227608) (xy 50.340781 -348.212245) (xy 50.394774 -348.204488) (xy 50.422048 -348.204028)
			(xy 51.285648 -348.204028) (xy 51.312914 -348.204538) (xy 51.366891 -348.212305) (xy 51.419214 -348.227674)
			(xy 51.468817 -348.250332) (xy 51.51469 -348.279819) (xy 51.555901 -348.315533) (xy 51.59161 -348.356748)
			(xy 51.621091 -348.402626) (xy 51.643743 -348.452231) (xy 51.659106 -348.504556) (xy 51.666866 -348.558534)
			(xy 51.666866 -348.613066) (xy 51.666865 -348.613074) (xy 60.990892 -348.613074) (xy 60.990892 -348.558526)
			(xy 60.998655 -348.504534) (xy 61.014024 -348.452197) (xy 61.036685 -348.40258) (xy 61.066177 -348.356693)
			(xy 61.1019 -348.315471) (xy 61.143127 -348.279752) (xy 61.189017 -348.250265) (xy 61.238636 -348.227609)
			(xy 61.290976 -348.212246) (xy 61.344968 -348.204489) (xy 61.372242 -348.204028) (xy 62.235842 -348.204028)
			(xy 62.263109 -348.204537) (xy 62.317086 -348.212304) (xy 62.369409 -348.227672) (xy 62.419013 -348.25033)
			(xy 62.464887 -348.279816) (xy 62.506099 -348.315531) (xy 62.541809 -348.356746) (xy 62.57129 -348.402624)
			(xy 62.593943 -348.45223) (xy 62.609305 -348.504555) (xy 62.617066 -348.558533) (xy 62.617066 -348.613067)
			(xy 62.617065 -348.613072) (xy 64.099892 -348.613072) (xy 64.099892 -348.558528) (xy 64.107654 -348.50454)
			(xy 64.123021 -348.452206) (xy 64.145679 -348.402591) (xy 64.175168 -348.356706) (xy 64.210886 -348.315485)
			(xy 64.252108 -348.279766) (xy 64.297993 -348.250278) (xy 64.347607 -348.22762) (xy 64.399942 -348.212253)
			(xy 64.45393 -348.204491) (xy 64.481202 -348.204028) (xy 65.344802 -348.204028) (xy 65.372071 -348.204535)
			(xy 65.426053 -348.212296) (xy 65.47838 -348.227661) (xy 65.527989 -348.250317) (xy 65.573869 -348.279802)
			(xy 65.615085 -348.315517) (xy 65.650799 -348.356733) (xy 65.680284 -348.402613) (xy 65.702939 -348.452221)
			(xy 65.718304 -348.504549) (xy 65.726066 -348.558531) (xy 65.726066 -348.613068) (xy 67.208914 -348.613068)
			(xy 67.208914 -348.558532) (xy 67.216675 -348.50455) (xy 67.232039 -348.452222) (xy 67.254693 -348.402613)
			(xy 67.284176 -348.356733) (xy 67.319888 -348.315515) (xy 67.361102 -348.279799) (xy 67.40698 -348.250311)
			(xy 67.456586 -348.227652) (xy 67.508913 -348.212283) (xy 67.562894 -348.204517) (xy 67.590162 -348.204028)
			(xy 68.453762 -348.204028) (xy 68.481034 -348.204509) (xy 68.535024 -348.212266) (xy 68.58736 -348.227629)
			(xy 68.636976 -348.250284) (xy 68.682863 -348.27977) (xy 68.724087 -348.315486) (xy 68.759808 -348.356706)
			(xy 68.789298 -348.40259) (xy 68.811958 -348.452205) (xy 68.827326 -348.504539) (xy 68.835088 -348.558528)
			(xy 68.835088 -348.613072) (xy 68.835088 -348.613073) (xy 70.317792 -348.613073) (xy 70.317792 -348.558527)
			(xy 70.325554 -348.504537) (xy 70.340922 -348.452201) (xy 70.363582 -348.402585) (xy 70.393072 -348.356699)
			(xy 70.428793 -348.315478) (xy 70.470017 -348.279759) (xy 70.515905 -348.250271) (xy 70.565522 -348.227615)
			(xy 70.617859 -348.21225) (xy 70.671849 -348.20449) (xy 70.699122 -348.204028) (xy 71.562722 -348.204028)
			(xy 71.58999 -348.204536) (xy 71.643969 -348.2123) (xy 71.696295 -348.227667) (xy 71.745901 -348.250324)
			(xy 71.791778 -348.279809) (xy 71.832992 -348.315524) (xy 71.868704 -348.35674) (xy 71.898187 -348.402618)
			(xy 71.920841 -348.452226) (xy 71.936205 -348.504552) (xy 71.943966 -348.558532) (xy 71.943966 -348.613068)
			(xy 71.943966 -348.613069) (xy 73.426814 -348.613069) (xy 73.426814 -348.558531) (xy 73.434576 -348.504547)
			(xy 73.449941 -348.452218) (xy 73.472596 -348.402608) (xy 73.502081 -348.356726) (xy 73.537795 -348.315508)
			(xy 73.579012 -348.279792) (xy 73.624892 -348.250305) (xy 73.674501 -348.227647) (xy 73.72683 -348.21228)
			(xy 73.780813 -348.204516) (xy 73.808082 -348.204028) (xy 74.671682 -348.204028) (xy 74.698953 -348.20451)
			(xy 74.752941 -348.21227) (xy 74.805274 -348.227634) (xy 74.854888 -348.25029) (xy 74.900773 -348.279777)
			(xy 74.941994 -348.315493) (xy 74.977712 -348.356713) (xy 75.007201 -348.402596) (xy 75.029859 -348.452209)
			(xy 75.045226 -348.504542) (xy 75.052988 -348.558529) (xy 75.052988 -348.613071) (xy 75.052988 -348.613074)
			(xy 76.535692 -348.613074) (xy 76.535692 -348.558526) (xy 76.543455 -348.504534) (xy 76.558824 -348.452197)
			(xy 76.581485 -348.40258) (xy 76.610977 -348.356693) (xy 76.6467 -348.315471) (xy 76.687927 -348.279752)
			(xy 76.733817 -348.250265) (xy 76.783436 -348.227609) (xy 76.835776 -348.212246) (xy 76.889768 -348.204489)
			(xy 76.917042 -348.204028) (xy 77.780642 -348.204028) (xy 77.807909 -348.204537) (xy 77.861886 -348.212304)
			(xy 77.914209 -348.227672) (xy 77.963813 -348.25033) (xy 78.009687 -348.279816) (xy 78.050899 -348.315531)
			(xy 78.086609 -348.356746) (xy 78.11609 -348.402624) (xy 78.138743 -348.45223) (xy 78.154105 -348.504555)
			(xy 78.161866 -348.558533) (xy 78.161866 -348.613067) (xy 78.161865 -348.613072) (xy 79.644692 -348.613072)
			(xy 79.644692 -348.558528) (xy 79.652454 -348.50454) (xy 79.667821 -348.452206) (xy 79.690479 -348.402591)
			(xy 79.719968 -348.356706) (xy 79.755686 -348.315485) (xy 79.796908 -348.279766) (xy 79.842793 -348.250278)
			(xy 79.892407 -348.22762) (xy 79.944742 -348.212253) (xy 79.99873 -348.204491) (xy 80.026002 -348.204028)
			(xy 80.889602 -348.204028) (xy 80.916871 -348.204535) (xy 80.970853 -348.212296) (xy 81.02318 -348.227661)
			(xy 81.072789 -348.250317) (xy 81.118669 -348.279802) (xy 81.159885 -348.315517) (xy 81.195599 -348.356733)
			(xy 81.225084 -348.402613) (xy 81.247739 -348.452221) (xy 81.263104 -348.504549) (xy 81.270866 -348.558531)
			(xy 81.270866 -348.613068) (xy 82.753714 -348.613068) (xy 82.753714 -348.558532) (xy 82.761475 -348.50455)
			(xy 82.776839 -348.452222) (xy 82.799493 -348.402613) (xy 82.828976 -348.356733) (xy 82.864688 -348.315515)
			(xy 82.905902 -348.279799) (xy 82.95178 -348.250311) (xy 83.001386 -348.227652) (xy 83.053713 -348.212283)
			(xy 83.107694 -348.204517) (xy 83.134962 -348.204028) (xy 83.998562 -348.204028) (xy 84.025834 -348.204509)
			(xy 84.079824 -348.212266) (xy 84.13216 -348.227629) (xy 84.181776 -348.250284) (xy 84.227663 -348.27977)
			(xy 84.268887 -348.315486) (xy 84.304608 -348.356706) (xy 84.334098 -348.40259) (xy 84.356758 -348.452205)
			(xy 84.372126 -348.504539) (xy 84.379888 -348.558528) (xy 84.379888 -348.613072) (xy 84.379888 -348.613073)
			(xy 85.862592 -348.613073) (xy 85.862592 -348.558527) (xy 85.870354 -348.504537) (xy 85.885722 -348.452201)
			(xy 85.908382 -348.402585) (xy 85.937872 -348.356699) (xy 85.973593 -348.315478) (xy 86.014817 -348.279759)
			(xy 86.060705 -348.250271) (xy 86.110322 -348.227615) (xy 86.162659 -348.21225) (xy 86.216649 -348.20449)
			(xy 86.243922 -348.204028) (xy 87.107522 -348.204028) (xy 87.13479 -348.204536) (xy 87.188769 -348.2123)
			(xy 87.241095 -348.227667) (xy 87.290701 -348.250324) (xy 87.336578 -348.279809) (xy 87.377792 -348.315524)
			(xy 87.413504 -348.35674) (xy 87.442987 -348.402618) (xy 87.465641 -348.452226) (xy 87.481005 -348.504552)
			(xy 87.488766 -348.558532) (xy 87.488766 -348.613068) (xy 87.488766 -348.613069) (xy 88.971614 -348.613069)
			(xy 88.971614 -348.558531) (xy 88.979376 -348.504547) (xy 88.994741 -348.452218) (xy 89.017396 -348.402608)
			(xy 89.046881 -348.356726) (xy 89.082595 -348.315508) (xy 89.123812 -348.279792) (xy 89.169692 -348.250305)
			(xy 89.219301 -348.227647) (xy 89.27163 -348.21228) (xy 89.325613 -348.204516) (xy 89.352882 -348.204028)
			(xy 90.216482 -348.204028) (xy 90.243753 -348.20451) (xy 90.297741 -348.21227) (xy 90.350074 -348.227634)
			(xy 90.399688 -348.25029) (xy 90.445573 -348.279777) (xy 90.486794 -348.315493) (xy 90.522512 -348.356713)
			(xy 90.552001 -348.402596) (xy 90.574659 -348.452209) (xy 90.590026 -348.504542) (xy 90.597788 -348.558529)
			(xy 90.597788 -348.613071) (xy 90.597788 -348.613074) (xy 92.080492 -348.613074) (xy 92.080492 -348.558526)
			(xy 92.088255 -348.504534) (xy 92.103624 -348.452197) (xy 92.126285 -348.40258) (xy 92.155777 -348.356693)
			(xy 92.1915 -348.315471) (xy 92.232727 -348.279752) (xy 92.278617 -348.250265) (xy 92.328236 -348.227609)
			(xy 92.380576 -348.212246) (xy 92.434568 -348.204489) (xy 92.461842 -348.204028) (xy 93.325442 -348.204028)
			(xy 93.352709 -348.204537) (xy 93.406686 -348.212304) (xy 93.459009 -348.227672) (xy 93.508613 -348.25033)
			(xy 93.554487 -348.279816) (xy 93.595699 -348.315531) (xy 93.631409 -348.356746) (xy 93.66089 -348.402624)
			(xy 93.683543 -348.45223) (xy 93.698905 -348.504555) (xy 93.706666 -348.558533) (xy 93.706666 -348.613067)
			(xy 93.706665 -348.613072) (xy 111.480792 -348.613072) (xy 111.480792 -348.558528) (xy 111.488554 -348.504539)
			(xy 111.503921 -348.452204) (xy 111.52658 -348.402589) (xy 111.556069 -348.356704) (xy 111.591788 -348.315483)
			(xy 111.63301 -348.279764) (xy 111.678896 -348.250276) (xy 111.728512 -348.227618) (xy 111.780847 -348.212252)
			(xy 111.834836 -348.204491) (xy 111.862108 -348.204028) (xy 112.725708 -348.204028) (xy 112.752976 -348.204535)
			(xy 112.806958 -348.212297) (xy 112.859285 -348.227663) (xy 112.908893 -348.250319) (xy 112.954771 -348.279804)
			(xy 112.995987 -348.315519) (xy 113.0317 -348.356735) (xy 113.061185 -348.402614) (xy 113.08384 -348.452223)
			(xy 113.099204 -348.50455) (xy 113.106966 -348.558532) (xy 113.106966 -348.613068) (xy 113.106966 -348.613069)
			(xy 114.589814 -348.613069) (xy 114.589814 -348.558531) (xy 114.597575 -348.504549) (xy 114.61294 -348.452221)
			(xy 114.635594 -348.402611) (xy 114.665078 -348.356731) (xy 114.70079 -348.315513) (xy 114.742005 -348.279797)
			(xy 114.787883 -348.250309) (xy 114.837491 -348.227651) (xy 114.889818 -348.212282) (xy 114.943799 -348.204517)
			(xy 114.971068 -348.204028) (xy 115.834668 -348.204028) (xy 115.86194 -348.204509) (xy 115.915929 -348.212268)
			(xy 115.968264 -348.227631) (xy 116.01788 -348.250286) (xy 116.063766 -348.279772) (xy 116.104989 -348.315488)
			(xy 116.140709 -348.356708) (xy 116.170199 -348.402592) (xy 116.192858 -348.452206) (xy 116.208226 -348.50454)
			(xy 116.215988 -348.558528) (xy 116.215988 -348.613072) (xy 116.215988 -348.613073) (xy 117.698692 -348.613073)
			(xy 117.698692 -348.558527) (xy 117.706455 -348.504536) (xy 117.721823 -348.4522) (xy 117.744483 -348.402584)
			(xy 117.773974 -348.356697) (xy 117.809695 -348.315476) (xy 117.85092 -348.279757) (xy 117.896808 -348.25027)
			(xy 117.946426 -348.227613) (xy 117.998764 -348.212249) (xy 118.052755 -348.20449) (xy 118.080028 -348.204028)
			(xy 118.943628 -348.204028) (xy 118.970895 -348.204536) (xy 119.024875 -348.212301) (xy 119.077199 -348.227668)
			(xy 119.126805 -348.250326) (xy 119.172681 -348.279811) (xy 119.213894 -348.315526) (xy 119.249605 -348.356742)
			(xy 119.279088 -348.40262) (xy 119.301741 -348.452227) (xy 119.317105 -348.504553) (xy 119.324866 -348.558533)
			(xy 119.324866 -348.613067) (xy 119.324866 -348.61307) (xy 120.807714 -348.61307) (xy 120.807714 -348.55853)
			(xy 120.815476 -348.504546) (xy 120.830841 -348.452217) (xy 120.853497 -348.402606) (xy 120.882983 -348.356724)
			(xy 120.918697 -348.315506) (xy 120.959915 -348.27979) (xy 121.005795 -348.250303) (xy 121.055405 -348.227645)
			(xy 121.107735 -348.212279) (xy 121.161718 -348.204515) (xy 121.188988 -348.204028) (xy 122.052588 -348.204028)
			(xy 122.079859 -348.204511) (xy 122.133846 -348.212271) (xy 122.186178 -348.227636) (xy 122.235792 -348.250292)
			(xy 122.281676 -348.279779) (xy 122.322896 -348.315495) (xy 122.358614 -348.356715) (xy 122.388102 -348.402598)
			(xy 122.41076 -348.45221) (xy 122.426126 -348.504543) (xy 122.433889 -348.558529) (xy 122.433889 -348.613071)
			(xy 122.433889 -348.613074) (xy 123.916592 -348.613074) (xy 123.916592 -348.558526) (xy 123.924355 -348.504534)
			(xy 123.939724 -348.452196) (xy 123.962386 -348.402578) (xy 123.991879 -348.356691) (xy 124.027602 -348.315468)
			(xy 124.068829 -348.27975) (xy 124.11472 -348.250263) (xy 124.164341 -348.227608) (xy 124.216681 -348.212245)
			(xy 124.270674 -348.204488) (xy 124.297948 -348.204028) (xy 125.161548 -348.204028) (xy 125.188814 -348.204538)
			(xy 125.242791 -348.212305) (xy 125.295114 -348.227674) (xy 125.344717 -348.250332) (xy 125.39059 -348.279819)
			(xy 125.431801 -348.315533) (xy 125.46751 -348.356748) (xy 125.496991 -348.402626) (xy 125.519643 -348.452231)
			(xy 125.535006 -348.504556) (xy 125.542766 -348.558534) (xy 125.542766 -348.613066) (xy 125.542765 -348.613072)
			(xy 127.025592 -348.613072) (xy 127.025592 -348.558528) (xy 127.033354 -348.504539) (xy 127.048721 -348.452204)
			(xy 127.07138 -348.402589) (xy 127.100869 -348.356704) (xy 127.136588 -348.315483) (xy 127.17781 -348.279764)
			(xy 127.223696 -348.250276) (xy 127.273312 -348.227618) (xy 127.325647 -348.212252) (xy 127.379636 -348.204491)
			(xy 127.406908 -348.204028) (xy 128.270508 -348.204028) (xy 128.297776 -348.204535) (xy 128.351758 -348.212297)
			(xy 128.404085 -348.227663) (xy 128.453693 -348.250319) (xy 128.499571 -348.279804) (xy 128.540787 -348.315519)
			(xy 128.5765 -348.356735) (xy 128.605985 -348.402614) (xy 128.62864 -348.452223) (xy 128.644004 -348.50455)
			(xy 128.651766 -348.558532) (xy 128.651766 -348.613068) (xy 128.651766 -348.613069) (xy 130.134614 -348.613069)
			(xy 130.134614 -348.558531) (xy 130.142375 -348.504549) (xy 130.15774 -348.452221) (xy 130.180394 -348.402611)
			(xy 130.209878 -348.356731) (xy 130.24559 -348.315513) (xy 130.286805 -348.279797) (xy 130.332683 -348.250309)
			(xy 130.382291 -348.227651) (xy 130.434618 -348.212282) (xy 130.488599 -348.204517) (xy 130.515868 -348.204028)
			(xy 131.379468 -348.204028) (xy 131.40674 -348.204509) (xy 131.460729 -348.212268) (xy 131.513064 -348.227631)
			(xy 131.56268 -348.250286) (xy 131.608566 -348.279772) (xy 131.649789 -348.315488) (xy 131.685509 -348.356708)
			(xy 131.714999 -348.402592) (xy 131.737658 -348.452206) (xy 131.753026 -348.50454) (xy 131.760788 -348.558528)
			(xy 131.760788 -348.613072) (xy 131.760788 -348.613073) (xy 133.243492 -348.613073) (xy 133.243492 -348.558527)
			(xy 133.251255 -348.504536) (xy 133.266623 -348.4522) (xy 133.289283 -348.402584) (xy 133.318774 -348.356697)
			(xy 133.354495 -348.315476) (xy 133.39572 -348.279757) (xy 133.441608 -348.25027) (xy 133.491226 -348.227613)
			(xy 133.543564 -348.212249) (xy 133.597555 -348.20449) (xy 133.624828 -348.204028) (xy 134.488428 -348.204028)
			(xy 134.515695 -348.204536) (xy 134.569675 -348.212301) (xy 134.621999 -348.227668) (xy 134.671605 -348.250326)
			(xy 134.717481 -348.279811) (xy 134.758694 -348.315526) (xy 134.794405 -348.356742) (xy 134.823888 -348.40262)
			(xy 134.846541 -348.452227) (xy 134.861905 -348.504553) (xy 134.869666 -348.558533) (xy 134.869666 -348.613067)
			(xy 134.869666 -348.61307) (xy 136.352514 -348.61307) (xy 136.352514 -348.55853) (xy 136.360276 -348.504546)
			(xy 136.375641 -348.452217) (xy 136.398297 -348.402606) (xy 136.427783 -348.356724) (xy 136.463497 -348.315506)
			(xy 136.504715 -348.27979) (xy 136.550595 -348.250303) (xy 136.600205 -348.227645) (xy 136.652535 -348.212279)
			(xy 136.706518 -348.204515) (xy 136.733788 -348.204028) (xy 137.597388 -348.204028) (xy 137.624659 -348.204511)
			(xy 137.678646 -348.212271) (xy 137.730978 -348.227636) (xy 137.780592 -348.250292) (xy 137.826476 -348.279779)
			(xy 137.867696 -348.315495) (xy 137.903414 -348.356715) (xy 137.932902 -348.402598) (xy 137.95556 -348.45221)
			(xy 137.970926 -348.504543) (xy 137.978689 -348.558529) (xy 137.978689 -348.613071) (xy 137.978689 -348.613074)
			(xy 139.461392 -348.613074) (xy 139.461392 -348.558526) (xy 139.469155 -348.504534) (xy 139.484524 -348.452196)
			(xy 139.507186 -348.402578) (xy 139.536679 -348.356691) (xy 139.572402 -348.315468) (xy 139.613629 -348.27975)
			(xy 139.65952 -348.250263) (xy 139.709141 -348.227608) (xy 139.761481 -348.212245) (xy 139.815474 -348.204488)
			(xy 139.842748 -348.204028) (xy 140.706348 -348.204028) (xy 140.733614 -348.204538) (xy 140.787591 -348.212305)
			(xy 140.839914 -348.227674) (xy 140.889517 -348.250332) (xy 140.93539 -348.279819) (xy 140.976601 -348.315533)
			(xy 141.01231 -348.356748) (xy 141.041791 -348.402626) (xy 141.064443 -348.452231) (xy 141.079806 -348.504556)
			(xy 141.087566 -348.558534) (xy 141.087566 -348.613066) (xy 141.087565 -348.613072) (xy 142.570392 -348.613072)
			(xy 142.570392 -348.558528) (xy 142.578154 -348.504539) (xy 142.593521 -348.452204) (xy 142.61618 -348.402589)
			(xy 142.645669 -348.356704) (xy 142.681388 -348.315483) (xy 142.72261 -348.279764) (xy 142.768496 -348.250276)
			(xy 142.818112 -348.227618) (xy 142.870447 -348.212252) (xy 142.924436 -348.204491) (xy 142.951708 -348.204028)
			(xy 143.815308 -348.204028) (xy 143.842576 -348.204535) (xy 143.896558 -348.212297) (xy 143.948885 -348.227663)
			(xy 143.998493 -348.250319) (xy 144.044371 -348.279804) (xy 144.085587 -348.315519) (xy 144.1213 -348.356735)
			(xy 144.150785 -348.402614) (xy 144.17344 -348.452223) (xy 144.188804 -348.50455) (xy 144.196566 -348.558532)
			(xy 144.196566 -348.613068) (xy 144.196565 -348.613072) (xy 161.804792 -348.613072) (xy 161.804792 -348.558528)
			(xy 161.812554 -348.504538) (xy 161.827921 -348.452203) (xy 161.850581 -348.402588) (xy 161.88007 -348.356703)
			(xy 161.91579 -348.315481) (xy 161.957012 -348.279763) (xy 162.002899 -348.250275) (xy 162.052515 -348.227617)
			(xy 162.10485 -348.212252) (xy 162.15884 -348.204491) (xy 162.186112 -348.204028) (xy 163.049712 -348.204028)
			(xy 163.07698 -348.204535) (xy 163.130961 -348.212298) (xy 163.183288 -348.227664) (xy 163.232895 -348.25032)
			(xy 163.278773 -348.279806) (xy 163.319988 -348.31552) (xy 163.355701 -348.356736) (xy 163.385185 -348.402615)
			(xy 163.40784 -348.452224) (xy 163.423204 -348.504551) (xy 163.430966 -348.558532) (xy 163.430966 -348.613068)
			(xy 163.430966 -348.613069) (xy 164.913814 -348.613069) (xy 164.913814 -348.558531) (xy 164.921576 -348.504549)
			(xy 164.93694 -348.45222) (xy 164.959595 -348.40261) (xy 164.989079 -348.35673) (xy 165.024792 -348.315512)
			(xy 165.066007 -348.279795) (xy 165.111886 -348.250308) (xy 165.161494 -348.22765) (xy 165.213821 -348.212281)
			(xy 165.267803 -348.204516) (xy 165.295072 -348.204028) (xy 166.158672 -348.204028) (xy 166.185944 -348.20451)
			(xy 166.239932 -348.212268) (xy 166.292267 -348.227632) (xy 166.341882 -348.250287) (xy 166.387768 -348.279773)
			(xy 166.42899 -348.31549) (xy 166.46471 -348.356709) (xy 166.494199 -348.402593) (xy 166.516859 -348.452207)
			(xy 166.532226 -348.504541) (xy 166.539988 -348.558528) (xy 166.539988 -348.613072) (xy 166.539988 -348.613073)
			(xy 168.022692 -348.613073) (xy 168.022692 -348.558527) (xy 168.030455 -348.504536) (xy 168.045823 -348.452199)
			(xy 168.068484 -348.402583) (xy 168.097975 -348.356696) (xy 168.133697 -348.315474) (xy 168.174922 -348.279756)
			(xy 168.220811 -348.250268) (xy 168.270429 -348.227612) (xy 168.322767 -348.212248) (xy 168.376759 -348.204489)
			(xy 168.404032 -348.204028) (xy 169.267632 -348.204028) (xy 169.294899 -348.204537) (xy 169.348878 -348.212302)
			(xy 169.401202 -348.227669) (xy 169.450807 -348.250327) (xy 169.496683 -348.279813) (xy 169.537895 -348.315527)
			(xy 169.573606 -348.356743) (xy 169.603088 -348.402621) (xy 169.625742 -348.452228) (xy 169.641105 -348.504553)
			(xy 169.648866 -348.558533) (xy 169.648866 -348.613067) (xy 169.648866 -348.61307) (xy 171.131714 -348.61307)
			(xy 171.131714 -348.55853) (xy 171.139476 -348.504546) (xy 171.154841 -348.452216) (xy 171.177498 -348.402605)
			(xy 171.206984 -348.356723) (xy 171.242699 -348.315505) (xy 171.283917 -348.279788) (xy 171.329798 -348.250301)
			(xy 171.379408 -348.227644) (xy 171.431738 -348.212278) (xy 171.485722 -348.204515) (xy 171.512992 -348.204028)
			(xy 172.376592 -348.204028) (xy 172.403863 -348.204511) (xy 172.457849 -348.212272) (xy 172.510181 -348.227637)
			(xy 172.559794 -348.250294) (xy 172.605678 -348.27978) (xy 172.646898 -348.315497) (xy 172.682615 -348.356716)
			(xy 172.712103 -348.402599) (xy 172.73476 -348.452211) (xy 172.750126 -348.504543) (xy 172.757889 -348.558529)
			(xy 172.757889 -348.613068) (xy 174.240714 -348.613068) (xy 174.240714 -348.558532) (xy 174.248475 -348.504551)
			(xy 174.263838 -348.452224) (xy 174.286492 -348.402616) (xy 174.315974 -348.356736) (xy 174.351685 -348.315519)
			(xy 174.392898 -348.279803) (xy 174.438774 -348.250315) (xy 174.488379 -348.227655) (xy 174.540704 -348.212285)
			(xy 174.594684 -348.204518) (xy 174.621952 -348.204028) (xy 175.485552 -348.204028) (xy 175.512825 -348.204508)
			(xy 175.566815 -348.212265) (xy 175.619152 -348.227626) (xy 175.66877 -348.250281) (xy 175.714659 -348.279766)
			(xy 175.755883 -348.315483) (xy 175.791605 -348.356703) (xy 175.821096 -348.402588) (xy 175.843757 -348.452203)
			(xy 175.859125 -348.504538) (xy 175.866888 -348.558528) (xy 175.866888 -348.613072) (xy 177.349592 -348.613072)
			(xy 177.349592 -348.558528) (xy 177.357354 -348.504538) (xy 177.372721 -348.452203) (xy 177.395381 -348.402588)
			(xy 177.42487 -348.356703) (xy 177.46059 -348.315481) (xy 177.501812 -348.279763) (xy 177.547699 -348.250275)
			(xy 177.597315 -348.227617) (xy 177.64965 -348.212252) (xy 177.70364 -348.204491) (xy 177.730912 -348.204028)
			(xy 178.594512 -348.204028) (xy 178.62178 -348.204535) (xy 178.675761 -348.212298) (xy 178.728088 -348.227664)
			(xy 178.777695 -348.25032) (xy 178.823573 -348.279806) (xy 178.864788 -348.31552) (xy 178.900501 -348.356736)
			(xy 178.929985 -348.402615) (xy 178.95264 -348.452224) (xy 178.968004 -348.504551) (xy 178.975766 -348.558532)
			(xy 178.975766 -348.613068) (xy 178.975766 -348.613069) (xy 180.458614 -348.613069) (xy 180.458614 -348.558531)
			(xy 180.466376 -348.504549) (xy 180.48174 -348.45222) (xy 180.504395 -348.40261) (xy 180.533879 -348.35673)
			(xy 180.569592 -348.315512) (xy 180.610807 -348.279795) (xy 180.656686 -348.250308) (xy 180.706294 -348.22765)
			(xy 180.758621 -348.212281) (xy 180.812603 -348.204516) (xy 180.839872 -348.204028) (xy 181.703472 -348.204028)
			(xy 181.730744 -348.20451) (xy 181.784732 -348.212268) (xy 181.837067 -348.227632) (xy 181.886682 -348.250287)
			(xy 181.932568 -348.279773) (xy 181.97379 -348.31549) (xy 182.00951 -348.356709) (xy 182.038999 -348.402593)
			(xy 182.061659 -348.452207) (xy 182.077026 -348.504541) (xy 182.084788 -348.558528) (xy 182.084788 -348.613072)
			(xy 182.084788 -348.613073) (xy 183.567492 -348.613073) (xy 183.567492 -348.558527) (xy 183.575255 -348.504536)
			(xy 183.590623 -348.452199) (xy 183.613284 -348.402583) (xy 183.642775 -348.356696) (xy 183.678497 -348.315474)
			(xy 183.719722 -348.279756) (xy 183.765611 -348.250268) (xy 183.815229 -348.227612) (xy 183.867567 -348.212248)
			(xy 183.921559 -348.204489) (xy 183.948832 -348.204028) (xy 184.812432 -348.204028) (xy 184.839699 -348.204537)
			(xy 184.893678 -348.212302) (xy 184.946002 -348.227669) (xy 184.995607 -348.250327) (xy 185.041483 -348.279813)
			(xy 185.082695 -348.315527) (xy 185.118406 -348.356743) (xy 185.147888 -348.402621) (xy 185.170542 -348.452228)
			(xy 185.185905 -348.504553) (xy 185.193666 -348.558533) (xy 185.193666 -348.613067) (xy 185.193666 -348.61307)
			(xy 186.676514 -348.61307) (xy 186.676514 -348.55853) (xy 186.684276 -348.504546) (xy 186.699641 -348.452216)
			(xy 186.722298 -348.402605) (xy 186.751784 -348.356723) (xy 186.787499 -348.315505) (xy 186.828717 -348.279788)
			(xy 186.874598 -348.250301) (xy 186.924208 -348.227644) (xy 186.976538 -348.212278) (xy 187.030522 -348.204515)
			(xy 187.057792 -348.204028) (xy 187.921392 -348.204028) (xy 187.948663 -348.204511) (xy 188.002649 -348.212272)
			(xy 188.054981 -348.227637) (xy 188.104594 -348.250294) (xy 188.150478 -348.27978) (xy 188.191698 -348.315497)
			(xy 188.227415 -348.356716) (xy 188.256903 -348.402599) (xy 188.27956 -348.452211) (xy 188.294926 -348.504543)
			(xy 188.302689 -348.558529) (xy 188.302689 -348.613068) (xy 189.785514 -348.613068) (xy 189.785514 -348.558532)
			(xy 189.793275 -348.504551) (xy 189.808638 -348.452224) (xy 189.831292 -348.402616) (xy 189.860774 -348.356736)
			(xy 189.896485 -348.315519) (xy 189.937698 -348.279803) (xy 189.983574 -348.250315) (xy 190.033179 -348.227655)
			(xy 190.085504 -348.212285) (xy 190.139484 -348.204518) (xy 190.166752 -348.204028) (xy 191.030352 -348.204028)
			(xy 191.057625 -348.204508) (xy 191.111615 -348.212265) (xy 191.163952 -348.227626) (xy 191.21357 -348.250281)
			(xy 191.259459 -348.279766) (xy 191.300683 -348.315483) (xy 191.336405 -348.356703) (xy 191.365896 -348.402588)
			(xy 191.388557 -348.452203) (xy 191.403925 -348.504538) (xy 191.411688 -348.558528) (xy 191.411688 -348.613072)
			(xy 192.894392 -348.613072) (xy 192.894392 -348.558528) (xy 192.902154 -348.504538) (xy 192.917521 -348.452203)
			(xy 192.940181 -348.402588) (xy 192.96967 -348.356703) (xy 193.00539 -348.315481) (xy 193.046612 -348.279763)
			(xy 193.092499 -348.250275) (xy 193.142115 -348.227617) (xy 193.19445 -348.212252) (xy 193.24844 -348.204491)
			(xy 193.275712 -348.204028) (xy 194.139312 -348.204028) (xy 194.16658 -348.204535) (xy 194.220561 -348.212298)
			(xy 194.272888 -348.227664) (xy 194.322495 -348.25032) (xy 194.368373 -348.279806) (xy 194.409588 -348.31552)
			(xy 194.445301 -348.356736) (xy 194.474785 -348.402615) (xy 194.49744 -348.452224) (xy 194.512804 -348.504551)
			(xy 194.520566 -348.558532) (xy 194.520566 -348.613068) (xy 194.520565 -348.613072) (xy 267.515792 -348.613072)
			(xy 267.515792 -348.558528) (xy 267.523554 -348.50454) (xy 267.538921 -348.452206) (xy 267.561579 -348.402591)
			(xy 267.591068 -348.356706) (xy 267.626786 -348.315485) (xy 267.668008 -348.279766) (xy 267.713893 -348.250278)
			(xy 267.763507 -348.22762) (xy 267.815842 -348.212253) (xy 267.86983 -348.204491) (xy 267.897102 -348.204028)
			(xy 268.760702 -348.204028) (xy 268.787971 -348.204535) (xy 268.841953 -348.212296) (xy 268.89428 -348.227661)
			(xy 268.943889 -348.250317) (xy 268.989769 -348.279802) (xy 269.030985 -348.315517) (xy 269.066699 -348.356733)
			(xy 269.096184 -348.402613) (xy 269.118839 -348.452221) (xy 269.134204 -348.504549) (xy 269.141966 -348.558531)
			(xy 269.141966 -348.613068) (xy 270.624814 -348.613068) (xy 270.624814 -348.558532) (xy 270.632575 -348.50455)
			(xy 270.647939 -348.452222) (xy 270.670593 -348.402613) (xy 270.700076 -348.356733) (xy 270.735788 -348.315515)
			(xy 270.777002 -348.279799) (xy 270.82288 -348.250311) (xy 270.872486 -348.227652) (xy 270.924813 -348.212283)
			(xy 270.978794 -348.204517) (xy 271.006062 -348.204028) (xy 271.869662 -348.204028) (xy 271.896934 -348.204509)
			(xy 271.950924 -348.212266) (xy 272.00326 -348.227629) (xy 272.052876 -348.250284) (xy 272.098763 -348.27977)
			(xy 272.139987 -348.315486) (xy 272.175708 -348.356706) (xy 272.205198 -348.40259) (xy 272.227858 -348.452205)
			(xy 272.243226 -348.504539) (xy 272.250988 -348.558528) (xy 272.250988 -348.613072) (xy 272.250988 -348.613073)
			(xy 273.733692 -348.613073) (xy 273.733692 -348.558527) (xy 273.741454 -348.504537) (xy 273.756822 -348.452201)
			(xy 273.779482 -348.402585) (xy 273.808972 -348.356699) (xy 273.844693 -348.315478) (xy 273.885917 -348.279759)
			(xy 273.931805 -348.250271) (xy 273.981422 -348.227615) (xy 274.033759 -348.21225) (xy 274.087749 -348.20449)
			(xy 274.115022 -348.204028) (xy 274.978622 -348.204028) (xy 275.00589 -348.204536) (xy 275.059869 -348.2123)
			(xy 275.112195 -348.227667) (xy 275.161801 -348.250324) (xy 275.207678 -348.279809) (xy 275.248892 -348.315524)
			(xy 275.284604 -348.35674) (xy 275.314087 -348.402618) (xy 275.336741 -348.452226) (xy 275.352105 -348.504552)
			(xy 275.359866 -348.558532) (xy 275.359866 -348.613068) (xy 275.359866 -348.613069) (xy 276.842714 -348.613069)
			(xy 276.842714 -348.558531) (xy 276.850476 -348.504547) (xy 276.865841 -348.452218) (xy 276.888496 -348.402608)
			(xy 276.917981 -348.356726) (xy 276.953695 -348.315508) (xy 276.994912 -348.279792) (xy 277.040792 -348.250305)
			(xy 277.090401 -348.227647) (xy 277.14273 -348.21228) (xy 277.196713 -348.204516) (xy 277.223982 -348.204028)
			(xy 278.087582 -348.204028) (xy 278.114853 -348.20451) (xy 278.168841 -348.21227) (xy 278.221174 -348.227634)
			(xy 278.270788 -348.25029) (xy 278.316673 -348.279777) (xy 278.357894 -348.315493) (xy 278.393612 -348.356713)
			(xy 278.423101 -348.402596) (xy 278.445759 -348.452209) (xy 278.461126 -348.504542) (xy 278.468888 -348.558529)
			(xy 278.468888 -348.613071) (xy 278.468888 -348.613074) (xy 279.951592 -348.613074) (xy 279.951592 -348.558526)
			(xy 279.959355 -348.504534) (xy 279.974724 -348.452197) (xy 279.997385 -348.40258) (xy 280.026877 -348.356693)
			(xy 280.0626 -348.315471) (xy 280.103827 -348.279752) (xy 280.149717 -348.250265) (xy 280.199336 -348.227609)
			(xy 280.251676 -348.212246) (xy 280.305668 -348.204489) (xy 280.332942 -348.204028) (xy 281.196542 -348.204028)
			(xy 281.223809 -348.204537) (xy 281.277786 -348.212304) (xy 281.330109 -348.227672) (xy 281.379713 -348.25033)
			(xy 281.425587 -348.279816) (xy 281.466799 -348.315531) (xy 281.502509 -348.356746) (xy 281.53199 -348.402624)
			(xy 281.554643 -348.45223) (xy 281.570005 -348.504555) (xy 281.577766 -348.558533) (xy 281.577766 -348.613067)
			(xy 281.577765 -348.613072) (xy 283.060592 -348.613072) (xy 283.060592 -348.558528) (xy 283.068354 -348.50454)
			(xy 283.083721 -348.452206) (xy 283.106379 -348.402591) (xy 283.135868 -348.356706) (xy 283.171586 -348.315485)
			(xy 283.212808 -348.279766) (xy 283.258693 -348.250278) (xy 283.308307 -348.22762) (xy 283.360642 -348.212253)
			(xy 283.41463 -348.204491) (xy 283.441902 -348.204028) (xy 284.305502 -348.204028) (xy 284.332771 -348.204535)
			(xy 284.386753 -348.212296) (xy 284.43908 -348.227661) (xy 284.488689 -348.250317) (xy 284.534569 -348.279802)
			(xy 284.575785 -348.315517) (xy 284.611499 -348.356733) (xy 284.640984 -348.402613) (xy 284.663639 -348.452221)
			(xy 284.679004 -348.504549) (xy 284.686766 -348.558531) (xy 284.686766 -348.613068) (xy 286.169614 -348.613068)
			(xy 286.169614 -348.558532) (xy 286.177375 -348.50455) (xy 286.192739 -348.452222) (xy 286.215393 -348.402613)
			(xy 286.244876 -348.356733) (xy 286.280588 -348.315515) (xy 286.321802 -348.279799) (xy 286.36768 -348.250311)
			(xy 286.417286 -348.227652) (xy 286.469613 -348.212283) (xy 286.523594 -348.204517) (xy 286.550862 -348.204028)
			(xy 287.414462 -348.204028) (xy 287.441734 -348.204509) (xy 287.495724 -348.212266) (xy 287.54806 -348.227629)
			(xy 287.597676 -348.250284) (xy 287.643563 -348.27977) (xy 287.684787 -348.315486) (xy 287.720508 -348.356706)
			(xy 287.749998 -348.40259) (xy 287.772658 -348.452205) (xy 287.788026 -348.504539) (xy 287.795788 -348.558528)
			(xy 287.795788 -348.613072) (xy 287.795788 -348.613073) (xy 289.278492 -348.613073) (xy 289.278492 -348.558527)
			(xy 289.286254 -348.504537) (xy 289.301622 -348.452201) (xy 289.324282 -348.402585) (xy 289.353772 -348.356699)
			(xy 289.389493 -348.315478) (xy 289.430717 -348.279759) (xy 289.476605 -348.250271) (xy 289.526222 -348.227615)
			(xy 289.578559 -348.21225) (xy 289.632549 -348.20449) (xy 289.659822 -348.204028) (xy 290.523422 -348.204028)
			(xy 290.55069 -348.204536) (xy 290.604669 -348.2123) (xy 290.656995 -348.227667) (xy 290.706601 -348.250324)
			(xy 290.752478 -348.279809) (xy 290.793692 -348.315524) (xy 290.829404 -348.35674) (xy 290.858887 -348.402618)
			(xy 290.881541 -348.452226) (xy 290.896905 -348.504552) (xy 290.904666 -348.558532) (xy 290.904666 -348.613068)
			(xy 290.904666 -348.613069) (xy 292.387514 -348.613069) (xy 292.387514 -348.558531) (xy 292.395276 -348.504547)
			(xy 292.410641 -348.452218) (xy 292.433296 -348.402608) (xy 292.462781 -348.356726) (xy 292.498495 -348.315508)
			(xy 292.539712 -348.279792) (xy 292.585592 -348.250305) (xy 292.635201 -348.227647) (xy 292.68753 -348.21228)
			(xy 292.741513 -348.204516) (xy 292.768782 -348.204028) (xy 293.632382 -348.204028) (xy 293.659653 -348.20451)
			(xy 293.713641 -348.21227) (xy 293.765974 -348.227634) (xy 293.815588 -348.25029) (xy 293.861473 -348.279777)
			(xy 293.902694 -348.315493) (xy 293.938412 -348.356713) (xy 293.967901 -348.402596) (xy 293.990559 -348.452209)
			(xy 294.005926 -348.504542) (xy 294.013688 -348.558529) (xy 294.013688 -348.613071) (xy 294.013688 -348.613074)
			(xy 295.496392 -348.613074) (xy 295.496392 -348.558526) (xy 295.504155 -348.504534) (xy 295.519524 -348.452197)
			(xy 295.542185 -348.40258) (xy 295.571677 -348.356693) (xy 295.6074 -348.315471) (xy 295.648627 -348.279752)
			(xy 295.694517 -348.250265) (xy 295.744136 -348.227609) (xy 295.796476 -348.212246) (xy 295.850468 -348.204489)
			(xy 295.877742 -348.204028) (xy 296.741342 -348.204028) (xy 296.768609 -348.204537) (xy 296.822586 -348.212304)
			(xy 296.874909 -348.227672) (xy 296.924513 -348.25033) (xy 296.970387 -348.279816) (xy 297.011599 -348.315531)
			(xy 297.047309 -348.356746) (xy 297.07679 -348.402624) (xy 297.099443 -348.45223) (xy 297.114805 -348.504555)
			(xy 297.122566 -348.558533) (xy 297.122566 -348.613067) (xy 297.122565 -348.613072) (xy 298.605392 -348.613072)
			(xy 298.605392 -348.558528) (xy 298.613154 -348.50454) (xy 298.628521 -348.452206) (xy 298.651179 -348.402591)
			(xy 298.680668 -348.356706) (xy 298.716386 -348.315485) (xy 298.757608 -348.279766) (xy 298.803493 -348.250278)
			(xy 298.853107 -348.22762) (xy 298.905442 -348.212253) (xy 298.95943 -348.204491) (xy 298.986702 -348.204028)
			(xy 299.850302 -348.204028) (xy 299.877571 -348.204535) (xy 299.931553 -348.212296) (xy 299.98388 -348.227661)
			(xy 300.033489 -348.250317) (xy 300.079369 -348.279802) (xy 300.120585 -348.315517) (xy 300.156299 -348.356733)
			(xy 300.185784 -348.402613) (xy 300.208439 -348.452221) (xy 300.223804 -348.504549) (xy 300.231566 -348.558531)
			(xy 300.231566 -348.613069) (xy 300.231566 -348.613072) (xy 312.121492 -348.613072) (xy 312.121492 -348.558528)
			(xy 312.129254 -348.504539) (xy 312.144621 -348.452205) (xy 312.167279 -348.40259) (xy 312.196768 -348.356705)
			(xy 312.232487 -348.315484) (xy 312.273709 -348.279766) (xy 312.319594 -348.250277) (xy 312.369209 -348.227619)
			(xy 312.421543 -348.212253) (xy 312.475532 -348.204491) (xy 312.502804 -348.204028) (xy 313.366404 -348.204028)
			(xy 313.393672 -348.204535) (xy 313.447654 -348.212297) (xy 313.499982 -348.227662) (xy 313.54959 -348.250318)
			(xy 313.595469 -348.279803) (xy 313.636686 -348.315517) (xy 313.672399 -348.356734) (xy 313.701884 -348.402613)
			(xy 313.72454 -348.452222) (xy 313.739904 -348.50455) (xy 313.747666 -348.558532) (xy 313.747666 -348.613068)
			(xy 315.230514 -348.613068) (xy 315.230514 -348.558532) (xy 315.238275 -348.50455) (xy 315.253639 -348.452222)
			(xy 315.276293 -348.402613) (xy 315.305777 -348.356732) (xy 315.341489 -348.315514) (xy 315.382703 -348.279798)
			(xy 315.428581 -348.250311) (xy 315.478188 -348.227652) (xy 315.530514 -348.212283) (xy 315.584496 -348.204517)
			(xy 315.611764 -348.204028) (xy 316.475364 -348.204028) (xy 316.502636 -348.204509) (xy 316.556625 -348.212267)
			(xy 316.608961 -348.22763) (xy 316.658577 -348.250284) (xy 316.704464 -348.27977) (xy 316.745688 -348.315487)
			(xy 316.781408 -348.356707) (xy 316.810898 -348.402591) (xy 316.833558 -348.452205) (xy 316.848926 -348.504539)
			(xy 316.856688 -348.558528) (xy 316.856688 -348.613072) (xy 316.856688 -348.613073) (xy 318.339392 -348.613073)
			(xy 318.339392 -348.558527) (xy 318.347155 -348.504537) (xy 318.362522 -348.452201) (xy 318.385182 -348.402585)
			(xy 318.414673 -348.356699) (xy 318.450394 -348.315477) (xy 318.491618 -348.279759) (xy 318.537506 -348.250271)
			(xy 318.587123 -348.227614) (xy 318.63946 -348.212249) (xy 318.693451 -348.20449) (xy 318.720724 -348.204028)
			(xy 319.584324 -348.204028) (xy 319.611592 -348.204536) (xy 319.665571 -348.2123) (xy 319.717896 -348.227667)
			(xy 319.767502 -348.250324) (xy 319.813379 -348.27981) (xy 319.854593 -348.315524) (xy 319.890304 -348.35674)
			(xy 319.919787 -348.402619) (xy 319.942441 -348.452226) (xy 319.957805 -348.504552) (xy 319.965566 -348.558532)
			(xy 319.965566 -348.613068) (xy 319.965566 -348.613069) (xy 321.448414 -348.613069) (xy 321.448414 -348.558531)
			(xy 321.456176 -348.504547) (xy 321.471541 -348.452217) (xy 321.494196 -348.402607) (xy 321.523682 -348.356726)
			(xy 321.559396 -348.315507) (xy 321.600613 -348.279791) (xy 321.646493 -348.250304) (xy 321.696102 -348.227646)
			(xy 321.748431 -348.212279) (xy 321.802415 -348.204516) (xy 321.829684 -348.204028) (xy 322.693284 -348.204028)
			(xy 322.720555 -348.20451) (xy 322.774542 -348.21227) (xy 322.826875 -348.227635) (xy 322.876489 -348.250291)
			(xy 322.922374 -348.279777) (xy 322.963595 -348.315494) (xy 322.999313 -348.356713) (xy 323.028801 -348.402597)
			(xy 323.051459 -348.45221) (xy 323.066826 -348.504542) (xy 323.074588 -348.558529) (xy 323.074588 -348.613071)
			(xy 323.074588 -348.613074) (xy 324.557292 -348.613074) (xy 324.557292 -348.558526) (xy 324.565055 -348.504534)
			(xy 324.580424 -348.452197) (xy 324.603085 -348.402579) (xy 324.632578 -348.356692) (xy 324.668301 -348.31547)
			(xy 324.709527 -348.279751) (xy 324.755418 -348.250264) (xy 324.805038 -348.227609) (xy 324.857377 -348.212246)
			(xy 324.91137 -348.204489) (xy 324.938644 -348.204028) (xy 325.802244 -348.204028) (xy 325.829511 -348.204537)
			(xy 325.883488 -348.212304) (xy 325.935811 -348.227673) (xy 325.985414 -348.250331) (xy 326.031288 -348.279817)
			(xy 326.0725 -348.315531) (xy 326.108209 -348.356747) (xy 326.13769 -348.402624) (xy 326.160343 -348.45223)
			(xy 326.175705 -348.504555) (xy 326.183466 -348.558533) (xy 326.183466 -348.613067) (xy 326.183465 -348.613072)
			(xy 327.666292 -348.613072) (xy 327.666292 -348.558528) (xy 327.674054 -348.504539) (xy 327.689421 -348.452205)
			(xy 327.712079 -348.40259) (xy 327.741568 -348.356705) (xy 327.777287 -348.315484) (xy 327.818509 -348.279766)
			(xy 327.864394 -348.250277) (xy 327.914009 -348.227619) (xy 327.966343 -348.212253) (xy 328.020332 -348.204491)
			(xy 328.047604 -348.204028) (xy 328.911204 -348.204028) (xy 328.938472 -348.204535) (xy 328.992454 -348.212297)
			(xy 329.044782 -348.227662) (xy 329.09439 -348.250318) (xy 329.140269 -348.279803) (xy 329.181486 -348.315517)
			(xy 329.217199 -348.356734) (xy 329.246684 -348.402613) (xy 329.26934 -348.452222) (xy 329.284704 -348.50455)
			(xy 329.292466 -348.558532) (xy 329.292466 -348.613068) (xy 330.775314 -348.613068) (xy 330.775314 -348.558532)
			(xy 330.783075 -348.50455) (xy 330.798439 -348.452222) (xy 330.821093 -348.402613) (xy 330.850577 -348.356732)
			(xy 330.886289 -348.315514) (xy 330.927503 -348.279798) (xy 330.973381 -348.250311) (xy 331.022988 -348.227652)
			(xy 331.075314 -348.212283) (xy 331.129296 -348.204517) (xy 331.156564 -348.204028) (xy 332.020164 -348.204028)
			(xy 332.047436 -348.204509) (xy 332.101425 -348.212267) (xy 332.153761 -348.22763) (xy 332.203377 -348.250284)
			(xy 332.249264 -348.27977) (xy 332.290488 -348.315487) (xy 332.326208 -348.356707) (xy 332.355698 -348.402591)
			(xy 332.378358 -348.452205) (xy 332.393726 -348.504539) (xy 332.401488 -348.558528) (xy 332.401488 -348.613072)
			(xy 332.401488 -348.613073) (xy 333.884192 -348.613073) (xy 333.884192 -348.558527) (xy 333.891955 -348.504537)
			(xy 333.907322 -348.452201) (xy 333.929982 -348.402585) (xy 333.959473 -348.356699) (xy 333.995194 -348.315477)
			(xy 334.036418 -348.279759) (xy 334.082306 -348.250271) (xy 334.131923 -348.227614) (xy 334.18426 -348.212249)
			(xy 334.238251 -348.20449) (xy 334.265524 -348.204028) (xy 335.129124 -348.204028) (xy 335.156392 -348.204536)
			(xy 335.210371 -348.2123) (xy 335.262696 -348.227667) (xy 335.312302 -348.250324) (xy 335.358179 -348.27981)
			(xy 335.399393 -348.315524) (xy 335.435104 -348.35674) (xy 335.464587 -348.402619) (xy 335.487241 -348.452226)
			(xy 335.502605 -348.504552) (xy 335.510366 -348.558532) (xy 335.510366 -348.613068) (xy 335.510366 -348.613069)
			(xy 336.993214 -348.613069) (xy 336.993214 -348.558531) (xy 337.000976 -348.504547) (xy 337.016341 -348.452217)
			(xy 337.038996 -348.402607) (xy 337.068482 -348.356726) (xy 337.104196 -348.315507) (xy 337.145413 -348.279791)
			(xy 337.191293 -348.250304) (xy 337.240902 -348.227646) (xy 337.293231 -348.212279) (xy 337.347215 -348.204516)
			(xy 337.374484 -348.204028) (xy 338.238084 -348.204028) (xy 338.265355 -348.20451) (xy 338.319342 -348.21227)
			(xy 338.371675 -348.227635) (xy 338.421289 -348.250291) (xy 338.467174 -348.279777) (xy 338.508395 -348.315494)
			(xy 338.544113 -348.356713) (xy 338.573601 -348.402597) (xy 338.596259 -348.45221) (xy 338.611626 -348.504542)
			(xy 338.619388 -348.558529) (xy 338.619388 -348.613071) (xy 338.619388 -348.613074) (xy 340.102092 -348.613074)
			(xy 340.102092 -348.558526) (xy 340.109855 -348.504534) (xy 340.125224 -348.452197) (xy 340.147885 -348.402579)
			(xy 340.177378 -348.356692) (xy 340.213101 -348.31547) (xy 340.254327 -348.279751) (xy 340.300218 -348.250264)
			(xy 340.349838 -348.227609) (xy 340.402177 -348.212246) (xy 340.45617 -348.204489) (xy 340.483444 -348.204028)
			(xy 341.347044 -348.204028) (xy 341.374311 -348.204537) (xy 341.428288 -348.212304) (xy 341.480611 -348.227673)
			(xy 341.530214 -348.250331) (xy 341.576088 -348.279817) (xy 341.6173 -348.315531) (xy 341.653009 -348.356747)
			(xy 341.68249 -348.402624) (xy 341.705143 -348.45223) (xy 341.720505 -348.504555) (xy 341.728266 -348.558533)
			(xy 341.728266 -348.613067) (xy 341.728265 -348.613072) (xy 343.211092 -348.613072) (xy 343.211092 -348.558528)
			(xy 343.218854 -348.504539) (xy 343.234221 -348.452205) (xy 343.256879 -348.40259) (xy 343.286368 -348.356705)
			(xy 343.322087 -348.315484) (xy 343.363309 -348.279766) (xy 343.409194 -348.250277) (xy 343.458809 -348.227619)
			(xy 343.511143 -348.212253) (xy 343.565132 -348.204491) (xy 343.592404 -348.204028) (xy 344.456004 -348.204028)
			(xy 344.483272 -348.204535) (xy 344.537254 -348.212297) (xy 344.589582 -348.227662) (xy 344.63919 -348.250318)
			(xy 344.685069 -348.279803) (xy 344.726286 -348.315517) (xy 344.761999 -348.356734) (xy 344.791484 -348.402613)
			(xy 344.81414 -348.452222) (xy 344.829504 -348.50455) (xy 344.837266 -348.558532) (xy 344.837266 -348.613068)
			(xy 344.837266 -348.613069) (xy 370.806714 -348.613069) (xy 370.806714 -348.558531) (xy 370.814476 -348.504548)
			(xy 370.82984 -348.452218) (xy 370.852496 -348.402608) (xy 370.881981 -348.356727) (xy 370.917695 -348.315509)
			(xy 370.958911 -348.279793) (xy 371.004791 -348.250305) (xy 371.054399 -348.227647) (xy 371.106728 -348.21228)
			(xy 371.160711 -348.204516) (xy 371.18798 -348.204028) (xy 372.05158 -348.204028) (xy 372.078851 -348.20451)
			(xy 372.132839 -348.21227) (xy 372.185173 -348.227634) (xy 372.234787 -348.25029) (xy 372.280672 -348.279776)
			(xy 372.321893 -348.315493) (xy 372.357612 -348.356712) (xy 372.387101 -348.402595) (xy 372.409759 -348.452209)
			(xy 372.425126 -348.504542) (xy 372.432888 -348.558529) (xy 372.432888 -348.613071) (xy 372.432888 -348.613074)
			(xy 373.915592 -348.613074) (xy 373.915592 -348.558526) (xy 373.923355 -348.504535) (xy 373.938724 -348.452197)
			(xy 373.961385 -348.40258) (xy 373.990877 -348.356694) (xy 374.0266 -348.315471) (xy 374.067826 -348.279753)
			(xy 374.113715 -348.250266) (xy 374.163335 -348.22761) (xy 374.215674 -348.212246) (xy 374.269666 -348.204489)
			(xy 374.29694 -348.204028) (xy 375.16054 -348.204028) (xy 375.187807 -348.204537) (xy 375.241785 -348.212303)
			(xy 375.294108 -348.227672) (xy 375.343712 -348.25033) (xy 375.389587 -348.279816) (xy 375.430798 -348.31553)
			(xy 375.466508 -348.356746) (xy 375.49599 -348.402623) (xy 375.518642 -348.45223) (xy 375.534005 -348.504554)
			(xy 375.541766 -348.558533) (xy 375.541766 -348.613067) (xy 375.541766 -348.61307) (xy 377.024614 -348.61307)
			(xy 377.024614 -348.55853) (xy 377.032376 -348.504545) (xy 377.047742 -348.452214) (xy 377.070399 -348.402603)
			(xy 377.099886 -348.35672) (xy 377.135602 -348.315502) (xy 377.17682 -348.279786) (xy 377.222703 -348.250299)
			(xy 377.272314 -348.227642) (xy 377.324645 -348.212276) (xy 377.37863 -348.204514) (xy 377.4059 -348.204028)
			(xy 378.2695 -348.204028) (xy 378.296769 -348.204534) (xy 378.350751 -348.212296) (xy 378.403079 -348.227661)
			(xy 378.452688 -348.250316) (xy 378.498568 -348.279802) (xy 378.539784 -348.315516) (xy 378.575498 -348.356732)
			(xy 378.604984 -348.402612) (xy 378.627639 -348.452221) (xy 378.643004 -348.504549) (xy 378.650766 -348.558531)
			(xy 378.650766 -348.613068) (xy 380.133614 -348.613068) (xy 380.133614 -348.558532) (xy 380.141375 -348.50455)
			(xy 380.156739 -348.452223) (xy 380.179393 -348.402614) (xy 380.208876 -348.356734) (xy 380.244588 -348.315516)
			(xy 380.285801 -348.2798) (xy 380.331679 -348.250312) (xy 380.381285 -348.227653) (xy 380.433611 -348.212284)
			(xy 380.487592 -348.204517) (xy 380.51486 -348.204028) (xy 381.37846 -348.204028) (xy 381.405732 -348.204509)
			(xy 381.459722 -348.212266) (xy 381.512058 -348.227628) (xy 381.561675 -348.250283) (xy 381.607562 -348.279769)
			(xy 381.648786 -348.315485) (xy 381.684507 -348.356706) (xy 381.713998 -348.40259) (xy 381.736658 -348.452204)
			(xy 381.752025 -348.504539) (xy 381.759788 -348.558528) (xy 381.759788 -348.613072) (xy 381.759788 -348.613073)
			(xy 383.242492 -348.613073) (xy 383.242492 -348.558527) (xy 383.250254 -348.504537) (xy 383.265622 -348.452202)
			(xy 383.288282 -348.402586) (xy 383.317772 -348.3567) (xy 383.353493 -348.315478) (xy 383.394716 -348.27976)
			(xy 383.440603 -348.250272) (xy 383.49022 -348.227615) (xy 383.542557 -348.21225) (xy 383.596547 -348.20449)
			(xy 383.62382 -348.204028) (xy 384.48742 -348.204028) (xy 384.514688 -348.204536) (xy 384.568668 -348.2123)
			(xy 384.620994 -348.227666) (xy 384.6706 -348.250323) (xy 384.716477 -348.279809) (xy 384.757691 -348.315523)
			(xy 384.793403 -348.356739) (xy 384.822887 -348.402618) (xy 384.845541 -348.452225) (xy 384.860905 -348.504552)
			(xy 384.868666 -348.558532) (xy 384.868666 -348.613068) (xy 384.868666 -348.613069) (xy 386.351514 -348.613069)
			(xy 386.351514 -348.558531) (xy 386.359276 -348.504548) (xy 386.37464 -348.452218) (xy 386.397296 -348.402608)
			(xy 386.426781 -348.356727) (xy 386.462495 -348.315509) (xy 386.503711 -348.279793) (xy 386.549591 -348.250305)
			(xy 386.599199 -348.227647) (xy 386.651528 -348.21228) (xy 386.705511 -348.204516) (xy 386.73278 -348.204028)
			(xy 387.59638 -348.204028) (xy 387.623651 -348.20451) (xy 387.677639 -348.21227) (xy 387.729973 -348.227634)
			(xy 387.779587 -348.25029) (xy 387.825472 -348.279776) (xy 387.866693 -348.315493) (xy 387.902412 -348.356712)
			(xy 387.931901 -348.402595) (xy 387.954559 -348.452209) (xy 387.969926 -348.504542) (xy 387.977688 -348.558529)
			(xy 387.977688 -348.613071) (xy 387.977688 -348.613074) (xy 389.460392 -348.613074) (xy 389.460392 -348.558526)
			(xy 389.468155 -348.504535) (xy 389.483524 -348.452197) (xy 389.506185 -348.40258) (xy 389.535677 -348.356694)
			(xy 389.5714 -348.315471) (xy 389.612626 -348.279753) (xy 389.658515 -348.250266) (xy 389.708135 -348.22761)
			(xy 389.760474 -348.212246) (xy 389.814466 -348.204489) (xy 389.84174 -348.204028) (xy 390.70534 -348.204028)
			(xy 390.732607 -348.204537) (xy 390.786585 -348.212303) (xy 390.838908 -348.227672) (xy 390.888512 -348.25033)
			(xy 390.934387 -348.279816) (xy 390.975598 -348.31553) (xy 391.011308 -348.356746) (xy 391.04079 -348.402623)
			(xy 391.063442 -348.45223) (xy 391.078805 -348.504554) (xy 391.086566 -348.558533) (xy 391.086566 -348.613067)
			(xy 391.086566 -348.61307) (xy 392.569414 -348.61307) (xy 392.569414 -348.55853) (xy 392.577176 -348.504545)
			(xy 392.592542 -348.452214) (xy 392.615199 -348.402603) (xy 392.644686 -348.35672) (xy 392.680402 -348.315502)
			(xy 392.72162 -348.279786) (xy 392.767503 -348.250299) (xy 392.817114 -348.227642) (xy 392.869445 -348.212276)
			(xy 392.92343 -348.204514) (xy 392.9507 -348.204028) (xy 393.8143 -348.204028) (xy 393.841569 -348.204534)
			(xy 393.895551 -348.212296) (xy 393.947879 -348.227661) (xy 393.997488 -348.250316) (xy 394.043368 -348.279802)
			(xy 394.084584 -348.315516) (xy 394.120298 -348.356732) (xy 394.149784 -348.402612) (xy 394.172439 -348.452221)
			(xy 394.187804 -348.504549) (xy 394.195566 -348.558531) (xy 394.195566 -348.613068) (xy 395.678414 -348.613068)
			(xy 395.678414 -348.558532) (xy 395.686175 -348.50455) (xy 395.701539 -348.452223) (xy 395.724193 -348.402614)
			(xy 395.753676 -348.356734) (xy 395.789388 -348.315516) (xy 395.830601 -348.2798) (xy 395.876479 -348.250312)
			(xy 395.926085 -348.227653) (xy 395.978411 -348.212284) (xy 396.032392 -348.204517) (xy 396.05966 -348.204028)
			(xy 396.92326 -348.204028) (xy 396.950532 -348.204509) (xy 397.004522 -348.212266) (xy 397.056858 -348.227628)
			(xy 397.106475 -348.250283) (xy 397.152362 -348.279769) (xy 397.193586 -348.315485) (xy 397.229307 -348.356706)
			(xy 397.258798 -348.40259) (xy 397.281458 -348.452204) (xy 397.296825 -348.504539) (xy 397.304588 -348.558528)
			(xy 397.304588 -348.613072) (xy 397.304588 -348.613073) (xy 398.787292 -348.613073) (xy 398.787292 -348.558527)
			(xy 398.795054 -348.504537) (xy 398.810422 -348.452202) (xy 398.833082 -348.402586) (xy 398.862572 -348.3567)
			(xy 398.898293 -348.315478) (xy 398.939516 -348.27976) (xy 398.985403 -348.250272) (xy 399.03502 -348.227615)
			(xy 399.087357 -348.21225) (xy 399.141347 -348.20449) (xy 399.16862 -348.204028) (xy 400.03222 -348.204028)
			(xy 400.059488 -348.204536) (xy 400.113468 -348.2123) (xy 400.165794 -348.227666) (xy 400.2154 -348.250323)
			(xy 400.261277 -348.279809) (xy 400.302491 -348.315523) (xy 400.338203 -348.356739) (xy 400.367687 -348.402618)
			(xy 400.390341 -348.452225) (xy 400.405705 -348.504552) (xy 400.413466 -348.558532) (xy 400.413466 -348.613068)
			(xy 400.413466 -348.613069) (xy 401.896314 -348.613069) (xy 401.896314 -348.558531) (xy 401.904076 -348.504548)
			(xy 401.91944 -348.452218) (xy 401.942096 -348.402608) (xy 401.971581 -348.356727) (xy 402.007295 -348.315509)
			(xy 402.048511 -348.279793) (xy 402.094391 -348.250305) (xy 402.143999 -348.227647) (xy 402.196328 -348.21228)
			(xy 402.250311 -348.204516) (xy 402.27758 -348.204028) (xy 403.14118 -348.204028) (xy 403.168451 -348.20451)
			(xy 403.222439 -348.21227) (xy 403.274773 -348.227634) (xy 403.324387 -348.25029) (xy 403.370272 -348.279776)
			(xy 403.411493 -348.315493) (xy 403.447212 -348.356712) (xy 403.476701 -348.402595) (xy 403.499359 -348.452209)
			(xy 403.514726 -348.504542) (xy 403.522488 -348.558529) (xy 403.522488 -348.61307) (xy 408.913814 -348.61307)
			(xy 408.913814 -348.55853) (xy 408.921576 -348.504546) (xy 408.936941 -348.452216) (xy 408.959598 -348.402605)
			(xy 408.989084 -348.356723) (xy 409.024799 -348.315505) (xy 409.066017 -348.279788) (xy 409.111898 -348.250301)
			(xy 409.161508 -348.227644) (xy 409.213838 -348.212278) (xy 409.267822 -348.204515) (xy 409.295092 -348.204028)
			(xy 410.158692 -348.204028) (xy 410.185963 -348.204511) (xy 410.239949 -348.212272) (xy 410.292281 -348.227637)
			(xy 410.341894 -348.250294) (xy 410.387778 -348.27978) (xy 410.428998 -348.315497) (xy 410.464715 -348.356716)
			(xy 410.494203 -348.402599) (xy 410.51686 -348.452211) (xy 410.532226 -348.504543) (xy 410.539989 -348.558529)
			(xy 410.539989 -348.613068) (xy 412.022814 -348.613068) (xy 412.022814 -348.558532) (xy 412.030575 -348.504551)
			(xy 412.045938 -348.452224) (xy 412.068592 -348.402616) (xy 412.098074 -348.356736) (xy 412.133785 -348.315519)
			(xy 412.174998 -348.279803) (xy 412.220874 -348.250315) (xy 412.270479 -348.227655) (xy 412.322804 -348.212285)
			(xy 412.376784 -348.204518) (xy 412.404052 -348.204028) (xy 413.267652 -348.204028) (xy 413.294925 -348.204508)
			(xy 413.348915 -348.212265) (xy 413.401252 -348.227626) (xy 413.45087 -348.250281) (xy 413.496759 -348.279766)
			(xy 413.537983 -348.315483) (xy 413.573705 -348.356703) (xy 413.603196 -348.402588) (xy 413.625857 -348.452203)
			(xy 413.641225 -348.504538) (xy 413.648988 -348.558528) (xy 413.648988 -348.613072) (xy 415.131692 -348.613072)
			(xy 415.131692 -348.558528) (xy 415.139454 -348.504538) (xy 415.154821 -348.452203) (xy 415.177481 -348.402588)
			(xy 415.20697 -348.356703) (xy 415.24269 -348.315481) (xy 415.283912 -348.279763) (xy 415.329799 -348.250275)
			(xy 415.379415 -348.227617) (xy 415.43175 -348.212252) (xy 415.48574 -348.204491) (xy 415.513012 -348.204028)
			(xy 416.376612 -348.204028) (xy 416.40388 -348.204535) (xy 416.457861 -348.212298) (xy 416.510188 -348.227664)
			(xy 416.559795 -348.25032) (xy 416.605673 -348.279806) (xy 416.646888 -348.31552) (xy 416.682601 -348.356736)
			(xy 416.712085 -348.402615) (xy 416.73474 -348.452224) (xy 416.750104 -348.504551) (xy 416.757866 -348.558532)
			(xy 416.757866 -348.613068) (xy 416.757866 -348.613069) (xy 418.240714 -348.613069) (xy 418.240714 -348.558531)
			(xy 418.248476 -348.504549) (xy 418.26384 -348.45222) (xy 418.286495 -348.40261) (xy 418.315979 -348.35673)
			(xy 418.351692 -348.315512) (xy 418.392907 -348.279795) (xy 418.438786 -348.250308) (xy 418.488394 -348.22765)
			(xy 418.540721 -348.212281) (xy 418.594703 -348.204516) (xy 418.621972 -348.204028) (xy 419.485572 -348.204028)
			(xy 419.512844 -348.20451) (xy 419.566832 -348.212268) (xy 419.619167 -348.227632) (xy 419.668782 -348.250287)
			(xy 419.714668 -348.279773) (xy 419.75589 -348.31549) (xy 419.79161 -348.356709) (xy 419.821099 -348.402593)
			(xy 419.843759 -348.452207) (xy 419.859126 -348.504541) (xy 419.866888 -348.558528) (xy 419.866888 -348.613072)
			(xy 419.866888 -348.613073) (xy 421.349592 -348.613073) (xy 421.349592 -348.558527) (xy 421.357355 -348.504536)
			(xy 421.372723 -348.452199) (xy 421.395384 -348.402583) (xy 421.424875 -348.356696) (xy 421.460597 -348.315474)
			(xy 421.501822 -348.279756) (xy 421.547711 -348.250268) (xy 421.597329 -348.227612) (xy 421.649667 -348.212248)
			(xy 421.703659 -348.204489) (xy 421.730932 -348.204028) (xy 422.594532 -348.204028) (xy 422.621799 -348.204537)
			(xy 422.675778 -348.212302) (xy 422.728102 -348.227669) (xy 422.777707 -348.250327) (xy 422.823583 -348.279813)
			(xy 422.864795 -348.315527) (xy 422.900506 -348.356743) (xy 422.929988 -348.402621) (xy 422.952642 -348.452228)
			(xy 422.968005 -348.504553) (xy 422.975766 -348.558533) (xy 422.975766 -348.613067) (xy 422.975766 -348.61307)
			(xy 424.458614 -348.61307) (xy 424.458614 -348.55853) (xy 424.466376 -348.504546) (xy 424.481741 -348.452216)
			(xy 424.504398 -348.402605) (xy 424.533884 -348.356723) (xy 424.569599 -348.315505) (xy 424.610817 -348.279788)
			(xy 424.656698 -348.250301) (xy 424.706308 -348.227644) (xy 424.758638 -348.212278) (xy 424.812622 -348.204515)
			(xy 424.839892 -348.204028) (xy 425.703492 -348.204028) (xy 425.730763 -348.204511) (xy 425.784749 -348.212272)
			(xy 425.837081 -348.227637) (xy 425.886694 -348.250294) (xy 425.932578 -348.27978) (xy 425.973798 -348.315497)
			(xy 426.009515 -348.356716) (xy 426.039003 -348.402599) (xy 426.06166 -348.452211) (xy 426.077026 -348.504543)
			(xy 426.084789 -348.558529) (xy 426.084789 -348.613068) (xy 427.567614 -348.613068) (xy 427.567614 -348.558532)
			(xy 427.575375 -348.504551) (xy 427.590738 -348.452224) (xy 427.613392 -348.402616) (xy 427.642874 -348.356736)
			(xy 427.678585 -348.315519) (xy 427.719798 -348.279803) (xy 427.765674 -348.250315) (xy 427.815279 -348.227655)
			(xy 427.867604 -348.212285) (xy 427.921584 -348.204518) (xy 427.948852 -348.204028) (xy 428.812452 -348.204028)
			(xy 428.839725 -348.204508) (xy 428.893715 -348.212265) (xy 428.946052 -348.227626) (xy 428.99567 -348.250281)
			(xy 429.041559 -348.279766) (xy 429.082783 -348.315483) (xy 429.118505 -348.356703) (xy 429.147996 -348.402588)
			(xy 429.170657 -348.452203) (xy 429.186025 -348.504538) (xy 429.193788 -348.558528) (xy 429.193788 -348.613072)
			(xy 430.676492 -348.613072) (xy 430.676492 -348.558528) (xy 430.684254 -348.504538) (xy 430.699621 -348.452203)
			(xy 430.722281 -348.402588) (xy 430.75177 -348.356703) (xy 430.78749 -348.315481) (xy 430.828712 -348.279763)
			(xy 430.874599 -348.250275) (xy 430.924215 -348.227617) (xy 430.97655 -348.212252) (xy 431.03054 -348.204491)
			(xy 431.057812 -348.204028) (xy 431.921412 -348.204028) (xy 431.94868 -348.204535) (xy 432.002661 -348.212298)
			(xy 432.054988 -348.227664) (xy 432.104595 -348.25032) (xy 432.150473 -348.279806) (xy 432.191688 -348.31552)
			(xy 432.227401 -348.356736) (xy 432.256885 -348.402615) (xy 432.27954 -348.452224) (xy 432.294904 -348.504551)
			(xy 432.302666 -348.558532) (xy 432.302666 -348.613068) (xy 432.302666 -348.613069) (xy 433.785514 -348.613069)
			(xy 433.785514 -348.558531) (xy 433.793276 -348.504549) (xy 433.80864 -348.45222) (xy 433.831295 -348.40261)
			(xy 433.860779 -348.35673) (xy 433.896492 -348.315512) (xy 433.937707 -348.279795) (xy 433.983586 -348.250308)
			(xy 434.033194 -348.22765) (xy 434.085521 -348.212281) (xy 434.139503 -348.204516) (xy 434.166772 -348.204028)
			(xy 435.030372 -348.204028) (xy 435.057644 -348.20451) (xy 435.111632 -348.212268) (xy 435.163967 -348.227632)
			(xy 435.213582 -348.250287) (xy 435.259468 -348.279773) (xy 435.30069 -348.31549) (xy 435.33641 -348.356709)
			(xy 435.365899 -348.402593) (xy 435.388559 -348.452207) (xy 435.403926 -348.504541) (xy 435.411688 -348.558528)
			(xy 435.411688 -348.613072) (xy 435.411688 -348.613073) (xy 436.894392 -348.613073) (xy 436.894392 -348.558527)
			(xy 436.902155 -348.504536) (xy 436.917523 -348.452199) (xy 436.940184 -348.402583) (xy 436.969675 -348.356696)
			(xy 437.005397 -348.315474) (xy 437.046622 -348.279756) (xy 437.092511 -348.250268) (xy 437.142129 -348.227612)
			(xy 437.194467 -348.212248) (xy 437.248459 -348.204489) (xy 437.275732 -348.204028) (xy 438.139332 -348.204028)
			(xy 438.166599 -348.204537) (xy 438.220578 -348.212302) (xy 438.272902 -348.227669) (xy 438.322507 -348.250327)
			(xy 438.368383 -348.279813) (xy 438.409595 -348.315527) (xy 438.445306 -348.356743) (xy 438.474788 -348.402621)
			(xy 438.497442 -348.452228) (xy 438.512805 -348.504553) (xy 438.520566 -348.558533) (xy 438.520566 -348.613067)
			(xy 438.520566 -348.61307) (xy 440.003414 -348.61307) (xy 440.003414 -348.55853) (xy 440.011176 -348.504546)
			(xy 440.026541 -348.452216) (xy 440.049198 -348.402605) (xy 440.078684 -348.356723) (xy 440.114399 -348.315505)
			(xy 440.155617 -348.279788) (xy 440.201498 -348.250301) (xy 440.251108 -348.227644) (xy 440.303438 -348.212278)
			(xy 440.357422 -348.204515) (xy 440.384692 -348.204028) (xy 441.248292 -348.204028) (xy 441.275563 -348.204511)
			(xy 441.329549 -348.212272) (xy 441.381881 -348.227637) (xy 441.431494 -348.250294) (xy 441.477378 -348.27978)
			(xy 441.518598 -348.315497) (xy 441.554315 -348.356716) (xy 441.583803 -348.402599) (xy 441.60646 -348.452211)
			(xy 441.621826 -348.504543) (xy 441.629589 -348.558529) (xy 441.629589 -348.613071) (xy 441.621826 -348.667057)
			(xy 441.60646 -348.719389) (xy 441.583803 -348.769001) (xy 441.554315 -348.814884) (xy 441.518598 -348.856103)
			(xy 441.477378 -348.89182) (xy 441.431494 -348.921306) (xy 441.381881 -348.943963) (xy 441.329549 -348.959328)
			(xy 441.275563 -348.967089) (xy 441.248292 -348.967552) (xy 440.384692 -348.967552) (xy 440.357422 -348.967085)
			(xy 440.303438 -348.959322) (xy 440.251108 -348.943956) (xy 440.201498 -348.921299) (xy 440.155617 -348.891812)
			(xy 440.114399 -348.856095) (xy 440.078684 -348.814877) (xy 440.049198 -348.768995) (xy 440.026541 -348.719384)
			(xy 440.011176 -348.667054) (xy 440.003414 -348.61307) (xy 438.520566 -348.61307) (xy 438.512805 -348.667047)
			(xy 438.497442 -348.719372) (xy 438.474788 -348.768979) (xy 438.445306 -348.814857) (xy 438.409595 -348.856073)
			(xy 438.368383 -348.891787) (xy 438.322507 -348.921273) (xy 438.272902 -348.943931) (xy 438.220578 -348.959298)
			(xy 438.166599 -348.967063) (xy 438.139332 -348.967552) (xy 437.275732 -348.967552) (xy 437.248459 -348.967111)
			(xy 437.194467 -348.959352) (xy 437.142129 -348.943988) (xy 437.092511 -348.921332) (xy 437.046622 -348.891844)
			(xy 437.005397 -348.856126) (xy 436.969675 -348.814904) (xy 436.940184 -348.769017) (xy 436.917523 -348.719401)
			(xy 436.902155 -348.667064) (xy 436.894392 -348.613073) (xy 435.411688 -348.613073) (xy 435.403926 -348.667059)
			(xy 435.388559 -348.719393) (xy 435.365899 -348.769007) (xy 435.33641 -348.814891) (xy 435.30069 -348.85611)
			(xy 435.259468 -348.891827) (xy 435.213582 -348.921313) (xy 435.163967 -348.943968) (xy 435.111632 -348.959332)
			(xy 435.057644 -348.96709) (xy 435.030372 -348.967552) (xy 434.166772 -348.967552) (xy 434.139503 -348.967084)
			(xy 434.085521 -348.959319) (xy 434.033194 -348.94395) (xy 433.983586 -348.921292) (xy 433.937707 -348.891805)
			(xy 433.896492 -348.856088) (xy 433.860779 -348.81487) (xy 433.831295 -348.76899) (xy 433.80864 -348.71938)
			(xy 433.793276 -348.667051) (xy 433.785514 -348.613069) (xy 432.302666 -348.613069) (xy 432.294904 -348.667049)
			(xy 432.27954 -348.719376) (xy 432.256885 -348.768985) (xy 432.227401 -348.814864) (xy 432.191688 -348.85608)
			(xy 432.150473 -348.891794) (xy 432.104595 -348.92128) (xy 432.054988 -348.943936) (xy 432.002661 -348.959302)
			(xy 431.94868 -348.967065) (xy 431.921412 -348.967552) (xy 431.057812 -348.967552) (xy 431.03054 -348.967109)
			(xy 430.97655 -348.959348) (xy 430.924215 -348.943983) (xy 430.874599 -348.921325) (xy 430.828712 -348.891837)
			(xy 430.78749 -348.856119) (xy 430.75177 -348.814897) (xy 430.722281 -348.769012) (xy 430.699621 -348.719397)
			(xy 430.684254 -348.667062) (xy 430.676492 -348.613072) (xy 429.193788 -348.613072) (xy 429.186025 -348.667062)
			(xy 429.170657 -348.719397) (xy 429.147996 -348.769012) (xy 429.118505 -348.814897) (xy 429.082783 -348.856117)
			(xy 429.041559 -348.891834) (xy 428.99567 -348.921319) (xy 428.946052 -348.943974) (xy 428.893715 -348.959335)
			(xy 428.839725 -348.967092) (xy 428.812452 -348.967552) (xy 427.948852 -348.967552) (xy 427.921584 -348.967082)
			(xy 427.867604 -348.959315) (xy 427.815279 -348.943945) (xy 427.765674 -348.921285) (xy 427.719798 -348.891797)
			(xy 427.678585 -348.856081) (xy 427.642874 -348.814864) (xy 427.613392 -348.768984) (xy 427.590738 -348.719376)
			(xy 427.575375 -348.667049) (xy 427.567614 -348.613068) (xy 426.084789 -348.613068) (xy 426.084789 -348.613071)
			(xy 426.077026 -348.667057) (xy 426.06166 -348.719389) (xy 426.039003 -348.769001) (xy 426.009515 -348.814884)
			(xy 425.973798 -348.856103) (xy 425.932578 -348.89182) (xy 425.886694 -348.921306) (xy 425.837081 -348.943963)
			(xy 425.784749 -348.959328) (xy 425.730763 -348.967089) (xy 425.703492 -348.967552) (xy 424.839892 -348.967552)
			(xy 424.812622 -348.967085) (xy 424.758638 -348.959322) (xy 424.706308 -348.943956) (xy 424.656698 -348.921299)
			(xy 424.610817 -348.891812) (xy 424.569599 -348.856095) (xy 424.533884 -348.814877) (xy 424.504398 -348.768995)
			(xy 424.481741 -348.719384) (xy 424.466376 -348.667054) (xy 424.458614 -348.61307) (xy 422.975766 -348.61307)
			(xy 422.968005 -348.667047) (xy 422.952642 -348.719372) (xy 422.929988 -348.768979) (xy 422.900506 -348.814857)
			(xy 422.864795 -348.856073) (xy 422.823583 -348.891787) (xy 422.777707 -348.921273) (xy 422.728102 -348.943931)
			(xy 422.675778 -348.959298) (xy 422.621799 -348.967063) (xy 422.594532 -348.967552) (xy 421.730932 -348.967552)
			(xy 421.703659 -348.967111) (xy 421.649667 -348.959352) (xy 421.597329 -348.943988) (xy 421.547711 -348.921332)
			(xy 421.501822 -348.891844) (xy 421.460597 -348.856126) (xy 421.424875 -348.814904) (xy 421.395384 -348.769017)
			(xy 421.372723 -348.719401) (xy 421.357355 -348.667064) (xy 421.349592 -348.613073) (xy 419.866888 -348.613073)
			(xy 419.859126 -348.667059) (xy 419.843759 -348.719393) (xy 419.821099 -348.769007) (xy 419.79161 -348.814891)
			(xy 419.75589 -348.85611) (xy 419.714668 -348.891827) (xy 419.668782 -348.921313) (xy 419.619167 -348.943968)
			(xy 419.566832 -348.959332) (xy 419.512844 -348.96709) (xy 419.485572 -348.967552) (xy 418.621972 -348.967552)
			(xy 418.594703 -348.967084) (xy 418.540721 -348.959319) (xy 418.488394 -348.94395) (xy 418.438786 -348.921292)
			(xy 418.392907 -348.891805) (xy 418.351692 -348.856088) (xy 418.315979 -348.81487) (xy 418.286495 -348.76899)
			(xy 418.26384 -348.71938) (xy 418.248476 -348.667051) (xy 418.240714 -348.613069) (xy 416.757866 -348.613069)
			(xy 416.750104 -348.667049) (xy 416.73474 -348.719376) (xy 416.712085 -348.768985) (xy 416.682601 -348.814864)
			(xy 416.646888 -348.85608) (xy 416.605673 -348.891794) (xy 416.559795 -348.92128) (xy 416.510188 -348.943936)
			(xy 416.457861 -348.959302) (xy 416.40388 -348.967065) (xy 416.376612 -348.967552) (xy 415.513012 -348.967552)
			(xy 415.48574 -348.967109) (xy 415.43175 -348.959348) (xy 415.379415 -348.943983) (xy 415.329799 -348.921325)
			(xy 415.283912 -348.891837) (xy 415.24269 -348.856119) (xy 415.20697 -348.814897) (xy 415.177481 -348.769012)
			(xy 415.154821 -348.719397) (xy 415.139454 -348.667062) (xy 415.131692 -348.613072) (xy 413.648988 -348.613072)
			(xy 413.641225 -348.667062) (xy 413.625857 -348.719397) (xy 413.603196 -348.769012) (xy 413.573705 -348.814897)
			(xy 413.537983 -348.856117) (xy 413.496759 -348.891834) (xy 413.45087 -348.921319) (xy 413.401252 -348.943974)
			(xy 413.348915 -348.959335) (xy 413.294925 -348.967092) (xy 413.267652 -348.967552) (xy 412.404052 -348.967552)
			(xy 412.376784 -348.967082) (xy 412.322804 -348.959315) (xy 412.270479 -348.943945) (xy 412.220874 -348.921285)
			(xy 412.174998 -348.891797) (xy 412.133785 -348.856081) (xy 412.098074 -348.814864) (xy 412.068592 -348.768984)
			(xy 412.045938 -348.719376) (xy 412.030575 -348.667049) (xy 412.022814 -348.613068) (xy 410.539989 -348.613068)
			(xy 410.539989 -348.613071) (xy 410.532226 -348.667057) (xy 410.51686 -348.719389) (xy 410.494203 -348.769001)
			(xy 410.464715 -348.814884) (xy 410.428998 -348.856103) (xy 410.387778 -348.89182) (xy 410.341894 -348.921306)
			(xy 410.292281 -348.943963) (xy 410.239949 -348.959328) (xy 410.185963 -348.967089) (xy 410.158692 -348.967552)
			(xy 409.295092 -348.967552) (xy 409.267822 -348.967085) (xy 409.213838 -348.959322) (xy 409.161508 -348.943956)
			(xy 409.111898 -348.921299) (xy 409.066017 -348.891812) (xy 409.024799 -348.856095) (xy 408.989084 -348.814877)
			(xy 408.959598 -348.768995) (xy 408.936941 -348.719384) (xy 408.921576 -348.667054) (xy 408.913814 -348.61307)
			(xy 403.522488 -348.61307) (xy 403.522488 -348.613071) (xy 403.514726 -348.667058) (xy 403.499359 -348.719391)
			(xy 403.476701 -348.769005) (xy 403.447212 -348.814888) (xy 403.411493 -348.856107) (xy 403.370272 -348.891824)
			(xy 403.324387 -348.92131) (xy 403.274773 -348.943966) (xy 403.222439 -348.95933) (xy 403.168451 -348.96709)
			(xy 403.14118 -348.967552) (xy 402.27758 -348.967552) (xy 402.250311 -348.967084) (xy 402.196328 -348.95932)
			(xy 402.143999 -348.943953) (xy 402.094391 -348.921295) (xy 402.048511 -348.891807) (xy 402.007295 -348.856091)
			(xy 401.971581 -348.814873) (xy 401.942096 -348.768992) (xy 401.91944 -348.719382) (xy 401.904076 -348.667052)
			(xy 401.896314 -348.613069) (xy 400.413466 -348.613069) (xy 400.405705 -348.667048) (xy 400.390341 -348.719375)
			(xy 400.367687 -348.768982) (xy 400.338203 -348.814861) (xy 400.302491 -348.856077) (xy 400.261277 -348.891791)
			(xy 400.2154 -348.921277) (xy 400.165794 -348.943934) (xy 400.113468 -348.9593) (xy 400.059488 -348.967064)
			(xy 400.03222 -348.967552) (xy 399.16862 -348.967552) (xy 399.141347 -348.96711) (xy 399.087357 -348.95935)
			(xy 399.03502 -348.943985) (xy 398.985403 -348.921328) (xy 398.939516 -348.89184) (xy 398.898293 -348.856122)
			(xy 398.862572 -348.8149) (xy 398.833082 -348.769014) (xy 398.810422 -348.719398) (xy 398.795054 -348.667063)
			(xy 398.787292 -348.613073) (xy 397.304588 -348.613073) (xy 397.296825 -348.667061) (xy 397.281458 -348.719396)
			(xy 397.258798 -348.76901) (xy 397.229307 -348.814894) (xy 397.193586 -348.856115) (xy 397.152362 -348.891831)
			(xy 397.106475 -348.921317) (xy 397.056858 -348.943972) (xy 397.004522 -348.959334) (xy 396.950532 -348.967091)
			(xy 396.92326 -348.967552) (xy 396.05966 -348.967552) (xy 396.032392 -348.967083) (xy 395.978411 -348.959316)
			(xy 395.926085 -348.943947) (xy 395.876479 -348.921288) (xy 395.830601 -348.8918) (xy 395.789388 -348.856084)
			(xy 395.753676 -348.814866) (xy 395.724193 -348.768986) (xy 395.701539 -348.719377) (xy 395.686175 -348.66705)
			(xy 395.678414 -348.613068) (xy 394.195566 -348.613068) (xy 394.195566 -348.613069) (xy 394.187804 -348.667051)
			(xy 394.172439 -348.719379) (xy 394.149784 -348.768988) (xy 394.120298 -348.814868) (xy 394.084584 -348.856084)
			(xy 394.043368 -348.891798) (xy 393.997488 -348.921284) (xy 393.947879 -348.943939) (xy 393.895551 -348.959304)
			(xy 393.841569 -348.967066) (xy 393.8143 -348.967552) (xy 392.9507 -348.967552) (xy 392.92343 -348.967086)
			(xy 392.869445 -348.959324) (xy 392.817114 -348.943958) (xy 392.767503 -348.921301) (xy 392.72162 -348.891814)
			(xy 392.680402 -348.856098) (xy 392.644686 -348.81488) (xy 392.615199 -348.768997) (xy 392.592542 -348.719386)
			(xy 392.577176 -348.667055) (xy 392.569414 -348.61307) (xy 391.086566 -348.61307) (xy 391.078805 -348.667046)
			(xy 391.063442 -348.71937) (xy 391.04079 -348.768977) (xy 391.011308 -348.814854) (xy 390.975598 -348.85607)
			(xy 390.934387 -348.891784) (xy 390.888512 -348.92127) (xy 390.838908 -348.943928) (xy 390.786585 -348.959297)
			(xy 390.732607 -348.967063) (xy 390.70534 -348.967552) (xy 389.84174 -348.967552) (xy 389.814466 -348.967111)
			(xy 389.760474 -348.959354) (xy 389.708135 -348.94399) (xy 389.658515 -348.921334) (xy 389.612626 -348.891847)
			(xy 389.5714 -348.856129) (xy 389.535677 -348.814906) (xy 389.506185 -348.76902) (xy 389.483524 -348.719403)
			(xy 389.468155 -348.667065) (xy 389.460392 -348.613074) (xy 387.977688 -348.613074) (xy 387.969926 -348.667058)
			(xy 387.954559 -348.719391) (xy 387.931901 -348.769005) (xy 387.902412 -348.814888) (xy 387.866693 -348.856107)
			(xy 387.825472 -348.891824) (xy 387.779587 -348.92131) (xy 387.729973 -348.943966) (xy 387.677639 -348.95933)
			(xy 387.623651 -348.96709) (xy 387.59638 -348.967552) (xy 386.73278 -348.967552) (xy 386.705511 -348.967084)
			(xy 386.651528 -348.95932) (xy 386.599199 -348.943953) (xy 386.549591 -348.921295) (xy 386.503711 -348.891807)
			(xy 386.462495 -348.856091) (xy 386.426781 -348.814873) (xy 386.397296 -348.768992) (xy 386.37464 -348.719382)
			(xy 386.359276 -348.667052) (xy 386.351514 -348.613069) (xy 384.868666 -348.613069) (xy 384.860905 -348.667048)
			(xy 384.845541 -348.719375) (xy 384.822887 -348.768982) (xy 384.793403 -348.814861) (xy 384.757691 -348.856077)
			(xy 384.716477 -348.891791) (xy 384.6706 -348.921277) (xy 384.620994 -348.943934) (xy 384.568668 -348.9593)
			(xy 384.514688 -348.967064) (xy 384.48742 -348.967552) (xy 383.62382 -348.967552) (xy 383.596547 -348.96711)
			(xy 383.542557 -348.95935) (xy 383.49022 -348.943985) (xy 383.440603 -348.921328) (xy 383.394716 -348.89184)
			(xy 383.353493 -348.856122) (xy 383.317772 -348.8149) (xy 383.288282 -348.769014) (xy 383.265622 -348.719398)
			(xy 383.250254 -348.667063) (xy 383.242492 -348.613073) (xy 381.759788 -348.613073) (xy 381.752025 -348.667061)
			(xy 381.736658 -348.719396) (xy 381.713998 -348.76901) (xy 381.684507 -348.814894) (xy 381.648786 -348.856115)
			(xy 381.607562 -348.891831) (xy 381.561675 -348.921317) (xy 381.512058 -348.943972) (xy 381.459722 -348.959334)
			(xy 381.405732 -348.967091) (xy 381.37846 -348.967552) (xy 380.51486 -348.967552) (xy 380.487592 -348.967083)
			(xy 380.433611 -348.959316) (xy 380.381285 -348.943947) (xy 380.331679 -348.921288) (xy 380.285801 -348.8918)
			(xy 380.244588 -348.856084) (xy 380.208876 -348.814866) (xy 380.179393 -348.768986) (xy 380.156739 -348.719377)
			(xy 380.141375 -348.66705) (xy 380.133614 -348.613068) (xy 378.650766 -348.613068) (xy 378.650766 -348.613069)
			(xy 378.643004 -348.667051) (xy 378.627639 -348.719379) (xy 378.604984 -348.768988) (xy 378.575498 -348.814868)
			(xy 378.539784 -348.856084) (xy 378.498568 -348.891798) (xy 378.452688 -348.921284) (xy 378.403079 -348.943939)
			(xy 378.350751 -348.959304) (xy 378.296769 -348.967066) (xy 378.2695 -348.967552) (xy 377.4059 -348.967552)
			(xy 377.37863 -348.967086) (xy 377.324645 -348.959324) (xy 377.272314 -348.943958) (xy 377.222703 -348.921301)
			(xy 377.17682 -348.891814) (xy 377.135602 -348.856098) (xy 377.099886 -348.81488) (xy 377.070399 -348.768997)
			(xy 377.047742 -348.719386) (xy 377.032376 -348.667055) (xy 377.024614 -348.61307) (xy 375.541766 -348.61307)
			(xy 375.534005 -348.667046) (xy 375.518642 -348.71937) (xy 375.49599 -348.768977) (xy 375.466508 -348.814854)
			(xy 375.430798 -348.85607) (xy 375.389587 -348.891784) (xy 375.343712 -348.92127) (xy 375.294108 -348.943928)
			(xy 375.241785 -348.959297) (xy 375.187807 -348.967063) (xy 375.16054 -348.967552) (xy 374.29694 -348.967552)
			(xy 374.269666 -348.967111) (xy 374.215674 -348.959354) (xy 374.163335 -348.94399) (xy 374.113715 -348.921334)
			(xy 374.067826 -348.891847) (xy 374.0266 -348.856129) (xy 373.990877 -348.814906) (xy 373.961385 -348.76902)
			(xy 373.938724 -348.719403) (xy 373.923355 -348.667065) (xy 373.915592 -348.613074) (xy 372.432888 -348.613074)
			(xy 372.425126 -348.667058) (xy 372.409759 -348.719391) (xy 372.387101 -348.769005) (xy 372.357612 -348.814888)
			(xy 372.321893 -348.856107) (xy 372.280672 -348.891824) (xy 372.234787 -348.92131) (xy 372.185173 -348.943966)
			(xy 372.132839 -348.95933) (xy 372.078851 -348.96709) (xy 372.05158 -348.967552) (xy 371.18798 -348.967552)
			(xy 371.160711 -348.967084) (xy 371.106728 -348.95932) (xy 371.054399 -348.943953) (xy 371.004791 -348.921295)
			(xy 370.958911 -348.891807) (xy 370.917695 -348.856091) (xy 370.881981 -348.814873) (xy 370.852496 -348.768992)
			(xy 370.82984 -348.719382) (xy 370.814476 -348.667052) (xy 370.806714 -348.613069) (xy 344.837266 -348.613069)
			(xy 344.829504 -348.66705) (xy 344.81414 -348.719378) (xy 344.791484 -348.768987) (xy 344.761999 -348.814866)
			(xy 344.726286 -348.856083) (xy 344.685069 -348.891797) (xy 344.63919 -348.921282) (xy 344.589582 -348.943938)
			(xy 344.537254 -348.959303) (xy 344.483272 -348.967065) (xy 344.456004 -348.967552) (xy 343.592404 -348.967552)
			(xy 343.565132 -348.967109) (xy 343.511143 -348.959347) (xy 343.458809 -348.943981) (xy 343.409194 -348.921323)
			(xy 343.363309 -348.891834) (xy 343.322087 -348.856116) (xy 343.286368 -348.814895) (xy 343.256879 -348.76901)
			(xy 343.234221 -348.719395) (xy 343.218854 -348.667061) (xy 343.211092 -348.613072) (xy 341.728265 -348.613072)
			(xy 341.720505 -348.667045) (xy 341.705143 -348.71937) (xy 341.68249 -348.768976) (xy 341.653009 -348.814853)
			(xy 341.6173 -348.856069) (xy 341.576088 -348.891783) (xy 341.530214 -348.921269) (xy 341.480611 -348.943927)
			(xy 341.428288 -348.959296) (xy 341.374311 -348.967063) (xy 341.347044 -348.967552) (xy 340.483444 -348.967552)
			(xy 340.45617 -348.967111) (xy 340.402177 -348.959354) (xy 340.349838 -348.943991) (xy 340.300218 -348.921336)
			(xy 340.254327 -348.891849) (xy 340.213101 -348.85613) (xy 340.177378 -348.814908) (xy 340.147885 -348.769021)
			(xy 340.125224 -348.719403) (xy 340.109855 -348.667066) (xy 340.102092 -348.613074) (xy 338.619388 -348.613074)
			(xy 338.611626 -348.667058) (xy 338.596259 -348.71939) (xy 338.573601 -348.769003) (xy 338.544113 -348.814887)
			(xy 338.508395 -348.856106) (xy 338.467174 -348.891823) (xy 338.421289 -348.921309) (xy 338.371675 -348.943965)
			(xy 338.319342 -348.95933) (xy 338.265355 -348.96709) (xy 338.238084 -348.967552) (xy 337.374484 -348.967552)
			(xy 337.347215 -348.967084) (xy 337.293231 -348.959321) (xy 337.240902 -348.943954) (xy 337.191293 -348.921296)
			(xy 337.145413 -348.891809) (xy 337.104196 -348.856093) (xy 337.068482 -348.814874) (xy 337.038996 -348.768993)
			(xy 337.016341 -348.719383) (xy 337.000976 -348.667053) (xy 336.993214 -348.613069) (xy 335.510366 -348.613069)
			(xy 335.502605 -348.667048) (xy 335.487241 -348.719374) (xy 335.464587 -348.768981) (xy 335.435104 -348.81486)
			(xy 335.399393 -348.856076) (xy 335.358179 -348.89179) (xy 335.312302 -348.921276) (xy 335.262696 -348.943933)
			(xy 335.210371 -348.9593) (xy 335.156392 -348.967064) (xy 335.129124 -348.967552) (xy 334.265524 -348.967552)
			(xy 334.238251 -348.96711) (xy 334.18426 -348.959351) (xy 334.131923 -348.943986) (xy 334.082306 -348.921329)
			(xy 334.036418 -348.891841) (xy 333.995194 -348.856123) (xy 333.959473 -348.814901) (xy 333.929982 -348.769015)
			(xy 333.907322 -348.719399) (xy 333.891955 -348.667063) (xy 333.884192 -348.613073) (xy 332.401488 -348.613073)
			(xy 332.393726 -348.667061) (xy 332.378358 -348.719395) (xy 332.355698 -348.769009) (xy 332.326208 -348.814893)
			(xy 332.290488 -348.856113) (xy 332.249264 -348.89183) (xy 332.203377 -348.921316) (xy 332.153761 -348.94397)
			(xy 332.101425 -348.959333) (xy 332.047436 -348.967091) (xy 332.020164 -348.967552) (xy 331.156564 -348.967552)
			(xy 331.129296 -348.967083) (xy 331.075314 -348.959317) (xy 331.022988 -348.943948) (xy 330.973381 -348.921289)
			(xy 330.927503 -348.891802) (xy 330.886289 -348.856086) (xy 330.850577 -348.814868) (xy 330.821093 -348.768987)
			(xy 330.798439 -348.719378) (xy 330.783075 -348.66705) (xy 330.775314 -348.613068) (xy 329.292466 -348.613068)
			(xy 329.284704 -348.66705) (xy 329.26934 -348.719378) (xy 329.246684 -348.768987) (xy 329.217199 -348.814866)
			(xy 329.181486 -348.856083) (xy 329.140269 -348.891797) (xy 329.09439 -348.921282) (xy 329.044782 -348.943938)
			(xy 328.992454 -348.959303) (xy 328.938472 -348.967065) (xy 328.911204 -348.967552) (xy 328.047604 -348.967552)
			(xy 328.020332 -348.967109) (xy 327.966343 -348.959347) (xy 327.914009 -348.943981) (xy 327.864394 -348.921323)
			(xy 327.818509 -348.891834) (xy 327.777287 -348.856116) (xy 327.741568 -348.814895) (xy 327.712079 -348.76901)
			(xy 327.689421 -348.719395) (xy 327.674054 -348.667061) (xy 327.666292 -348.613072) (xy 326.183465 -348.613072)
			(xy 326.175705 -348.667045) (xy 326.160343 -348.71937) (xy 326.13769 -348.768976) (xy 326.108209 -348.814853)
			(xy 326.0725 -348.856069) (xy 326.031288 -348.891783) (xy 325.985414 -348.921269) (xy 325.935811 -348.943927)
			(xy 325.883488 -348.959296) (xy 325.829511 -348.967063) (xy 325.802244 -348.967552) (xy 324.938644 -348.967552)
			(xy 324.91137 -348.967111) (xy 324.857377 -348.959354) (xy 324.805038 -348.943991) (xy 324.755418 -348.921336)
			(xy 324.709527 -348.891849) (xy 324.668301 -348.85613) (xy 324.632578 -348.814908) (xy 324.603085 -348.769021)
			(xy 324.580424 -348.719403) (xy 324.565055 -348.667066) (xy 324.557292 -348.613074) (xy 323.074588 -348.613074)
			(xy 323.066826 -348.667058) (xy 323.051459 -348.71939) (xy 323.028801 -348.769003) (xy 322.999313 -348.814887)
			(xy 322.963595 -348.856106) (xy 322.922374 -348.891823) (xy 322.876489 -348.921309) (xy 322.826875 -348.943965)
			(xy 322.774542 -348.95933) (xy 322.720555 -348.96709) (xy 322.693284 -348.967552) (xy 321.829684 -348.967552)
			(xy 321.802415 -348.967084) (xy 321.748431 -348.959321) (xy 321.696102 -348.943954) (xy 321.646493 -348.921296)
			(xy 321.600613 -348.891809) (xy 321.559396 -348.856093) (xy 321.523682 -348.814874) (xy 321.494196 -348.768993)
			(xy 321.471541 -348.719383) (xy 321.456176 -348.667053) (xy 321.448414 -348.613069) (xy 319.965566 -348.613069)
			(xy 319.957805 -348.667048) (xy 319.942441 -348.719374) (xy 319.919787 -348.768981) (xy 319.890304 -348.81486)
			(xy 319.854593 -348.856076) (xy 319.813379 -348.89179) (xy 319.767502 -348.921276) (xy 319.717896 -348.943933)
			(xy 319.665571 -348.9593) (xy 319.611592 -348.967064) (xy 319.584324 -348.967552) (xy 318.720724 -348.967552)
			(xy 318.693451 -348.96711) (xy 318.63946 -348.959351) (xy 318.587123 -348.943986) (xy 318.537506 -348.921329)
			(xy 318.491618 -348.891841) (xy 318.450394 -348.856123) (xy 318.414673 -348.814901) (xy 318.385182 -348.769015)
			(xy 318.362522 -348.719399) (xy 318.347155 -348.667063) (xy 318.339392 -348.613073) (xy 316.856688 -348.613073)
			(xy 316.848926 -348.667061) (xy 316.833558 -348.719395) (xy 316.810898 -348.769009) (xy 316.781408 -348.814893)
			(xy 316.745688 -348.856113) (xy 316.704464 -348.89183) (xy 316.658577 -348.921316) (xy 316.608961 -348.94397)
			(xy 316.556625 -348.959333) (xy 316.502636 -348.967091) (xy 316.475364 -348.967552) (xy 315.611764 -348.967552)
			(xy 315.584496 -348.967083) (xy 315.530514 -348.959317) (xy 315.478188 -348.943948) (xy 315.428581 -348.921289)
			(xy 315.382703 -348.891802) (xy 315.341489 -348.856086) (xy 315.305777 -348.814868) (xy 315.276293 -348.768987)
			(xy 315.253639 -348.719378) (xy 315.238275 -348.66705) (xy 315.230514 -348.613068) (xy 313.747666 -348.613068)
			(xy 313.739904 -348.66705) (xy 313.72454 -348.719378) (xy 313.701884 -348.768987) (xy 313.672399 -348.814866)
			(xy 313.636686 -348.856083) (xy 313.595469 -348.891797) (xy 313.54959 -348.921282) (xy 313.499982 -348.943938)
			(xy 313.447654 -348.959303) (xy 313.393672 -348.967065) (xy 313.366404 -348.967552) (xy 312.502804 -348.967552)
			(xy 312.475532 -348.967109) (xy 312.421543 -348.959347) (xy 312.369209 -348.943981) (xy 312.319594 -348.921323)
			(xy 312.273709 -348.891834) (xy 312.232487 -348.856116) (xy 312.196768 -348.814895) (xy 312.167279 -348.76901)
			(xy 312.144621 -348.719395) (xy 312.129254 -348.667061) (xy 312.121492 -348.613072) (xy 300.231566 -348.613072)
			(xy 300.223804 -348.667051) (xy 300.208439 -348.719379) (xy 300.185784 -348.768987) (xy 300.156299 -348.814867)
			(xy 300.120585 -348.856083) (xy 300.079369 -348.891798) (xy 300.033489 -348.921283) (xy 299.98388 -348.943939)
			(xy 299.931553 -348.959304) (xy 299.877571 -348.967065) (xy 299.850302 -348.967552) (xy 298.986702 -348.967552)
			(xy 298.95943 -348.967109) (xy 298.905442 -348.959347) (xy 298.853107 -348.94398) (xy 298.803493 -348.921322)
			(xy 298.757608 -348.891834) (xy 298.716386 -348.856115) (xy 298.680668 -348.814894) (xy 298.651179 -348.769009)
			(xy 298.628521 -348.719394) (xy 298.613154 -348.66706) (xy 298.605392 -348.613072) (xy 297.122565 -348.613072)
			(xy 297.114805 -348.667045) (xy 297.099443 -348.71937) (xy 297.07679 -348.768976) (xy 297.047309 -348.814854)
			(xy 297.011599 -348.856069) (xy 296.970387 -348.891784) (xy 296.924513 -348.92127) (xy 296.874909 -348.943928)
			(xy 296.822586 -348.959296) (xy 296.768609 -348.967063) (xy 296.741342 -348.967552) (xy 295.877742 -348.967552)
			(xy 295.850468 -348.967111) (xy 295.796476 -348.959354) (xy 295.744136 -348.943991) (xy 295.694517 -348.921335)
			(xy 295.648627 -348.891848) (xy 295.6074 -348.856129) (xy 295.571677 -348.814907) (xy 295.542185 -348.76902)
			(xy 295.519524 -348.719403) (xy 295.504155 -348.667066) (xy 295.496392 -348.613074) (xy 294.013688 -348.613074)
			(xy 294.005926 -348.667058) (xy 293.990559 -348.719391) (xy 293.967901 -348.769004) (xy 293.938412 -348.814887)
			(xy 293.902694 -348.856107) (xy 293.861473 -348.891823) (xy 293.815588 -348.92131) (xy 293.765974 -348.943966)
			(xy 293.713641 -348.95933) (xy 293.659653 -348.96709) (xy 293.632382 -348.967552) (xy 292.768782 -348.967552)
			(xy 292.741513 -348.967084) (xy 292.68753 -348.95932) (xy 292.635201 -348.943953) (xy 292.585592 -348.921295)
			(xy 292.539712 -348.891808) (xy 292.498495 -348.856092) (xy 292.462781 -348.814874) (xy 292.433296 -348.768992)
			(xy 292.410641 -348.719382) (xy 292.395276 -348.667053) (xy 292.387514 -348.613069) (xy 290.904666 -348.613069)
			(xy 290.896905 -348.667048) (xy 290.881541 -348.719374) (xy 290.858887 -348.768982) (xy 290.829404 -348.81486)
			(xy 290.793692 -348.856076) (xy 290.752478 -348.891791) (xy 290.706601 -348.921276) (xy 290.656995 -348.943933)
			(xy 290.604669 -348.9593) (xy 290.55069 -348.967064) (xy 290.523422 -348.967552) (xy 289.659822 -348.967552)
			(xy 289.632549 -348.96711) (xy 289.578559 -348.95935) (xy 289.526222 -348.943985) (xy 289.476605 -348.921329)
			(xy 289.430717 -348.891841) (xy 289.389493 -348.856122) (xy 289.353772 -348.814901) (xy 289.324282 -348.769015)
			(xy 289.301622 -348.719399) (xy 289.286254 -348.667063) (xy 289.278492 -348.613073) (xy 287.795788 -348.613073)
			(xy 287.788026 -348.667061) (xy 287.772658 -348.719395) (xy 287.749998 -348.76901) (xy 287.720508 -348.814894)
			(xy 287.684787 -348.856114) (xy 287.643563 -348.89183) (xy 287.597676 -348.921316) (xy 287.54806 -348.943971)
			(xy 287.495724 -348.959334) (xy 287.441734 -348.967091) (xy 287.414462 -348.967552) (xy 286.550862 -348.967552)
			(xy 286.523594 -348.967083) (xy 286.469613 -348.959317) (xy 286.417286 -348.943948) (xy 286.36768 -348.921289)
			(xy 286.321802 -348.891801) (xy 286.280588 -348.856085) (xy 286.244876 -348.814867) (xy 286.215393 -348.768987)
			(xy 286.192739 -348.719378) (xy 286.177375 -348.66705) (xy 286.169614 -348.613068) (xy 284.686766 -348.613068)
			(xy 284.686766 -348.613069) (xy 284.679004 -348.667051) (xy 284.663639 -348.719379) (xy 284.640984 -348.768987)
			(xy 284.611499 -348.814867) (xy 284.575785 -348.856083) (xy 284.534569 -348.891798) (xy 284.488689 -348.921283)
			(xy 284.43908 -348.943939) (xy 284.386753 -348.959304) (xy 284.332771 -348.967065) (xy 284.305502 -348.967552)
			(xy 283.441902 -348.967552) (xy 283.41463 -348.967109) (xy 283.360642 -348.959347) (xy 283.308307 -348.94398)
			(xy 283.258693 -348.921322) (xy 283.212808 -348.891834) (xy 283.171586 -348.856115) (xy 283.135868 -348.814894)
			(xy 283.106379 -348.769009) (xy 283.083721 -348.719394) (xy 283.068354 -348.66706) (xy 283.060592 -348.613072)
			(xy 281.577765 -348.613072) (xy 281.570005 -348.667045) (xy 281.554643 -348.71937) (xy 281.53199 -348.768976)
			(xy 281.502509 -348.814854) (xy 281.466799 -348.856069) (xy 281.425587 -348.891784) (xy 281.379713 -348.92127)
			(xy 281.330109 -348.943928) (xy 281.277786 -348.959296) (xy 281.223809 -348.967063) (xy 281.196542 -348.967552)
			(xy 280.332942 -348.967552) (xy 280.305668 -348.967111) (xy 280.251676 -348.959354) (xy 280.199336 -348.943991)
			(xy 280.149717 -348.921335) (xy 280.103827 -348.891848) (xy 280.0626 -348.856129) (xy 280.026877 -348.814907)
			(xy 279.997385 -348.76902) (xy 279.974724 -348.719403) (xy 279.959355 -348.667066) (xy 279.951592 -348.613074)
			(xy 278.468888 -348.613074) (xy 278.461126 -348.667058) (xy 278.445759 -348.719391) (xy 278.423101 -348.769004)
			(xy 278.393612 -348.814887) (xy 278.357894 -348.856107) (xy 278.316673 -348.891823) (xy 278.270788 -348.92131)
			(xy 278.221174 -348.943966) (xy 278.168841 -348.95933) (xy 278.114853 -348.96709) (xy 278.087582 -348.967552)
			(xy 277.223982 -348.967552) (xy 277.196713 -348.967084) (xy 277.14273 -348.95932) (xy 277.090401 -348.943953)
			(xy 277.040792 -348.921295) (xy 276.994912 -348.891808) (xy 276.953695 -348.856092) (xy 276.917981 -348.814874)
			(xy 276.888496 -348.768992) (xy 276.865841 -348.719382) (xy 276.850476 -348.667053) (xy 276.842714 -348.613069)
			(xy 275.359866 -348.613069) (xy 275.352105 -348.667048) (xy 275.336741 -348.719374) (xy 275.314087 -348.768982)
			(xy 275.284604 -348.81486) (xy 275.248892 -348.856076) (xy 275.207678 -348.891791) (xy 275.161801 -348.921276)
			(xy 275.112195 -348.943933) (xy 275.059869 -348.9593) (xy 275.00589 -348.967064) (xy 274.978622 -348.967552)
			(xy 274.115022 -348.967552) (xy 274.087749 -348.96711) (xy 274.033759 -348.95935) (xy 273.981422 -348.943985)
			(xy 273.931805 -348.921329) (xy 273.885917 -348.891841) (xy 273.844693 -348.856122) (xy 273.808972 -348.814901)
			(xy 273.779482 -348.769015) (xy 273.756822 -348.719399) (xy 273.741454 -348.667063) (xy 273.733692 -348.613073)
			(xy 272.250988 -348.613073) (xy 272.243226 -348.667061) (xy 272.227858 -348.719395) (xy 272.205198 -348.76901)
			(xy 272.175708 -348.814894) (xy 272.139987 -348.856114) (xy 272.098763 -348.89183) (xy 272.052876 -348.921316)
			(xy 272.00326 -348.943971) (xy 271.950924 -348.959334) (xy 271.896934 -348.967091) (xy 271.869662 -348.967552)
			(xy 271.006062 -348.967552) (xy 270.978794 -348.967083) (xy 270.924813 -348.959317) (xy 270.872486 -348.943948)
			(xy 270.82288 -348.921289) (xy 270.777002 -348.891801) (xy 270.735788 -348.856085) (xy 270.700076 -348.814867)
			(xy 270.670593 -348.768987) (xy 270.647939 -348.719378) (xy 270.632575 -348.66705) (xy 270.624814 -348.613068)
			(xy 269.141966 -348.613068) (xy 269.141966 -348.613069) (xy 269.134204 -348.667051) (xy 269.118839 -348.719379)
			(xy 269.096184 -348.768987) (xy 269.066699 -348.814867) (xy 269.030985 -348.856083) (xy 268.989769 -348.891798)
			(xy 268.943889 -348.921283) (xy 268.89428 -348.943939) (xy 268.841953 -348.959304) (xy 268.787971 -348.967065)
			(xy 268.760702 -348.967552) (xy 267.897102 -348.967552) (xy 267.86983 -348.967109) (xy 267.815842 -348.959347)
			(xy 267.763507 -348.94398) (xy 267.713893 -348.921322) (xy 267.668008 -348.891834) (xy 267.626786 -348.856115)
			(xy 267.591068 -348.814894) (xy 267.561579 -348.769009) (xy 267.538921 -348.719394) (xy 267.523554 -348.66706)
			(xy 267.515792 -348.613072) (xy 194.520565 -348.613072) (xy 194.512804 -348.667049) (xy 194.49744 -348.719376)
			(xy 194.474785 -348.768985) (xy 194.445301 -348.814864) (xy 194.409588 -348.85608) (xy 194.368373 -348.891794)
			(xy 194.322495 -348.92128) (xy 194.272888 -348.943936) (xy 194.220561 -348.959302) (xy 194.16658 -348.967065)
			(xy 194.139312 -348.967552) (xy 193.275712 -348.967552) (xy 193.24844 -348.967109) (xy 193.19445 -348.959348)
			(xy 193.142115 -348.943983) (xy 193.092499 -348.921325) (xy 193.046612 -348.891837) (xy 193.00539 -348.856119)
			(xy 192.96967 -348.814897) (xy 192.940181 -348.769012) (xy 192.917521 -348.719397) (xy 192.902154 -348.667062)
			(xy 192.894392 -348.613072) (xy 191.411688 -348.613072) (xy 191.403925 -348.667062) (xy 191.388557 -348.719397)
			(xy 191.365896 -348.769012) (xy 191.336405 -348.814897) (xy 191.300683 -348.856117) (xy 191.259459 -348.891834)
			(xy 191.21357 -348.921319) (xy 191.163952 -348.943974) (xy 191.111615 -348.959335) (xy 191.057625 -348.967092)
			(xy 191.030352 -348.967552) (xy 190.166752 -348.967552) (xy 190.139484 -348.967082) (xy 190.085504 -348.959315)
			(xy 190.033179 -348.943945) (xy 189.983574 -348.921285) (xy 189.937698 -348.891797) (xy 189.896485 -348.856081)
			(xy 189.860774 -348.814864) (xy 189.831292 -348.768984) (xy 189.808638 -348.719376) (xy 189.793275 -348.667049)
			(xy 189.785514 -348.613068) (xy 188.302689 -348.613068) (xy 188.302689 -348.613071) (xy 188.294926 -348.667057)
			(xy 188.27956 -348.719389) (xy 188.256903 -348.769001) (xy 188.227415 -348.814884) (xy 188.191698 -348.856103)
			(xy 188.150478 -348.89182) (xy 188.104594 -348.921306) (xy 188.054981 -348.943963) (xy 188.002649 -348.959328)
			(xy 187.948663 -348.967089) (xy 187.921392 -348.967552) (xy 187.057792 -348.967552) (xy 187.030522 -348.967085)
			(xy 186.976538 -348.959322) (xy 186.924208 -348.943956) (xy 186.874598 -348.921299) (xy 186.828717 -348.891812)
			(xy 186.787499 -348.856095) (xy 186.751784 -348.814877) (xy 186.722298 -348.768995) (xy 186.699641 -348.719384)
			(xy 186.684276 -348.667054) (xy 186.676514 -348.61307) (xy 185.193666 -348.61307) (xy 185.185905 -348.667047)
			(xy 185.170542 -348.719372) (xy 185.147888 -348.768979) (xy 185.118406 -348.814857) (xy 185.082695 -348.856073)
			(xy 185.041483 -348.891787) (xy 184.995607 -348.921273) (xy 184.946002 -348.943931) (xy 184.893678 -348.959298)
			(xy 184.839699 -348.967063) (xy 184.812432 -348.967552) (xy 183.948832 -348.967552) (xy 183.921559 -348.967111)
			(xy 183.867567 -348.959352) (xy 183.815229 -348.943988) (xy 183.765611 -348.921332) (xy 183.719722 -348.891844)
			(xy 183.678497 -348.856126) (xy 183.642775 -348.814904) (xy 183.613284 -348.769017) (xy 183.590623 -348.719401)
			(xy 183.575255 -348.667064) (xy 183.567492 -348.613073) (xy 182.084788 -348.613073) (xy 182.077026 -348.667059)
			(xy 182.061659 -348.719393) (xy 182.038999 -348.769007) (xy 182.00951 -348.814891) (xy 181.97379 -348.85611)
			(xy 181.932568 -348.891827) (xy 181.886682 -348.921313) (xy 181.837067 -348.943968) (xy 181.784732 -348.959332)
			(xy 181.730744 -348.96709) (xy 181.703472 -348.967552) (xy 180.839872 -348.967552) (xy 180.812603 -348.967084)
			(xy 180.758621 -348.959319) (xy 180.706294 -348.94395) (xy 180.656686 -348.921292) (xy 180.610807 -348.891805)
			(xy 180.569592 -348.856088) (xy 180.533879 -348.81487) (xy 180.504395 -348.76899) (xy 180.48174 -348.71938)
			(xy 180.466376 -348.667051) (xy 180.458614 -348.613069) (xy 178.975766 -348.613069) (xy 178.968004 -348.667049)
			(xy 178.95264 -348.719376) (xy 178.929985 -348.768985) (xy 178.900501 -348.814864) (xy 178.864788 -348.85608)
			(xy 178.823573 -348.891794) (xy 178.777695 -348.92128) (xy 178.728088 -348.943936) (xy 178.675761 -348.959302)
			(xy 178.62178 -348.967065) (xy 178.594512 -348.967552) (xy 177.730912 -348.967552) (xy 177.70364 -348.967109)
			(xy 177.64965 -348.959348) (xy 177.597315 -348.943983) (xy 177.547699 -348.921325) (xy 177.501812 -348.891837)
			(xy 177.46059 -348.856119) (xy 177.42487 -348.814897) (xy 177.395381 -348.769012) (xy 177.372721 -348.719397)
			(xy 177.357354 -348.667062) (xy 177.349592 -348.613072) (xy 175.866888 -348.613072) (xy 175.859125 -348.667062)
			(xy 175.843757 -348.719397) (xy 175.821096 -348.769012) (xy 175.791605 -348.814897) (xy 175.755883 -348.856117)
			(xy 175.714659 -348.891834) (xy 175.66877 -348.921319) (xy 175.619152 -348.943974) (xy 175.566815 -348.959335)
			(xy 175.512825 -348.967092) (xy 175.485552 -348.967552) (xy 174.621952 -348.967552) (xy 174.594684 -348.967082)
			(xy 174.540704 -348.959315) (xy 174.488379 -348.943945) (xy 174.438774 -348.921285) (xy 174.392898 -348.891797)
			(xy 174.351685 -348.856081) (xy 174.315974 -348.814864) (xy 174.286492 -348.768984) (xy 174.263838 -348.719376)
			(xy 174.248475 -348.667049) (xy 174.240714 -348.613068) (xy 172.757889 -348.613068) (xy 172.757889 -348.613071)
			(xy 172.750126 -348.667057) (xy 172.73476 -348.719389) (xy 172.712103 -348.769001) (xy 172.682615 -348.814884)
			(xy 172.646898 -348.856103) (xy 172.605678 -348.89182) (xy 172.559794 -348.921306) (xy 172.510181 -348.943963)
			(xy 172.457849 -348.959328) (xy 172.403863 -348.967089) (xy 172.376592 -348.967552) (xy 171.512992 -348.967552)
			(xy 171.485722 -348.967085) (xy 171.431738 -348.959322) (xy 171.379408 -348.943956) (xy 171.329798 -348.921299)
			(xy 171.283917 -348.891812) (xy 171.242699 -348.856095) (xy 171.206984 -348.814877) (xy 171.177498 -348.768995)
			(xy 171.154841 -348.719384) (xy 171.139476 -348.667054) (xy 171.131714 -348.61307) (xy 169.648866 -348.61307)
			(xy 169.641105 -348.667047) (xy 169.625742 -348.719372) (xy 169.603088 -348.768979) (xy 169.573606 -348.814857)
			(xy 169.537895 -348.856073) (xy 169.496683 -348.891787) (xy 169.450807 -348.921273) (xy 169.401202 -348.943931)
			(xy 169.348878 -348.959298) (xy 169.294899 -348.967063) (xy 169.267632 -348.967552) (xy 168.404032 -348.967552)
			(xy 168.376759 -348.967111) (xy 168.322767 -348.959352) (xy 168.270429 -348.943988) (xy 168.220811 -348.921332)
			(xy 168.174922 -348.891844) (xy 168.133697 -348.856126) (xy 168.097975 -348.814904) (xy 168.068484 -348.769017)
			(xy 168.045823 -348.719401) (xy 168.030455 -348.667064) (xy 168.022692 -348.613073) (xy 166.539988 -348.613073)
			(xy 166.532226 -348.667059) (xy 166.516859 -348.719393) (xy 166.494199 -348.769007) (xy 166.46471 -348.814891)
			(xy 166.42899 -348.85611) (xy 166.387768 -348.891827) (xy 166.341882 -348.921313) (xy 166.292267 -348.943968)
			(xy 166.239932 -348.959332) (xy 166.185944 -348.96709) (xy 166.158672 -348.967552) (xy 165.295072 -348.967552)
			(xy 165.267803 -348.967084) (xy 165.213821 -348.959319) (xy 165.161494 -348.94395) (xy 165.111886 -348.921292)
			(xy 165.066007 -348.891805) (xy 165.024792 -348.856088) (xy 164.989079 -348.81487) (xy 164.959595 -348.76899)
			(xy 164.93694 -348.71938) (xy 164.921576 -348.667051) (xy 164.913814 -348.613069) (xy 163.430966 -348.613069)
			(xy 163.423204 -348.667049) (xy 163.40784 -348.719376) (xy 163.385185 -348.768985) (xy 163.355701 -348.814864)
			(xy 163.319988 -348.85608) (xy 163.278773 -348.891794) (xy 163.232895 -348.92128) (xy 163.183288 -348.943936)
			(xy 163.130961 -348.959302) (xy 163.07698 -348.967065) (xy 163.049712 -348.967552) (xy 162.186112 -348.967552)
			(xy 162.15884 -348.967109) (xy 162.10485 -348.959348) (xy 162.052515 -348.943983) (xy 162.002899 -348.921325)
			(xy 161.957012 -348.891837) (xy 161.91579 -348.856119) (xy 161.88007 -348.814897) (xy 161.850581 -348.769012)
			(xy 161.827921 -348.719397) (xy 161.812554 -348.667062) (xy 161.804792 -348.613072) (xy 144.196565 -348.613072)
			(xy 144.188804 -348.66705) (xy 144.17344 -348.719377) (xy 144.150785 -348.768986) (xy 144.1213 -348.814865)
			(xy 144.085587 -348.856081) (xy 144.044371 -348.891796) (xy 143.998493 -348.921281) (xy 143.948885 -348.943937)
			(xy 143.896558 -348.959303) (xy 143.842576 -348.967065) (xy 143.815308 -348.967552) (xy 142.951708 -348.967552)
			(xy 142.924436 -348.967109) (xy 142.870447 -348.959348) (xy 142.818112 -348.943982) (xy 142.768496 -348.921324)
			(xy 142.72261 -348.891836) (xy 142.681388 -348.856117) (xy 142.645669 -348.814896) (xy 142.61618 -348.769011)
			(xy 142.593521 -348.719396) (xy 142.578154 -348.667061) (xy 142.570392 -348.613072) (xy 141.087565 -348.613072)
			(xy 141.079806 -348.667044) (xy 141.064443 -348.719369) (xy 141.041791 -348.768974) (xy 141.01231 -348.814852)
			(xy 140.976601 -348.856067) (xy 140.93539 -348.891781) (xy 140.889517 -348.921268) (xy 140.839914 -348.943926)
			(xy 140.787591 -348.959295) (xy 140.733614 -348.967062) (xy 140.706348 -348.967552) (xy 139.842748 -348.967552)
			(xy 139.815474 -348.967112) (xy 139.761481 -348.959355) (xy 139.709141 -348.943992) (xy 139.65952 -348.921337)
			(xy 139.613629 -348.89185) (xy 139.572402 -348.856132) (xy 139.536679 -348.814909) (xy 139.507186 -348.769022)
			(xy 139.484524 -348.719404) (xy 139.469155 -348.667066) (xy 139.461392 -348.613074) (xy 137.978689 -348.613074)
			(xy 137.970926 -348.667057) (xy 137.95556 -348.71939) (xy 137.932902 -348.769002) (xy 137.903414 -348.814885)
			(xy 137.867696 -348.856105) (xy 137.826476 -348.891821) (xy 137.780592 -348.921308) (xy 137.730978 -348.943964)
			(xy 137.678646 -348.959329) (xy 137.624659 -348.967089) (xy 137.597388 -348.967552) (xy 136.733788 -348.967552)
			(xy 136.706518 -348.967085) (xy 136.652535 -348.959321) (xy 136.600205 -348.943955) (xy 136.550595 -348.921297)
			(xy 136.504715 -348.89181) (xy 136.463497 -348.856094) (xy 136.427783 -348.814876) (xy 136.398297 -348.768994)
			(xy 136.375641 -348.719383) (xy 136.360276 -348.667053) (xy 136.352514 -348.61307) (xy 134.869666 -348.61307)
			(xy 134.861905 -348.667047) (xy 134.846541 -348.719373) (xy 134.823888 -348.76898) (xy 134.794405 -348.814858)
			(xy 134.758694 -348.856074) (xy 134.717481 -348.891789) (xy 134.671605 -348.921274) (xy 134.621999 -348.943932)
			(xy 134.569675 -348.959299) (xy 134.515695 -348.967064) (xy 134.488428 -348.967552) (xy 133.624828 -348.967552)
			(xy 133.597555 -348.96711) (xy 133.543564 -348.959351) (xy 133.491226 -348.943987) (xy 133.441608 -348.92133)
			(xy 133.39572 -348.891843) (xy 133.354495 -348.856124) (xy 133.318774 -348.814903) (xy 133.289283 -348.769016)
			(xy 133.266623 -348.7194) (xy 133.251255 -348.667064) (xy 133.243492 -348.613073) (xy 131.760788 -348.613073)
			(xy 131.753026 -348.66706) (xy 131.737658 -348.719394) (xy 131.714999 -348.769008) (xy 131.685509 -348.814892)
			(xy 131.649789 -348.856112) (xy 131.608566 -348.891828) (xy 131.56268 -348.921314) (xy 131.513064 -348.943969)
			(xy 131.460729 -348.959332) (xy 131.40674 -348.967091) (xy 131.379468 -348.967552) (xy 130.515868 -348.967552)
			(xy 130.488599 -348.967083) (xy 130.434618 -348.959318) (xy 130.382291 -348.943949) (xy 130.332683 -348.921291)
			(xy 130.286805 -348.891803) (xy 130.24559 -348.856087) (xy 130.209878 -348.814869) (xy 130.180394 -348.768989)
			(xy 130.15774 -348.719379) (xy 130.142375 -348.667051) (xy 130.134614 -348.613069) (xy 128.651766 -348.613069)
			(xy 128.644004 -348.66705) (xy 128.62864 -348.719377) (xy 128.605985 -348.768986) (xy 128.5765 -348.814865)
			(xy 128.540787 -348.856081) (xy 128.499571 -348.891796) (xy 128.453693 -348.921281) (xy 128.404085 -348.943937)
			(xy 128.351758 -348.959303) (xy 128.297776 -348.967065) (xy 128.270508 -348.967552) (xy 127.406908 -348.967552)
			(xy 127.379636 -348.967109) (xy 127.325647 -348.959348) (xy 127.273312 -348.943982) (xy 127.223696 -348.921324)
			(xy 127.17781 -348.891836) (xy 127.136588 -348.856117) (xy 127.100869 -348.814896) (xy 127.07138 -348.769011)
			(xy 127.048721 -348.719396) (xy 127.033354 -348.667061) (xy 127.025592 -348.613072) (xy 125.542765 -348.613072)
			(xy 125.535006 -348.667044) (xy 125.519643 -348.719369) (xy 125.496991 -348.768974) (xy 125.46751 -348.814852)
			(xy 125.431801 -348.856067) (xy 125.39059 -348.891781) (xy 125.344717 -348.921268) (xy 125.295114 -348.943926)
			(xy 125.242791 -348.959295) (xy 125.188814 -348.967062) (xy 125.161548 -348.967552) (xy 124.297948 -348.967552)
			(xy 124.270674 -348.967112) (xy 124.216681 -348.959355) (xy 124.164341 -348.943992) (xy 124.11472 -348.921337)
			(xy 124.068829 -348.89185) (xy 124.027602 -348.856132) (xy 123.991879 -348.814909) (xy 123.962386 -348.769022)
			(xy 123.939724 -348.719404) (xy 123.924355 -348.667066) (xy 123.916592 -348.613074) (xy 122.433889 -348.613074)
			(xy 122.426126 -348.667057) (xy 122.41076 -348.71939) (xy 122.388102 -348.769002) (xy 122.358614 -348.814885)
			(xy 122.322896 -348.856105) (xy 122.281676 -348.891821) (xy 122.235792 -348.921308) (xy 122.186178 -348.943964)
			(xy 122.133846 -348.959329) (xy 122.079859 -348.967089) (xy 122.052588 -348.967552) (xy 121.188988 -348.967552)
			(xy 121.161718 -348.967085) (xy 121.107735 -348.959321) (xy 121.055405 -348.943955) (xy 121.005795 -348.921297)
			(xy 120.959915 -348.89181) (xy 120.918697 -348.856094) (xy 120.882983 -348.814876) (xy 120.853497 -348.768994)
			(xy 120.830841 -348.719383) (xy 120.815476 -348.667053) (xy 120.807714 -348.61307) (xy 119.324866 -348.61307)
			(xy 119.317105 -348.667047) (xy 119.301741 -348.719373) (xy 119.279088 -348.76898) (xy 119.249605 -348.814858)
			(xy 119.213894 -348.856074) (xy 119.172681 -348.891789) (xy 119.126805 -348.921274) (xy 119.077199 -348.943932)
			(xy 119.024875 -348.959299) (xy 118.970895 -348.967064) (xy 118.943628 -348.967552) (xy 118.080028 -348.967552)
			(xy 118.052755 -348.96711) (xy 117.998764 -348.959351) (xy 117.946426 -348.943987) (xy 117.896808 -348.92133)
			(xy 117.85092 -348.891843) (xy 117.809695 -348.856124) (xy 117.773974 -348.814903) (xy 117.744483 -348.769016)
			(xy 117.721823 -348.7194) (xy 117.706455 -348.667064) (xy 117.698692 -348.613073) (xy 116.215988 -348.613073)
			(xy 116.208226 -348.66706) (xy 116.192858 -348.719394) (xy 116.170199 -348.769008) (xy 116.140709 -348.814892)
			(xy 116.104989 -348.856112) (xy 116.063766 -348.891828) (xy 116.01788 -348.921314) (xy 115.968264 -348.943969)
			(xy 115.915929 -348.959332) (xy 115.86194 -348.967091) (xy 115.834668 -348.967552) (xy 114.971068 -348.967552)
			(xy 114.943799 -348.967083) (xy 114.889818 -348.959318) (xy 114.837491 -348.943949) (xy 114.787883 -348.921291)
			(xy 114.742005 -348.891803) (xy 114.70079 -348.856087) (xy 114.665078 -348.814869) (xy 114.635594 -348.768989)
			(xy 114.61294 -348.719379) (xy 114.597575 -348.667051) (xy 114.589814 -348.613069) (xy 113.106966 -348.613069)
			(xy 113.099204 -348.66705) (xy 113.08384 -348.719377) (xy 113.061185 -348.768986) (xy 113.0317 -348.814865)
			(xy 112.995987 -348.856081) (xy 112.954771 -348.891796) (xy 112.908893 -348.921281) (xy 112.859285 -348.943937)
			(xy 112.806958 -348.959303) (xy 112.752976 -348.967065) (xy 112.725708 -348.967552) (xy 111.862108 -348.967552)
			(xy 111.834836 -348.967109) (xy 111.780847 -348.959348) (xy 111.728512 -348.943982) (xy 111.678896 -348.921324)
			(xy 111.63301 -348.891836) (xy 111.591788 -348.856117) (xy 111.556069 -348.814896) (xy 111.52658 -348.769011)
			(xy 111.503921 -348.719396) (xy 111.488554 -348.667061) (xy 111.480792 -348.613072) (xy 93.706665 -348.613072)
			(xy 93.698905 -348.667045) (xy 93.683543 -348.71937) (xy 93.66089 -348.768976) (xy 93.631409 -348.814854)
			(xy 93.595699 -348.856069) (xy 93.554487 -348.891784) (xy 93.508613 -348.92127) (xy 93.459009 -348.943928)
			(xy 93.406686 -348.959296) (xy 93.352709 -348.967063) (xy 93.325442 -348.967552) (xy 92.461842 -348.967552)
			(xy 92.434568 -348.967111) (xy 92.380576 -348.959354) (xy 92.328236 -348.943991) (xy 92.278617 -348.921335)
			(xy 92.232727 -348.891848) (xy 92.1915 -348.856129) (xy 92.155777 -348.814907) (xy 92.126285 -348.76902)
			(xy 92.103624 -348.719403) (xy 92.088255 -348.667066) (xy 92.080492 -348.613074) (xy 90.597788 -348.613074)
			(xy 90.590026 -348.667058) (xy 90.574659 -348.719391) (xy 90.552001 -348.769004) (xy 90.522512 -348.814887)
			(xy 90.486794 -348.856107) (xy 90.445573 -348.891823) (xy 90.399688 -348.92131) (xy 90.350074 -348.943966)
			(xy 90.297741 -348.95933) (xy 90.243753 -348.96709) (xy 90.216482 -348.967552) (xy 89.352882 -348.967552)
			(xy 89.325613 -348.967084) (xy 89.27163 -348.95932) (xy 89.219301 -348.943953) (xy 89.169692 -348.921295)
			(xy 89.123812 -348.891808) (xy 89.082595 -348.856092) (xy 89.046881 -348.814874) (xy 89.017396 -348.768992)
			(xy 88.994741 -348.719382) (xy 88.979376 -348.667053) (xy 88.971614 -348.613069) (xy 87.488766 -348.613069)
			(xy 87.481005 -348.667048) (xy 87.465641 -348.719374) (xy 87.442987 -348.768982) (xy 87.413504 -348.81486)
			(xy 87.377792 -348.856076) (xy 87.336578 -348.891791) (xy 87.290701 -348.921276) (xy 87.241095 -348.943933)
			(xy 87.188769 -348.9593) (xy 87.13479 -348.967064) (xy 87.107522 -348.967552) (xy 86.243922 -348.967552)
			(xy 86.216649 -348.96711) (xy 86.162659 -348.95935) (xy 86.110322 -348.943985) (xy 86.060705 -348.921329)
			(xy 86.014817 -348.891841) (xy 85.973593 -348.856122) (xy 85.937872 -348.814901) (xy 85.908382 -348.769015)
			(xy 85.885722 -348.719399) (xy 85.870354 -348.667063) (xy 85.862592 -348.613073) (xy 84.379888 -348.613073)
			(xy 84.372126 -348.667061) (xy 84.356758 -348.719395) (xy 84.334098 -348.76901) (xy 84.304608 -348.814894)
			(xy 84.268887 -348.856114) (xy 84.227663 -348.89183) (xy 84.181776 -348.921316) (xy 84.13216 -348.943971)
			(xy 84.079824 -348.959334) (xy 84.025834 -348.967091) (xy 83.998562 -348.967552) (xy 83.134962 -348.967552)
			(xy 83.107694 -348.967083) (xy 83.053713 -348.959317) (xy 83.001386 -348.943948) (xy 82.95178 -348.921289)
			(xy 82.905902 -348.891801) (xy 82.864688 -348.856085) (xy 82.828976 -348.814867) (xy 82.799493 -348.768987)
			(xy 82.776839 -348.719378) (xy 82.761475 -348.66705) (xy 82.753714 -348.613068) (xy 81.270866 -348.613068)
			(xy 81.270866 -348.613069) (xy 81.263104 -348.667051) (xy 81.247739 -348.719379) (xy 81.225084 -348.768987)
			(xy 81.195599 -348.814867) (xy 81.159885 -348.856083) (xy 81.118669 -348.891798) (xy 81.072789 -348.921283)
			(xy 81.02318 -348.943939) (xy 80.970853 -348.959304) (xy 80.916871 -348.967065) (xy 80.889602 -348.967552)
			(xy 80.026002 -348.967552) (xy 79.99873 -348.967109) (xy 79.944742 -348.959347) (xy 79.892407 -348.94398)
			(xy 79.842793 -348.921322) (xy 79.796908 -348.891834) (xy 79.755686 -348.856115) (xy 79.719968 -348.814894)
			(xy 79.690479 -348.769009) (xy 79.667821 -348.719394) (xy 79.652454 -348.66706) (xy 79.644692 -348.613072)
			(xy 78.161865 -348.613072) (xy 78.154105 -348.667045) (xy 78.138743 -348.71937) (xy 78.11609 -348.768976)
			(xy 78.086609 -348.814854) (xy 78.050899 -348.856069) (xy 78.009687 -348.891784) (xy 77.963813 -348.92127)
			(xy 77.914209 -348.943928) (xy 77.861886 -348.959296) (xy 77.807909 -348.967063) (xy 77.780642 -348.967552)
			(xy 76.917042 -348.967552) (xy 76.889768 -348.967111) (xy 76.835776 -348.959354) (xy 76.783436 -348.943991)
			(xy 76.733817 -348.921335) (xy 76.687927 -348.891848) (xy 76.6467 -348.856129) (xy 76.610977 -348.814907)
			(xy 76.581485 -348.76902) (xy 76.558824 -348.719403) (xy 76.543455 -348.667066) (xy 76.535692 -348.613074)
			(xy 75.052988 -348.613074) (xy 75.045226 -348.667058) (xy 75.029859 -348.719391) (xy 75.007201 -348.769004)
			(xy 74.977712 -348.814887) (xy 74.941994 -348.856107) (xy 74.900773 -348.891823) (xy 74.854888 -348.92131)
			(xy 74.805274 -348.943966) (xy 74.752941 -348.95933) (xy 74.698953 -348.96709) (xy 74.671682 -348.967552)
			(xy 73.808082 -348.967552) (xy 73.780813 -348.967084) (xy 73.72683 -348.95932) (xy 73.674501 -348.943953)
			(xy 73.624892 -348.921295) (xy 73.579012 -348.891808) (xy 73.537795 -348.856092) (xy 73.502081 -348.814874)
			(xy 73.472596 -348.768992) (xy 73.449941 -348.719382) (xy 73.434576 -348.667053) (xy 73.426814 -348.613069)
			(xy 71.943966 -348.613069) (xy 71.936205 -348.667048) (xy 71.920841 -348.719374) (xy 71.898187 -348.768982)
			(xy 71.868704 -348.81486) (xy 71.832992 -348.856076) (xy 71.791778 -348.891791) (xy 71.745901 -348.921276)
			(xy 71.696295 -348.943933) (xy 71.643969 -348.9593) (xy 71.58999 -348.967064) (xy 71.562722 -348.967552)
			(xy 70.699122 -348.967552) (xy 70.671849 -348.96711) (xy 70.617859 -348.95935) (xy 70.565522 -348.943985)
			(xy 70.515905 -348.921329) (xy 70.470017 -348.891841) (xy 70.428793 -348.856122) (xy 70.393072 -348.814901)
			(xy 70.363582 -348.769015) (xy 70.340922 -348.719399) (xy 70.325554 -348.667063) (xy 70.317792 -348.613073)
			(xy 68.835088 -348.613073) (xy 68.827326 -348.667061) (xy 68.811958 -348.719395) (xy 68.789298 -348.76901)
			(xy 68.759808 -348.814894) (xy 68.724087 -348.856114) (xy 68.682863 -348.89183) (xy 68.636976 -348.921316)
			(xy 68.58736 -348.943971) (xy 68.535024 -348.959334) (xy 68.481034 -348.967091) (xy 68.453762 -348.967552)
			(xy 67.590162 -348.967552) (xy 67.562894 -348.967083) (xy 67.508913 -348.959317) (xy 67.456586 -348.943948)
			(xy 67.40698 -348.921289) (xy 67.361102 -348.891801) (xy 67.319888 -348.856085) (xy 67.284176 -348.814867)
			(xy 67.254693 -348.768987) (xy 67.232039 -348.719378) (xy 67.216675 -348.66705) (xy 67.208914 -348.613068)
			(xy 65.726066 -348.613068) (xy 65.726066 -348.613069) (xy 65.718304 -348.667051) (xy 65.702939 -348.719379)
			(xy 65.680284 -348.768987) (xy 65.650799 -348.814867) (xy 65.615085 -348.856083) (xy 65.573869 -348.891798)
			(xy 65.527989 -348.921283) (xy 65.47838 -348.943939) (xy 65.426053 -348.959304) (xy 65.372071 -348.967065)
			(xy 65.344802 -348.967552) (xy 64.481202 -348.967552) (xy 64.45393 -348.967109) (xy 64.399942 -348.959347)
			(xy 64.347607 -348.94398) (xy 64.297993 -348.921322) (xy 64.252108 -348.891834) (xy 64.210886 -348.856115)
			(xy 64.175168 -348.814894) (xy 64.145679 -348.769009) (xy 64.123021 -348.719394) (xy 64.107654 -348.66706)
			(xy 64.099892 -348.613072) (xy 62.617065 -348.613072) (xy 62.609305 -348.667045) (xy 62.593943 -348.71937)
			(xy 62.57129 -348.768976) (xy 62.541809 -348.814854) (xy 62.506099 -348.856069) (xy 62.464887 -348.891784)
			(xy 62.419013 -348.92127) (xy 62.369409 -348.943928) (xy 62.317086 -348.959296) (xy 62.263109 -348.967063)
			(xy 62.235842 -348.967552) (xy 61.372242 -348.967552) (xy 61.344968 -348.967111) (xy 61.290976 -348.959354)
			(xy 61.238636 -348.943991) (xy 61.189017 -348.921335) (xy 61.143127 -348.891848) (xy 61.1019 -348.856129)
			(xy 61.066177 -348.814907) (xy 61.036685 -348.76902) (xy 61.014024 -348.719403) (xy 60.998655 -348.667066)
			(xy 60.990892 -348.613074) (xy 51.666865 -348.613074) (xy 51.659106 -348.667044) (xy 51.643743 -348.719369)
			(xy 51.621091 -348.768974) (xy 51.59161 -348.814852) (xy 51.555901 -348.856067) (xy 51.51469 -348.891781)
			(xy 51.468817 -348.921268) (xy 51.419214 -348.943926) (xy 51.366891 -348.959295) (xy 51.312914 -348.967062)
			(xy 51.285648 -348.967552) (xy 50.422048 -348.967552) (xy 50.394774 -348.967112) (xy 50.340781 -348.959355)
			(xy 50.288441 -348.943992) (xy 50.23882 -348.921337) (xy 50.192929 -348.89185) (xy 50.151702 -348.856132)
			(xy 50.115979 -348.814909) (xy 50.086486 -348.769022) (xy 50.063824 -348.719404) (xy 50.048455 -348.667066)
			(xy 50.040692 -348.613074) (xy 48.557989 -348.613074) (xy 48.550226 -348.667057) (xy 48.53486 -348.71939)
			(xy 48.512202 -348.769002) (xy 48.482714 -348.814885) (xy 48.446996 -348.856105) (xy 48.405776 -348.891821)
			(xy 48.359892 -348.921308) (xy 48.310278 -348.943964) (xy 48.257946 -348.959329) (xy 48.203959 -348.967089)
			(xy 48.176688 -348.967552) (xy 47.313088 -348.967552) (xy 47.285818 -348.967085) (xy 47.231835 -348.959321)
			(xy 47.179505 -348.943955) (xy 47.129895 -348.921297) (xy 47.084015 -348.89181) (xy 47.042797 -348.856094)
			(xy 47.007083 -348.814876) (xy 46.977597 -348.768994) (xy 46.954941 -348.719383) (xy 46.939576 -348.667053)
			(xy 46.931814 -348.61307) (xy 45.448966 -348.61307) (xy 45.441205 -348.667047) (xy 45.425841 -348.719373)
			(xy 45.403188 -348.76898) (xy 45.373705 -348.814858) (xy 45.337994 -348.856074) (xy 45.296781 -348.891789)
			(xy 45.250905 -348.921274) (xy 45.201299 -348.943932) (xy 45.148975 -348.959299) (xy 45.094995 -348.967064)
			(xy 45.067728 -348.967552) (xy 44.204128 -348.967552) (xy 44.176855 -348.96711) (xy 44.122864 -348.959351)
			(xy 44.070526 -348.943987) (xy 44.020908 -348.92133) (xy 43.97502 -348.891843) (xy 43.933795 -348.856124)
			(xy 43.898074 -348.814903) (xy 43.868583 -348.769016) (xy 43.845923 -348.7194) (xy 43.830555 -348.667064)
			(xy 43.822792 -348.613073) (xy 42.340088 -348.613073) (xy 42.332326 -348.66706) (xy 42.316958 -348.719394)
			(xy 42.294299 -348.769008) (xy 42.264809 -348.814892) (xy 42.229089 -348.856112) (xy 42.187866 -348.891828)
			(xy 42.14198 -348.921314) (xy 42.092364 -348.943969) (xy 42.040029 -348.959332) (xy 41.98604 -348.967091)
			(xy 41.958768 -348.967552) (xy 41.095168 -348.967552) (xy 41.067899 -348.967083) (xy 41.013918 -348.959318)
			(xy 40.961591 -348.943949) (xy 40.911983 -348.921291) (xy 40.866105 -348.891803) (xy 40.82489 -348.856087)
			(xy 40.789178 -348.814869) (xy 40.759694 -348.768989) (xy 40.73704 -348.719379) (xy 40.721675 -348.667051)
			(xy 40.713914 -348.613069) (xy 39.231066 -348.613069) (xy 39.223304 -348.66705) (xy 39.20794 -348.719377)
			(xy 39.185285 -348.768986) (xy 39.1558 -348.814865) (xy 39.120087 -348.856081) (xy 39.078871 -348.891796)
			(xy 39.032993 -348.921281) (xy 38.983385 -348.943937) (xy 38.931058 -348.959303) (xy 38.877076 -348.967065)
			(xy 38.849808 -348.967552) (xy 37.986208 -348.967552) (xy 37.958936 -348.967109) (xy 37.904947 -348.959348)
			(xy 37.852612 -348.943982) (xy 37.802996 -348.921324) (xy 37.75711 -348.891836) (xy 37.715888 -348.856117)
			(xy 37.680169 -348.814896) (xy 37.65068 -348.769011) (xy 37.628021 -348.719396) (xy 37.612654 -348.667061)
			(xy 37.604892 -348.613072) (xy 36.122065 -348.613072) (xy 36.114306 -348.667044) (xy 36.098943 -348.719369)
			(xy 36.076291 -348.768974) (xy 36.04681 -348.814852) (xy 36.011101 -348.856067) (xy 35.96989 -348.891781)
			(xy 35.924017 -348.921268) (xy 35.874414 -348.943926) (xy 35.822091 -348.959295) (xy 35.768114 -348.967062)
			(xy 35.740848 -348.967552) (xy 34.877248 -348.967552) (xy 34.849974 -348.967112) (xy 34.795981 -348.959355)
			(xy 34.743641 -348.943992) (xy 34.69402 -348.921337) (xy 34.648129 -348.89185) (xy 34.606902 -348.856132)
			(xy 34.571179 -348.814909) (xy 34.541686 -348.769022) (xy 34.519024 -348.719404) (xy 34.503655 -348.667066)
			(xy 34.495892 -348.613074) (xy 33.013189 -348.613074) (xy 33.005426 -348.667057) (xy 32.99006 -348.71939)
			(xy 32.967402 -348.769002) (xy 32.937914 -348.814885) (xy 32.902196 -348.856105) (xy 32.860976 -348.891821)
			(xy 32.815092 -348.921308) (xy 32.765478 -348.943964) (xy 32.713146 -348.959329) (xy 32.659159 -348.967089)
			(xy 32.631888 -348.967552) (xy 31.768288 -348.967552) (xy 31.741018 -348.967085) (xy 31.687035 -348.959321)
			(xy 31.634705 -348.943955) (xy 31.585095 -348.921297) (xy 31.539215 -348.89181) (xy 31.497997 -348.856094)
			(xy 31.462283 -348.814876) (xy 31.432797 -348.768994) (xy 31.410141 -348.719383) (xy 31.394776 -348.667053)
			(xy 31.387014 -348.61307) (xy 29.904166 -348.61307) (xy 29.896405 -348.667047) (xy 29.881041 -348.719373)
			(xy 29.858388 -348.76898) (xy 29.828905 -348.814858) (xy 29.793194 -348.856074) (xy 29.751981 -348.891789)
			(xy 29.706105 -348.921274) (xy 29.656499 -348.943932) (xy 29.604175 -348.959299) (xy 29.550195 -348.967064)
			(xy 29.522928 -348.967552) (xy 28.659328 -348.967552) (xy 28.632055 -348.96711) (xy 28.578064 -348.959351)
			(xy 28.525726 -348.943987) (xy 28.476108 -348.92133) (xy 28.43022 -348.891843) (xy 28.388995 -348.856124)
			(xy 28.353274 -348.814903) (xy 28.323783 -348.769016) (xy 28.301123 -348.7194) (xy 28.285755 -348.667064)
			(xy 28.277992 -348.613073) (xy 26.795288 -348.613073) (xy 26.787526 -348.66706) (xy 26.772158 -348.719394)
			(xy 26.749499 -348.769008) (xy 26.720009 -348.814892) (xy 26.684289 -348.856112) (xy 26.643066 -348.891828)
			(xy 26.59718 -348.921314) (xy 26.547564 -348.943969) (xy 26.495229 -348.959332) (xy 26.44124 -348.967091)
			(xy 26.413968 -348.967552) (xy 25.550368 -348.967552) (xy 25.523099 -348.967083) (xy 25.469118 -348.959318)
			(xy 25.416791 -348.943949) (xy 25.367183 -348.921291) (xy 25.321305 -348.891803) (xy 25.28009 -348.856087)
			(xy 25.244378 -348.814869) (xy 25.214894 -348.768989) (xy 25.19224 -348.719379) (xy 25.176875 -348.667051)
			(xy 25.169114 -348.613069) (xy 23.686266 -348.613069) (xy 23.678504 -348.66705) (xy 23.66314 -348.719377)
			(xy 23.640485 -348.768986) (xy 23.611 -348.814865) (xy 23.575287 -348.856081) (xy 23.534071 -348.891796)
			(xy 23.488193 -348.921281) (xy 23.438585 -348.943937) (xy 23.386258 -348.959303) (xy 23.332276 -348.967065)
			(xy 23.305008 -348.967552) (xy 22.441408 -348.967552) (xy 22.414136 -348.967109) (xy 22.360147 -348.959348)
			(xy 22.307812 -348.943982) (xy 22.258196 -348.921324) (xy 22.21231 -348.891836) (xy 22.171088 -348.856117)
			(xy 22.135369 -348.814896) (xy 22.10588 -348.769011) (xy 22.083221 -348.719396) (xy 22.067854 -348.667061)
			(xy 22.060092 -348.613072) (xy 20.577347 -348.613072) (xy 20.569586 -348.667048) (xy 20.55422 -348.719381)
			(xy 20.531562 -348.768994) (xy 20.502074 -348.814878) (xy 20.466357 -348.856098) (xy 20.425136 -348.891816)
			(xy 20.379253 -348.921303) (xy 20.329639 -348.943961) (xy 20.277306 -348.959327) (xy 20.223319 -348.967089)
			(xy 20.196048 -348.967552) (xy 19.332448 -348.967552) (xy 19.305179 -348.967065) (xy 19.251195 -348.959304)
			(xy 19.198866 -348.943938) (xy 19.149256 -348.921282) (xy 19.103375 -348.891796) (xy 19.062158 -348.856081)
			(xy 19.026443 -348.814863) (xy 18.996957 -348.768982) (xy 18.974301 -348.719372) (xy 18.958936 -348.667043)
			(xy 18.951174 -348.613059) (xy 8.879169 -348.613059) (xy 8.892221 -348.718461) (xy 8.900171 -348.847356)
			(xy 8.900668 -348.911926) (xy 8.900171 -348.976496) (xy 8.892221 -349.105391) (xy 8.876351 -349.233551)
			(xy 8.852622 -349.360492) (xy 8.821123 -349.485731) (xy 8.781974 -349.608794) (xy 8.735323 -349.729213)
			(xy 8.681348 -349.846532) (xy 8.620253 -349.960306) (xy 8.55227 -350.070103) (xy 8.477656 -350.175506)
			(xy 8.396695 -350.276116) (xy 8.309695 -350.371551) (xy 8.216984 -350.46145) (xy 8.118914 -350.545471)
			(xy 8.015859 -350.623295) (xy 7.908208 -350.694627) (xy 7.796369 -350.759197) (xy 7.680768 -350.816759)
			(xy 7.561843 -350.867096) (xy 7.440044 -350.910016) (xy 7.315834 -350.945357) (xy 7.189685 -350.972984)
			(xy 7.062073 -350.992793) (xy 6.933484 -351.004709) (xy 6.804406 -351.008686) (xy 6.675328 -351.004709)
			(xy 6.546739 -350.992793) (xy 6.419127 -350.972984) (xy 6.292978 -350.945357) (xy 6.168768 -350.910016)
			(xy 6.046969 -350.867096) (xy 5.928044 -350.816759) (xy 5.812443 -350.759197) (xy 5.700604 -350.694627)
			(xy 5.592953 -350.623295) (xy 5.489898 -350.545471) (xy 5.391828 -350.46145) (xy 5.299117 -350.371551)
			(xy 5.212117 -350.276116) (xy 5.131156 -350.175506) (xy 5.056542 -350.070103) (xy 4.988559 -349.960306)
			(xy 4.927464 -349.846532) (xy 4.873489 -349.729213) (xy 4.826838 -349.608794) (xy 4.787689 -349.485731)
			(xy 4.75619 -349.360492) (xy 4.732461 -349.233551) (xy 4.716591 -349.105391) (xy 4.708641 -348.976496)
			(xy 0.508 -348.976496) (xy 0.508 -351.638709) (xy 18.951172 -351.638709) (xy 18.951172 -351.584171)
			(xy 18.958934 -351.530187) (xy 18.974299 -351.477857) (xy 18.996956 -351.428247) (xy 19.026441 -351.382366)
			(xy 19.062157 -351.341148) (xy 19.103374 -351.305433) (xy 19.149255 -351.275947) (xy 19.198865 -351.25329)
			(xy 19.251195 -351.237925) (xy 19.305179 -351.230163) (xy 19.332448 -351.229676) (xy 20.196048 -351.229676)
			(xy 20.223319 -351.230143) (xy 20.277306 -351.237905) (xy 20.329638 -351.253271) (xy 20.379252 -351.275929)
			(xy 20.425135 -351.305416) (xy 20.466355 -351.341133) (xy 20.502073 -351.382353) (xy 20.53156 -351.428237)
			(xy 20.554218 -351.47785) (xy 20.569584 -351.530182) (xy 20.577347 -351.584169) (xy 20.577347 -351.638669)
			(xy 22.060139 -351.638669) (xy 22.060139 -351.584131) (xy 22.067901 -351.530149) (xy 22.083266 -351.477821)
			(xy 22.105922 -351.428212) (xy 22.135407 -351.382333) (xy 22.171122 -351.341117) (xy 22.212339 -351.305403)
			(xy 22.258219 -351.275918) (xy 22.307829 -351.253263) (xy 22.360157 -351.237899) (xy 22.414139 -351.230139)
			(xy 22.441408 -351.229676) (xy 23.305008 -351.229676) (xy 23.33228 -351.230087) (xy 23.386268 -351.23785)
			(xy 23.438602 -351.253218) (xy 23.488216 -351.275877) (xy 23.5341 -351.305366) (xy 23.575321 -351.341085)
			(xy 23.611039 -351.382306) (xy 23.640527 -351.428191) (xy 23.663185 -351.477806) (xy 23.678551 -351.53014)
			(xy 23.686314 -351.584128) (xy 23.686314 -351.638665) (xy 25.169162 -351.638665) (xy 25.169162 -351.584135)
			(xy 25.176922 -351.530159) (xy 25.192284 -351.477838) (xy 25.214936 -351.428234) (xy 25.244416 -351.38236)
			(xy 25.280124 -351.341147) (xy 25.321334 -351.305435) (xy 25.367206 -351.275951) (xy 25.416808 -351.253296)
			(xy 25.469128 -351.237929) (xy 25.523103 -351.230165) (xy 25.550368 -351.229676) (xy 26.413968 -351.229676)
			(xy 26.441243 -351.230061) (xy 26.495239 -351.237821) (xy 26.547581 -351.253186) (xy 26.597203 -351.275844)
			(xy 26.643095 -351.305333) (xy 26.684323 -351.341054) (xy 26.720047 -351.382279) (xy 26.749541 -351.428169)
			(xy 26.772203 -351.477789) (xy 26.787573 -351.53013) (xy 26.795336 -351.584125) (xy 26.795336 -351.63867)
			(xy 28.278039 -351.63867) (xy 28.278039 -351.58413) (xy 28.285802 -351.530146) (xy 28.301168 -351.477817)
			(xy 28.323825 -351.428207) (xy 28.353312 -351.382326) (xy 28.389029 -351.341109) (xy 28.430249 -351.305396)
			(xy 28.476131 -351.275912) (xy 28.525743 -351.253258) (xy 28.578074 -351.237896) (xy 28.632058 -351.230137)
			(xy 28.659328 -351.229676) (xy 29.522928 -351.229676) (xy 29.550199 -351.230088) (xy 29.604185 -351.237854)
			(xy 29.656516 -351.253223) (xy 29.706128 -351.275883) (xy 29.75201 -351.305373) (xy 29.793228 -351.341092)
			(xy 29.828944 -351.382313) (xy 29.85843 -351.428197) (xy 29.881086 -351.47781) (xy 29.896452 -351.530143)
			(xy 29.904214 -351.584129) (xy 29.904214 -351.638666) (xy 31.387062 -351.638666) (xy 31.387062 -351.584134)
			(xy 31.394823 -351.530157) (xy 31.410186 -351.477833) (xy 31.432839 -351.428229) (xy 31.462321 -351.382353)
			(xy 31.498031 -351.34114) (xy 31.539243 -351.305428) (xy 31.585118 -351.275945) (xy 31.634722 -351.25329)
			(xy 31.687045 -351.237925) (xy 31.741022 -351.230163) (xy 31.768288 -351.229676) (xy 32.631888 -351.229676)
			(xy 32.659162 -351.230063) (xy 32.713156 -351.237824) (xy 32.765495 -351.253191) (xy 32.815115 -351.27585)
			(xy 32.861004 -351.30534) (xy 32.90223 -351.341061) (xy 32.937952 -351.382286) (xy 32.967444 -351.428175)
			(xy 32.990105 -351.477794) (xy 33.005473 -351.530132) (xy 33.013236 -351.584126) (xy 33.013236 -351.63867)
			(xy 34.49594 -351.63867) (xy 34.49594 -351.58413) (xy 34.503702 -351.530144) (xy 34.519069 -351.477812)
			(xy 34.541728 -351.428201) (xy 34.571217 -351.38232) (xy 34.606936 -351.341102) (xy 34.648158 -351.305388)
			(xy 34.694043 -351.275905) (xy 34.743658 -351.253253) (xy 34.795991 -351.237892) (xy 34.849977 -351.230136)
			(xy 34.877248 -351.229676) (xy 35.740848 -351.229676) (xy 35.768118 -351.23009) (xy 35.822102 -351.237858)
			(xy 35.874431 -351.253229) (xy 35.92404 -351.27589) (xy 35.969919 -351.30538) (xy 36.011135 -351.341099)
			(xy 36.046849 -351.382319) (xy 36.076333 -351.428203) (xy 36.098988 -351.477814) (xy 36.114352 -351.530145)
			(xy 36.122114 -351.58413) (xy 36.122114 -351.638669) (xy 37.604939 -351.638669) (xy 37.604939 -351.584131)
			(xy 37.612701 -351.530149) (xy 37.628066 -351.477821) (xy 37.650722 -351.428212) (xy 37.680207 -351.382333)
			(xy 37.715922 -351.341117) (xy 37.757139 -351.305403) (xy 37.803019 -351.275918) (xy 37.852629 -351.253263)
			(xy 37.904957 -351.237899) (xy 37.958939 -351.230139) (xy 37.986208 -351.229676) (xy 38.849808 -351.229676)
			(xy 38.87708 -351.230087) (xy 38.931068 -351.23785) (xy 38.983402 -351.253218) (xy 39.033016 -351.275877)
			(xy 39.0789 -351.305366) (xy 39.120121 -351.341085) (xy 39.155839 -351.382306) (xy 39.185327 -351.428191)
			(xy 39.207985 -351.477806) (xy 39.223351 -351.53014) (xy 39.231114 -351.584128) (xy 39.231114 -351.638665)
			(xy 40.713962 -351.638665) (xy 40.713962 -351.584135) (xy 40.721722 -351.530159) (xy 40.737084 -351.477838)
			(xy 40.759736 -351.428234) (xy 40.789216 -351.38236) (xy 40.824924 -351.341147) (xy 40.866134 -351.305435)
			(xy 40.912006 -351.275951) (xy 40.961608 -351.253296) (xy 41.013928 -351.237929) (xy 41.067903 -351.230165)
			(xy 41.095168 -351.229676) (xy 41.958768 -351.229676) (xy 41.986043 -351.230061) (xy 42.040039 -351.237821)
			(xy 42.092381 -351.253186) (xy 42.142003 -351.275844) (xy 42.187895 -351.305333) (xy 42.229123 -351.341054)
			(xy 42.264847 -351.382279) (xy 42.294341 -351.428169) (xy 42.317003 -351.477789) (xy 42.332373 -351.53013)
			(xy 42.340136 -351.584125) (xy 42.340136 -351.63867) (xy 43.822839 -351.63867) (xy 43.822839 -351.58413)
			(xy 43.830602 -351.530146) (xy 43.845968 -351.477817) (xy 43.868625 -351.428207) (xy 43.898112 -351.382326)
			(xy 43.933829 -351.341109) (xy 43.975049 -351.305396) (xy 44.020931 -351.275912) (xy 44.070543 -351.253258)
			(xy 44.122874 -351.237896) (xy 44.176858 -351.230137) (xy 44.204128 -351.229676) (xy 45.067728 -351.229676)
			(xy 45.094999 -351.230088) (xy 45.148985 -351.237854) (xy 45.201316 -351.253223) (xy 45.250928 -351.275883)
			(xy 45.29681 -351.305373) (xy 45.338028 -351.341092) (xy 45.373744 -351.382313) (xy 45.40323 -351.428197)
			(xy 45.425886 -351.47781) (xy 45.441252 -351.530143) (xy 45.449014 -351.584129) (xy 45.449014 -351.638666)
			(xy 46.931862 -351.638666) (xy 46.931862 -351.584134) (xy 46.939623 -351.530157) (xy 46.954986 -351.477833)
			(xy 46.977639 -351.428229) (xy 47.007121 -351.382353) (xy 47.042831 -351.34114) (xy 47.084043 -351.305428)
			(xy 47.129918 -351.275945) (xy 47.179522 -351.25329) (xy 47.231845 -351.237925) (xy 47.285822 -351.230163)
			(xy 47.313088 -351.229676) (xy 48.176688 -351.229676) (xy 48.203962 -351.230063) (xy 48.257956 -351.237824)
			(xy 48.310295 -351.253191) (xy 48.359915 -351.27585) (xy 48.405804 -351.30534) (xy 48.44703 -351.341061)
			(xy 48.482752 -351.382286) (xy 48.512244 -351.428175) (xy 48.534905 -351.477794) (xy 48.550273 -351.530132)
			(xy 48.558036 -351.584126) (xy 48.558036 -351.63867) (xy 50.04074 -351.63867) (xy 50.04074 -351.58413)
			(xy 50.048502 -351.530144) (xy 50.063869 -351.477812) (xy 50.086528 -351.428201) (xy 50.116017 -351.38232)
			(xy 50.151736 -351.341102) (xy 50.192958 -351.305388) (xy 50.238843 -351.275905) (xy 50.288458 -351.253253)
			(xy 50.340791 -351.237892) (xy 50.394777 -351.230136) (xy 50.422048 -351.229676) (xy 51.285648 -351.229676)
			(xy 51.312918 -351.23009) (xy 51.366902 -351.237858) (xy 51.419231 -351.253229) (xy 51.46884 -351.27589)
			(xy 51.514719 -351.30538) (xy 51.555935 -351.341099) (xy 51.591649 -351.382319) (xy 51.621133 -351.428203)
			(xy 51.643788 -351.477814) (xy 51.659152 -351.530145) (xy 51.666914 -351.58413) (xy 51.666914 -351.63867)
			(xy 60.99094 -351.63867) (xy 60.99094 -351.58413) (xy 60.998702 -351.530145) (xy 61.014069 -351.477814)
			(xy 61.036727 -351.428203) (xy 61.066216 -351.382322) (xy 61.101934 -351.341105) (xy 61.143155 -351.305391)
			(xy 61.18904 -351.275907) (xy 61.238653 -351.253254) (xy 61.290986 -351.237893) (xy 61.344972 -351.230137)
			(xy 61.372242 -351.229676) (xy 62.235842 -351.229676) (xy 62.263112 -351.230089) (xy 62.317097 -351.237857)
			(xy 62.369426 -351.253227) (xy 62.419036 -351.275888) (xy 62.464916 -351.305378) (xy 62.506133 -351.341097)
			(xy 62.541847 -351.382317) (xy 62.571332 -351.428201) (xy 62.593988 -351.477813) (xy 62.609352 -351.530145)
			(xy 62.617114 -351.58413) (xy 62.617114 -351.638668) (xy 64.099939 -351.638668) (xy 64.099939 -351.584132)
			(xy 64.107701 -351.53015) (xy 64.123066 -351.477822) (xy 64.145721 -351.428214) (xy 64.175206 -351.382335)
			(xy 64.21092 -351.341119) (xy 64.252136 -351.305405) (xy 64.298016 -351.27592) (xy 64.347624 -351.253265)
			(xy 64.399952 -351.2379) (xy 64.453934 -351.230139) (xy 64.481202 -351.229676) (xy 65.344802 -351.229676)
			(xy 65.372074 -351.230087) (xy 65.426063 -351.237849) (xy 65.478397 -351.253216) (xy 65.528012 -351.275875)
			(xy 65.573897 -351.305364) (xy 65.615119 -351.341083) (xy 65.650837 -351.382304) (xy 65.680326 -351.42819)
			(xy 65.702984 -351.477805) (xy 65.718351 -351.530139) (xy 65.726113 -351.584128) (xy 65.726113 -351.638665)
			(xy 67.208962 -351.638665) (xy 67.208962 -351.584135) (xy 67.216722 -351.53016) (xy 67.232084 -351.477839)
			(xy 67.254735 -351.428236) (xy 67.284215 -351.382362) (xy 67.319922 -351.341149) (xy 67.361131 -351.305437)
			(xy 67.407003 -351.275953) (xy 67.456603 -351.253297) (xy 67.508923 -351.23793) (xy 67.562897 -351.230165)
			(xy 67.590162 -351.229676) (xy 68.453762 -351.229676) (xy 68.481037 -351.230061) (xy 68.535034 -351.23782)
			(xy 68.587376 -351.253184) (xy 68.636999 -351.275842) (xy 68.682892 -351.305331) (xy 68.724121 -351.341052)
			(xy 68.759846 -351.382277) (xy 68.78934 -351.428167) (xy 68.812003 -351.477788) (xy 68.827372 -351.530129)
			(xy 68.835136 -351.584125) (xy 68.835136 -351.638669) (xy 70.317839 -351.638669) (xy 70.317839 -351.584131)
			(xy 70.325601 -351.530147) (xy 70.340967 -351.477818) (xy 70.363624 -351.428208) (xy 70.393111 -351.382328)
			(xy 70.428827 -351.341112) (xy 70.470046 -351.305398) (xy 70.515928 -351.275914) (xy 70.565539 -351.25326)
			(xy 70.617869 -351.237897) (xy 70.671853 -351.230138) (xy 70.699122 -351.229676) (xy 71.562722 -351.229676)
			(xy 71.589993 -351.230088) (xy 71.64398 -351.237853) (xy 71.696312 -351.253222) (xy 71.745924 -351.275881)
			(xy 71.791807 -351.305371) (xy 71.833026 -351.34109) (xy 71.868742 -351.382311) (xy 71.898229 -351.428195)
			(xy 71.920886 -351.477809) (xy 71.936252 -351.530142) (xy 71.944014 -351.584129) (xy 71.944014 -351.638666)
			(xy 73.426862 -351.638666) (xy 73.426862 -351.584134) (xy 73.434623 -351.530158) (xy 73.449986 -351.477835)
			(xy 73.472638 -351.428231) (xy 73.50212 -351.382355) (xy 73.537829 -351.341142) (xy 73.579041 -351.30543)
			(xy 73.624915 -351.275947) (xy 73.674518 -351.253292) (xy 73.72684 -351.237927) (xy 73.780816 -351.230164)
			(xy 73.808082 -351.229676) (xy 74.671682 -351.229676) (xy 74.698957 -351.230062) (xy 74.752951 -351.237823)
			(xy 74.805291 -351.253189) (xy 74.854911 -351.275848) (xy 74.900802 -351.305338) (xy 74.942028 -351.341059)
			(xy 74.977751 -351.382284) (xy 75.007243 -351.428173) (xy 75.029904 -351.477792) (xy 75.045273 -351.530132)
			(xy 75.053036 -351.584125) (xy 75.053036 -351.63867) (xy 76.53574 -351.63867) (xy 76.53574 -351.58413)
			(xy 76.543502 -351.530145) (xy 76.558869 -351.477814) (xy 76.581527 -351.428203) (xy 76.611016 -351.382322)
			(xy 76.646734 -351.341105) (xy 76.687955 -351.305391) (xy 76.73384 -351.275907) (xy 76.783453 -351.253254)
			(xy 76.835786 -351.237893) (xy 76.889772 -351.230137) (xy 76.917042 -351.229676) (xy 77.780642 -351.229676)
			(xy 77.807912 -351.230089) (xy 77.861897 -351.237857) (xy 77.914226 -351.253227) (xy 77.963836 -351.275888)
			(xy 78.009716 -351.305378) (xy 78.050933 -351.341097) (xy 78.086647 -351.382317) (xy 78.116132 -351.428201)
			(xy 78.138788 -351.477813) (xy 78.154152 -351.530145) (xy 78.161914 -351.58413) (xy 78.161914 -351.638668)
			(xy 79.644739 -351.638668) (xy 79.644739 -351.584132) (xy 79.652501 -351.53015) (xy 79.667866 -351.477822)
			(xy 79.690521 -351.428214) (xy 79.720006 -351.382335) (xy 79.75572 -351.341119) (xy 79.796936 -351.305405)
			(xy 79.842816 -351.27592) (xy 79.892424 -351.253265) (xy 79.944752 -351.2379) (xy 79.998734 -351.230139)
			(xy 80.026002 -351.229676) (xy 80.889602 -351.229676) (xy 80.916874 -351.230087) (xy 80.970863 -351.237849)
			(xy 81.023197 -351.253216) (xy 81.072812 -351.275875) (xy 81.118697 -351.305364) (xy 81.159919 -351.341083)
			(xy 81.195637 -351.382304) (xy 81.225126 -351.42819) (xy 81.247784 -351.477805) (xy 81.263151 -351.530139)
			(xy 81.270913 -351.584128) (xy 81.270913 -351.638665) (xy 82.753762 -351.638665) (xy 82.753762 -351.584135)
			(xy 82.761522 -351.53016) (xy 82.776884 -351.477839) (xy 82.799535 -351.428236) (xy 82.829015 -351.382362)
			(xy 82.864722 -351.341149) (xy 82.905931 -351.305437) (xy 82.951803 -351.275953) (xy 83.001403 -351.253297)
			(xy 83.053723 -351.23793) (xy 83.107697 -351.230165) (xy 83.134962 -351.229676) (xy 83.998562 -351.229676)
			(xy 84.025837 -351.230061) (xy 84.079834 -351.23782) (xy 84.132176 -351.253184) (xy 84.181799 -351.275842)
			(xy 84.227692 -351.305331) (xy 84.268921 -351.341052) (xy 84.304646 -351.382277) (xy 84.33414 -351.428167)
			(xy 84.356803 -351.477788) (xy 84.372172 -351.530129) (xy 84.379936 -351.584125) (xy 84.379936 -351.638669)
			(xy 85.862639 -351.638669) (xy 85.862639 -351.584131) (xy 85.870401 -351.530147) (xy 85.885767 -351.477818)
			(xy 85.908424 -351.428208) (xy 85.937911 -351.382328) (xy 85.973627 -351.341112) (xy 86.014846 -351.305398)
			(xy 86.060728 -351.275914) (xy 86.110339 -351.25326) (xy 86.162669 -351.237897) (xy 86.216653 -351.230138)
			(xy 86.243922 -351.229676) (xy 87.107522 -351.229676) (xy 87.134793 -351.230088) (xy 87.18878 -351.237853)
			(xy 87.241112 -351.253222) (xy 87.290724 -351.275881) (xy 87.336607 -351.305371) (xy 87.377826 -351.34109)
			(xy 87.413542 -351.382311) (xy 87.443029 -351.428195) (xy 87.465686 -351.477809) (xy 87.481052 -351.530142)
			(xy 87.488814 -351.584129) (xy 87.488814 -351.638666) (xy 88.971662 -351.638666) (xy 88.971662 -351.584134)
			(xy 88.979423 -351.530158) (xy 88.994786 -351.477835) (xy 89.017438 -351.428231) (xy 89.04692 -351.382355)
			(xy 89.082629 -351.341142) (xy 89.123841 -351.30543) (xy 89.169715 -351.275947) (xy 89.219318 -351.253292)
			(xy 89.27164 -351.237927) (xy 89.325616 -351.230164) (xy 89.352882 -351.229676) (xy 90.216482 -351.229676)
			(xy 90.243757 -351.230062) (xy 90.297751 -351.237823) (xy 90.350091 -351.253189) (xy 90.399711 -351.275848)
			(xy 90.445602 -351.305338) (xy 90.486828 -351.341059) (xy 90.522551 -351.382284) (xy 90.552043 -351.428173)
			(xy 90.574704 -351.477792) (xy 90.590073 -351.530132) (xy 90.597836 -351.584125) (xy 90.597836 -351.63867)
			(xy 92.08054 -351.63867) (xy 92.08054 -351.58413) (xy 92.088302 -351.530145) (xy 92.103669 -351.477814)
			(xy 92.126327 -351.428203) (xy 92.155816 -351.382322) (xy 92.191534 -351.341105) (xy 92.232755 -351.305391)
			(xy 92.27864 -351.275907) (xy 92.328253 -351.253254) (xy 92.380586 -351.237893) (xy 92.434572 -351.230137)
			(xy 92.461842 -351.229676) (xy 93.325442 -351.229676) (xy 93.352712 -351.230089) (xy 93.406697 -351.237857)
			(xy 93.459026 -351.253227) (xy 93.508636 -351.275888) (xy 93.554516 -351.305378) (xy 93.595733 -351.341097)
			(xy 93.631447 -351.382317) (xy 93.660932 -351.428201) (xy 93.683588 -351.477813) (xy 93.698952 -351.530145)
			(xy 93.706714 -351.58413) (xy 93.706714 -351.638669) (xy 111.480839 -351.638669) (xy 111.480839 -351.584131)
			(xy 111.488601 -351.530149) (xy 111.503966 -351.477821) (xy 111.526622 -351.428212) (xy 111.556107 -351.382333)
			(xy 111.591822 -351.341117) (xy 111.633039 -351.305403) (xy 111.678919 -351.275918) (xy 111.728529 -351.253263)
			(xy 111.780857 -351.237899) (xy 111.834839 -351.230139) (xy 111.862108 -351.229676) (xy 112.725708 -351.229676)
			(xy 112.75298 -351.230087) (xy 112.806968 -351.23785) (xy 112.859302 -351.253218) (xy 112.908916 -351.275877)
			(xy 112.9548 -351.305366) (xy 112.996021 -351.341085) (xy 113.031739 -351.382306) (xy 113.061227 -351.428191)
			(xy 113.083885 -351.477806) (xy 113.099251 -351.53014) (xy 113.107014 -351.584128) (xy 113.107014 -351.638665)
			(xy 114.589862 -351.638665) (xy 114.589862 -351.584135) (xy 114.597622 -351.530159) (xy 114.612984 -351.477838)
			(xy 114.635636 -351.428234) (xy 114.665116 -351.38236) (xy 114.700824 -351.341147) (xy 114.742034 -351.305435)
			(xy 114.787906 -351.275951) (xy 114.837508 -351.253296) (xy 114.889828 -351.237929) (xy 114.943803 -351.230165)
			(xy 114.971068 -351.229676) (xy 115.834668 -351.229676) (xy 115.861943 -351.230061) (xy 115.915939 -351.237821)
			(xy 115.968281 -351.253186) (xy 116.017903 -351.275844) (xy 116.063795 -351.305333) (xy 116.105023 -351.341054)
			(xy 116.140747 -351.382279) (xy 116.170241 -351.428169) (xy 116.192903 -351.477789) (xy 116.208273 -351.53013)
			(xy 116.216036 -351.584125) (xy 116.216036 -351.63867) (xy 117.698739 -351.63867) (xy 117.698739 -351.58413)
			(xy 117.706502 -351.530146) (xy 117.721868 -351.477817) (xy 117.744525 -351.428207) (xy 117.774012 -351.382326)
			(xy 117.809729 -351.341109) (xy 117.850949 -351.305396) (xy 117.896831 -351.275912) (xy 117.946443 -351.253258)
			(xy 117.998774 -351.237896) (xy 118.052758 -351.230137) (xy 118.080028 -351.229676) (xy 118.943628 -351.229676)
			(xy 118.970899 -351.230088) (xy 119.024885 -351.237854) (xy 119.077216 -351.253223) (xy 119.126828 -351.275883)
			(xy 119.17271 -351.305373) (xy 119.213928 -351.341092) (xy 119.249644 -351.382313) (xy 119.27913 -351.428197)
			(xy 119.301786 -351.47781) (xy 119.317152 -351.530143) (xy 119.324914 -351.584129) (xy 119.324914 -351.638666)
			(xy 120.807762 -351.638666) (xy 120.807762 -351.584134) (xy 120.815523 -351.530157) (xy 120.830886 -351.477833)
			(xy 120.853539 -351.428229) (xy 120.883021 -351.382353) (xy 120.918731 -351.34114) (xy 120.959943 -351.305428)
			(xy 121.005818 -351.275945) (xy 121.055422 -351.25329) (xy 121.107745 -351.237925) (xy 121.161722 -351.230163)
			(xy 121.188988 -351.229676) (xy 122.052588 -351.229676) (xy 122.079862 -351.230063) (xy 122.133856 -351.237824)
			(xy 122.186195 -351.253191) (xy 122.235815 -351.27585) (xy 122.281704 -351.30534) (xy 122.32293 -351.341061)
			(xy 122.358652 -351.382286) (xy 122.388144 -351.428175) (xy 122.410805 -351.477794) (xy 122.426173 -351.530132)
			(xy 122.433936 -351.584126) (xy 122.433936 -351.63867) (xy 123.91664 -351.63867) (xy 123.91664 -351.58413)
			(xy 123.924402 -351.530144) (xy 123.939769 -351.477812) (xy 123.962428 -351.428201) (xy 123.991917 -351.38232)
			(xy 124.027636 -351.341102) (xy 124.068858 -351.305388) (xy 124.114743 -351.275905) (xy 124.164358 -351.253253)
			(xy 124.216691 -351.237892) (xy 124.270677 -351.230136) (xy 124.297948 -351.229676) (xy 125.161548 -351.229676)
			(xy 125.188818 -351.23009) (xy 125.242802 -351.237858) (xy 125.295131 -351.253229) (xy 125.34474 -351.27589)
			(xy 125.390619 -351.30538) (xy 125.431835 -351.341099) (xy 125.467549 -351.382319) (xy 125.497033 -351.428203)
			(xy 125.519688 -351.477814) (xy 125.535052 -351.530145) (xy 125.542814 -351.58413) (xy 125.542814 -351.638669)
			(xy 127.025639 -351.638669) (xy 127.025639 -351.584131) (xy 127.033401 -351.530149) (xy 127.048766 -351.477821)
			(xy 127.071422 -351.428212) (xy 127.100907 -351.382333) (xy 127.136622 -351.341117) (xy 127.177839 -351.305403)
			(xy 127.223719 -351.275918) (xy 127.273329 -351.253263) (xy 127.325657 -351.237899) (xy 127.379639 -351.230139)
			(xy 127.406908 -351.229676) (xy 128.270508 -351.229676) (xy 128.29778 -351.230087) (xy 128.351768 -351.23785)
			(xy 128.404102 -351.253218) (xy 128.453716 -351.275877) (xy 128.4996 -351.305366) (xy 128.540821 -351.341085)
			(xy 128.576539 -351.382306) (xy 128.606027 -351.428191) (xy 128.628685 -351.477806) (xy 128.644051 -351.53014)
			(xy 128.651814 -351.584128) (xy 128.651814 -351.638665) (xy 130.134662 -351.638665) (xy 130.134662 -351.584135)
			(xy 130.142422 -351.530159) (xy 130.157784 -351.477838) (xy 130.180436 -351.428234) (xy 130.209916 -351.38236)
			(xy 130.245624 -351.341147) (xy 130.286834 -351.305435) (xy 130.332706 -351.275951) (xy 130.382308 -351.253296)
			(xy 130.434628 -351.237929) (xy 130.488603 -351.230165) (xy 130.515868 -351.229676) (xy 131.379468 -351.229676)
			(xy 131.406743 -351.230061) (xy 131.460739 -351.237821) (xy 131.513081 -351.253186) (xy 131.562703 -351.275844)
			(xy 131.608595 -351.305333) (xy 131.649823 -351.341054) (xy 131.685547 -351.382279) (xy 131.715041 -351.428169)
			(xy 131.737703 -351.477789) (xy 131.753073 -351.53013) (xy 131.760836 -351.584125) (xy 131.760836 -351.63867)
			(xy 133.243539 -351.63867) (xy 133.243539 -351.58413) (xy 133.251302 -351.530146) (xy 133.266668 -351.477817)
			(xy 133.289325 -351.428207) (xy 133.318812 -351.382326) (xy 133.354529 -351.341109) (xy 133.395749 -351.305396)
			(xy 133.441631 -351.275912) (xy 133.491243 -351.253258) (xy 133.543574 -351.237896) (xy 133.597558 -351.230137)
			(xy 133.624828 -351.229676) (xy 134.488428 -351.229676) (xy 134.515699 -351.230088) (xy 134.569685 -351.237854)
			(xy 134.622016 -351.253223) (xy 134.671628 -351.275883) (xy 134.71751 -351.305373) (xy 134.758728 -351.341092)
			(xy 134.794444 -351.382313) (xy 134.82393 -351.428197) (xy 134.846586 -351.47781) (xy 134.861952 -351.530143)
			(xy 134.869714 -351.584129) (xy 134.869714 -351.638666) (xy 136.352562 -351.638666) (xy 136.352562 -351.584134)
			(xy 136.360323 -351.530157) (xy 136.375686 -351.477833) (xy 136.398339 -351.428229) (xy 136.427821 -351.382353)
			(xy 136.463531 -351.34114) (xy 136.504743 -351.305428) (xy 136.550618 -351.275945) (xy 136.600222 -351.25329)
			(xy 136.652545 -351.237925) (xy 136.706522 -351.230163) (xy 136.733788 -351.229676) (xy 137.597388 -351.229676)
			(xy 137.624662 -351.230063) (xy 137.678656 -351.237824) (xy 137.730995 -351.253191) (xy 137.780615 -351.27585)
			(xy 137.826504 -351.30534) (xy 137.86773 -351.341061) (xy 137.903452 -351.382286) (xy 137.932944 -351.428175)
			(xy 137.955605 -351.477794) (xy 137.970973 -351.530132) (xy 137.978736 -351.584126) (xy 137.978736 -351.63867)
			(xy 139.46144 -351.63867) (xy 139.46144 -351.58413) (xy 139.469202 -351.530144) (xy 139.484569 -351.477812)
			(xy 139.507228 -351.428201) (xy 139.536717 -351.38232) (xy 139.572436 -351.341102) (xy 139.613658 -351.305388)
			(xy 139.659543 -351.275905) (xy 139.709158 -351.253253) (xy 139.761491 -351.237892) (xy 139.815477 -351.230136)
			(xy 139.842748 -351.229676) (xy 140.706348 -351.229676) (xy 140.733618 -351.23009) (xy 140.787602 -351.237858)
			(xy 140.839931 -351.253229) (xy 140.88954 -351.27589) (xy 140.935419 -351.30538) (xy 140.976635 -351.341099)
			(xy 141.012349 -351.382319) (xy 141.041833 -351.428203) (xy 141.064488 -351.477814) (xy 141.079852 -351.530145)
			(xy 141.087614 -351.58413) (xy 141.087614 -351.638669) (xy 142.570439 -351.638669) (xy 142.570439 -351.584131)
			(xy 142.578201 -351.530149) (xy 142.593566 -351.477821) (xy 142.616222 -351.428212) (xy 142.645707 -351.382333)
			(xy 142.681422 -351.341117) (xy 142.722639 -351.305403) (xy 142.768519 -351.275918) (xy 142.818129 -351.253263)
			(xy 142.870457 -351.237899) (xy 142.924439 -351.230139) (xy 142.951708 -351.229676) (xy 143.815308 -351.229676)
			(xy 143.84258 -351.230087) (xy 143.896568 -351.23785) (xy 143.948902 -351.253218) (xy 143.998516 -351.275877)
			(xy 144.0444 -351.305366) (xy 144.085621 -351.341085) (xy 144.121339 -351.382306) (xy 144.150827 -351.428191)
			(xy 144.173485 -351.477806) (xy 144.188851 -351.53014) (xy 144.196614 -351.584128) (xy 144.196614 -351.638669)
			(xy 161.804839 -351.638669) (xy 161.804839 -351.584131) (xy 161.812601 -351.530149) (xy 161.827966 -351.47782)
			(xy 161.850623 -351.428211) (xy 161.880108 -351.382331) (xy 161.915824 -351.341115) (xy 161.957041 -351.305401)
			(xy 162.002922 -351.275917) (xy 162.052531 -351.253262) (xy 162.10486 -351.237899) (xy 162.158843 -351.230139)
			(xy 162.186112 -351.229676) (xy 163.049712 -351.229676) (xy 163.076984 -351.230087) (xy 163.130971 -351.237851)
			(xy 163.183304 -351.253219) (xy 163.232918 -351.275878) (xy 163.278802 -351.305367) (xy 163.320022 -351.341086)
			(xy 163.35574 -351.382308) (xy 163.385228 -351.428192) (xy 163.407885 -351.477807) (xy 163.423251 -351.530141)
			(xy 163.431014 -351.584128) (xy 163.431014 -351.638665) (xy 164.913862 -351.638665) (xy 164.913862 -351.584135)
			(xy 164.921622 -351.530159) (xy 164.936985 -351.477837) (xy 164.959637 -351.428233) (xy 164.989117 -351.382358)
			(xy 165.024826 -351.341146) (xy 165.066036 -351.305434) (xy 165.111909 -351.27595) (xy 165.16151 -351.253295)
			(xy 165.213831 -351.237928) (xy 165.267807 -351.230164) (xy 165.295072 -351.229676) (xy 166.158672 -351.229676)
			(xy 166.185947 -351.230062) (xy 166.239942 -351.237821) (xy 166.292284 -351.253187) (xy 166.341905 -351.275845)
			(xy 166.387797 -351.305335) (xy 166.429024 -351.341056) (xy 166.464748 -351.382281) (xy 166.494242 -351.42817)
			(xy 166.516903 -351.47779) (xy 166.532273 -351.53013) (xy 166.540036 -351.584125) (xy 166.540036 -351.63867)
			(xy 168.022739 -351.63867) (xy 168.022739 -351.58413) (xy 168.030502 -351.530146) (xy 168.045868 -351.477816)
			(xy 168.068526 -351.428206) (xy 168.098013 -351.382325) (xy 168.133731 -351.341108) (xy 168.174951 -351.305394)
			(xy 168.220834 -351.27591) (xy 168.270446 -351.253257) (xy 168.322777 -351.237895) (xy 168.376762 -351.230137)
			(xy 168.404032 -351.229676) (xy 169.267632 -351.229676) (xy 169.294903 -351.230089) (xy 169.348888 -351.237855)
			(xy 169.401219 -351.253224) (xy 169.45083 -351.275885) (xy 169.496712 -351.305374) (xy 169.537929 -351.341093)
			(xy 169.573645 -351.382314) (xy 169.603131 -351.428198) (xy 169.625787 -351.477811) (xy 169.641152 -351.530143)
			(xy 169.648914 -351.584129) (xy 169.648914 -351.638666) (xy 171.131762 -351.638666) (xy 171.131762 -351.584134)
			(xy 171.139523 -351.530156) (xy 171.154886 -351.477832) (xy 171.17754 -351.428228) (xy 171.207022 -351.382352)
			(xy 171.242733 -351.341138) (xy 171.283945 -351.305427) (xy 171.329821 -351.275944) (xy 171.379425 -351.253289)
			(xy 171.431748 -351.237925) (xy 171.485726 -351.230163) (xy 171.512992 -351.229676) (xy 172.376592 -351.229676)
			(xy 172.403866 -351.230063) (xy 172.457859 -351.237825) (xy 172.510198 -351.253192) (xy 172.559817 -351.275851)
			(xy 172.605706 -351.305342) (xy 172.646932 -351.341063) (xy 172.682653 -351.382287) (xy 172.712145 -351.428176)
			(xy 172.734805 -351.477794) (xy 172.750173 -351.530133) (xy 172.757936 -351.584126) (xy 172.757936 -351.638664)
			(xy 174.240762 -351.638664) (xy 174.240762 -351.584136) (xy 174.248522 -351.530162) (xy 174.263883 -351.477841)
			(xy 174.286534 -351.428239) (xy 174.316012 -351.382365) (xy 174.351719 -351.341153) (xy 174.392926 -351.305441)
			(xy 174.438797 -351.275957) (xy 174.488396 -351.2533) (xy 174.540715 -351.237932) (xy 174.594688 -351.230166)
			(xy 174.621952 -351.229676) (xy 175.485552 -351.229676) (xy 175.512828 -351.23006) (xy 175.566825 -351.237818)
			(xy 175.619169 -351.253181) (xy 175.668793 -351.275838) (xy 175.714687 -351.305328) (xy 175.755917 -351.341049)
			(xy 175.791644 -351.382274) (xy 175.821139 -351.428165) (xy 175.843802 -351.477786) (xy 175.859172 -351.530128)
			(xy 175.866936 -351.584124) (xy 175.866936 -351.638669) (xy 177.349639 -351.638669) (xy 177.349639 -351.584131)
			(xy 177.357401 -351.530149) (xy 177.372766 -351.47782) (xy 177.395423 -351.428211) (xy 177.424908 -351.382331)
			(xy 177.460624 -351.341115) (xy 177.501841 -351.305401) (xy 177.547722 -351.275917) (xy 177.597331 -351.253262)
			(xy 177.64966 -351.237899) (xy 177.703643 -351.230139) (xy 177.730912 -351.229676) (xy 178.594512 -351.229676)
			(xy 178.621784 -351.230087) (xy 178.675771 -351.237851) (xy 178.728104 -351.253219) (xy 178.777718 -351.275878)
			(xy 178.823602 -351.305367) (xy 178.864822 -351.341086) (xy 178.90054 -351.382308) (xy 178.930028 -351.428192)
			(xy 178.952685 -351.477807) (xy 178.968051 -351.530141) (xy 178.975814 -351.584128) (xy 178.975814 -351.638665)
			(xy 180.458662 -351.638665) (xy 180.458662 -351.584135) (xy 180.466422 -351.530159) (xy 180.481785 -351.477837)
			(xy 180.504437 -351.428233) (xy 180.533917 -351.382358) (xy 180.569626 -351.341146) (xy 180.610836 -351.305434)
			(xy 180.656709 -351.27595) (xy 180.70631 -351.253295) (xy 180.758631 -351.237928) (xy 180.812607 -351.230164)
			(xy 180.839872 -351.229676) (xy 181.703472 -351.229676) (xy 181.730747 -351.230062) (xy 181.784742 -351.237821)
			(xy 181.837084 -351.253187) (xy 181.886705 -351.275845) (xy 181.932597 -351.305335) (xy 181.973824 -351.341056)
			(xy 182.009548 -351.382281) (xy 182.039042 -351.42817) (xy 182.061703 -351.47779) (xy 182.077073 -351.53013)
			(xy 182.084836 -351.584125) (xy 182.084836 -351.63867) (xy 183.567539 -351.63867) (xy 183.567539 -351.58413)
			(xy 183.575302 -351.530146) (xy 183.590668 -351.477816) (xy 183.613326 -351.428206) (xy 183.642813 -351.382325)
			(xy 183.678531 -351.341108) (xy 183.719751 -351.305394) (xy 183.765634 -351.27591) (xy 183.815246 -351.253257)
			(xy 183.867577 -351.237895) (xy 183.921562 -351.230137) (xy 183.948832 -351.229676) (xy 184.812432 -351.229676)
			(xy 184.839703 -351.230089) (xy 184.893688 -351.237855) (xy 184.946019 -351.253224) (xy 184.99563 -351.275885)
			(xy 185.041512 -351.305374) (xy 185.082729 -351.341093) (xy 185.118445 -351.382314) (xy 185.147931 -351.428198)
			(xy 185.170587 -351.477811) (xy 185.185952 -351.530143) (xy 185.193714 -351.584129) (xy 185.193714 -351.638666)
			(xy 186.676562 -351.638666) (xy 186.676562 -351.584134) (xy 186.684323 -351.530156) (xy 186.699686 -351.477832)
			(xy 186.72234 -351.428228) (xy 186.751822 -351.382352) (xy 186.787533 -351.341138) (xy 186.828745 -351.305427)
			(xy 186.874621 -351.275944) (xy 186.924225 -351.253289) (xy 186.976548 -351.237925) (xy 187.030526 -351.230163)
			(xy 187.057792 -351.229676) (xy 187.921392 -351.229676) (xy 187.948666 -351.230063) (xy 188.002659 -351.237825)
			(xy 188.054998 -351.253192) (xy 188.104617 -351.275851) (xy 188.150506 -351.305342) (xy 188.191732 -351.341063)
			(xy 188.227453 -351.382287) (xy 188.256945 -351.428176) (xy 188.279605 -351.477794) (xy 188.294973 -351.530133)
			(xy 188.302736 -351.584126) (xy 188.302736 -351.638664) (xy 189.785562 -351.638664) (xy 189.785562 -351.584136)
			(xy 189.793322 -351.530162) (xy 189.808683 -351.477841) (xy 189.831334 -351.428239) (xy 189.860812 -351.382365)
			(xy 189.896519 -351.341153) (xy 189.937726 -351.305441) (xy 189.983597 -351.275957) (xy 190.033196 -351.2533)
			(xy 190.085515 -351.237932) (xy 190.139488 -351.230166) (xy 190.166752 -351.229676) (xy 191.030352 -351.229676)
			(xy 191.057628 -351.23006) (xy 191.111625 -351.237818) (xy 191.163969 -351.253181) (xy 191.213593 -351.275838)
			(xy 191.259487 -351.305328) (xy 191.300717 -351.341049) (xy 191.336444 -351.382274) (xy 191.365939 -351.428165)
			(xy 191.388602 -351.477786) (xy 191.403972 -351.530128) (xy 191.411736 -351.584124) (xy 191.411736 -351.638669)
			(xy 192.894439 -351.638669) (xy 192.894439 -351.584131) (xy 192.902201 -351.530149) (xy 192.917566 -351.47782)
			(xy 192.940223 -351.428211) (xy 192.969708 -351.382331) (xy 193.005424 -351.341115) (xy 193.046641 -351.305401)
			(xy 193.092522 -351.275917) (xy 193.142131 -351.253262) (xy 193.19446 -351.237899) (xy 193.248443 -351.230139)
			(xy 193.275712 -351.229676) (xy 194.139312 -351.229676) (xy 194.166584 -351.230087) (xy 194.220571 -351.237851)
			(xy 194.272904 -351.253219) (xy 194.322518 -351.275878) (xy 194.368402 -351.305367) (xy 194.409622 -351.341086)
			(xy 194.44534 -351.382308) (xy 194.474828 -351.428192) (xy 194.497485 -351.477807) (xy 194.512851 -351.530141)
			(xy 194.520614 -351.584128) (xy 194.520614 -351.638668) (xy 267.515839 -351.638668) (xy 267.515839 -351.584132)
			(xy 267.523601 -351.53015) (xy 267.538966 -351.477822) (xy 267.561621 -351.428214) (xy 267.591106 -351.382335)
			(xy 267.62682 -351.341119) (xy 267.668036 -351.305405) (xy 267.713916 -351.27592) (xy 267.763524 -351.253265)
			(xy 267.815852 -351.2379) (xy 267.869834 -351.230139) (xy 267.897102 -351.229676) (xy 268.760702 -351.229676)
			(xy 268.787974 -351.230087) (xy 268.841963 -351.237849) (xy 268.894297 -351.253216) (xy 268.943912 -351.275875)
			(xy 268.989797 -351.305364) (xy 269.031019 -351.341083) (xy 269.066737 -351.382304) (xy 269.096226 -351.42819)
			(xy 269.118884 -351.477805) (xy 269.134251 -351.530139) (xy 269.142013 -351.584128) (xy 269.142013 -351.638665)
			(xy 270.624862 -351.638665) (xy 270.624862 -351.584135) (xy 270.632622 -351.53016) (xy 270.647984 -351.477839)
			(xy 270.670635 -351.428236) (xy 270.700115 -351.382362) (xy 270.735822 -351.341149) (xy 270.777031 -351.305437)
			(xy 270.822903 -351.275953) (xy 270.872503 -351.253297) (xy 270.924823 -351.23793) (xy 270.978797 -351.230165)
			(xy 271.006062 -351.229676) (xy 271.869662 -351.229676) (xy 271.896937 -351.230061) (xy 271.950934 -351.23782)
			(xy 272.003276 -351.253184) (xy 272.052899 -351.275842) (xy 272.098792 -351.305331) (xy 272.140021 -351.341052)
			(xy 272.175746 -351.382277) (xy 272.20524 -351.428167) (xy 272.227903 -351.477788) (xy 272.243272 -351.530129)
			(xy 272.251036 -351.584125) (xy 272.251036 -351.638669) (xy 273.733739 -351.638669) (xy 273.733739 -351.584131)
			(xy 273.741501 -351.530147) (xy 273.756867 -351.477818) (xy 273.779524 -351.428208) (xy 273.809011 -351.382328)
			(xy 273.844727 -351.341112) (xy 273.885946 -351.305398) (xy 273.931828 -351.275914) (xy 273.981439 -351.25326)
			(xy 274.033769 -351.237897) (xy 274.087753 -351.230138) (xy 274.115022 -351.229676) (xy 274.978622 -351.229676)
			(xy 275.005893 -351.230088) (xy 275.05988 -351.237853) (xy 275.112212 -351.253222) (xy 275.161824 -351.275881)
			(xy 275.207707 -351.305371) (xy 275.248926 -351.34109) (xy 275.284642 -351.382311) (xy 275.314129 -351.428195)
			(xy 275.336786 -351.477809) (xy 275.352152 -351.530142) (xy 275.359914 -351.584129) (xy 275.359914 -351.638666)
			(xy 276.842762 -351.638666) (xy 276.842762 -351.584134) (xy 276.850523 -351.530158) (xy 276.865886 -351.477835)
			(xy 276.888538 -351.428231) (xy 276.91802 -351.382355) (xy 276.953729 -351.341142) (xy 276.994941 -351.30543)
			(xy 277.040815 -351.275947) (xy 277.090418 -351.253292) (xy 277.14274 -351.237927) (xy 277.196716 -351.230164)
			(xy 277.223982 -351.229676) (xy 278.087582 -351.229676) (xy 278.114857 -351.230062) (xy 278.168851 -351.237823)
			(xy 278.221191 -351.253189) (xy 278.270811 -351.275848) (xy 278.316702 -351.305338) (xy 278.357928 -351.341059)
			(xy 278.393651 -351.382284) (xy 278.423143 -351.428173) (xy 278.445804 -351.477792) (xy 278.461173 -351.530132)
			(xy 278.468936 -351.584125) (xy 278.468936 -351.63867) (xy 279.95164 -351.63867) (xy 279.95164 -351.58413)
			(xy 279.959402 -351.530145) (xy 279.974769 -351.477814) (xy 279.997427 -351.428203) (xy 280.026916 -351.382322)
			(xy 280.062634 -351.341105) (xy 280.103855 -351.305391) (xy 280.14974 -351.275907) (xy 280.199353 -351.253254)
			(xy 280.251686 -351.237893) (xy 280.305672 -351.230137) (xy 280.332942 -351.229676) (xy 281.196542 -351.229676)
			(xy 281.223812 -351.230089) (xy 281.277797 -351.237857) (xy 281.330126 -351.253227) (xy 281.379736 -351.275888)
			(xy 281.425616 -351.305378) (xy 281.466833 -351.341097) (xy 281.502547 -351.382317) (xy 281.532032 -351.428201)
			(xy 281.554688 -351.477813) (xy 281.570052 -351.530145) (xy 281.577814 -351.58413) (xy 281.577814 -351.638668)
			(xy 283.060639 -351.638668) (xy 283.060639 -351.584132) (xy 283.068401 -351.53015) (xy 283.083766 -351.477822)
			(xy 283.106421 -351.428214) (xy 283.135906 -351.382335) (xy 283.17162 -351.341119) (xy 283.212836 -351.305405)
			(xy 283.258716 -351.27592) (xy 283.308324 -351.253265) (xy 283.360652 -351.2379) (xy 283.414634 -351.230139)
			(xy 283.441902 -351.229676) (xy 284.305502 -351.229676) (xy 284.332774 -351.230087) (xy 284.386763 -351.237849)
			(xy 284.439097 -351.253216) (xy 284.488712 -351.275875) (xy 284.534597 -351.305364) (xy 284.575819 -351.341083)
			(xy 284.611537 -351.382304) (xy 284.641026 -351.42819) (xy 284.663684 -351.477805) (xy 284.679051 -351.530139)
			(xy 284.686813 -351.584128) (xy 284.686813 -351.638665) (xy 286.169662 -351.638665) (xy 286.169662 -351.584135)
			(xy 286.177422 -351.53016) (xy 286.192784 -351.477839) (xy 286.215435 -351.428236) (xy 286.244915 -351.382362)
			(xy 286.280622 -351.341149) (xy 286.321831 -351.305437) (xy 286.367703 -351.275953) (xy 286.417303 -351.253297)
			(xy 286.469623 -351.23793) (xy 286.523597 -351.230165) (xy 286.550862 -351.229676) (xy 287.414462 -351.229676)
			(xy 287.441737 -351.230061) (xy 287.495734 -351.23782) (xy 287.548076 -351.253184) (xy 287.597699 -351.275842)
			(xy 287.643592 -351.305331) (xy 287.684821 -351.341052) (xy 287.720546 -351.382277) (xy 287.75004 -351.428167)
			(xy 287.772703 -351.477788) (xy 287.788072 -351.530129) (xy 287.795836 -351.584125) (xy 287.795836 -351.638669)
			(xy 289.278539 -351.638669) (xy 289.278539 -351.584131) (xy 289.286301 -351.530147) (xy 289.301667 -351.477818)
			(xy 289.324324 -351.428208) (xy 289.353811 -351.382328) (xy 289.389527 -351.341112) (xy 289.430746 -351.305398)
			(xy 289.476628 -351.275914) (xy 289.526239 -351.25326) (xy 289.578569 -351.237897) (xy 289.632553 -351.230138)
			(xy 289.659822 -351.229676) (xy 290.523422 -351.229676) (xy 290.550693 -351.230088) (xy 290.60468 -351.237853)
			(xy 290.657012 -351.253222) (xy 290.706624 -351.275881) (xy 290.752507 -351.305371) (xy 290.793726 -351.34109)
			(xy 290.829442 -351.382311) (xy 290.858929 -351.428195) (xy 290.881586 -351.477809) (xy 290.896952 -351.530142)
			(xy 290.904714 -351.584129) (xy 290.904714 -351.638666) (xy 292.387562 -351.638666) (xy 292.387562 -351.584134)
			(xy 292.395323 -351.530158) (xy 292.410686 -351.477835) (xy 292.433338 -351.428231) (xy 292.46282 -351.382355)
			(xy 292.498529 -351.341142) (xy 292.539741 -351.30543) (xy 292.585615 -351.275947) (xy 292.635218 -351.253292)
			(xy 292.68754 -351.237927) (xy 292.741516 -351.230164) (xy 292.768782 -351.229676) (xy 293.632382 -351.229676)
			(xy 293.659657 -351.230062) (xy 293.713651 -351.237823) (xy 293.765991 -351.253189) (xy 293.815611 -351.275848)
			(xy 293.861502 -351.305338) (xy 293.902728 -351.341059) (xy 293.938451 -351.382284) (xy 293.967943 -351.428173)
			(xy 293.990604 -351.477792) (xy 294.005973 -351.530132) (xy 294.013736 -351.584125) (xy 294.013736 -351.63867)
			(xy 295.49644 -351.63867) (xy 295.49644 -351.58413) (xy 295.504202 -351.530145) (xy 295.519569 -351.477814)
			(xy 295.542227 -351.428203) (xy 295.571716 -351.382322) (xy 295.607434 -351.341105) (xy 295.648655 -351.305391)
			(xy 295.69454 -351.275907) (xy 295.744153 -351.253254) (xy 295.796486 -351.237893) (xy 295.850472 -351.230137)
			(xy 295.877742 -351.229676) (xy 296.741342 -351.229676) (xy 296.768612 -351.230089) (xy 296.822597 -351.237857)
			(xy 296.874926 -351.253227) (xy 296.924536 -351.275888) (xy 296.970416 -351.305378) (xy 297.011633 -351.341097)
			(xy 297.047347 -351.382317) (xy 297.076832 -351.428201) (xy 297.099488 -351.477813) (xy 297.114852 -351.530145)
			(xy 297.122614 -351.58413) (xy 297.122614 -351.638668) (xy 298.605439 -351.638668) (xy 298.605439 -351.584132)
			(xy 298.613201 -351.53015) (xy 298.628566 -351.477822) (xy 298.651221 -351.428214) (xy 298.680706 -351.382335)
			(xy 298.71642 -351.341119) (xy 298.757636 -351.305405) (xy 298.803516 -351.27592) (xy 298.853124 -351.253265)
			(xy 298.905452 -351.2379) (xy 298.959434 -351.230139) (xy 298.986702 -351.229676) (xy 299.850302 -351.229676)
			(xy 299.877574 -351.230087) (xy 299.931563 -351.237849) (xy 299.983897 -351.253216) (xy 300.033512 -351.275875)
			(xy 300.079397 -351.305364) (xy 300.120619 -351.341083) (xy 300.156337 -351.382304) (xy 300.185826 -351.42819)
			(xy 300.208484 -351.477805) (xy 300.223851 -351.530139) (xy 300.231613 -351.584128) (xy 300.231613 -351.638668)
			(xy 312.121539 -351.638668) (xy 312.121539 -351.584132) (xy 312.129301 -351.53015) (xy 312.144666 -351.477822)
			(xy 312.167321 -351.428213) (xy 312.196807 -351.382334) (xy 312.232521 -351.341118) (xy 312.273737 -351.305404)
			(xy 312.319617 -351.27592) (xy 312.369226 -351.253264) (xy 312.421554 -351.2379) (xy 312.475536 -351.230139)
			(xy 312.502804 -351.229676) (xy 313.366404 -351.229676) (xy 313.393676 -351.230087) (xy 313.447664 -351.23785)
			(xy 313.499999 -351.253217) (xy 313.549613 -351.275876) (xy 313.595498 -351.305365) (xy 313.63672 -351.341083)
			(xy 313.672438 -351.382305) (xy 313.701926 -351.42819) (xy 313.724584 -351.477805) (xy 313.739951 -351.530139)
			(xy 313.747713 -351.584128) (xy 313.747713 -351.638665) (xy 315.230562 -351.638665) (xy 315.230562 -351.584135)
			(xy 315.238322 -351.53016) (xy 315.253684 -351.477838) (xy 315.276335 -351.428236) (xy 315.305815 -351.382361)
			(xy 315.341523 -351.341148) (xy 315.382732 -351.305437) (xy 315.428604 -351.275953) (xy 315.478205 -351.253297)
			(xy 315.530525 -351.23793) (xy 315.584499 -351.230165) (xy 315.611764 -351.229676) (xy 316.475364 -351.229676)
			(xy 316.502639 -351.230061) (xy 316.556636 -351.23782) (xy 316.608978 -351.253185) (xy 316.6586 -351.275842)
			(xy 316.704493 -351.305332) (xy 316.745722 -351.341053) (xy 316.781446 -351.382278) (xy 316.81094 -351.428168)
			(xy 316.833603 -351.477788) (xy 316.848972 -351.530129) (xy 316.856736 -351.584125) (xy 316.856736 -351.638669)
			(xy 318.339439 -351.638669) (xy 318.339439 -351.584131) (xy 318.347201 -351.530147) (xy 318.362567 -351.477818)
			(xy 318.385224 -351.428208) (xy 318.414711 -351.382328) (xy 318.450428 -351.341111) (xy 318.491647 -351.305397)
			(xy 318.537529 -351.275913) (xy 318.58714 -351.253259) (xy 318.63947 -351.237896) (xy 318.693455 -351.230138)
			(xy 318.720724 -351.229676) (xy 319.584324 -351.229676) (xy 319.611595 -351.230088) (xy 319.665581 -351.237853)
			(xy 319.717913 -351.253222) (xy 319.767525 -351.275882) (xy 319.813408 -351.305372) (xy 319.854627 -351.34109)
			(xy 319.890343 -351.382312) (xy 319.919829 -351.428196) (xy 319.942486 -351.477809) (xy 319.957852 -351.530142)
			(xy 319.965614 -351.584129) (xy 319.965614 -351.638666) (xy 321.448462 -351.638666) (xy 321.448462 -351.584134)
			(xy 321.456223 -351.530157) (xy 321.471586 -351.477834) (xy 321.494239 -351.42823) (xy 321.52372 -351.382354)
			(xy 321.55943 -351.341141) (xy 321.600642 -351.30543) (xy 321.646516 -351.275946) (xy 321.696119 -351.253291)
			(xy 321.748442 -351.237926) (xy 321.802418 -351.230163) (xy 321.829684 -351.229676) (xy 322.693284 -351.229676)
			(xy 322.720558 -351.230062) (xy 322.774552 -351.237824) (xy 322.826892 -351.25319) (xy 322.876512 -351.275849)
			(xy 322.922403 -351.305339) (xy 322.963629 -351.34106) (xy 322.999351 -351.382285) (xy 323.028843 -351.428174)
			(xy 323.051504 -351.477793) (xy 323.066873 -351.530132) (xy 323.074636 -351.584126) (xy 323.074636 -351.63867)
			(xy 324.55734 -351.63867) (xy 324.55734 -351.58413) (xy 324.565102 -351.530144) (xy 324.580469 -351.477813)
			(xy 324.603128 -351.428202) (xy 324.632616 -351.382321) (xy 324.668335 -351.341104) (xy 324.709556 -351.30539)
			(xy 324.755441 -351.275906) (xy 324.805055 -351.253254) (xy 324.857387 -351.237893) (xy 324.911374 -351.230136)
			(xy 324.938644 -351.229676) (xy 325.802244 -351.229676) (xy 325.829514 -351.23009) (xy 325.883498 -351.237857)
			(xy 325.935828 -351.253228) (xy 325.985437 -351.275889) (xy 326.031317 -351.305379) (xy 326.072534 -351.341097)
			(xy 326.108248 -351.382318) (xy 326.137732 -351.428201) (xy 326.160388 -351.477814) (xy 326.175752 -351.530145)
			(xy 326.183514 -351.58413) (xy 326.183514 -351.638668) (xy 327.666339 -351.638668) (xy 327.666339 -351.584132)
			(xy 327.674101 -351.53015) (xy 327.689466 -351.477822) (xy 327.712121 -351.428213) (xy 327.741607 -351.382334)
			(xy 327.777321 -351.341118) (xy 327.818537 -351.305404) (xy 327.864417 -351.27592) (xy 327.914026 -351.253264)
			(xy 327.966354 -351.2379) (xy 328.020336 -351.230139) (xy 328.047604 -351.229676) (xy 328.911204 -351.229676)
			(xy 328.938476 -351.230087) (xy 328.992464 -351.23785) (xy 329.044799 -351.253217) (xy 329.094413 -351.275876)
			(xy 329.140298 -351.305365) (xy 329.18152 -351.341083) (xy 329.217238 -351.382305) (xy 329.246726 -351.42819)
			(xy 329.269384 -351.477805) (xy 329.284751 -351.530139) (xy 329.292513 -351.584128) (xy 329.292513 -351.638665)
			(xy 330.775362 -351.638665) (xy 330.775362 -351.584135) (xy 330.783122 -351.53016) (xy 330.798484 -351.477838)
			(xy 330.821135 -351.428236) (xy 330.850615 -351.382361) (xy 330.886323 -351.341148) (xy 330.927532 -351.305437)
			(xy 330.973404 -351.275953) (xy 331.023005 -351.253297) (xy 331.075325 -351.23793) (xy 331.129299 -351.230165)
			(xy 331.156564 -351.229676) (xy 332.020164 -351.229676) (xy 332.047439 -351.230061) (xy 332.101436 -351.23782)
			(xy 332.153778 -351.253185) (xy 332.2034 -351.275842) (xy 332.249293 -351.305332) (xy 332.290522 -351.341053)
			(xy 332.326246 -351.382278) (xy 332.35574 -351.428168) (xy 332.378403 -351.477788) (xy 332.393772 -351.530129)
			(xy 332.401536 -351.584125) (xy 332.401536 -351.638669) (xy 333.884239 -351.638669) (xy 333.884239 -351.584131)
			(xy 333.892001 -351.530147) (xy 333.907367 -351.477818) (xy 333.930024 -351.428208) (xy 333.959511 -351.382328)
			(xy 333.995228 -351.341111) (xy 334.036447 -351.305397) (xy 334.082329 -351.275913) (xy 334.13194 -351.253259)
			(xy 334.18427 -351.237896) (xy 334.238255 -351.230138) (xy 334.265524 -351.229676) (xy 335.129124 -351.229676)
			(xy 335.156395 -351.230088) (xy 335.210381 -351.237853) (xy 335.262713 -351.253222) (xy 335.312325 -351.275882)
			(xy 335.358208 -351.305372) (xy 335.399427 -351.34109) (xy 335.435143 -351.382312) (xy 335.464629 -351.428196)
			(xy 335.487286 -351.477809) (xy 335.502652 -351.530142) (xy 335.510414 -351.584129) (xy 335.510414 -351.638666)
			(xy 336.993262 -351.638666) (xy 336.993262 -351.584134) (xy 337.001023 -351.530157) (xy 337.016386 -351.477834)
			(xy 337.039039 -351.42823) (xy 337.06852 -351.382354) (xy 337.10423 -351.341141) (xy 337.145442 -351.30543)
			(xy 337.191316 -351.275946) (xy 337.240919 -351.253291) (xy 337.293242 -351.237926) (xy 337.347218 -351.230163)
			(xy 337.374484 -351.229676) (xy 338.238084 -351.229676) (xy 338.265358 -351.230062) (xy 338.319352 -351.237824)
			(xy 338.371692 -351.25319) (xy 338.421312 -351.275849) (xy 338.467203 -351.305339) (xy 338.508429 -351.34106)
			(xy 338.544151 -351.382285) (xy 338.573643 -351.428174) (xy 338.596304 -351.477793) (xy 338.611673 -351.530132)
			(xy 338.619436 -351.584126) (xy 338.619436 -351.63867) (xy 340.10214 -351.63867) (xy 340.10214 -351.58413)
			(xy 340.109902 -351.530144) (xy 340.125269 -351.477813) (xy 340.147928 -351.428202) (xy 340.177416 -351.382321)
			(xy 340.213135 -351.341104) (xy 340.254356 -351.30539) (xy 340.300241 -351.275906) (xy 340.349855 -351.253254)
			(xy 340.402187 -351.237893) (xy 340.456174 -351.230136) (xy 340.483444 -351.229676) (xy 341.347044 -351.229676)
			(xy 341.374314 -351.23009) (xy 341.428298 -351.237857) (xy 341.480628 -351.253228) (xy 341.530237 -351.275889)
			(xy 341.576117 -351.305379) (xy 341.617334 -351.341097) (xy 341.653048 -351.382318) (xy 341.682532 -351.428201)
			(xy 341.705188 -351.477814) (xy 341.720552 -351.530145) (xy 341.728314 -351.58413) (xy 341.728314 -351.638668)
			(xy 343.211139 -351.638668) (xy 343.211139 -351.584132) (xy 343.218901 -351.53015) (xy 343.234266 -351.477822)
			(xy 343.256921 -351.428213) (xy 343.286407 -351.382334) (xy 343.322121 -351.341118) (xy 343.363337 -351.305404)
			(xy 343.409217 -351.27592) (xy 343.458826 -351.253264) (xy 343.511154 -351.2379) (xy 343.565136 -351.230139)
			(xy 343.592404 -351.229676) (xy 344.456004 -351.229676) (xy 344.483276 -351.230087) (xy 344.537264 -351.23785)
			(xy 344.589599 -351.253217) (xy 344.639213 -351.275876) (xy 344.685098 -351.305365) (xy 344.72632 -351.341083)
			(xy 344.762038 -351.382305) (xy 344.791526 -351.42819) (xy 344.814184 -351.477805) (xy 344.829551 -351.530139)
			(xy 344.837313 -351.584128) (xy 344.837313 -351.638666) (xy 370.806762 -351.638666) (xy 370.806762 -351.584134)
			(xy 370.814523 -351.530158) (xy 370.829885 -351.477835) (xy 370.852538 -351.428231) (xy 370.882019 -351.382356)
			(xy 370.917729 -351.341143) (xy 370.95894 -351.305431) (xy 371.004814 -351.275948) (xy 371.054416 -351.253292)
			(xy 371.106738 -351.237927) (xy 371.160714 -351.230164) (xy 371.18798 -351.229676) (xy 372.05158 -351.229676)
			(xy 372.078855 -351.230062) (xy 372.132849 -351.237823) (xy 372.185189 -351.253189) (xy 372.23481 -351.275848)
			(xy 372.280701 -351.305338) (xy 372.321927 -351.341059) (xy 372.35765 -351.382283) (xy 372.387143 -351.428172)
			(xy 372.409804 -351.477792) (xy 372.425173 -351.530131) (xy 372.432936 -351.584125) (xy 372.432936 -351.63867)
			(xy 373.91564 -351.63867) (xy 373.91564 -351.58413) (xy 373.923402 -351.530145) (xy 373.938769 -351.477814)
			(xy 373.961427 -351.428203) (xy 373.990915 -351.382322) (xy 374.026634 -351.341105) (xy 374.067854 -351.305391)
			(xy 374.113738 -351.275908) (xy 374.163352 -351.253255) (xy 374.215684 -351.237893) (xy 374.26967 -351.230137)
			(xy 374.29694 -351.229676) (xy 375.16054 -351.229676) (xy 375.18781 -351.230089) (xy 375.241795 -351.237856)
			(xy 375.294125 -351.253227) (xy 375.343735 -351.275887) (xy 375.389615 -351.305377) (xy 375.430832 -351.341096)
			(xy 375.466547 -351.382317) (xy 375.496032 -351.4282) (xy 375.518687 -351.477813) (xy 375.534052 -351.530144)
			(xy 375.541814 -351.58413) (xy 375.541814 -351.638667) (xy 377.024662 -351.638667) (xy 377.024662 -351.584133)
			(xy 377.032423 -351.530155) (xy 377.047787 -351.477831) (xy 377.070441 -351.428226) (xy 377.099924 -351.382349)
			(xy 377.135636 -351.341136) (xy 377.176849 -351.305424) (xy 377.222726 -351.275941) (xy 377.272331 -351.253287)
			(xy 377.324655 -351.237923) (xy 377.378633 -351.230162) (xy 377.4059 -351.229676) (xy 378.2695 -351.229676)
			(xy 378.296772 -351.230087) (xy 378.350761 -351.237849) (xy 378.403096 -351.253216) (xy 378.452711 -351.275874)
			(xy 378.498596 -351.305363) (xy 378.539818 -351.341082) (xy 378.575537 -351.382304) (xy 378.605026 -351.428189)
			(xy 378.627684 -351.477804) (xy 378.643051 -351.530139) (xy 378.650813 -351.584128) (xy 378.650813 -351.638665)
			(xy 380.133662 -351.638665) (xy 380.133662 -351.584135) (xy 380.141422 -351.53016) (xy 380.156784 -351.477839)
			(xy 380.179435 -351.428237) (xy 380.208914 -351.382362) (xy 380.244621 -351.34115) (xy 380.28583 -351.305438)
			(xy 380.331702 -351.275954) (xy 380.381302 -351.253298) (xy 380.433621 -351.237931) (xy 380.487595 -351.230165)
			(xy 380.51486 -351.229676) (xy 381.37846 -351.229676) (xy 381.405736 -351.230061) (xy 381.459732 -351.237819)
			(xy 381.512075 -351.253183) (xy 381.561698 -351.275841) (xy 381.607591 -351.30533) (xy 381.64882 -351.341051)
			(xy 381.684546 -351.382277) (xy 381.71404 -351.428167) (xy 381.736703 -351.477788) (xy 381.752072 -351.530129)
			(xy 381.759836 -351.584124) (xy 381.759836 -351.638669) (xy 383.242539 -351.638669) (xy 383.242539 -351.584131)
			(xy 383.250301 -351.530148) (xy 383.265667 -351.477818) (xy 383.288324 -351.428209) (xy 383.31781 -351.382329)
			(xy 383.353526 -351.341112) (xy 383.394745 -351.305398) (xy 383.440626 -351.275914) (xy 383.490237 -351.25326)
			(xy 383.542567 -351.237897) (xy 383.596551 -351.230138) (xy 383.62382 -351.229676) (xy 384.48742 -351.229676)
			(xy 384.514691 -351.230088) (xy 384.568678 -351.237853) (xy 384.62101 -351.253221) (xy 384.670623 -351.275881)
			(xy 384.716506 -351.30537) (xy 384.757725 -351.341089) (xy 384.793442 -351.38231) (xy 384.822929 -351.428195)
			(xy 384.845586 -351.477808) (xy 384.860952 -351.530142) (xy 384.868714 -351.584129) (xy 384.868714 -351.638666)
			(xy 386.351562 -351.638666) (xy 386.351562 -351.584134) (xy 386.359323 -351.530158) (xy 386.374685 -351.477835)
			(xy 386.397338 -351.428231) (xy 386.426819 -351.382356) (xy 386.462529 -351.341143) (xy 386.50374 -351.305431)
			(xy 386.549614 -351.275948) (xy 386.599216 -351.253292) (xy 386.651538 -351.237927) (xy 386.705514 -351.230164)
			(xy 386.73278 -351.229676) (xy 387.59638 -351.229676) (xy 387.623655 -351.230062) (xy 387.677649 -351.237823)
			(xy 387.729989 -351.253189) (xy 387.77961 -351.275848) (xy 387.825501 -351.305338) (xy 387.866727 -351.341059)
			(xy 387.90245 -351.382283) (xy 387.931943 -351.428172) (xy 387.954604 -351.477792) (xy 387.969973 -351.530131)
			(xy 387.977736 -351.584125) (xy 387.977736 -351.63867) (xy 389.46044 -351.63867) (xy 389.46044 -351.58413)
			(xy 389.468202 -351.530145) (xy 389.483569 -351.477814) (xy 389.506227 -351.428203) (xy 389.535715 -351.382322)
			(xy 389.571434 -351.341105) (xy 389.612654 -351.305391) (xy 389.658538 -351.275908) (xy 389.708152 -351.253255)
			(xy 389.760484 -351.237893) (xy 389.81447 -351.230137) (xy 389.84174 -351.229676) (xy 390.70534 -351.229676)
			(xy 390.73261 -351.230089) (xy 390.786595 -351.237856) (xy 390.838925 -351.253227) (xy 390.888535 -351.275887)
			(xy 390.934415 -351.305377) (xy 390.975632 -351.341096) (xy 391.011347 -351.382317) (xy 391.040832 -351.4282)
			(xy 391.063487 -351.477813) (xy 391.078852 -351.530144) (xy 391.086614 -351.58413) (xy 391.086614 -351.638667)
			(xy 392.569462 -351.638667) (xy 392.569462 -351.584133) (xy 392.577223 -351.530155) (xy 392.592587 -351.477831)
			(xy 392.615241 -351.428226) (xy 392.644724 -351.382349) (xy 392.680436 -351.341136) (xy 392.721649 -351.305424)
			(xy 392.767526 -351.275941) (xy 392.817131 -351.253287) (xy 392.869455 -351.237923) (xy 392.923433 -351.230162)
			(xy 392.9507 -351.229676) (xy 393.8143 -351.229676) (xy 393.841572 -351.230087) (xy 393.895561 -351.237849)
			(xy 393.947896 -351.253216) (xy 393.997511 -351.275874) (xy 394.043396 -351.305363) (xy 394.084618 -351.341082)
			(xy 394.120337 -351.382304) (xy 394.149826 -351.428189) (xy 394.172484 -351.477804) (xy 394.187851 -351.530139)
			(xy 394.195613 -351.584128) (xy 394.195613 -351.638665) (xy 395.678462 -351.638665) (xy 395.678462 -351.584135)
			(xy 395.686222 -351.53016) (xy 395.701584 -351.477839) (xy 395.724235 -351.428237) (xy 395.753714 -351.382362)
			(xy 395.789421 -351.34115) (xy 395.83063 -351.305438) (xy 395.876502 -351.275954) (xy 395.926102 -351.253298)
			(xy 395.978421 -351.237931) (xy 396.032395 -351.230165) (xy 396.05966 -351.229676) (xy 396.92326 -351.229676)
			(xy 396.950536 -351.230061) (xy 397.004532 -351.237819) (xy 397.056875 -351.253183) (xy 397.106498 -351.275841)
			(xy 397.152391 -351.30533) (xy 397.19362 -351.341051) (xy 397.229346 -351.382277) (xy 397.25884 -351.428167)
			(xy 397.281503 -351.477788) (xy 397.296872 -351.530129) (xy 397.304636 -351.584124) (xy 397.304636 -351.638669)
			(xy 398.787339 -351.638669) (xy 398.787339 -351.584131) (xy 398.795101 -351.530148) (xy 398.810467 -351.477818)
			(xy 398.833124 -351.428209) (xy 398.86261 -351.382329) (xy 398.898326 -351.341112) (xy 398.939545 -351.305398)
			(xy 398.985426 -351.275914) (xy 399.035037 -351.25326) (xy 399.087367 -351.237897) (xy 399.141351 -351.230138)
			(xy 399.16862 -351.229676) (xy 400.03222 -351.229676) (xy 400.059491 -351.230088) (xy 400.113478 -351.237853)
			(xy 400.16581 -351.253221) (xy 400.215423 -351.275881) (xy 400.261306 -351.30537) (xy 400.302525 -351.341089)
			(xy 400.338242 -351.38231) (xy 400.367729 -351.428195) (xy 400.390386 -351.477808) (xy 400.405752 -351.530142)
			(xy 400.413514 -351.584129) (xy 400.413514 -351.638666) (xy 401.896362 -351.638666) (xy 401.896362 -351.584134)
			(xy 401.904123 -351.530158) (xy 401.919485 -351.477835) (xy 401.942138 -351.428231) (xy 401.971619 -351.382356)
			(xy 402.007329 -351.341143) (xy 402.04854 -351.305431) (xy 402.094414 -351.275948) (xy 402.144016 -351.253292)
			(xy 402.196338 -351.237927) (xy 402.250314 -351.230164) (xy 402.27758 -351.229676) (xy 403.14118 -351.229676)
			(xy 403.168455 -351.230062) (xy 403.222449 -351.237823) (xy 403.274789 -351.253189) (xy 403.32441 -351.275848)
			(xy 403.370301 -351.305338) (xy 403.411527 -351.341059) (xy 403.44725 -351.382283) (xy 403.476743 -351.428172)
			(xy 403.499404 -351.477792) (xy 403.514773 -351.530131) (xy 403.522536 -351.584125) (xy 403.522536 -351.638666)
			(xy 408.913862 -351.638666) (xy 408.913862 -351.584134) (xy 408.921623 -351.530156) (xy 408.936986 -351.477832)
			(xy 408.95964 -351.428228) (xy 408.989122 -351.382352) (xy 409.024833 -351.341138) (xy 409.066045 -351.305427)
			(xy 409.111921 -351.275944) (xy 409.161525 -351.253289) (xy 409.213848 -351.237925) (xy 409.267826 -351.230163)
			(xy 409.295092 -351.229676) (xy 410.158692 -351.229676) (xy 410.185966 -351.230063) (xy 410.239959 -351.237825)
			(xy 410.292298 -351.253192) (xy 410.341917 -351.275851) (xy 410.387806 -351.305342) (xy 410.429032 -351.341063)
			(xy 410.464753 -351.382287) (xy 410.494245 -351.428176) (xy 410.516905 -351.477794) (xy 410.532273 -351.530133)
			(xy 410.540036 -351.584126) (xy 410.540036 -351.638664) (xy 412.022862 -351.638664) (xy 412.022862 -351.584136)
			(xy 412.030622 -351.530162) (xy 412.045983 -351.477841) (xy 412.068634 -351.428239) (xy 412.098112 -351.382365)
			(xy 412.133819 -351.341153) (xy 412.175026 -351.305441) (xy 412.220897 -351.275957) (xy 412.270496 -351.2533)
			(xy 412.322815 -351.237932) (xy 412.376788 -351.230166) (xy 412.404052 -351.229676) (xy 413.267652 -351.229676)
			(xy 413.294928 -351.23006) (xy 413.348925 -351.237818) (xy 413.401269 -351.253181) (xy 413.450893 -351.275838)
			(xy 413.496787 -351.305328) (xy 413.538017 -351.341049) (xy 413.573744 -351.382274) (xy 413.603239 -351.428165)
			(xy 413.625902 -351.477786) (xy 413.641272 -351.530128) (xy 413.649036 -351.584124) (xy 413.649036 -351.638669)
			(xy 415.131739 -351.638669) (xy 415.131739 -351.584131) (xy 415.139501 -351.530149) (xy 415.154866 -351.47782)
			(xy 415.177523 -351.428211) (xy 415.207008 -351.382331) (xy 415.242724 -351.341115) (xy 415.283941 -351.305401)
			(xy 415.329822 -351.275917) (xy 415.379431 -351.253262) (xy 415.43176 -351.237899) (xy 415.485743 -351.230139)
			(xy 415.513012 -351.229676) (xy 416.376612 -351.229676) (xy 416.403884 -351.230087) (xy 416.457871 -351.237851)
			(xy 416.510204 -351.253219) (xy 416.559818 -351.275878) (xy 416.605702 -351.305367) (xy 416.646922 -351.341086)
			(xy 416.68264 -351.382308) (xy 416.712128 -351.428192) (xy 416.734785 -351.477807) (xy 416.750151 -351.530141)
			(xy 416.757914 -351.584128) (xy 416.757914 -351.638665) (xy 418.240762 -351.638665) (xy 418.240762 -351.584135)
			(xy 418.248522 -351.530159) (xy 418.263885 -351.477837) (xy 418.286537 -351.428233) (xy 418.316017 -351.382358)
			(xy 418.351726 -351.341146) (xy 418.392936 -351.305434) (xy 418.438809 -351.27595) (xy 418.48841 -351.253295)
			(xy 418.540731 -351.237928) (xy 418.594707 -351.230164) (xy 418.621972 -351.229676) (xy 419.485572 -351.229676)
			(xy 419.512847 -351.230062) (xy 419.566842 -351.237821) (xy 419.619184 -351.253187) (xy 419.668805 -351.275845)
			(xy 419.714697 -351.305335) (xy 419.755924 -351.341056) (xy 419.791648 -351.382281) (xy 419.821142 -351.42817)
			(xy 419.843803 -351.47779) (xy 419.859173 -351.53013) (xy 419.866936 -351.584125) (xy 419.866936 -351.63867)
			(xy 421.349639 -351.63867) (xy 421.349639 -351.58413) (xy 421.357402 -351.530146) (xy 421.372768 -351.477816)
			(xy 421.395426 -351.428206) (xy 421.424913 -351.382325) (xy 421.460631 -351.341108) (xy 421.501851 -351.305394)
			(xy 421.547734 -351.27591) (xy 421.597346 -351.253257) (xy 421.649677 -351.237895) (xy 421.703662 -351.230137)
			(xy 421.730932 -351.229676) (xy 422.594532 -351.229676) (xy 422.621803 -351.230089) (xy 422.675788 -351.237855)
			(xy 422.728119 -351.253224) (xy 422.77773 -351.275885) (xy 422.823612 -351.305374) (xy 422.864829 -351.341093)
			(xy 422.900545 -351.382314) (xy 422.930031 -351.428198) (xy 422.952687 -351.477811) (xy 422.968052 -351.530143)
			(xy 422.975814 -351.584129) (xy 422.975814 -351.638666) (xy 424.458662 -351.638666) (xy 424.458662 -351.584134)
			(xy 424.466423 -351.530156) (xy 424.481786 -351.477832) (xy 424.50444 -351.428228) (xy 424.533922 -351.382352)
			(xy 424.569633 -351.341138) (xy 424.610845 -351.305427) (xy 424.656721 -351.275944) (xy 424.706325 -351.253289)
			(xy 424.758648 -351.237925) (xy 424.812626 -351.230163) (xy 424.839892 -351.229676) (xy 425.703492 -351.229676)
			(xy 425.730766 -351.230063) (xy 425.784759 -351.237825) (xy 425.837098 -351.253192) (xy 425.886717 -351.275851)
			(xy 425.932606 -351.305342) (xy 425.973832 -351.341063) (xy 426.009553 -351.382287) (xy 426.039045 -351.428176)
			(xy 426.061705 -351.477794) (xy 426.077073 -351.530133) (xy 426.084836 -351.584126) (xy 426.084836 -351.638664)
			(xy 427.567662 -351.638664) (xy 427.567662 -351.584136) (xy 427.575422 -351.530162) (xy 427.590783 -351.477841)
			(xy 427.613434 -351.428239) (xy 427.642912 -351.382365) (xy 427.678619 -351.341153) (xy 427.719826 -351.305441)
			(xy 427.765697 -351.275957) (xy 427.815296 -351.2533) (xy 427.867615 -351.237932) (xy 427.921588 -351.230166)
			(xy 427.948852 -351.229676) (xy 428.812452 -351.229676) (xy 428.839728 -351.23006) (xy 428.893725 -351.237818)
			(xy 428.946069 -351.253181) (xy 428.995693 -351.275838) (xy 429.041587 -351.305328) (xy 429.082817 -351.341049)
			(xy 429.118544 -351.382274) (xy 429.148039 -351.428165) (xy 429.170702 -351.477786) (xy 429.186072 -351.530128)
			(xy 429.193836 -351.584124) (xy 429.193836 -351.638669) (xy 430.676539 -351.638669) (xy 430.676539 -351.584131)
			(xy 430.684301 -351.530149) (xy 430.699666 -351.47782) (xy 430.722323 -351.428211) (xy 430.751808 -351.382331)
			(xy 430.787524 -351.341115) (xy 430.828741 -351.305401) (xy 430.874622 -351.275917) (xy 430.924231 -351.253262)
			(xy 430.97656 -351.237899) (xy 431.030543 -351.230139) (xy 431.057812 -351.229676) (xy 431.921412 -351.229676)
			(xy 431.948684 -351.230087) (xy 432.002671 -351.237851) (xy 432.055004 -351.253219) (xy 432.104618 -351.275878)
			(xy 432.150502 -351.305367) (xy 432.191722 -351.341086) (xy 432.22744 -351.382308) (xy 432.256928 -351.428192)
			(xy 432.279585 -351.477807) (xy 432.294951 -351.530141) (xy 432.302714 -351.584128) (xy 432.302714 -351.638665)
			(xy 433.785562 -351.638665) (xy 433.785562 -351.584135) (xy 433.793322 -351.530159) (xy 433.808685 -351.477837)
			(xy 433.831337 -351.428233) (xy 433.860817 -351.382358) (xy 433.896526 -351.341146) (xy 433.937736 -351.305434)
			(xy 433.983609 -351.27595) (xy 434.03321 -351.253295) (xy 434.085531 -351.237928) (xy 434.139507 -351.230164)
			(xy 434.166772 -351.229676) (xy 435.030372 -351.229676) (xy 435.057647 -351.230062) (xy 435.111642 -351.237821)
			(xy 435.163984 -351.253187) (xy 435.213605 -351.275845) (xy 435.259497 -351.305335) (xy 435.300724 -351.341056)
			(xy 435.336448 -351.382281) (xy 435.365942 -351.42817) (xy 435.388603 -351.47779) (xy 435.403973 -351.53013)
			(xy 435.411736 -351.584125) (xy 435.411736 -351.63867) (xy 436.894439 -351.63867) (xy 436.894439 -351.58413)
			(xy 436.902202 -351.530146) (xy 436.917568 -351.477816) (xy 436.940226 -351.428206) (xy 436.969713 -351.382325)
			(xy 437.005431 -351.341108) (xy 437.046651 -351.305394) (xy 437.092534 -351.27591) (xy 437.142146 -351.253257)
			(xy 437.194477 -351.237895) (xy 437.248462 -351.230137) (xy 437.275732 -351.229676) (xy 438.139332 -351.229676)
			(xy 438.166603 -351.230089) (xy 438.220588 -351.237855) (xy 438.272919 -351.253224) (xy 438.32253 -351.275885)
			(xy 438.368412 -351.305374) (xy 438.409629 -351.341093) (xy 438.445345 -351.382314) (xy 438.474831 -351.428198)
			(xy 438.497487 -351.477811) (xy 438.512852 -351.530143) (xy 438.520614 -351.584129) (xy 438.520614 -351.638666)
			(xy 440.003462 -351.638666) (xy 440.003462 -351.584134) (xy 440.011223 -351.530156) (xy 440.026586 -351.477832)
			(xy 440.04924 -351.428228) (xy 440.078722 -351.382352) (xy 440.114433 -351.341138) (xy 440.155645 -351.305427)
			(xy 440.201521 -351.275944) (xy 440.251125 -351.253289) (xy 440.303448 -351.237925) (xy 440.357426 -351.230163)
			(xy 440.384692 -351.229676) (xy 441.248292 -351.229676) (xy 441.275566 -351.230063) (xy 441.329559 -351.237825)
			(xy 441.381898 -351.253192) (xy 441.431517 -351.275851) (xy 441.477406 -351.305342) (xy 441.518632 -351.341063)
			(xy 441.554353 -351.382287) (xy 441.583845 -351.428176) (xy 441.606505 -351.477794) (xy 441.621873 -351.530133)
			(xy 441.629636 -351.584126) (xy 441.629636 -351.638674) (xy 441.621873 -351.692667) (xy 441.606505 -351.745006)
			(xy 441.583845 -351.794624) (xy 441.554353 -351.840513) (xy 441.518632 -351.881737) (xy 441.477406 -351.917458)
			(xy 441.431517 -351.946949) (xy 441.381898 -351.969608) (xy 441.329559 -351.984975) (xy 441.275566 -351.992737)
			(xy 441.248292 -351.9932) (xy 440.384692 -351.9932) (xy 440.357426 -351.992637) (xy 440.303448 -351.984875)
			(xy 440.251125 -351.969511) (xy 440.201521 -351.946856) (xy 440.155645 -351.917373) (xy 440.114433 -351.881662)
			(xy 440.078722 -351.840448) (xy 440.04924 -351.794572) (xy 440.026586 -351.744968) (xy 440.011223 -351.692644)
			(xy 440.003462 -351.638666) (xy 438.520614 -351.638666) (xy 438.520614 -351.638671) (xy 438.512852 -351.692657)
			(xy 438.497487 -351.744989) (xy 438.474831 -351.794602) (xy 438.445345 -351.840486) (xy 438.409629 -351.881707)
			(xy 438.368412 -351.917426) (xy 438.32253 -351.946915) (xy 438.272919 -351.969576) (xy 438.220588 -351.984945)
			(xy 438.166603 -351.992711) (xy 438.139332 -351.9932) (xy 437.275732 -351.9932) (xy 437.248462 -351.992663)
			(xy 437.194477 -351.984905) (xy 437.142146 -351.969543) (xy 437.092534 -351.94689) (xy 437.046651 -351.917406)
			(xy 437.005431 -351.881692) (xy 436.969713 -351.840475) (xy 436.940226 -351.794594) (xy 436.917568 -351.744984)
			(xy 436.902202 -351.692654) (xy 436.894439 -351.63867) (xy 435.411736 -351.63867) (xy 435.411736 -351.638675)
			(xy 435.403973 -351.69267) (xy 435.388603 -351.74501) (xy 435.365942 -351.79463) (xy 435.336448 -351.840519)
			(xy 435.300724 -351.881744) (xy 435.259497 -351.917465) (xy 435.213605 -351.946955) (xy 435.163984 -351.969613)
			(xy 435.111642 -351.984979) (xy 435.057647 -351.992738) (xy 435.030372 -351.9932) (xy 434.166772 -351.9932)
			(xy 434.139507 -351.992636) (xy 434.085531 -351.984872) (xy 434.03321 -351.969505) (xy 433.983609 -351.94685)
			(xy 433.937736 -351.917366) (xy 433.896526 -351.881654) (xy 433.860817 -351.840442) (xy 433.831337 -351.794567)
			(xy 433.808685 -351.744963) (xy 433.793322 -351.692641) (xy 433.785562 -351.638665) (xy 432.302714 -351.638665)
			(xy 432.302714 -351.638672) (xy 432.294951 -351.692659) (xy 432.279585 -351.744993) (xy 432.256928 -351.794608)
			(xy 432.22744 -351.840492) (xy 432.191722 -351.881714) (xy 432.150502 -351.917433) (xy 432.104618 -351.946922)
			(xy 432.055004 -351.969581) (xy 432.002671 -351.984949) (xy 431.948684 -351.992713) (xy 431.921412 -351.9932)
			(xy 431.057812 -351.9932) (xy 431.030543 -351.992661) (xy 430.97656 -351.984901) (xy 430.924231 -351.969538)
			(xy 430.874622 -351.946883) (xy 430.828741 -351.917399) (xy 430.787524 -351.881685) (xy 430.751808 -351.840469)
			(xy 430.722323 -351.794589) (xy 430.699666 -351.74498) (xy 430.684301 -351.692651) (xy 430.676539 -351.638669)
			(xy 429.193836 -351.638669) (xy 429.193836 -351.638676) (xy 429.186072 -351.692672) (xy 429.170702 -351.745014)
			(xy 429.148039 -351.794635) (xy 429.118544 -351.840526) (xy 429.082817 -351.881751) (xy 429.041587 -351.917472)
			(xy 428.995693 -351.946962) (xy 428.946069 -351.969619) (xy 428.893725 -351.984982) (xy 428.839728 -351.99274)
			(xy 428.812452 -351.9932) (xy 427.948852 -351.9932) (xy 427.921588 -351.992634) (xy 427.867615 -351.984868)
			(xy 427.815296 -351.9695) (xy 427.765697 -351.946843) (xy 427.719826 -351.917359) (xy 427.678619 -351.881647)
			(xy 427.642912 -351.840435) (xy 427.613434 -351.794561) (xy 427.590783 -351.744959) (xy 427.575422 -351.692639)
			(xy 427.567662 -351.638664) (xy 426.084836 -351.638664) (xy 426.084836 -351.638674) (xy 426.077073 -351.692667)
			(xy 426.061705 -351.745006) (xy 426.039045 -351.794624) (xy 426.009553 -351.840513) (xy 425.973832 -351.881737)
			(xy 425.932606 -351.917458) (xy 425.886717 -351.946949) (xy 425.837098 -351.969608) (xy 425.784759 -351.984975)
			(xy 425.730766 -351.992737) (xy 425.703492 -351.9932) (xy 424.839892 -351.9932) (xy 424.812626 -351.992637)
			(xy 424.758648 -351.984875) (xy 424.706325 -351.969511) (xy 424.656721 -351.946856) (xy 424.610845 -351.917373)
			(xy 424.569633 -351.881662) (xy 424.533922 -351.840448) (xy 424.50444 -351.794572) (xy 424.481786 -351.744968)
			(xy 424.466423 -351.692644) (xy 424.458662 -351.638666) (xy 422.975814 -351.638666) (xy 422.975814 -351.638671)
			(xy 422.968052 -351.692657) (xy 422.952687 -351.744989) (xy 422.930031 -351.794602) (xy 422.900545 -351.840486)
			(xy 422.864829 -351.881707) (xy 422.823612 -351.917426) (xy 422.77773 -351.946915) (xy 422.728119 -351.969576)
			(xy 422.675788 -351.984945) (xy 422.621803 -351.992711) (xy 422.594532 -351.9932) (xy 421.730932 -351.9932)
			(xy 421.703662 -351.992663) (xy 421.649677 -351.984905) (xy 421.597346 -351.969543) (xy 421.547734 -351.94689)
			(xy 421.501851 -351.917406) (xy 421.460631 -351.881692) (xy 421.424913 -351.840475) (xy 421.395426 -351.794594)
			(xy 421.372768 -351.744984) (xy 421.357402 -351.692654) (xy 421.349639 -351.63867) (xy 419.866936 -351.63867)
			(xy 419.866936 -351.638675) (xy 419.859173 -351.69267) (xy 419.843803 -351.74501) (xy 419.821142 -351.79463)
			(xy 419.791648 -351.840519) (xy 419.755924 -351.881744) (xy 419.714697 -351.917465) (xy 419.668805 -351.946955)
			(xy 419.619184 -351.969613) (xy 419.566842 -351.984979) (xy 419.512847 -351.992738) (xy 419.485572 -351.9932)
			(xy 418.621972 -351.9932) (xy 418.594707 -351.992636) (xy 418.540731 -351.984872) (xy 418.48841 -351.969505)
			(xy 418.438809 -351.94685) (xy 418.392936 -351.917366) (xy 418.351726 -351.881654) (xy 418.316017 -351.840442)
			(xy 418.286537 -351.794567) (xy 418.263885 -351.744963) (xy 418.248522 -351.692641) (xy 418.240762 -351.638665)
			(xy 416.757914 -351.638665) (xy 416.757914 -351.638672) (xy 416.750151 -351.692659) (xy 416.734785 -351.744993)
			(xy 416.712128 -351.794608) (xy 416.68264 -351.840492) (xy 416.646922 -351.881714) (xy 416.605702 -351.917433)
			(xy 416.559818 -351.946922) (xy 416.510204 -351.969581) (xy 416.457871 -351.984949) (xy 416.403884 -351.992713)
			(xy 416.376612 -351.9932) (xy 415.513012 -351.9932) (xy 415.485743 -351.992661) (xy 415.43176 -351.984901)
			(xy 415.379431 -351.969538) (xy 415.329822 -351.946883) (xy 415.283941 -351.917399) (xy 415.242724 -351.881685)
			(xy 415.207008 -351.840469) (xy 415.177523 -351.794589) (xy 415.154866 -351.74498) (xy 415.139501 -351.692651)
			(xy 415.131739 -351.638669) (xy 413.649036 -351.638669) (xy 413.649036 -351.638676) (xy 413.641272 -351.692672)
			(xy 413.625902 -351.745014) (xy 413.603239 -351.794635) (xy 413.573744 -351.840526) (xy 413.538017 -351.881751)
			(xy 413.496787 -351.917472) (xy 413.450893 -351.946962) (xy 413.401269 -351.969619) (xy 413.348925 -351.984982)
			(xy 413.294928 -351.99274) (xy 413.267652 -351.9932) (xy 412.404052 -351.9932) (xy 412.376788 -351.992634)
			(xy 412.322815 -351.984868) (xy 412.270496 -351.9695) (xy 412.220897 -351.946843) (xy 412.175026 -351.917359)
			(xy 412.133819 -351.881647) (xy 412.098112 -351.840435) (xy 412.068634 -351.794561) (xy 412.045983 -351.744959)
			(xy 412.030622 -351.692639) (xy 412.022862 -351.638664) (xy 410.540036 -351.638664) (xy 410.540036 -351.638674)
			(xy 410.532273 -351.692667) (xy 410.516905 -351.745006) (xy 410.494245 -351.794624) (xy 410.464753 -351.840513)
			(xy 410.429032 -351.881737) (xy 410.387806 -351.917458) (xy 410.341917 -351.946949) (xy 410.292298 -351.969608)
			(xy 410.239959 -351.984975) (xy 410.185966 -351.992737) (xy 410.158692 -351.9932) (xy 409.295092 -351.9932)
			(xy 409.267826 -351.992637) (xy 409.213848 -351.984875) (xy 409.161525 -351.969511) (xy 409.111921 -351.946856)
			(xy 409.066045 -351.917373) (xy 409.024833 -351.881662) (xy 408.989122 -351.840448) (xy 408.95964 -351.794572)
			(xy 408.936986 -351.744968) (xy 408.921623 -351.692644) (xy 408.913862 -351.638666) (xy 403.522536 -351.638666)
			(xy 403.522536 -351.638675) (xy 403.514773 -351.692669) (xy 403.499404 -351.745008) (xy 403.476743 -351.794628)
			(xy 403.44725 -351.840517) (xy 403.411527 -351.881741) (xy 403.370301 -351.917462) (xy 403.32441 -351.946952)
			(xy 403.274789 -351.969611) (xy 403.222449 -351.984977) (xy 403.168455 -351.992738) (xy 403.14118 -351.9932)
			(xy 402.27758 -351.9932) (xy 402.250314 -351.992636) (xy 402.196338 -351.984873) (xy 402.144016 -351.969508)
			(xy 402.094414 -351.946852) (xy 402.04854 -351.917369) (xy 402.007329 -351.881657) (xy 401.971619 -351.840444)
			(xy 401.942138 -351.794569) (xy 401.919485 -351.744965) (xy 401.904123 -351.692642) (xy 401.896362 -351.638666)
			(xy 400.413514 -351.638666) (xy 400.413514 -351.638671) (xy 400.405752 -351.692658) (xy 400.390386 -351.744992)
			(xy 400.367729 -351.794605) (xy 400.338242 -351.84049) (xy 400.302525 -351.881711) (xy 400.261306 -351.91743)
			(xy 400.215423 -351.946919) (xy 400.16581 -351.969579) (xy 400.113478 -351.984947) (xy 400.059491 -351.992712)
			(xy 400.03222 -351.9932) (xy 399.16862 -351.9932) (xy 399.141351 -351.992662) (xy 399.087367 -351.984903)
			(xy 399.035037 -351.96954) (xy 398.985426 -351.946886) (xy 398.939545 -351.917402) (xy 398.898326 -351.881688)
			(xy 398.86261 -351.840471) (xy 398.833124 -351.794591) (xy 398.810467 -351.744982) (xy 398.795101 -351.692652)
			(xy 398.787339 -351.638669) (xy 397.304636 -351.638669) (xy 397.304636 -351.638676) (xy 397.296872 -351.692671)
			(xy 397.281503 -351.745012) (xy 397.25884 -351.794633) (xy 397.229346 -351.840523) (xy 397.19362 -351.881749)
			(xy 397.152391 -351.91747) (xy 397.106498 -351.946959) (xy 397.056875 -351.969617) (xy 397.004532 -351.984981)
			(xy 396.950536 -351.992739) (xy 396.92326 -351.9932) (xy 396.05966 -351.9932) (xy 396.032395 -351.992635)
			(xy 395.978421 -351.984869) (xy 395.926102 -351.969502) (xy 395.876502 -351.946846) (xy 395.83063 -351.917362)
			(xy 395.789421 -351.88165) (xy 395.753714 -351.840438) (xy 395.724235 -351.794563) (xy 395.701584 -351.744961)
			(xy 395.686222 -351.69264) (xy 395.678462 -351.638665) (xy 394.195613 -351.638665) (xy 394.195613 -351.638672)
			(xy 394.187851 -351.692661) (xy 394.172484 -351.744996) (xy 394.149826 -351.794611) (xy 394.120337 -351.840496)
			(xy 394.084618 -351.881718) (xy 394.043396 -351.917437) (xy 393.997511 -351.946926) (xy 393.947896 -351.969584)
			(xy 393.895561 -351.984951) (xy 393.841572 -351.992713) (xy 393.8143 -351.9932) (xy 392.9507 -351.9932)
			(xy 392.923433 -351.992638) (xy 392.869455 -351.984877) (xy 392.817131 -351.969513) (xy 392.767526 -351.946859)
			(xy 392.721649 -351.917376) (xy 392.680436 -351.881664) (xy 392.644724 -351.840451) (xy 392.615241 -351.794574)
			(xy 392.592587 -351.744969) (xy 392.577223 -351.692645) (xy 392.569462 -351.638667) (xy 391.086614 -351.638667)
			(xy 391.086614 -351.63867) (xy 391.078852 -351.692656) (xy 391.063487 -351.744987) (xy 391.040832 -351.7946)
			(xy 391.011347 -351.840483) (xy 390.975632 -351.881704) (xy 390.934415 -351.917423) (xy 390.888535 -351.946913)
			(xy 390.838925 -351.969573) (xy 390.786595 -351.984944) (xy 390.73261 -351.992711) (xy 390.70534 -351.9932)
			(xy 389.84174 -351.9932) (xy 389.81447 -351.992663) (xy 389.760484 -351.984907) (xy 389.708152 -351.969545)
			(xy 389.658538 -351.946892) (xy 389.612654 -351.917409) (xy 389.571434 -351.881695) (xy 389.535715 -351.840478)
			(xy 389.506227 -351.794597) (xy 389.483569 -351.744986) (xy 389.468202 -351.692655) (xy 389.46044 -351.63867)
			(xy 387.977736 -351.63867) (xy 387.977736 -351.638675) (xy 387.969973 -351.692669) (xy 387.954604 -351.745008)
			(xy 387.931943 -351.794628) (xy 387.90245 -351.840517) (xy 387.866727 -351.881741) (xy 387.825501 -351.917462)
			(xy 387.77961 -351.946952) (xy 387.729989 -351.969611) (xy 387.677649 -351.984977) (xy 387.623655 -351.992738)
			(xy 387.59638 -351.9932) (xy 386.73278 -351.9932) (xy 386.705514 -351.992636) (xy 386.651538 -351.984873)
			(xy 386.599216 -351.969508) (xy 386.549614 -351.946852) (xy 386.50374 -351.917369) (xy 386.462529 -351.881657)
			(xy 386.426819 -351.840444) (xy 386.397338 -351.794569) (xy 386.374685 -351.744965) (xy 386.359323 -351.692642)
			(xy 386.351562 -351.638666) (xy 384.868714 -351.638666) (xy 384.868714 -351.638671) (xy 384.860952 -351.692658)
			(xy 384.845586 -351.744992) (xy 384.822929 -351.794605) (xy 384.793442 -351.84049) (xy 384.757725 -351.881711)
			(xy 384.716506 -351.91743) (xy 384.670623 -351.946919) (xy 384.62101 -351.969579) (xy 384.568678 -351.984947)
			(xy 384.514691 -351.992712) (xy 384.48742 -351.9932) (xy 383.62382 -351.9932) (xy 383.596551 -351.992662)
			(xy 383.542567 -351.984903) (xy 383.490237 -351.96954) (xy 383.440626 -351.946886) (xy 383.394745 -351.917402)
			(xy 383.353526 -351.881688) (xy 383.31781 -351.840471) (xy 383.288324 -351.794591) (xy 383.265667 -351.744982)
			(xy 383.250301 -351.692652) (xy 383.242539 -351.638669) (xy 381.759836 -351.638669) (xy 381.759836 -351.638676)
			(xy 381.752072 -351.692671) (xy 381.736703 -351.745012) (xy 381.71404 -351.794633) (xy 381.684546 -351.840523)
			(xy 381.64882 -351.881749) (xy 381.607591 -351.91747) (xy 381.561698 -351.946959) (xy 381.512075 -351.969617)
			(xy 381.459732 -351.984981) (xy 381.405736 -351.992739) (xy 381.37846 -351.9932) (xy 380.51486 -351.9932)
			(xy 380.487595 -351.992635) (xy 380.433621 -351.984869) (xy 380.381302 -351.969502) (xy 380.331702 -351.946846)
			(xy 380.28583 -351.917362) (xy 380.244621 -351.88165) (xy 380.208914 -351.840438) (xy 380.179435 -351.794563)
			(xy 380.156784 -351.744961) (xy 380.141422 -351.69264) (xy 380.133662 -351.638665) (xy 378.650813 -351.638665)
			(xy 378.650813 -351.638672) (xy 378.643051 -351.692661) (xy 378.627684 -351.744996) (xy 378.605026 -351.794611)
			(xy 378.575537 -351.840496) (xy 378.539818 -351.881718) (xy 378.498596 -351.917437) (xy 378.452711 -351.946926)
			(xy 378.403096 -351.969584) (xy 378.350761 -351.984951) (xy 378.296772 -351.992713) (xy 378.2695 -351.9932)
			(xy 377.4059 -351.9932) (xy 377.378633 -351.992638) (xy 377.324655 -351.984877) (xy 377.272331 -351.969513)
			(xy 377.222726 -351.946859) (xy 377.176849 -351.917376) (xy 377.135636 -351.881664) (xy 377.099924 -351.840451)
			(xy 377.070441 -351.794574) (xy 377.047787 -351.744969) (xy 377.032423 -351.692645) (xy 377.024662 -351.638667)
			(xy 375.541814 -351.638667) (xy 375.541814 -351.63867) (xy 375.534052 -351.692656) (xy 375.518687 -351.744987)
			(xy 375.496032 -351.7946) (xy 375.466547 -351.840483) (xy 375.430832 -351.881704) (xy 375.389615 -351.917423)
			(xy 375.343735 -351.946913) (xy 375.294125 -351.969573) (xy 375.241795 -351.984944) (xy 375.18781 -351.992711)
			(xy 375.16054 -351.9932) (xy 374.29694 -351.9932) (xy 374.26967 -351.992663) (xy 374.215684 -351.984907)
			(xy 374.163352 -351.969545) (xy 374.113738 -351.946892) (xy 374.067854 -351.917409) (xy 374.026634 -351.881695)
			(xy 373.990915 -351.840478) (xy 373.961427 -351.794597) (xy 373.938769 -351.744986) (xy 373.923402 -351.692655)
			(xy 373.91564 -351.63867) (xy 372.432936 -351.63867) (xy 372.432936 -351.638675) (xy 372.425173 -351.692669)
			(xy 372.409804 -351.745008) (xy 372.387143 -351.794628) (xy 372.35765 -351.840517) (xy 372.321927 -351.881741)
			(xy 372.280701 -351.917462) (xy 372.23481 -351.946952) (xy 372.185189 -351.969611) (xy 372.132849 -351.984977)
			(xy 372.078855 -351.992738) (xy 372.05158 -351.9932) (xy 371.18798 -351.9932) (xy 371.160714 -351.992636)
			(xy 371.106738 -351.984873) (xy 371.054416 -351.969508) (xy 371.004814 -351.946852) (xy 370.95894 -351.917369)
			(xy 370.917729 -351.881657) (xy 370.882019 -351.840444) (xy 370.852538 -351.794569) (xy 370.829885 -351.744965)
			(xy 370.814523 -351.692642) (xy 370.806762 -351.638666) (xy 344.837313 -351.638666) (xy 344.837313 -351.638672)
			(xy 344.829551 -351.692661) (xy 344.814184 -351.744995) (xy 344.791526 -351.79461) (xy 344.762038 -351.840495)
			(xy 344.726319 -351.881717) (xy 344.685098 -351.917435) (xy 344.639213 -351.946924) (xy 344.589599 -351.969583)
			(xy 344.537264 -351.98495) (xy 344.483276 -351.992713) (xy 344.456004 -351.9932) (xy 343.592404 -351.9932)
			(xy 343.565136 -351.992661) (xy 343.511154 -351.9849) (xy 343.458826 -351.969536) (xy 343.409217 -351.94688)
			(xy 343.363337 -351.917396) (xy 343.322121 -351.881682) (xy 343.286407 -351.840466) (xy 343.256921 -351.794587)
			(xy 343.234266 -351.744978) (xy 343.218901 -351.69265) (xy 343.211139 -351.638668) (xy 341.728314 -351.638668)
			(xy 341.728314 -351.63867) (xy 341.720552 -351.692655) (xy 341.705188 -351.744986) (xy 341.682532 -351.794599)
			(xy 341.653048 -351.840482) (xy 341.617334 -351.881703) (xy 341.576117 -351.917421) (xy 341.530237 -351.946911)
			(xy 341.480628 -351.969572) (xy 341.428298 -351.984943) (xy 341.374314 -351.99271) (xy 341.347044 -351.9932)
			(xy 340.483444 -351.9932) (xy 340.456174 -351.992664) (xy 340.402187 -351.984907) (xy 340.349855 -351.969546)
			(xy 340.300241 -351.946894) (xy 340.254356 -351.91741) (xy 340.213135 -351.881696) (xy 340.177416 -351.840479)
			(xy 340.147928 -351.794598) (xy 340.125269 -351.744987) (xy 340.109902 -351.692656) (xy 340.10214 -351.63867)
			(xy 338.619436 -351.63867) (xy 338.619436 -351.638674) (xy 338.611673 -351.692668) (xy 338.596304 -351.745007)
			(xy 338.573643 -351.794626) (xy 338.544151 -351.840515) (xy 338.508429 -351.88174) (xy 338.467203 -351.917461)
			(xy 338.421312 -351.946951) (xy 338.371692 -351.96961) (xy 338.319352 -351.984976) (xy 338.265358 -351.992738)
			(xy 338.238084 -351.9932) (xy 337.374484 -351.9932) (xy 337.347218 -351.992637) (xy 337.293242 -351.984874)
			(xy 337.240919 -351.969509) (xy 337.191316 -351.946854) (xy 337.145442 -351.91737) (xy 337.10423 -351.881659)
			(xy 337.06852 -351.840446) (xy 337.039039 -351.79457) (xy 337.016386 -351.744966) (xy 337.001023 -351.692643)
			(xy 336.993262 -351.638666) (xy 335.510414 -351.638666) (xy 335.510414 -351.638671) (xy 335.502652 -351.692658)
			(xy 335.487286 -351.744991) (xy 335.464629 -351.794604) (xy 335.435143 -351.840488) (xy 335.399427 -351.88171)
			(xy 335.358208 -351.917428) (xy 335.312325 -351.946918) (xy 335.262713 -351.969578) (xy 335.210381 -351.984947)
			(xy 335.156395 -351.992712) (xy 335.129124 -351.9932) (xy 334.265524 -351.9932) (xy 334.238255 -351.992662)
			(xy 334.18427 -351.984904) (xy 334.13194 -351.969541) (xy 334.082329 -351.946887) (xy 334.036447 -351.917403)
			(xy 333.995228 -351.881689) (xy 333.959511 -351.840472) (xy 333.930024 -351.794592) (xy 333.907367 -351.744982)
			(xy 333.892001 -351.692653) (xy 333.884239 -351.638669) (xy 332.401536 -351.638669) (xy 332.401536 -351.638675)
			(xy 332.393772 -351.692671) (xy 332.378403 -351.745011) (xy 332.35574 -351.794632) (xy 332.326246 -351.840522)
			(xy 332.290522 -351.881747) (xy 332.249293 -351.917468) (xy 332.2034 -351.946958) (xy 332.153778 -351.969615)
			(xy 332.101436 -351.98498) (xy 332.047439 -351.992739) (xy 332.020164 -351.9932) (xy 331.156564 -351.9932)
			(xy 331.129299 -351.992635) (xy 331.075325 -351.98487) (xy 331.023005 -351.969503) (xy 330.973404 -351.946847)
			(xy 330.927532 -351.917363) (xy 330.886323 -351.881652) (xy 330.850615 -351.840439) (xy 330.821136 -351.794564)
			(xy 330.798484 -351.744962) (xy 330.783122 -351.69264) (xy 330.775362 -351.638665) (xy 329.292513 -351.638665)
			(xy 329.292513 -351.638672) (xy 329.284751 -351.692661) (xy 329.269384 -351.744995) (xy 329.246726 -351.79461)
			(xy 329.217238 -351.840495) (xy 329.181519 -351.881717) (xy 329.140298 -351.917435) (xy 329.094413 -351.946924)
			(xy 329.044799 -351.969583) (xy 328.992464 -351.98495) (xy 328.938476 -351.992713) (xy 328.911204 -351.9932)
			(xy 328.047604 -351.9932) (xy 328.020336 -351.992661) (xy 327.966354 -351.9849) (xy 327.914026 -351.969536)
			(xy 327.864417 -351.94688) (xy 327.818537 -351.917396) (xy 327.777321 -351.881682) (xy 327.741607 -351.840466)
			(xy 327.712121 -351.794587) (xy 327.689466 -351.744978) (xy 327.674101 -351.69265) (xy 327.666339 -351.638668)
			(xy 326.183514 -351.638668) (xy 326.183514 -351.63867) (xy 326.175752 -351.692655) (xy 326.160388 -351.744986)
			(xy 326.137732 -351.794599) (xy 326.108248 -351.840482) (xy 326.072534 -351.881703) (xy 326.031317 -351.917421)
			(xy 325.985437 -351.946911) (xy 325.935828 -351.969572) (xy 325.883498 -351.984943) (xy 325.829514 -351.99271)
			(xy 325.802244 -351.9932) (xy 324.938644 -351.9932) (xy 324.911374 -351.992664) (xy 324.857387 -351.984907)
			(xy 324.805055 -351.969546) (xy 324.755441 -351.946894) (xy 324.709556 -351.91741) (xy 324.668335 -351.881696)
			(xy 324.632616 -351.840479) (xy 324.603128 -351.794598) (xy 324.580469 -351.744987) (xy 324.565102 -351.692656)
			(xy 324.55734 -351.63867) (xy 323.074636 -351.63867) (xy 323.074636 -351.638674) (xy 323.066873 -351.692668)
			(xy 323.051504 -351.745007) (xy 323.028843 -351.794626) (xy 322.999351 -351.840515) (xy 322.963629 -351.88174)
			(xy 322.922403 -351.917461) (xy 322.876512 -351.946951) (xy 322.826892 -351.96961) (xy 322.774552 -351.984976)
			(xy 322.720558 -351.992738) (xy 322.693284 -351.9932) (xy 321.829684 -351.9932) (xy 321.802418 -351.992637)
			(xy 321.748442 -351.984874) (xy 321.696119 -351.969509) (xy 321.646516 -351.946854) (xy 321.600642 -351.91737)
			(xy 321.55943 -351.881659) (xy 321.52372 -351.840446) (xy 321.494239 -351.79457) (xy 321.471586 -351.744966)
			(xy 321.456223 -351.692643) (xy 321.448462 -351.638666) (xy 319.965614 -351.638666) (xy 319.965614 -351.638671)
			(xy 319.957852 -351.692658) (xy 319.942486 -351.744991) (xy 319.919829 -351.794604) (xy 319.890343 -351.840488)
			(xy 319.854627 -351.88171) (xy 319.813408 -351.917428) (xy 319.767525 -351.946918) (xy 319.717913 -351.969578)
			(xy 319.665581 -351.984947) (xy 319.611595 -351.992712) (xy 319.584324 -351.9932) (xy 318.720724 -351.9932)
			(xy 318.693455 -351.992662) (xy 318.63947 -351.984904) (xy 318.58714 -351.969541) (xy 318.537529 -351.946887)
			(xy 318.491647 -351.917403) (xy 318.450428 -351.881689) (xy 318.414711 -351.840472) (xy 318.385224 -351.794592)
			(xy 318.362567 -351.744982) (xy 318.347201 -351.692653) (xy 318.339439 -351.638669) (xy 316.856736 -351.638669)
			(xy 316.856736 -351.638675) (xy 316.848972 -351.692671) (xy 316.833603 -351.745011) (xy 316.81094 -351.794632)
			(xy 316.781446 -351.840522) (xy 316.745722 -351.881747) (xy 316.704493 -351.917468) (xy 316.6586 -351.946958)
			(xy 316.608978 -351.969615) (xy 316.556636 -351.98498) (xy 316.502639 -351.992739) (xy 316.475364 -351.9932)
			(xy 315.611764 -351.9932) (xy 315.584499 -351.992635) (xy 315.530525 -351.98487) (xy 315.478205 -351.969503)
			(xy 315.428604 -351.946847) (xy 315.382732 -351.917363) (xy 315.341523 -351.881652) (xy 315.305815 -351.840439)
			(xy 315.276336 -351.794564) (xy 315.253684 -351.744962) (xy 315.238322 -351.69264) (xy 315.230562 -351.638665)
			(xy 313.747713 -351.638665) (xy 313.747713 -351.638672) (xy 313.739951 -351.692661) (xy 313.724584 -351.744995)
			(xy 313.701926 -351.79461) (xy 313.672438 -351.840495) (xy 313.636719 -351.881717) (xy 313.595498 -351.917435)
			(xy 313.549613 -351.946924) (xy 313.499999 -351.969583) (xy 313.447664 -351.98495) (xy 313.393676 -351.992713)
			(xy 313.366404 -351.9932) (xy 312.502804 -351.9932) (xy 312.475536 -351.992661) (xy 312.421554 -351.9849)
			(xy 312.369226 -351.969536) (xy 312.319617 -351.94688) (xy 312.273737 -351.917396) (xy 312.232521 -351.881682)
			(xy 312.196807 -351.840466) (xy 312.167321 -351.794587) (xy 312.144666 -351.744978) (xy 312.129301 -351.69265)
			(xy 312.121539 -351.638668) (xy 300.231613 -351.638668) (xy 300.231613 -351.638672) (xy 300.223851 -351.692661)
			(xy 300.208484 -351.744995) (xy 300.185826 -351.79461) (xy 300.156337 -351.840496) (xy 300.120619 -351.881717)
			(xy 300.079397 -351.917436) (xy 300.033512 -351.946925) (xy 299.983897 -351.969584) (xy 299.931563 -351.984951)
			(xy 299.877574 -351.992713) (xy 299.850302 -351.9932) (xy 298.986702 -351.9932) (xy 298.959434 -351.992661)
			(xy 298.905452 -351.9849) (xy 298.853124 -351.969535) (xy 298.803516 -351.94688) (xy 298.757636 -351.917395)
			(xy 298.71642 -351.881681) (xy 298.680706 -351.840465) (xy 298.651221 -351.794586) (xy 298.628566 -351.744978)
			(xy 298.613201 -351.69265) (xy 298.605439 -351.638668) (xy 297.122614 -351.638668) (xy 297.122614 -351.63867)
			(xy 297.114852 -351.692655) (xy 297.099488 -351.744987) (xy 297.076832 -351.794599) (xy 297.047347 -351.840483)
			(xy 297.011633 -351.881703) (xy 296.970416 -351.917422) (xy 296.924536 -351.946912) (xy 296.874926 -351.969573)
			(xy 296.822597 -351.984943) (xy 296.768612 -351.992711) (xy 296.741342 -351.9932) (xy 295.877742 -351.9932)
			(xy 295.850472 -351.992663) (xy 295.796486 -351.984907) (xy 295.744153 -351.969546) (xy 295.69454 -351.946893)
			(xy 295.648655 -351.917409) (xy 295.607434 -351.881695) (xy 295.571716 -351.840478) (xy 295.542227 -351.794597)
			(xy 295.519569 -351.744986) (xy 295.504202 -351.692655) (xy 295.49644 -351.63867) (xy 294.013736 -351.63867)
			(xy 294.013736 -351.638675) (xy 294.005973 -351.692668) (xy 293.990604 -351.745008) (xy 293.967943 -351.794627)
			(xy 293.938451 -351.840516) (xy 293.902728 -351.881741) (xy 293.861502 -351.917462) (xy 293.815611 -351.946952)
			(xy 293.765991 -351.969611) (xy 293.713651 -351.984977) (xy 293.659657 -351.992738) (xy 293.632382 -351.9932)
			(xy 292.768782 -351.9932) (xy 292.741516 -351.992636) (xy 292.68754 -351.984873) (xy 292.635218 -351.969508)
			(xy 292.585615 -351.946853) (xy 292.539741 -351.91737) (xy 292.498529 -351.881658) (xy 292.46282 -351.840445)
			(xy 292.433338 -351.794569) (xy 292.410686 -351.744965) (xy 292.395323 -351.692642) (xy 292.387562 -351.638666)
			(xy 290.904714 -351.638666) (xy 290.904714 -351.638671) (xy 290.896952 -351.692658) (xy 290.881586 -351.744991)
			(xy 290.858929 -351.794605) (xy 290.829442 -351.840489) (xy 290.793726 -351.88171) (xy 290.752507 -351.917429)
			(xy 290.706624 -351.946919) (xy 290.657012 -351.969578) (xy 290.60468 -351.984947) (xy 290.550693 -351.992712)
			(xy 290.523422 -351.9932) (xy 289.659822 -351.9932) (xy 289.632553 -351.992662) (xy 289.578569 -351.984903)
			(xy 289.526239 -351.96954) (xy 289.476628 -351.946886) (xy 289.430746 -351.917402) (xy 289.389527 -351.881688)
			(xy 289.353811 -351.840472) (xy 289.324324 -351.794592) (xy 289.301667 -351.744982) (xy 289.286301 -351.692653)
			(xy 289.278539 -351.638669) (xy 287.795836 -351.638669) (xy 287.795836 -351.638675) (xy 287.788072 -351.692671)
			(xy 287.772703 -351.745012) (xy 287.75004 -351.794633) (xy 287.720546 -351.840523) (xy 287.684821 -351.881748)
			(xy 287.643592 -351.917469) (xy 287.597699 -351.946958) (xy 287.548076 -351.969616) (xy 287.495734 -351.98498)
			(xy 287.441737 -351.992739) (xy 287.414462 -351.9932) (xy 286.550862 -351.9932) (xy 286.523597 -351.992635)
			(xy 286.469623 -351.98487) (xy 286.417303 -351.969503) (xy 286.367703 -351.946847) (xy 286.321831 -351.917363)
			(xy 286.280622 -351.881651) (xy 286.244915 -351.840438) (xy 286.215435 -351.794564) (xy 286.192784 -351.744961)
			(xy 286.177422 -351.69264) (xy 286.169662 -351.638665) (xy 284.686813 -351.638665) (xy 284.686813 -351.638672)
			(xy 284.679051 -351.692661) (xy 284.663684 -351.744995) (xy 284.641026 -351.79461) (xy 284.611537 -351.840496)
			(xy 284.575819 -351.881717) (xy 284.534597 -351.917436) (xy 284.488712 -351.946925) (xy 284.439097 -351.969584)
			(xy 284.386763 -351.984951) (xy 284.332774 -351.992713) (xy 284.305502 -351.9932) (xy 283.441902 -351.9932)
			(xy 283.414634 -351.992661) (xy 283.360652 -351.9849) (xy 283.308324 -351.969535) (xy 283.258716 -351.94688)
			(xy 283.212836 -351.917395) (xy 283.17162 -351.881681) (xy 283.135906 -351.840465) (xy 283.106421 -351.794586)
			(xy 283.083766 -351.744978) (xy 283.068401 -351.69265) (xy 283.060639 -351.638668) (xy 281.577814 -351.638668)
			(xy 281.577814 -351.63867) (xy 281.570052 -351.692655) (xy 281.554688 -351.744987) (xy 281.532032 -351.794599)
			(xy 281.502547 -351.840483) (xy 281.466833 -351.881703) (xy 281.425616 -351.917422) (xy 281.379736 -351.946912)
			(xy 281.330126 -351.969573) (xy 281.277797 -351.984943) (xy 281.223812 -351.992711) (xy 281.196542 -351.9932)
			(xy 280.332942 -351.9932) (xy 280.305672 -351.992663) (xy 280.251686 -351.984907) (xy 280.199353 -351.969546)
			(xy 280.14974 -351.946893) (xy 280.103855 -351.917409) (xy 280.062634 -351.881695) (xy 280.026916 -351.840478)
			(xy 279.997427 -351.794597) (xy 279.974769 -351.744986) (xy 279.959402 -351.692655) (xy 279.95164 -351.63867)
			(xy 278.468936 -351.63867) (xy 278.468936 -351.638675) (xy 278.461173 -351.692668) (xy 278.445804 -351.745008)
			(xy 278.423143 -351.794627) (xy 278.393651 -351.840516) (xy 278.357928 -351.881741) (xy 278.316702 -351.917462)
			(xy 278.270811 -351.946952) (xy 278.221191 -351.969611) (xy 278.168851 -351.984977) (xy 278.114857 -351.992738)
			(xy 278.087582 -351.9932) (xy 277.223982 -351.9932) (xy 277.196716 -351.992636) (xy 277.14274 -351.984873)
			(xy 277.090418 -351.969508) (xy 277.040815 -351.946853) (xy 276.994941 -351.91737) (xy 276.953729 -351.881658)
			(xy 276.91802 -351.840445) (xy 276.888538 -351.794569) (xy 276.865886 -351.744965) (xy 276.850523 -351.692642)
			(xy 276.842762 -351.638666) (xy 275.359914 -351.638666) (xy 275.359914 -351.638671) (xy 275.352152 -351.692658)
			(xy 275.336786 -351.744991) (xy 275.314129 -351.794605) (xy 275.284642 -351.840489) (xy 275.248926 -351.88171)
			(xy 275.207707 -351.917429) (xy 275.161824 -351.946919) (xy 275.112212 -351.969578) (xy 275.05988 -351.984947)
			(xy 275.005893 -351.992712) (xy 274.978622 -351.9932) (xy 274.115022 -351.9932) (xy 274.087753 -351.992662)
			(xy 274.033769 -351.984903) (xy 273.981439 -351.96954) (xy 273.931828 -351.946886) (xy 273.885946 -351.917402)
			(xy 273.844727 -351.881688) (xy 273.809011 -351.840472) (xy 273.779524 -351.794592) (xy 273.756867 -351.744982)
			(xy 273.741501 -351.692653) (xy 273.733739 -351.638669) (xy 272.251036 -351.638669) (xy 272.251036 -351.638675)
			(xy 272.243272 -351.692671) (xy 272.227903 -351.745012) (xy 272.20524 -351.794633) (xy 272.175746 -351.840523)
			(xy 272.140021 -351.881748) (xy 272.098792 -351.917469) (xy 272.052899 -351.946958) (xy 272.003276 -351.969616)
			(xy 271.950934 -351.98498) (xy 271.896937 -351.992739) (xy 271.869662 -351.9932) (xy 271.006062 -351.9932)
			(xy 270.978797 -351.992635) (xy 270.924823 -351.98487) (xy 270.872503 -351.969503) (xy 270.822903 -351.946847)
			(xy 270.777031 -351.917363) (xy 270.735822 -351.881651) (xy 270.700115 -351.840438) (xy 270.670635 -351.794564)
			(xy 270.647984 -351.744961) (xy 270.632622 -351.69264) (xy 270.624862 -351.638665) (xy 269.142013 -351.638665)
			(xy 269.142013 -351.638672) (xy 269.134251 -351.692661) (xy 269.118884 -351.744995) (xy 269.096226 -351.79461)
			(xy 269.066737 -351.840496) (xy 269.031019 -351.881717) (xy 268.989797 -351.917436) (xy 268.943912 -351.946925)
			(xy 268.894297 -351.969584) (xy 268.841963 -351.984951) (xy 268.787974 -351.992713) (xy 268.760702 -351.9932)
			(xy 267.897102 -351.9932) (xy 267.869834 -351.992661) (xy 267.815852 -351.9849) (xy 267.763524 -351.969535)
			(xy 267.713916 -351.94688) (xy 267.668036 -351.917395) (xy 267.62682 -351.881681) (xy 267.591106 -351.840465)
			(xy 267.561621 -351.794586) (xy 267.538966 -351.744978) (xy 267.523601 -351.69265) (xy 267.515839 -351.638668)
			(xy 194.520614 -351.638668) (xy 194.520614 -351.638672) (xy 194.512851 -351.692659) (xy 194.497485 -351.744993)
			(xy 194.474828 -351.794608) (xy 194.44534 -351.840492) (xy 194.409622 -351.881714) (xy 194.368402 -351.917433)
			(xy 194.322518 -351.946922) (xy 194.272904 -351.969581) (xy 194.220571 -351.984949) (xy 194.166584 -351.992713)
			(xy 194.139312 -351.9932) (xy 193.275712 -351.9932) (xy 193.248443 -351.992661) (xy 193.19446 -351.984901)
			(xy 193.142131 -351.969538) (xy 193.092522 -351.946883) (xy 193.046641 -351.917399) (xy 193.005424 -351.881685)
			(xy 192.969708 -351.840469) (xy 192.940223 -351.794589) (xy 192.917566 -351.74498) (xy 192.902201 -351.692651)
			(xy 192.894439 -351.638669) (xy 191.411736 -351.638669) (xy 191.411736 -351.638676) (xy 191.403972 -351.692672)
			(xy 191.388602 -351.745014) (xy 191.365939 -351.794635) (xy 191.336444 -351.840526) (xy 191.300717 -351.881751)
			(xy 191.259487 -351.917472) (xy 191.213593 -351.946962) (xy 191.163969 -351.969619) (xy 191.111625 -351.984982)
			(xy 191.057628 -351.99274) (xy 191.030352 -351.9932) (xy 190.166752 -351.9932) (xy 190.139488 -351.992634)
			(xy 190.085515 -351.984868) (xy 190.033196 -351.9695) (xy 189.983597 -351.946843) (xy 189.937726 -351.917359)
			(xy 189.896519 -351.881647) (xy 189.860812 -351.840435) (xy 189.831334 -351.794561) (xy 189.808683 -351.744959)
			(xy 189.793322 -351.692639) (xy 189.785562 -351.638664) (xy 188.302736 -351.638664) (xy 188.302736 -351.638674)
			(xy 188.294973 -351.692667) (xy 188.279605 -351.745006) (xy 188.256945 -351.794624) (xy 188.227453 -351.840513)
			(xy 188.191732 -351.881737) (xy 188.150506 -351.917458) (xy 188.104617 -351.946949) (xy 188.054998 -351.969608)
			(xy 188.002659 -351.984975) (xy 187.948666 -351.992737) (xy 187.921392 -351.9932) (xy 187.057792 -351.9932)
			(xy 187.030526 -351.992637) (xy 186.976548 -351.984875) (xy 186.924225 -351.969511) (xy 186.874621 -351.946856)
			(xy 186.828745 -351.917373) (xy 186.787533 -351.881662) (xy 186.751822 -351.840448) (xy 186.72234 -351.794572)
			(xy 186.699686 -351.744968) (xy 186.684323 -351.692644) (xy 186.676562 -351.638666) (xy 185.193714 -351.638666)
			(xy 185.193714 -351.638671) (xy 185.185952 -351.692657) (xy 185.170587 -351.744989) (xy 185.147931 -351.794602)
			(xy 185.118445 -351.840486) (xy 185.082729 -351.881707) (xy 185.041512 -351.917426) (xy 184.99563 -351.946915)
			(xy 184.946019 -351.969576) (xy 184.893688 -351.984945) (xy 184.839703 -351.992711) (xy 184.812432 -351.9932)
			(xy 183.948832 -351.9932) (xy 183.921562 -351.992663) (xy 183.867577 -351.984905) (xy 183.815246 -351.969543)
			(xy 183.765634 -351.94689) (xy 183.719751 -351.917406) (xy 183.678531 -351.881692) (xy 183.642813 -351.840475)
			(xy 183.613326 -351.794594) (xy 183.590668 -351.744984) (xy 183.575302 -351.692654) (xy 183.567539 -351.63867)
			(xy 182.084836 -351.63867) (xy 182.084836 -351.638675) (xy 182.077073 -351.69267) (xy 182.061703 -351.74501)
			(xy 182.039042 -351.79463) (xy 182.009548 -351.840519) (xy 181.973824 -351.881744) (xy 181.932597 -351.917465)
			(xy 181.886705 -351.946955) (xy 181.837084 -351.969613) (xy 181.784742 -351.984979) (xy 181.730747 -351.992738)
			(xy 181.703472 -351.9932) (xy 180.839872 -351.9932) (xy 180.812607 -351.992636) (xy 180.758631 -351.984872)
			(xy 180.70631 -351.969505) (xy 180.656709 -351.94685) (xy 180.610836 -351.917366) (xy 180.569626 -351.881654)
			(xy 180.533917 -351.840442) (xy 180.504437 -351.794567) (xy 180.481785 -351.744963) (xy 180.466422 -351.692641)
			(xy 180.458662 -351.638665) (xy 178.975814 -351.638665) (xy 178.975814 -351.638672) (xy 178.968051 -351.692659)
			(xy 178.952685 -351.744993) (xy 178.930028 -351.794608) (xy 178.90054 -351.840492) (xy 178.864822 -351.881714)
			(xy 178.823602 -351.917433) (xy 178.777718 -351.946922) (xy 178.728104 -351.969581) (xy 178.675771 -351.984949)
			(xy 178.621784 -351.992713) (xy 178.594512 -351.9932) (xy 177.730912 -351.9932) (xy 177.703643 -351.992661)
			(xy 177.64966 -351.984901) (xy 177.597331 -351.969538) (xy 177.547722 -351.946883) (xy 177.501841 -351.917399)
			(xy 177.460624 -351.881685) (xy 177.424908 -351.840469) (xy 177.395423 -351.794589) (xy 177.372766 -351.74498)
			(xy 177.357401 -351.692651) (xy 177.349639 -351.638669) (xy 175.866936 -351.638669) (xy 175.866936 -351.638676)
			(xy 175.859172 -351.692672) (xy 175.843802 -351.745014) (xy 175.821139 -351.794635) (xy 175.791644 -351.840526)
			(xy 175.755917 -351.881751) (xy 175.714687 -351.917472) (xy 175.668793 -351.946962) (xy 175.619169 -351.969619)
			(xy 175.566825 -351.984982) (xy 175.512828 -351.99274) (xy 175.485552 -351.9932) (xy 174.621952 -351.9932)
			(xy 174.594688 -351.992634) (xy 174.540715 -351.984868) (xy 174.488396 -351.9695) (xy 174.438797 -351.946843)
			(xy 174.392926 -351.917359) (xy 174.351719 -351.881647) (xy 174.316012 -351.840435) (xy 174.286534 -351.794561)
			(xy 174.263883 -351.744959) (xy 174.248522 -351.692639) (xy 174.240762 -351.638664) (xy 172.757936 -351.638664)
			(xy 172.757936 -351.638674) (xy 172.750173 -351.692667) (xy 172.734805 -351.745006) (xy 172.712145 -351.794624)
			(xy 172.682653 -351.840513) (xy 172.646932 -351.881737) (xy 172.605706 -351.917458) (xy 172.559817 -351.946949)
			(xy 172.510198 -351.969608) (xy 172.457859 -351.984975) (xy 172.403866 -351.992737) (xy 172.376592 -351.9932)
			(xy 171.512992 -351.9932) (xy 171.485726 -351.992637) (xy 171.431748 -351.984875) (xy 171.379425 -351.969511)
			(xy 171.329821 -351.946856) (xy 171.283945 -351.917373) (xy 171.242733 -351.881662) (xy 171.207022 -351.840448)
			(xy 171.17754 -351.794572) (xy 171.154886 -351.744968) (xy 171.139523 -351.692644) (xy 171.131762 -351.638666)
			(xy 169.648914 -351.638666) (xy 169.648914 -351.638671) (xy 169.641152 -351.692657) (xy 169.625787 -351.744989)
			(xy 169.603131 -351.794602) (xy 169.573645 -351.840486) (xy 169.537929 -351.881707) (xy 169.496712 -351.917426)
			(xy 169.45083 -351.946915) (xy 169.401219 -351.969576) (xy 169.348888 -351.984945) (xy 169.294903 -351.992711)
			(xy 169.267632 -351.9932) (xy 168.404032 -351.9932) (xy 168.376762 -351.992663) (xy 168.322777 -351.984905)
			(xy 168.270446 -351.969543) (xy 168.220834 -351.94689) (xy 168.174951 -351.917406) (xy 168.133731 -351.881692)
			(xy 168.098013 -351.840475) (xy 168.068526 -351.794594) (xy 168.045868 -351.744984) (xy 168.030502 -351.692654)
			(xy 168.022739 -351.63867) (xy 166.540036 -351.63867) (xy 166.540036 -351.638675) (xy 166.532273 -351.69267)
			(xy 166.516903 -351.74501) (xy 166.494242 -351.79463) (xy 166.464748 -351.840519) (xy 166.429024 -351.881744)
			(xy 166.387797 -351.917465) (xy 166.341905 -351.946955) (xy 166.292284 -351.969613) (xy 166.239942 -351.984979)
			(xy 166.185947 -351.992738) (xy 166.158672 -351.9932) (xy 165.295072 -351.9932) (xy 165.267807 -351.992636)
			(xy 165.213831 -351.984872) (xy 165.16151 -351.969505) (xy 165.111909 -351.94685) (xy 165.066036 -351.917366)
			(xy 165.024826 -351.881654) (xy 164.989117 -351.840442) (xy 164.959637 -351.794567) (xy 164.936985 -351.744963)
			(xy 164.921622 -351.692641) (xy 164.913862 -351.638665) (xy 163.431014 -351.638665) (xy 163.431014 -351.638672)
			(xy 163.423251 -351.692659) (xy 163.407885 -351.744993) (xy 163.385228 -351.794608) (xy 163.35574 -351.840492)
			(xy 163.320022 -351.881714) (xy 163.278802 -351.917433) (xy 163.232918 -351.946922) (xy 163.183304 -351.969581)
			(xy 163.130971 -351.984949) (xy 163.076984 -351.992713) (xy 163.049712 -351.9932) (xy 162.186112 -351.9932)
			(xy 162.158843 -351.992661) (xy 162.10486 -351.984901) (xy 162.052531 -351.969538) (xy 162.002922 -351.946883)
			(xy 161.957041 -351.917399) (xy 161.915824 -351.881685) (xy 161.880108 -351.840469) (xy 161.850623 -351.794589)
			(xy 161.827966 -351.74498) (xy 161.812601 -351.692651) (xy 161.804839 -351.638669) (xy 144.196614 -351.638669)
			(xy 144.196614 -351.638672) (xy 144.188851 -351.69266) (xy 144.173485 -351.744994) (xy 144.150827 -351.794609)
			(xy 144.121339 -351.840494) (xy 144.085621 -351.881715) (xy 144.0444 -351.917434) (xy 143.998516 -351.946923)
			(xy 143.948902 -351.969582) (xy 143.896568 -351.98495) (xy 143.84258 -351.992713) (xy 143.815308 -351.9932)
			(xy 142.951708 -351.9932) (xy 142.924439 -351.992661) (xy 142.870457 -351.984901) (xy 142.818129 -351.969537)
			(xy 142.768519 -351.946882) (xy 142.722639 -351.917397) (xy 142.681422 -351.881683) (xy 142.645707 -351.840467)
			(xy 142.616222 -351.794588) (xy 142.593566 -351.744979) (xy 142.578201 -351.692651) (xy 142.570439 -351.638669)
			(xy 141.087614 -351.638669) (xy 141.087614 -351.63867) (xy 141.079852 -351.692655) (xy 141.064488 -351.744986)
			(xy 141.041833 -351.794597) (xy 141.012349 -351.840481) (xy 140.976635 -351.881701) (xy 140.935419 -351.91742)
			(xy 140.88954 -351.94691) (xy 140.839931 -351.969571) (xy 140.787602 -351.984942) (xy 140.733618 -351.99271)
			(xy 140.706348 -351.9932) (xy 139.842748 -351.9932) (xy 139.815477 -351.992664) (xy 139.761491 -351.984908)
			(xy 139.709158 -351.969547) (xy 139.659543 -351.946895) (xy 139.613658 -351.917411) (xy 139.572436 -351.881698)
			(xy 139.536717 -351.84048) (xy 139.507228 -351.794599) (xy 139.484569 -351.744987) (xy 139.469202 -351.692656)
			(xy 139.46144 -351.63867) (xy 137.978736 -351.63867) (xy 137.978736 -351.638674) (xy 137.970973 -351.692668)
			(xy 137.955605 -351.745006) (xy 137.932944 -351.794625) (xy 137.903452 -351.840514) (xy 137.86773 -351.881739)
			(xy 137.826504 -351.91746) (xy 137.780615 -351.94695) (xy 137.730995 -351.969609) (xy 137.678656 -351.984976)
			(xy 137.624662 -351.992737) (xy 137.597388 -351.9932) (xy 136.733788 -351.9932) (xy 136.706522 -351.992637)
			(xy 136.652545 -351.984875) (xy 136.600222 -351.96951) (xy 136.550618 -351.946855) (xy 136.504744 -351.917372)
			(xy 136.463531 -351.88166) (xy 136.427821 -351.840447) (xy 136.398339 -351.794571) (xy 136.375686 -351.744967)
			(xy 136.360323 -351.692643) (xy 136.352562 -351.638666) (xy 134.869714 -351.638666) (xy 134.869714 -351.638671)
			(xy 134.861952 -351.692657) (xy 134.846586 -351.74499) (xy 134.82393 -351.794603) (xy 134.794444 -351.840487)
			(xy 134.758728 -351.881708) (xy 134.71751 -351.917427) (xy 134.671628 -351.946917) (xy 134.622016 -351.969577)
			(xy 134.569685 -351.984946) (xy 134.515699 -351.992712) (xy 134.488428 -351.9932) (xy 133.624828 -351.9932)
			(xy 133.597558 -351.992663) (xy 133.543574 -351.984904) (xy 133.491243 -351.969542) (xy 133.441631 -351.946888)
			(xy 133.395749 -351.917404) (xy 133.354529 -351.881691) (xy 133.318812 -351.840474) (xy 133.289325 -351.794593)
			(xy 133.266668 -351.744983) (xy 133.251302 -351.692654) (xy 133.243539 -351.63867) (xy 131.760836 -351.63867)
			(xy 131.760836 -351.638675) (xy 131.753073 -351.69267) (xy 131.737703 -351.745011) (xy 131.715041 -351.794631)
			(xy 131.685547 -351.840521) (xy 131.649823 -351.881746) (xy 131.608595 -351.917467) (xy 131.562703 -351.946956)
			(xy 131.513081 -351.969614) (xy 131.460739 -351.984979) (xy 131.406743 -351.992739) (xy 131.379468 -351.9932)
			(xy 130.515868 -351.9932) (xy 130.488603 -351.992635) (xy 130.434628 -351.984871) (xy 130.382308 -351.969504)
			(xy 130.332706 -351.946849) (xy 130.286834 -351.917365) (xy 130.245624 -351.881653) (xy 130.209916 -351.84044)
			(xy 130.180436 -351.794566) (xy 130.157784 -351.744962) (xy 130.142422 -351.692641) (xy 130.134662 -351.638665)
			(xy 128.651814 -351.638665) (xy 128.651814 -351.638672) (xy 128.644051 -351.69266) (xy 128.628685 -351.744994)
			(xy 128.606027 -351.794609) (xy 128.576539 -351.840494) (xy 128.540821 -351.881715) (xy 128.4996 -351.917434)
			(xy 128.453716 -351.946923) (xy 128.404102 -351.969582) (xy 128.351768 -351.98495) (xy 128.29778 -351.992713)
			(xy 128.270508 -351.9932) (xy 127.406908 -351.9932) (xy 127.379639 -351.992661) (xy 127.325657 -351.984901)
			(xy 127.273329 -351.969537) (xy 127.223719 -351.946882) (xy 127.177839 -351.917397) (xy 127.136622 -351.881683)
			(xy 127.100907 -351.840467) (xy 127.071422 -351.794588) (xy 127.048766 -351.744979) (xy 127.033401 -351.692651)
			(xy 127.025639 -351.638669) (xy 125.542814 -351.638669) (xy 125.542814 -351.63867) (xy 125.535052 -351.692655)
			(xy 125.519688 -351.744986) (xy 125.497033 -351.794597) (xy 125.467549 -351.840481) (xy 125.431835 -351.881701)
			(xy 125.390619 -351.91742) (xy 125.34474 -351.94691) (xy 125.295131 -351.969571) (xy 125.242802 -351.984942)
			(xy 125.188818 -351.99271) (xy 125.161548 -351.9932) (xy 124.297948 -351.9932) (xy 124.270677 -351.992664)
			(xy 124.216691 -351.984908) (xy 124.164358 -351.969547) (xy 124.114743 -351.946895) (xy 124.068858 -351.917411)
			(xy 124.027636 -351.881698) (xy 123.991917 -351.84048) (xy 123.962428 -351.794599) (xy 123.939769 -351.744987)
			(xy 123.924402 -351.692656) (xy 123.91664 -351.63867) (xy 122.433936 -351.63867) (xy 122.433936 -351.638674)
			(xy 122.426173 -351.692668) (xy 122.410805 -351.745006) (xy 122.388144 -351.794625) (xy 122.358652 -351.840514)
			(xy 122.32293 -351.881739) (xy 122.281704 -351.91746) (xy 122.235815 -351.94695) (xy 122.186195 -351.969609)
			(xy 122.133856 -351.984976) (xy 122.079862 -351.992737) (xy 122.052588 -351.9932) (xy 121.188988 -351.9932)
			(xy 121.161722 -351.992637) (xy 121.107745 -351.984875) (xy 121.055422 -351.96951) (xy 121.005818 -351.946855)
			(xy 120.959944 -351.917372) (xy 120.918731 -351.88166) (xy 120.883021 -351.840447) (xy 120.853539 -351.794571)
			(xy 120.830886 -351.744967) (xy 120.815523 -351.692643) (xy 120.807762 -351.638666) (xy 119.324914 -351.638666)
			(xy 119.324914 -351.638671) (xy 119.317152 -351.692657) (xy 119.301786 -351.74499) (xy 119.27913 -351.794603)
			(xy 119.249644 -351.840487) (xy 119.213928 -351.881708) (xy 119.17271 -351.917427) (xy 119.126828 -351.946917)
			(xy 119.077216 -351.969577) (xy 119.024885 -351.984946) (xy 118.970899 -351.992712) (xy 118.943628 -351.9932)
			(xy 118.080028 -351.9932) (xy 118.052758 -351.992663) (xy 117.998774 -351.984904) (xy 117.946443 -351.969542)
			(xy 117.896831 -351.946888) (xy 117.850949 -351.917404) (xy 117.809729 -351.881691) (xy 117.774012 -351.840474)
			(xy 117.744525 -351.794593) (xy 117.721868 -351.744983) (xy 117.706502 -351.692654) (xy 117.698739 -351.63867)
			(xy 116.216036 -351.63867) (xy 116.216036 -351.638675) (xy 116.208273 -351.69267) (xy 116.192903 -351.745011)
			(xy 116.170241 -351.794631) (xy 116.140747 -351.840521) (xy 116.105023 -351.881746) (xy 116.063795 -351.917467)
			(xy 116.017903 -351.946956) (xy 115.968281 -351.969614) (xy 115.915939 -351.984979) (xy 115.861943 -351.992739)
			(xy 115.834668 -351.9932) (xy 114.971068 -351.9932) (xy 114.943803 -351.992635) (xy 114.889828 -351.984871)
			(xy 114.837508 -351.969504) (xy 114.787906 -351.946849) (xy 114.742034 -351.917365) (xy 114.700824 -351.881653)
			(xy 114.665116 -351.84044) (xy 114.635636 -351.794566) (xy 114.612984 -351.744962) (xy 114.597622 -351.692641)
			(xy 114.589862 -351.638665) (xy 113.107014 -351.638665) (xy 113.107014 -351.638672) (xy 113.099251 -351.69266)
			(xy 113.083885 -351.744994) (xy 113.061227 -351.794609) (xy 113.031739 -351.840494) (xy 112.996021 -351.881715)
			(xy 112.9548 -351.917434) (xy 112.908916 -351.946923) (xy 112.859302 -351.969582) (xy 112.806968 -351.98495)
			(xy 112.75298 -351.992713) (xy 112.725708 -351.9932) (xy 111.862108 -351.9932) (xy 111.834839 -351.992661)
			(xy 111.780857 -351.984901) (xy 111.728529 -351.969537) (xy 111.678919 -351.946882) (xy 111.633039 -351.917397)
			(xy 111.591822 -351.881683) (xy 111.556107 -351.840467) (xy 111.526622 -351.794588) (xy 111.503966 -351.744979)
			(xy 111.488601 -351.692651) (xy 111.480839 -351.638669) (xy 93.706714 -351.638669) (xy 93.706714 -351.63867)
			(xy 93.698952 -351.692655) (xy 93.683588 -351.744987) (xy 93.660932 -351.794599) (xy 93.631447 -351.840483)
			(xy 93.595733 -351.881703) (xy 93.554516 -351.917422) (xy 93.508636 -351.946912) (xy 93.459026 -351.969573)
			(xy 93.406697 -351.984943) (xy 93.352712 -351.992711) (xy 93.325442 -351.9932) (xy 92.461842 -351.9932)
			(xy 92.434572 -351.992663) (xy 92.380586 -351.984907) (xy 92.328253 -351.969546) (xy 92.27864 -351.946893)
			(xy 92.232755 -351.917409) (xy 92.191534 -351.881695) (xy 92.155816 -351.840478) (xy 92.126327 -351.794597)
			(xy 92.103669 -351.744986) (xy 92.088302 -351.692655) (xy 92.08054 -351.63867) (xy 90.597836 -351.63867)
			(xy 90.597836 -351.638675) (xy 90.590073 -351.692668) (xy 90.574704 -351.745008) (xy 90.552043 -351.794627)
			(xy 90.522551 -351.840516) (xy 90.486828 -351.881741) (xy 90.445602 -351.917462) (xy 90.399711 -351.946952)
			(xy 90.350091 -351.969611) (xy 90.297751 -351.984977) (xy 90.243757 -351.992738) (xy 90.216482 -351.9932)
			(xy 89.352882 -351.9932) (xy 89.325616 -351.992636) (xy 89.27164 -351.984873) (xy 89.219318 -351.969508)
			(xy 89.169715 -351.946853) (xy 89.123841 -351.91737) (xy 89.082629 -351.881658) (xy 89.04692 -351.840445)
			(xy 89.017438 -351.794569) (xy 88.994786 -351.744965) (xy 88.979423 -351.692642) (xy 88.971662 -351.638666)
			(xy 87.488814 -351.638666) (xy 87.488814 -351.638671) (xy 87.481052 -351.692658) (xy 87.465686 -351.744991)
			(xy 87.443029 -351.794605) (xy 87.413542 -351.840489) (xy 87.377826 -351.88171) (xy 87.336607 -351.917429)
			(xy 87.290724 -351.946919) (xy 87.241112 -351.969578) (xy 87.18878 -351.984947) (xy 87.134793 -351.992712)
			(xy 87.107522 -351.9932) (xy 86.243922 -351.9932) (xy 86.216653 -351.992662) (xy 86.162669 -351.984903)
			(xy 86.110339 -351.96954) (xy 86.060728 -351.946886) (xy 86.014846 -351.917402) (xy 85.973627 -351.881688)
			(xy 85.937911 -351.840472) (xy 85.908424 -351.794592) (xy 85.885767 -351.744982) (xy 85.870401 -351.692653)
			(xy 85.862639 -351.638669) (xy 84.379936 -351.638669) (xy 84.379936 -351.638675) (xy 84.372172 -351.692671)
			(xy 84.356803 -351.745012) (xy 84.33414 -351.794633) (xy 84.304646 -351.840523) (xy 84.268921 -351.881748)
			(xy 84.227692 -351.917469) (xy 84.181799 -351.946958) (xy 84.132176 -351.969616) (xy 84.079834 -351.98498)
			(xy 84.025837 -351.992739) (xy 83.998562 -351.9932) (xy 83.134962 -351.9932) (xy 83.107697 -351.992635)
			(xy 83.053723 -351.98487) (xy 83.001403 -351.969503) (xy 82.951803 -351.946847) (xy 82.905931 -351.917363)
			(xy 82.864722 -351.881651) (xy 82.829015 -351.840438) (xy 82.799535 -351.794564) (xy 82.776884 -351.744961)
			(xy 82.761522 -351.69264) (xy 82.753762 -351.638665) (xy 81.270913 -351.638665) (xy 81.270913 -351.638672)
			(xy 81.263151 -351.692661) (xy 81.247784 -351.744995) (xy 81.225126 -351.79461) (xy 81.195637 -351.840496)
			(xy 81.159919 -351.881717) (xy 81.118697 -351.917436) (xy 81.072812 -351.946925) (xy 81.023197 -351.969584)
			(xy 80.970863 -351.984951) (xy 80.916874 -351.992713) (xy 80.889602 -351.9932) (xy 80.026002 -351.9932)
			(xy 79.998734 -351.992661) (xy 79.944752 -351.9849) (xy 79.892424 -351.969535) (xy 79.842816 -351.94688)
			(xy 79.796936 -351.917395) (xy 79.75572 -351.881681) (xy 79.720006 -351.840465) (xy 79.690521 -351.794586)
			(xy 79.667866 -351.744978) (xy 79.652501 -351.69265) (xy 79.644739 -351.638668) (xy 78.161914 -351.638668)
			(xy 78.161914 -351.63867) (xy 78.154152 -351.692655) (xy 78.138788 -351.744987) (xy 78.116132 -351.794599)
			(xy 78.086647 -351.840483) (xy 78.050933 -351.881703) (xy 78.009716 -351.917422) (xy 77.963836 -351.946912)
			(xy 77.914226 -351.969573) (xy 77.861897 -351.984943) (xy 77.807912 -351.992711) (xy 77.780642 -351.9932)
			(xy 76.917042 -351.9932) (xy 76.889772 -351.992663) (xy 76.835786 -351.984907) (xy 76.783453 -351.969546)
			(xy 76.73384 -351.946893) (xy 76.687955 -351.917409) (xy 76.646734 -351.881695) (xy 76.611016 -351.840478)
			(xy 76.581527 -351.794597) (xy 76.558869 -351.744986) (xy 76.543502 -351.692655) (xy 76.53574 -351.63867)
			(xy 75.053036 -351.63867) (xy 75.053036 -351.638675) (xy 75.045273 -351.692668) (xy 75.029904 -351.745008)
			(xy 75.007243 -351.794627) (xy 74.977751 -351.840516) (xy 74.942028 -351.881741) (xy 74.900802 -351.917462)
			(xy 74.854911 -351.946952) (xy 74.805291 -351.969611) (xy 74.752951 -351.984977) (xy 74.698957 -351.992738)
			(xy 74.671682 -351.9932) (xy 73.808082 -351.9932) (xy 73.780816 -351.992636) (xy 73.72684 -351.984873)
			(xy 73.674518 -351.969508) (xy 73.624915 -351.946853) (xy 73.579041 -351.91737) (xy 73.537829 -351.881658)
			(xy 73.50212 -351.840445) (xy 73.472638 -351.794569) (xy 73.449986 -351.744965) (xy 73.434623 -351.692642)
			(xy 73.426862 -351.638666) (xy 71.944014 -351.638666) (xy 71.944014 -351.638671) (xy 71.936252 -351.692658)
			(xy 71.920886 -351.744991) (xy 71.898229 -351.794605) (xy 71.868742 -351.840489) (xy 71.833026 -351.88171)
			(xy 71.791807 -351.917429) (xy 71.745924 -351.946919) (xy 71.696312 -351.969578) (xy 71.64398 -351.984947)
			(xy 71.589993 -351.992712) (xy 71.562722 -351.9932) (xy 70.699122 -351.9932) (xy 70.671853 -351.992662)
			(xy 70.617869 -351.984903) (xy 70.565539 -351.96954) (xy 70.515928 -351.946886) (xy 70.470046 -351.917402)
			(xy 70.428827 -351.881688) (xy 70.393111 -351.840472) (xy 70.363624 -351.794592) (xy 70.340967 -351.744982)
			(xy 70.325601 -351.692653) (xy 70.317839 -351.638669) (xy 68.835136 -351.638669) (xy 68.835136 -351.638675)
			(xy 68.827372 -351.692671) (xy 68.812003 -351.745012) (xy 68.78934 -351.794633) (xy 68.759846 -351.840523)
			(xy 68.724121 -351.881748) (xy 68.682892 -351.917469) (xy 68.636999 -351.946958) (xy 68.587376 -351.969616)
			(xy 68.535034 -351.98498) (xy 68.481037 -351.992739) (xy 68.453762 -351.9932) (xy 67.590162 -351.9932)
			(xy 67.562897 -351.992635) (xy 67.508923 -351.98487) (xy 67.456603 -351.969503) (xy 67.407003 -351.946847)
			(xy 67.361131 -351.917363) (xy 67.319922 -351.881651) (xy 67.284215 -351.840438) (xy 67.254735 -351.794564)
			(xy 67.232084 -351.744961) (xy 67.216722 -351.69264) (xy 67.208962 -351.638665) (xy 65.726113 -351.638665)
			(xy 65.726113 -351.638672) (xy 65.718351 -351.692661) (xy 65.702984 -351.744995) (xy 65.680326 -351.79461)
			(xy 65.650837 -351.840496) (xy 65.615119 -351.881717) (xy 65.573897 -351.917436) (xy 65.528012 -351.946925)
			(xy 65.478397 -351.969584) (xy 65.426063 -351.984951) (xy 65.372074 -351.992713) (xy 65.344802 -351.9932)
			(xy 64.481202 -351.9932) (xy 64.453934 -351.992661) (xy 64.399952 -351.9849) (xy 64.347624 -351.969535)
			(xy 64.298016 -351.94688) (xy 64.252136 -351.917395) (xy 64.21092 -351.881681) (xy 64.175206 -351.840465)
			(xy 64.145721 -351.794586) (xy 64.123066 -351.744978) (xy 64.107701 -351.69265) (xy 64.099939 -351.638668)
			(xy 62.617114 -351.638668) (xy 62.617114 -351.63867) (xy 62.609352 -351.692655) (xy 62.593988 -351.744987)
			(xy 62.571332 -351.794599) (xy 62.541847 -351.840483) (xy 62.506133 -351.881703) (xy 62.464916 -351.917422)
			(xy 62.419036 -351.946912) (xy 62.369426 -351.969573) (xy 62.317097 -351.984943) (xy 62.263112 -351.992711)
			(xy 62.235842 -351.9932) (xy 61.372242 -351.9932) (xy 61.344972 -351.992663) (xy 61.290986 -351.984907)
			(xy 61.238653 -351.969546) (xy 61.18904 -351.946893) (xy 61.143155 -351.917409) (xy 61.101934 -351.881695)
			(xy 61.066216 -351.840478) (xy 61.036727 -351.794597) (xy 61.014069 -351.744986) (xy 60.998702 -351.692655)
			(xy 60.99094 -351.63867) (xy 51.666914 -351.63867) (xy 51.659152 -351.692655) (xy 51.643788 -351.744986)
			(xy 51.621133 -351.794597) (xy 51.591649 -351.840481) (xy 51.555935 -351.881701) (xy 51.514719 -351.91742)
			(xy 51.46884 -351.94691) (xy 51.419231 -351.969571) (xy 51.366902 -351.984942) (xy 51.312918 -351.99271)
			(xy 51.285648 -351.9932) (xy 50.422048 -351.9932) (xy 50.394777 -351.992664) (xy 50.340791 -351.984908)
			(xy 50.288458 -351.969547) (xy 50.238843 -351.946895) (xy 50.192958 -351.917411) (xy 50.151736 -351.881698)
			(xy 50.116017 -351.84048) (xy 50.086528 -351.794599) (xy 50.063869 -351.744987) (xy 50.048502 -351.692656)
			(xy 50.04074 -351.63867) (xy 48.558036 -351.63867) (xy 48.558036 -351.638674) (xy 48.550273 -351.692668)
			(xy 48.534905 -351.745006) (xy 48.512244 -351.794625) (xy 48.482752 -351.840514) (xy 48.44703 -351.881739)
			(xy 48.405804 -351.91746) (xy 48.359915 -351.94695) (xy 48.310295 -351.969609) (xy 48.257956 -351.984976)
			(xy 48.203962 -351.992737) (xy 48.176688 -351.9932) (xy 47.313088 -351.9932) (xy 47.285822 -351.992637)
			(xy 47.231845 -351.984875) (xy 47.179522 -351.96951) (xy 47.129918 -351.946855) (xy 47.084044 -351.917372)
			(xy 47.042831 -351.88166) (xy 47.007121 -351.840447) (xy 46.977639 -351.794571) (xy 46.954986 -351.744967)
			(xy 46.939623 -351.692643) (xy 46.931862 -351.638666) (xy 45.449014 -351.638666) (xy 45.449014 -351.638671)
			(xy 45.441252 -351.692657) (xy 45.425886 -351.74499) (xy 45.40323 -351.794603) (xy 45.373744 -351.840487)
			(xy 45.338028 -351.881708) (xy 45.29681 -351.917427) (xy 45.250928 -351.946917) (xy 45.201316 -351.969577)
			(xy 45.148985 -351.984946) (xy 45.094999 -351.992712) (xy 45.067728 -351.9932) (xy 44.204128 -351.9932)
			(xy 44.176858 -351.992663) (xy 44.122874 -351.984904) (xy 44.070543 -351.969542) (xy 44.020931 -351.946888)
			(xy 43.975049 -351.917404) (xy 43.933829 -351.881691) (xy 43.898112 -351.840474) (xy 43.868625 -351.794593)
			(xy 43.845968 -351.744983) (xy 43.830602 -351.692654) (xy 43.822839 -351.63867) (xy 42.340136 -351.63867)
			(xy 42.340136 -351.638675) (xy 42.332373 -351.69267) (xy 42.317003 -351.745011) (xy 42.294341 -351.794631)
			(xy 42.264847 -351.840521) (xy 42.229123 -351.881746) (xy 42.187895 -351.917467) (xy 42.142003 -351.946956)
			(xy 42.092381 -351.969614) (xy 42.040039 -351.984979) (xy 41.986043 -351.992739) (xy 41.958768 -351.9932)
			(xy 41.095168 -351.9932) (xy 41.067903 -351.992635) (xy 41.013928 -351.984871) (xy 40.961608 -351.969504)
			(xy 40.912006 -351.946849) (xy 40.866134 -351.917365) (xy 40.824924 -351.881653) (xy 40.789216 -351.84044)
			(xy 40.759736 -351.794566) (xy 40.737084 -351.744962) (xy 40.721722 -351.692641) (xy 40.713962 -351.638665)
			(xy 39.231114 -351.638665) (xy 39.231114 -351.638672) (xy 39.223351 -351.69266) (xy 39.207985 -351.744994)
			(xy 39.185327 -351.794609) (xy 39.155839 -351.840494) (xy 39.120121 -351.881715) (xy 39.0789 -351.917434)
			(xy 39.033016 -351.946923) (xy 38.983402 -351.969582) (xy 38.931068 -351.98495) (xy 38.87708 -351.992713)
			(xy 38.849808 -351.9932) (xy 37.986208 -351.9932) (xy 37.958939 -351.992661) (xy 37.904957 -351.984901)
			(xy 37.852629 -351.969537) (xy 37.803019 -351.946882) (xy 37.757139 -351.917397) (xy 37.715922 -351.881683)
			(xy 37.680207 -351.840467) (xy 37.650722 -351.794588) (xy 37.628066 -351.744979) (xy 37.612701 -351.692651)
			(xy 37.604939 -351.638669) (xy 36.122114 -351.638669) (xy 36.122114 -351.63867) (xy 36.114352 -351.692655)
			(xy 36.098988 -351.744986) (xy 36.076333 -351.794597) (xy 36.046849 -351.840481) (xy 36.011135 -351.881701)
			(xy 35.969919 -351.91742) (xy 35.92404 -351.94691) (xy 35.874431 -351.969571) (xy 35.822102 -351.984942)
			(xy 35.768118 -351.99271) (xy 35.740848 -351.9932) (xy 34.877248 -351.9932) (xy 34.849977 -351.992664)
			(xy 34.795991 -351.984908) (xy 34.743658 -351.969547) (xy 34.694043 -351.946895) (xy 34.648158 -351.917411)
			(xy 34.606936 -351.881698) (xy 34.571217 -351.84048) (xy 34.541728 -351.794599) (xy 34.519069 -351.744987)
			(xy 34.503702 -351.692656) (xy 34.49594 -351.63867) (xy 33.013236 -351.63867) (xy 33.013236 -351.638674)
			(xy 33.005473 -351.692668) (xy 32.990105 -351.745006) (xy 32.967444 -351.794625) (xy 32.937952 -351.840514)
			(xy 32.90223 -351.881739) (xy 32.861004 -351.91746) (xy 32.815115 -351.94695) (xy 32.765495 -351.969609)
			(xy 32.713156 -351.984976) (xy 32.659162 -351.992737) (xy 32.631888 -351.9932) (xy 31.768288 -351.9932)
			(xy 31.741022 -351.992637) (xy 31.687045 -351.984875) (xy 31.634722 -351.96951) (xy 31.585118 -351.946855)
			(xy 31.539244 -351.917372) (xy 31.498031 -351.88166) (xy 31.462321 -351.840447) (xy 31.432839 -351.794571)
			(xy 31.410186 -351.744967) (xy 31.394823 -351.692643) (xy 31.387062 -351.638666) (xy 29.904214 -351.638666)
			(xy 29.904214 -351.638671) (xy 29.896452 -351.692657) (xy 29.881086 -351.74499) (xy 29.85843 -351.794603)
			(xy 29.828944 -351.840487) (xy 29.793228 -351.881708) (xy 29.75201 -351.917427) (xy 29.706128 -351.946917)
			(xy 29.656516 -351.969577) (xy 29.604185 -351.984946) (xy 29.550199 -351.992712) (xy 29.522928 -351.9932)
			(xy 28.659328 -351.9932) (xy 28.632058 -351.992663) (xy 28.578074 -351.984904) (xy 28.525743 -351.969542)
			(xy 28.476131 -351.946888) (xy 28.430249 -351.917404) (xy 28.389029 -351.881691) (xy 28.353312 -351.840474)
			(xy 28.323825 -351.794593) (xy 28.301168 -351.744983) (xy 28.285802 -351.692654) (xy 28.278039 -351.63867)
			(xy 26.795336 -351.63867) (xy 26.795336 -351.638675) (xy 26.787573 -351.69267) (xy 26.772203 -351.745011)
			(xy 26.749541 -351.794631) (xy 26.720047 -351.840521) (xy 26.684323 -351.881746) (xy 26.643095 -351.917467)
			(xy 26.597203 -351.946956) (xy 26.547581 -351.969614) (xy 26.495239 -351.984979) (xy 26.441243 -351.992739)
			(xy 26.413968 -351.9932) (xy 25.550368 -351.9932) (xy 25.523103 -351.992635) (xy 25.469128 -351.984871)
			(xy 25.416808 -351.969504) (xy 25.367206 -351.946849) (xy 25.321334 -351.917365) (xy 25.280124 -351.881653)
			(xy 25.244416 -351.84044) (xy 25.214936 -351.794566) (xy 25.192284 -351.744962) (xy 25.176922 -351.692641)
			(xy 25.169162 -351.638665) (xy 23.686314 -351.638665) (xy 23.686314 -351.638672) (xy 23.678551 -351.69266)
			(xy 23.663185 -351.744994) (xy 23.640527 -351.794609) (xy 23.611039 -351.840494) (xy 23.575321 -351.881715)
			(xy 23.5341 -351.917434) (xy 23.488216 -351.946923) (xy 23.438602 -351.969582) (xy 23.386268 -351.98495)
			(xy 23.33228 -351.992713) (xy 23.305008 -351.9932) (xy 22.441408 -351.9932) (xy 22.414139 -351.992661)
			(xy 22.360157 -351.984901) (xy 22.307829 -351.969537) (xy 22.258219 -351.946882) (xy 22.212339 -351.917397)
			(xy 22.171122 -351.881683) (xy 22.135407 -351.840467) (xy 22.105922 -351.794588) (xy 22.083266 -351.744979)
			(xy 22.067901 -351.692651) (xy 22.060139 -351.638669) (xy 20.577347 -351.638669) (xy 20.577347 -351.638711)
			(xy 20.569584 -351.692698) (xy 20.554218 -351.74503) (xy 20.53156 -351.794643) (xy 20.502073 -351.840527)
			(xy 20.466355 -351.881747) (xy 20.425135 -351.917464) (xy 20.379252 -351.946951) (xy 20.329638 -351.969609)
			(xy 20.277306 -351.984975) (xy 20.223319 -351.992737) (xy 20.196048 -351.9932) (xy 19.332448 -351.9932)
			(xy 19.305179 -351.992717) (xy 19.251195 -351.984955) (xy 19.198865 -351.96959) (xy 19.149255 -351.946933)
			(xy 19.103374 -351.917447) (xy 19.062157 -351.881732) (xy 19.026441 -351.840514) (xy 18.996956 -351.794633)
			(xy 18.974299 -351.745023) (xy 18.958934 -351.692693) (xy 18.951172 -351.638709) (xy 0.508 -351.638709)
			(xy 0.508 -354.759373) (xy 22.060084 -354.759373) (xy 22.060084 -354.704827) (xy 22.067846 -354.650837)
			(xy 22.083214 -354.598501) (xy 22.105873 -354.548885) (xy 22.135363 -354.502999) (xy 22.171083 -354.461777)
			(xy 22.212306 -354.426058) (xy 22.258192 -354.396569) (xy 22.307809 -354.373911) (xy 22.360145 -354.358545)
			(xy 22.414135 -354.350783) (xy 22.441408 -354.35032) (xy 23.305008 -354.35032) (xy 23.332276 -354.350843)
			(xy 23.386256 -354.358605) (xy 23.438582 -354.37397) (xy 23.488189 -354.396626) (xy 23.534067 -354.426111)
			(xy 23.575281 -354.461824) (xy 23.610994 -354.50304) (xy 23.640478 -354.548918) (xy 23.663132 -354.598525)
			(xy 23.678497 -354.650852) (xy 23.686258 -354.704832) (xy 23.686258 -354.759368) (xy 23.686258 -354.759369)
			(xy 25.169106 -354.759369) (xy 25.169106 -354.704831) (xy 25.176868 -354.650847) (xy 25.192232 -354.598518)
			(xy 25.214887 -354.548908) (xy 25.244371 -354.503026) (xy 25.280085 -354.461807) (xy 25.3213 -354.42609)
			(xy 25.36718 -354.396602) (xy 25.416788 -354.373943) (xy 25.469116 -354.358574) (xy 25.523099 -354.350809)
			(xy 25.550368 -354.35032) (xy 26.413968 -354.35032) (xy 26.441239 -354.350817) (xy 26.495227 -354.358575)
			(xy 26.547561 -354.373938) (xy 26.597176 -354.396593) (xy 26.643061 -354.426078) (xy 26.684283 -354.461794)
			(xy 26.720003 -354.503013) (xy 26.749492 -354.548896) (xy 26.772151 -354.598509) (xy 26.787518 -354.650842)
			(xy 26.79528 -354.704829) (xy 26.79528 -354.759371) (xy 26.79528 -354.759374) (xy 28.277984 -354.759374)
			(xy 28.277984 -354.704826) (xy 28.285747 -354.650835) (xy 28.301115 -354.598497) (xy 28.323776 -354.54888)
			(xy 28.353268 -354.502993) (xy 28.38899 -354.46177) (xy 28.430215 -354.426051) (xy 28.476104 -354.396562)
			(xy 28.525723 -354.373905) (xy 28.578062 -354.358541) (xy 28.632054 -354.350782) (xy 28.659328 -354.35032)
			(xy 29.522928 -354.35032) (xy 29.550195 -354.350844) (xy 29.604173 -354.358609) (xy 29.656497 -354.373976)
			(xy 29.706101 -354.396633) (xy 29.751976 -354.426118) (xy 29.793188 -354.461831) (xy 29.828899 -354.503046)
			(xy 29.858381 -354.548924) (xy 29.881034 -354.59853) (xy 29.896397 -354.650855) (xy 29.904158 -354.704833)
			(xy 29.904158 -354.759367) (xy 29.904158 -354.75937) (xy 31.387006 -354.75937) (xy 31.387006 -354.70483)
			(xy 31.394768 -354.650845) (xy 31.410134 -354.598514) (xy 31.43279 -354.548902) (xy 31.462276 -354.50302)
			(xy 31.497992 -354.4618) (xy 31.53921 -354.426083) (xy 31.585091 -354.396596) (xy 31.634703 -354.373938)
			(xy 31.687033 -354.358571) (xy 31.741018 -354.350807) (xy 31.768288 -354.35032) (xy 32.631888 -354.35032)
			(xy 32.659158 -354.350819) (xy 32.713144 -354.358579) (xy 32.765476 -354.373944) (xy 32.815088 -354.396599)
			(xy 32.860971 -354.426085) (xy 32.902191 -354.461801) (xy 32.937908 -354.503019) (xy 32.967395 -354.548902)
			(xy 32.990052 -354.598513) (xy 33.005418 -354.650844) (xy 33.013181 -354.70483) (xy 33.013181 -354.75937)
			(xy 33.01318 -354.759374) (xy 34.495884 -354.759374) (xy 34.495884 -354.704826) (xy 34.503647 -354.650832)
			(xy 34.519017 -354.598493) (xy 34.541679 -354.548874) (xy 34.571172 -354.502986) (xy 34.606897 -354.461763)
			(xy 34.648125 -354.426044) (xy 34.694016 -354.396556) (xy 34.743638 -354.3739) (xy 34.795979 -354.358537)
			(xy 34.849973 -354.35078) (xy 34.877248 -354.35032) (xy 35.740848 -354.35032) (xy 35.768114 -354.350846)
			(xy 35.82209 -354.358613) (xy 35.874411 -354.373981) (xy 35.924013 -354.396639) (xy 35.969886 -354.426125)
			(xy 36.011095 -354.461839) (xy 36.046804 -354.503053) (xy 36.076284 -354.548929) (xy 36.098936 -354.598534)
			(xy 36.114298 -354.650857) (xy 36.122058 -354.704834) (xy 36.122058 -354.759366) (xy 36.122057 -354.759373)
			(xy 37.604884 -354.759373) (xy 37.604884 -354.704827) (xy 37.612646 -354.650837) (xy 37.628014 -354.598501)
			(xy 37.650673 -354.548885) (xy 37.680163 -354.502999) (xy 37.715883 -354.461777) (xy 37.757106 -354.426058)
			(xy 37.802992 -354.396569) (xy 37.852609 -354.373911) (xy 37.904945 -354.358545) (xy 37.958935 -354.350783)
			(xy 37.986208 -354.35032) (xy 38.849808 -354.35032) (xy 38.877076 -354.350843) (xy 38.931056 -354.358605)
			(xy 38.983382 -354.37397) (xy 39.032989 -354.396626) (xy 39.078867 -354.426111) (xy 39.120081 -354.461824)
			(xy 39.155794 -354.50304) (xy 39.185278 -354.548918) (xy 39.207932 -354.598525) (xy 39.223297 -354.650852)
			(xy 39.231058 -354.704832) (xy 39.231058 -354.759368) (xy 39.231058 -354.759369) (xy 40.713906 -354.759369)
			(xy 40.713906 -354.704831) (xy 40.721668 -354.650847) (xy 40.737032 -354.598518) (xy 40.759687 -354.548908)
			(xy 40.789171 -354.503026) (xy 40.824885 -354.461807) (xy 40.8661 -354.42609) (xy 40.91198 -354.396602)
			(xy 40.961588 -354.373943) (xy 41.013916 -354.358574) (xy 41.067899 -354.350809) (xy 41.095168 -354.35032)
			(xy 41.958768 -354.35032) (xy 41.986039 -354.350817) (xy 42.040027 -354.358575) (xy 42.092361 -354.373938)
			(xy 42.141976 -354.396593) (xy 42.187861 -354.426078) (xy 42.229083 -354.461794) (xy 42.264803 -354.503013)
			(xy 42.294292 -354.548896) (xy 42.316951 -354.598509) (xy 42.332318 -354.650842) (xy 42.34008 -354.704829)
			(xy 42.34008 -354.759371) (xy 42.34008 -354.759374) (xy 43.822784 -354.759374) (xy 43.822784 -354.704826)
			(xy 43.830547 -354.650835) (xy 43.845915 -354.598497) (xy 43.868576 -354.54888) (xy 43.898068 -354.502993)
			(xy 43.93379 -354.46177) (xy 43.975015 -354.426051) (xy 44.020904 -354.396562) (xy 44.070523 -354.373905)
			(xy 44.122862 -354.358541) (xy 44.176854 -354.350782) (xy 44.204128 -354.35032) (xy 45.067728 -354.35032)
			(xy 45.094995 -354.350844) (xy 45.148973 -354.358609) (xy 45.201297 -354.373976) (xy 45.250901 -354.396633)
			(xy 45.296776 -354.426118) (xy 45.337988 -354.461831) (xy 45.373699 -354.503046) (xy 45.403181 -354.548924)
			(xy 45.425834 -354.59853) (xy 45.441197 -354.650855) (xy 45.448958 -354.704833) (xy 45.448958 -354.759367)
			(xy 45.448958 -354.75937) (xy 46.931806 -354.75937) (xy 46.931806 -354.70483) (xy 46.939568 -354.650845)
			(xy 46.954934 -354.598514) (xy 46.97759 -354.548902) (xy 47.007076 -354.50302) (xy 47.042792 -354.4618)
			(xy 47.08401 -354.426083) (xy 47.129891 -354.396596) (xy 47.179503 -354.373938) (xy 47.231833 -354.358571)
			(xy 47.285818 -354.350807) (xy 47.313088 -354.35032) (xy 48.176688 -354.35032) (xy 48.203958 -354.350819)
			(xy 48.257944 -354.358579) (xy 48.310276 -354.373944) (xy 48.359888 -354.396599) (xy 48.405771 -354.426085)
			(xy 48.446991 -354.461801) (xy 48.482708 -354.503019) (xy 48.512195 -354.548902) (xy 48.534852 -354.598513)
			(xy 48.550218 -354.650844) (xy 48.557981 -354.70483) (xy 48.557981 -354.75937) (xy 48.55798 -354.759374)
			(xy 50.040684 -354.759374) (xy 50.040684 -354.704826) (xy 50.048447 -354.650832) (xy 50.063817 -354.598493)
			(xy 50.086479 -354.548874) (xy 50.115972 -354.502986) (xy 50.151697 -354.461763) (xy 50.192925 -354.426044)
			(xy 50.238816 -354.396556) (xy 50.288438 -354.3739) (xy 50.340779 -354.358537) (xy 50.394773 -354.35078)
			(xy 50.422048 -354.35032) (xy 51.285648 -354.35032) (xy 51.312914 -354.350846) (xy 51.36689 -354.358613)
			(xy 51.419211 -354.373981) (xy 51.468813 -354.396639) (xy 51.514686 -354.426125) (xy 51.555895 -354.461839)
			(xy 51.591604 -354.503053) (xy 51.621084 -354.548929) (xy 51.643736 -354.598534) (xy 51.659098 -354.650857)
			(xy 51.666858 -354.704834) (xy 51.666858 -354.759366) (xy 51.666857 -354.759372) (xy 64.099884 -354.759372)
			(xy 64.099884 -354.704828) (xy 64.107646 -354.650838) (xy 64.123013 -354.598503) (xy 64.145672 -354.548887)
			(xy 64.175161 -354.503001) (xy 64.210881 -354.461779) (xy 64.252103 -354.42606) (xy 64.297989 -354.396571)
			(xy 64.347605 -354.373912) (xy 64.39994 -354.358546) (xy 64.45393 -354.350783) (xy 64.481202 -354.35032)
			(xy 65.344802 -354.35032) (xy 65.37207 -354.350843) (xy 65.426051 -354.358604) (xy 65.478378 -354.373969)
			(xy 65.527985 -354.396624) (xy 65.573864 -354.426109) (xy 65.615079 -354.461822) (xy 65.650793 -354.503038)
			(xy 65.680277 -354.548917) (xy 65.702932 -354.598524) (xy 65.718296 -354.650851) (xy 65.726058 -354.704832)
			(xy 65.726058 -354.759368) (xy 65.726058 -354.759369) (xy 67.208906 -354.759369) (xy 67.208906 -354.704831)
			(xy 67.216667 -354.650848) (xy 67.232032 -354.598519) (xy 67.254686 -354.548909) (xy 67.28417 -354.503028)
			(xy 67.319883 -354.46181) (xy 67.361098 -354.426093) (xy 67.406976 -354.396604) (xy 67.456584 -354.373945)
			(xy 67.508911 -354.358575) (xy 67.562893 -354.350809) (xy 67.590162 -354.35032) (xy 68.453762 -354.35032)
			(xy 68.481033 -354.350817) (xy 68.535022 -354.358574) (xy 68.587357 -354.373936) (xy 68.636972 -354.396591)
			(xy 68.682859 -354.426076) (xy 68.724081 -354.461792) (xy 68.759801 -354.503011) (xy 68.789291 -354.548894)
			(xy 68.81195 -354.598508) (xy 68.827318 -354.650841) (xy 68.83508 -354.704829) (xy 68.83508 -354.759371)
			(xy 68.83508 -354.759373) (xy 70.317784 -354.759373) (xy 70.317784 -354.704827) (xy 70.325547 -354.650835)
			(xy 70.340915 -354.598498) (xy 70.363575 -354.548882) (xy 70.393066 -354.502995) (xy 70.428788 -354.461772)
			(xy 70.470012 -354.426053) (xy 70.515901 -354.396564) (xy 70.565519 -354.373907) (xy 70.617857 -354.358542)
			(xy 70.671849 -354.350782) (xy 70.699122 -354.35032) (xy 71.562722 -354.35032) (xy 71.589989 -354.350844)
			(xy 71.643968 -354.358608) (xy 71.696292 -354.373974) (xy 71.745897 -354.396631) (xy 71.791773 -354.426116)
			(xy 71.832986 -354.461829) (xy 71.868697 -354.503044) (xy 71.89818 -354.548922) (xy 71.920833 -354.598528)
			(xy 71.936197 -354.650854) (xy 71.943958 -354.704833) (xy 71.943958 -354.759367) (xy 71.943958 -354.75937)
			(xy 73.426806 -354.75937) (xy 73.426806 -354.70483) (xy 73.434568 -354.650846) (xy 73.449933 -354.598515)
			(xy 73.472589 -354.548904) (xy 73.502075 -354.503022) (xy 73.53779 -354.461802) (xy 73.579007 -354.426085)
			(xy 73.624888 -354.396598) (xy 73.674498 -354.373939) (xy 73.726828 -354.358572) (xy 73.780812 -354.350808)
			(xy 73.808082 -354.35032) (xy 74.671682 -354.35032) (xy 74.698953 -354.350818) (xy 74.752939 -354.358578)
			(xy 74.805271 -354.373942) (xy 74.854884 -354.396597) (xy 74.900768 -354.426083) (xy 74.941988 -354.461799)
			(xy 74.977706 -354.503018) (xy 75.007194 -354.5489) (xy 75.029852 -354.598512) (xy 75.045218 -354.650844)
			(xy 75.052981 -354.704829) (xy 75.052981 -354.759371) (xy 75.052981 -354.759374) (xy 76.535684 -354.759374)
			(xy 76.535684 -354.704826) (xy 76.543447 -354.650833) (xy 76.558816 -354.598494) (xy 76.581478 -354.548876)
			(xy 76.610971 -354.502988) (xy 76.646695 -354.461765) (xy 76.687922 -354.426046) (xy 76.733813 -354.396558)
			(xy 76.783434 -354.373902) (xy 76.835774 -354.358538) (xy 76.889768 -354.350781) (xy 76.917042 -354.35032)
			(xy 77.780642 -354.35032) (xy 77.807908 -354.350845) (xy 77.861885 -354.358611) (xy 77.914207 -354.37398)
			(xy 77.963809 -354.396637) (xy 78.009683 -354.426123) (xy 78.050893 -354.461836) (xy 78.086602 -354.503051)
			(xy 78.116083 -354.548928) (xy 78.138735 -354.598533) (xy 78.154098 -354.650856) (xy 78.161858 -354.704834)
			(xy 78.161858 -354.759366) (xy 78.161857 -354.759372) (xy 79.644684 -354.759372) (xy 79.644684 -354.704828)
			(xy 79.652446 -354.650838) (xy 79.667813 -354.598503) (xy 79.690472 -354.548887) (xy 79.719961 -354.503001)
			(xy 79.755681 -354.461779) (xy 79.796903 -354.42606) (xy 79.842789 -354.396571) (xy 79.892405 -354.373912)
			(xy 79.94474 -354.358546) (xy 79.99873 -354.350783) (xy 80.026002 -354.35032) (xy 80.889602 -354.35032)
			(xy 80.91687 -354.350843) (xy 80.970851 -354.358604) (xy 81.023178 -354.373969) (xy 81.072785 -354.396624)
			(xy 81.118664 -354.426109) (xy 81.159879 -354.461822) (xy 81.195593 -354.503038) (xy 81.225077 -354.548917)
			(xy 81.247732 -354.598524) (xy 81.263096 -354.650851) (xy 81.270858 -354.704832) (xy 81.270858 -354.759368)
			(xy 81.270858 -354.759369) (xy 82.753706 -354.759369) (xy 82.753706 -354.704831) (xy 82.761467 -354.650848)
			(xy 82.776832 -354.598519) (xy 82.799486 -354.548909) (xy 82.82897 -354.503028) (xy 82.864683 -354.46181)
			(xy 82.905898 -354.426093) (xy 82.951776 -354.396604) (xy 83.001384 -354.373945) (xy 83.053711 -354.358575)
			(xy 83.107693 -354.350809) (xy 83.134962 -354.35032) (xy 83.998562 -354.35032) (xy 84.025833 -354.350817)
			(xy 84.079822 -354.358574) (xy 84.132157 -354.373936) (xy 84.181772 -354.396591) (xy 84.227659 -354.426076)
			(xy 84.268881 -354.461792) (xy 84.304601 -354.503011) (xy 84.334091 -354.548894) (xy 84.35675 -354.598508)
			(xy 84.372118 -354.650841) (xy 84.37988 -354.704829) (xy 84.37988 -354.759371) (xy 84.37988 -354.759373)
			(xy 85.862584 -354.759373) (xy 85.862584 -354.704827) (xy 85.870347 -354.650835) (xy 85.885715 -354.598498)
			(xy 85.908375 -354.548882) (xy 85.937866 -354.502995) (xy 85.973588 -354.461772) (xy 86.014812 -354.426053)
			(xy 86.060701 -354.396564) (xy 86.110319 -354.373907) (xy 86.162657 -354.358542) (xy 86.216649 -354.350782)
			(xy 86.243922 -354.35032) (xy 87.107522 -354.35032) (xy 87.134789 -354.350844) (xy 87.188768 -354.358608)
			(xy 87.241092 -354.373974) (xy 87.290697 -354.396631) (xy 87.336573 -354.426116) (xy 87.377786 -354.461829)
			(xy 87.413497 -354.503044) (xy 87.44298 -354.548922) (xy 87.465633 -354.598528) (xy 87.480997 -354.650854)
			(xy 87.488758 -354.704833) (xy 87.488758 -354.759367) (xy 87.488758 -354.75937) (xy 88.971606 -354.75937)
			(xy 88.971606 -354.70483) (xy 88.979368 -354.650846) (xy 88.994733 -354.598515) (xy 89.017389 -354.548904)
			(xy 89.046875 -354.503022) (xy 89.08259 -354.461802) (xy 89.123807 -354.426085) (xy 89.169688 -354.396598)
			(xy 89.219298 -354.373939) (xy 89.271628 -354.358572) (xy 89.325612 -354.350808) (xy 89.352882 -354.35032)
			(xy 90.216482 -354.35032) (xy 90.243753 -354.350818) (xy 90.297739 -354.358578) (xy 90.350071 -354.373942)
			(xy 90.399684 -354.396597) (xy 90.445568 -354.426083) (xy 90.486788 -354.461799) (xy 90.522506 -354.503018)
			(xy 90.551994 -354.5489) (xy 90.574652 -354.598512) (xy 90.590018 -354.650844) (xy 90.597781 -354.704829)
			(xy 90.597781 -354.759371) (xy 90.597781 -354.759374) (xy 92.080484 -354.759374) (xy 92.080484 -354.704826)
			(xy 92.088247 -354.650833) (xy 92.103616 -354.598494) (xy 92.126278 -354.548876) (xy 92.155771 -354.502988)
			(xy 92.191495 -354.461765) (xy 92.232722 -354.426046) (xy 92.278613 -354.396558) (xy 92.328234 -354.373902)
			(xy 92.380574 -354.358538) (xy 92.434568 -354.350781) (xy 92.461842 -354.35032) (xy 93.325442 -354.35032)
			(xy 93.352708 -354.350845) (xy 93.406685 -354.358611) (xy 93.459007 -354.37398) (xy 93.508609 -354.396637)
			(xy 93.554483 -354.426123) (xy 93.595693 -354.461836) (xy 93.631402 -354.503051) (xy 93.660883 -354.548928)
			(xy 93.683535 -354.598533) (xy 93.698898 -354.650856) (xy 93.706658 -354.704834) (xy 93.706658 -354.759366)
			(xy 93.706658 -354.759369) (xy 114.589806 -354.759369) (xy 114.589806 -354.704831) (xy 114.597568 -354.650847)
			(xy 114.612932 -354.598518) (xy 114.635587 -354.548908) (xy 114.665071 -354.503026) (xy 114.700785 -354.461807)
			(xy 114.742 -354.42609) (xy 114.78788 -354.396602) (xy 114.837488 -354.373943) (xy 114.889816 -354.358574)
			(xy 114.943799 -354.350809) (xy 114.971068 -354.35032) (xy 115.834668 -354.35032) (xy 115.861939 -354.350817)
			(xy 115.915927 -354.358575) (xy 115.968261 -354.373938) (xy 116.017876 -354.396593) (xy 116.063761 -354.426078)
			(xy 116.104983 -354.461794) (xy 116.140703 -354.503013) (xy 116.170192 -354.548896) (xy 116.192851 -354.598509)
			(xy 116.208218 -354.650842) (xy 116.21598 -354.704829) (xy 116.21598 -354.759371) (xy 116.21598 -354.759374)
			(xy 117.698684 -354.759374) (xy 117.698684 -354.704826) (xy 117.706447 -354.650835) (xy 117.721815 -354.598497)
			(xy 117.744476 -354.54888) (xy 117.773968 -354.502993) (xy 117.80969 -354.46177) (xy 117.850915 -354.426051)
			(xy 117.896804 -354.396562) (xy 117.946423 -354.373905) (xy 117.998762 -354.358541) (xy 118.052754 -354.350782)
			(xy 118.080028 -354.35032) (xy 118.943628 -354.35032) (xy 118.970895 -354.350844) (xy 119.024873 -354.358609)
			(xy 119.077197 -354.373976) (xy 119.126801 -354.396633) (xy 119.172676 -354.426118) (xy 119.213888 -354.461831)
			(xy 119.249599 -354.503046) (xy 119.279081 -354.548924) (xy 119.301734 -354.59853) (xy 119.317097 -354.650855)
			(xy 119.324858 -354.704833) (xy 119.324858 -354.759367) (xy 119.324858 -354.75937) (xy 120.807706 -354.75937)
			(xy 120.807706 -354.70483) (xy 120.815468 -354.650845) (xy 120.830834 -354.598514) (xy 120.85349 -354.548902)
			(xy 120.882976 -354.50302) (xy 120.918692 -354.4618) (xy 120.95991 -354.426083) (xy 121.005791 -354.396596)
			(xy 121.055403 -354.373938) (xy 121.107733 -354.358571) (xy 121.161718 -354.350807) (xy 121.188988 -354.35032)
			(xy 122.052588 -354.35032) (xy 122.079858 -354.350819) (xy 122.133844 -354.358579) (xy 122.186176 -354.373944)
			(xy 122.235788 -354.396599) (xy 122.281671 -354.426085) (xy 122.322891 -354.461801) (xy 122.358608 -354.503019)
			(xy 122.388095 -354.548902) (xy 122.410752 -354.598513) (xy 122.426118 -354.650844) (xy 122.433881 -354.70483)
			(xy 122.433881 -354.75937) (xy 122.43388 -354.759374) (xy 123.916584 -354.759374) (xy 123.916584 -354.704826)
			(xy 123.924347 -354.650832) (xy 123.939717 -354.598493) (xy 123.962379 -354.548874) (xy 123.991872 -354.502986)
			(xy 124.027597 -354.461763) (xy 124.068825 -354.426044) (xy 124.114716 -354.396556) (xy 124.164338 -354.3739)
			(xy 124.216679 -354.358537) (xy 124.270673 -354.35078) (xy 124.297948 -354.35032) (xy 125.161548 -354.35032)
			(xy 125.188814 -354.350846) (xy 125.24279 -354.358613) (xy 125.295111 -354.373981) (xy 125.344713 -354.396639)
			(xy 125.390586 -354.426125) (xy 125.431795 -354.461839) (xy 125.467504 -354.503053) (xy 125.496984 -354.548929)
			(xy 125.519636 -354.598534) (xy 125.534998 -354.650857) (xy 125.542758 -354.704834) (xy 125.542758 -354.759366)
			(xy 125.542757 -354.759373) (xy 127.025584 -354.759373) (xy 127.025584 -354.704827) (xy 127.033346 -354.650837)
			(xy 127.048714 -354.598501) (xy 127.071373 -354.548885) (xy 127.100863 -354.502999) (xy 127.136583 -354.461777)
			(xy 127.177806 -354.426058) (xy 127.223692 -354.396569) (xy 127.273309 -354.373911) (xy 127.325645 -354.358545)
			(xy 127.379635 -354.350783) (xy 127.406908 -354.35032) (xy 128.270508 -354.35032) (xy 128.297776 -354.350843)
			(xy 128.351756 -354.358605) (xy 128.404082 -354.37397) (xy 128.453689 -354.396626) (xy 128.499567 -354.426111)
			(xy 128.540781 -354.461824) (xy 128.576494 -354.50304) (xy 128.605978 -354.548918) (xy 128.628632 -354.598525)
			(xy 128.643997 -354.650852) (xy 128.651758 -354.704832) (xy 128.651758 -354.759368) (xy 128.651758 -354.759369)
			(xy 130.134606 -354.759369) (xy 130.134606 -354.704831) (xy 130.142368 -354.650847) (xy 130.157732 -354.598518)
			(xy 130.180387 -354.548908) (xy 130.209871 -354.503026) (xy 130.245585 -354.461807) (xy 130.2868 -354.42609)
			(xy 130.33268 -354.396602) (xy 130.382288 -354.373943) (xy 130.434616 -354.358574) (xy 130.488599 -354.350809)
			(xy 130.515868 -354.35032) (xy 131.379468 -354.35032) (xy 131.406739 -354.350817) (xy 131.460727 -354.358575)
			(xy 131.513061 -354.373938) (xy 131.562676 -354.396593) (xy 131.608561 -354.426078) (xy 131.649783 -354.461794)
			(xy 131.685503 -354.503013) (xy 131.714992 -354.548896) (xy 131.737651 -354.598509) (xy 131.753018 -354.650842)
			(xy 131.76078 -354.704829) (xy 131.76078 -354.759371) (xy 131.76078 -354.759374) (xy 133.243484 -354.759374)
			(xy 133.243484 -354.704826) (xy 133.251247 -354.650835) (xy 133.266615 -354.598497) (xy 133.289276 -354.54888)
			(xy 133.318768 -354.502993) (xy 133.35449 -354.46177) (xy 133.395715 -354.426051) (xy 133.441604 -354.396562)
			(xy 133.491223 -354.373905) (xy 133.543562 -354.358541) (xy 133.597554 -354.350782) (xy 133.624828 -354.35032)
			(xy 134.488428 -354.35032) (xy 134.515695 -354.350844) (xy 134.569673 -354.358609) (xy 134.621997 -354.373976)
			(xy 134.671601 -354.396633) (xy 134.717476 -354.426118) (xy 134.758688 -354.461831) (xy 134.794399 -354.503046)
			(xy 134.823881 -354.548924) (xy 134.846534 -354.59853) (xy 134.861897 -354.650855) (xy 134.869658 -354.704833)
			(xy 134.869658 -354.759367) (xy 134.869658 -354.75937) (xy 136.352506 -354.75937) (xy 136.352506 -354.70483)
			(xy 136.360268 -354.650845) (xy 136.375634 -354.598514) (xy 136.39829 -354.548902) (xy 136.427776 -354.50302)
			(xy 136.463492 -354.4618) (xy 136.50471 -354.426083) (xy 136.550591 -354.396596) (xy 136.600203 -354.373938)
			(xy 136.652533 -354.358571) (xy 136.706518 -354.350807) (xy 136.733788 -354.35032) (xy 137.597388 -354.35032)
			(xy 137.624658 -354.350819) (xy 137.678644 -354.358579) (xy 137.730976 -354.373944) (xy 137.780588 -354.396599)
			(xy 137.826471 -354.426085) (xy 137.867691 -354.461801) (xy 137.903408 -354.503019) (xy 137.932895 -354.548902)
			(xy 137.955552 -354.598513) (xy 137.970918 -354.650844) (xy 137.978681 -354.70483) (xy 137.978681 -354.75937)
			(xy 137.97868 -354.759374) (xy 139.461384 -354.759374) (xy 139.461384 -354.704826) (xy 139.469147 -354.650832)
			(xy 139.484517 -354.598493) (xy 139.507179 -354.548874) (xy 139.536672 -354.502986) (xy 139.572397 -354.461763)
			(xy 139.613625 -354.426044) (xy 139.659516 -354.396556) (xy 139.709138 -354.3739) (xy 139.761479 -354.358537)
			(xy 139.815473 -354.35078) (xy 139.842748 -354.35032) (xy 140.706348 -354.35032) (xy 140.733614 -354.350846)
			(xy 140.78759 -354.358613) (xy 140.839911 -354.373981) (xy 140.889513 -354.396639) (xy 140.935386 -354.426125)
			(xy 140.976595 -354.461839) (xy 141.012304 -354.503053) (xy 141.041784 -354.548929) (xy 141.064436 -354.598534)
			(xy 141.079798 -354.650857) (xy 141.087558 -354.704834) (xy 141.087558 -354.759366) (xy 141.087557 -354.759373)
			(xy 142.570384 -354.759373) (xy 142.570384 -354.704827) (xy 142.578146 -354.650837) (xy 142.593514 -354.598501)
			(xy 142.616173 -354.548885) (xy 142.645663 -354.502999) (xy 142.681383 -354.461777) (xy 142.722606 -354.426058)
			(xy 142.768492 -354.396569) (xy 142.818109 -354.373911) (xy 142.870445 -354.358545) (xy 142.924435 -354.350783)
			(xy 142.951708 -354.35032) (xy 143.815308 -354.35032) (xy 143.842576 -354.350843) (xy 143.896556 -354.358605)
			(xy 143.948882 -354.37397) (xy 143.998489 -354.396626) (xy 144.044367 -354.426111) (xy 144.085581 -354.461824)
			(xy 144.121294 -354.50304) (xy 144.150778 -354.548918) (xy 144.173432 -354.598525) (xy 144.188797 -354.650852)
			(xy 144.196558 -354.704832) (xy 144.196558 -354.759368) (xy 158.695906 -354.759368) (xy 158.695906 -354.704832)
			(xy 158.703667 -354.65085) (xy 158.719031 -354.598521) (xy 158.741685 -354.548912) (xy 158.771167 -354.503031)
			(xy 158.806879 -354.461813) (xy 158.848093 -354.426096) (xy 158.89397 -354.396608) (xy 158.943576 -354.373948)
			(xy 158.995903 -354.358577) (xy 159.049884 -354.35081) (xy 159.077152 -354.35032) (xy 159.940752 -354.35032)
			(xy 159.968024 -354.350816) (xy 160.022013 -354.358572) (xy 160.074349 -354.373934) (xy 160.123966 -354.396588)
			(xy 160.169854 -354.426072) (xy 160.211078 -354.461788) (xy 160.246799 -354.503008) (xy 160.276289 -354.548891)
			(xy 160.298949 -354.598506) (xy 160.314317 -354.65084) (xy 160.32208 -354.704828) (xy 160.32208 -354.759372)
			(xy 160.32208 -354.759373) (xy 161.804784 -354.759373) (xy 161.804784 -354.704827) (xy 161.812546 -354.650837)
			(xy 161.827914 -354.598501) (xy 161.850573 -354.548884) (xy 161.880064 -354.502998) (xy 161.915784 -354.461776)
			(xy 161.957008 -354.426056) (xy 162.002895 -354.396568) (xy 162.052512 -354.37391) (xy 162.104848 -354.358544)
			(xy 162.158839 -354.350783) (xy 162.186112 -354.35032) (xy 163.049712 -354.35032) (xy 163.07698 -354.350843)
			(xy 163.130959 -354.358606) (xy 163.183285 -354.373972) (xy 163.232891 -354.396627) (xy 163.278768 -354.426112)
			(xy 163.319983 -354.461826) (xy 163.355695 -354.503041) (xy 163.385178 -354.548919) (xy 163.407833 -354.598526)
			(xy 163.423197 -354.650852) (xy 163.430958 -354.704832) (xy 163.430958 -354.759368) (xy 163.430958 -354.759369)
			(xy 164.913806 -354.759369) (xy 164.913806 -354.704831) (xy 164.921568 -354.650847) (xy 164.936932 -354.598517)
			(xy 164.959588 -354.548907) (xy 164.989072 -354.503025) (xy 165.024786 -354.461806) (xy 165.066002 -354.426089)
			(xy 165.111882 -354.396601) (xy 165.161491 -354.373942) (xy 165.21382 -354.358574) (xy 165.267803 -354.350808)
			(xy 165.295072 -354.35032) (xy 166.158672 -354.35032) (xy 166.185943 -354.350818) (xy 166.23993 -354.358576)
			(xy 166.292264 -354.373939) (xy 166.341878 -354.396594) (xy 166.387763 -354.42608) (xy 166.428985 -354.461795)
			(xy 166.464704 -354.503014) (xy 166.494192 -354.548897) (xy 166.516851 -354.59851) (xy 166.532218 -354.650842)
			(xy 166.53998 -354.704829) (xy 166.53998 -354.759371) (xy 166.53998 -354.759374) (xy 168.022684 -354.759374)
			(xy 168.022684 -354.704826) (xy 168.030447 -354.650834) (xy 168.045816 -354.598496) (xy 168.068477 -354.548879)
			(xy 168.097969 -354.502991) (xy 168.133691 -354.461768) (xy 168.174917 -354.426049) (xy 168.220807 -354.396561)
			(xy 168.270426 -354.373904) (xy 168.322765 -354.35854) (xy 168.376758 -354.350781) (xy 168.404032 -354.35032)
			(xy 169.267632 -354.35032) (xy 169.294899 -354.350845) (xy 169.348876 -354.35861) (xy 169.401199 -354.373977)
			(xy 169.450803 -354.396634) (xy 169.496678 -354.426119) (xy 169.53789 -354.461833) (xy 169.5736 -354.503048)
			(xy 169.603081 -354.548925) (xy 169.625734 -354.598531) (xy 169.641097 -354.650855) (xy 169.648858 -354.704833)
			(xy 169.648858 -354.759367) (xy 169.648858 -354.75937) (xy 171.131706 -354.75937) (xy 171.131706 -354.70483)
			(xy 171.139468 -354.650844) (xy 171.154834 -354.598513) (xy 171.177491 -354.548901) (xy 171.206977 -354.503018)
			(xy 171.242693 -354.461799) (xy 171.283912 -354.426082) (xy 171.329794 -354.396594) (xy 171.379405 -354.373937)
			(xy 171.431736 -354.35857) (xy 171.485722 -354.350807) (xy 171.512992 -354.35032) (xy 172.376592 -354.35032)
			(xy 172.403862 -354.350819) (xy 172.457847 -354.35858) (xy 172.510178 -354.373945) (xy 172.55979 -354.396601)
			(xy 172.605673 -354.426087) (xy 172.646892 -354.461802) (xy 172.682609 -354.503021) (xy 172.712096 -354.548903)
			(xy 172.734753 -354.598514) (xy 172.750119 -354.650845) (xy 172.757881 -354.70483) (xy 172.757881 -354.759368)
			(xy 174.240706 -354.759368) (xy 174.240706 -354.704832) (xy 174.248467 -354.65085) (xy 174.263831 -354.598521)
			(xy 174.286485 -354.548912) (xy 174.315967 -354.503031) (xy 174.351679 -354.461813) (xy 174.392893 -354.426096)
			(xy 174.43877 -354.396608) (xy 174.488376 -354.373948) (xy 174.540703 -354.358577) (xy 174.594684 -354.35081)
			(xy 174.621952 -354.35032) (xy 175.485552 -354.35032) (xy 175.512824 -354.350816) (xy 175.566813 -354.358572)
			(xy 175.619149 -354.373934) (xy 175.668766 -354.396588) (xy 175.714654 -354.426072) (xy 175.755878 -354.461788)
			(xy 175.791599 -354.503008) (xy 175.821089 -354.548891) (xy 175.843749 -354.598506) (xy 175.859117 -354.65084)
			(xy 175.86688 -354.704828) (xy 175.86688 -354.759372) (xy 175.86688 -354.759373) (xy 177.349584 -354.759373)
			(xy 177.349584 -354.704827) (xy 177.357346 -354.650837) (xy 177.372714 -354.598501) (xy 177.395373 -354.548884)
			(xy 177.424864 -354.502998) (xy 177.460584 -354.461776) (xy 177.501808 -354.426056) (xy 177.547695 -354.396568)
			(xy 177.597312 -354.37391) (xy 177.649648 -354.358544) (xy 177.703639 -354.350783) (xy 177.730912 -354.35032)
			(xy 178.594512 -354.35032) (xy 178.62178 -354.350843) (xy 178.675759 -354.358606) (xy 178.728085 -354.373972)
			(xy 178.777691 -354.396627) (xy 178.823568 -354.426112) (xy 178.864783 -354.461826) (xy 178.900495 -354.503041)
			(xy 178.929978 -354.548919) (xy 178.952633 -354.598526) (xy 178.967997 -354.650852) (xy 178.975758 -354.704832)
			(xy 178.975758 -354.759368) (xy 178.975758 -354.759369) (xy 180.458606 -354.759369) (xy 180.458606 -354.704831)
			(xy 180.466368 -354.650847) (xy 180.481732 -354.598517) (xy 180.504388 -354.548907) (xy 180.533872 -354.503025)
			(xy 180.569586 -354.461806) (xy 180.610802 -354.426089) (xy 180.656682 -354.396601) (xy 180.706291 -354.373942)
			(xy 180.75862 -354.358574) (xy 180.812603 -354.350808) (xy 180.839872 -354.35032) (xy 181.703472 -354.35032)
			(xy 181.730743 -354.350818) (xy 181.78473 -354.358576) (xy 181.837064 -354.373939) (xy 181.886678 -354.396594)
			(xy 181.932563 -354.42608) (xy 181.973785 -354.461795) (xy 182.009504 -354.503014) (xy 182.038992 -354.548897)
			(xy 182.061651 -354.59851) (xy 182.077018 -354.650842) (xy 182.08478 -354.704829) (xy 182.08478 -354.735472)
			(xy 183.567508 -354.735472) (xy 183.567508 -354.680928) (xy 183.57527 -354.626939) (xy 183.590638 -354.574605)
			(xy 183.613298 -354.52499) (xy 183.642788 -354.479106) (xy 183.678508 -354.437885) (xy 183.719731 -354.402169)
			(xy 183.765618 -354.372682) (xy 183.815235 -354.350027) (xy 183.86757 -354.334664) (xy 183.92156 -354.326905)
			(xy 183.948832 -354.326444) (xy 184.812432 -354.326444) (xy 184.8397 -354.326921) (xy 184.893681 -354.334686)
			(xy 184.946008 -354.350054) (xy 184.995615 -354.372713) (xy 185.041492 -354.4022) (xy 185.082707 -354.437916)
			(xy 185.118419 -354.479133) (xy 185.147903 -354.525013) (xy 185.170557 -354.574622) (xy 185.185921 -354.62695)
			(xy 185.193682 -354.680932) (xy 185.193682 -354.735468) (xy 185.193682 -354.735469) (xy 186.67653 -354.735469)
			(xy 186.67653 -354.680931) (xy 186.684292 -354.626949) (xy 186.699656 -354.574621) (xy 186.722312 -354.525012)
			(xy 186.751796 -354.479133) (xy 186.78751 -354.437916) (xy 186.828726 -354.402201) (xy 186.874605 -354.372716)
			(xy 186.924214 -354.350059) (xy 186.976542 -354.334693) (xy 187.030523 -354.326931) (xy 187.057792 -354.326444)
			(xy 187.921392 -354.326444) (xy 187.948664 -354.326895) (xy 188.002652 -354.334656) (xy 188.054987 -354.350022)
			(xy 188.104602 -354.37268) (xy 188.150487 -354.402167) (xy 188.191709 -354.437885) (xy 188.227428 -354.479106)
			(xy 188.256917 -354.524991) (xy 188.279575 -354.574606) (xy 188.294942 -354.62694) (xy 188.302704 -354.680928)
			(xy 188.302704 -354.735472) (xy 188.299268 -354.759369) (xy 270.624806 -354.759369) (xy 270.624806 -354.704831)
			(xy 270.632567 -354.650848) (xy 270.647932 -354.598519) (xy 270.670586 -354.548909) (xy 270.70007 -354.503028)
			(xy 270.735783 -354.46181) (xy 270.776998 -354.426093) (xy 270.822876 -354.396604) (xy 270.872484 -354.373945)
			(xy 270.924811 -354.358575) (xy 270.978793 -354.350809) (xy 271.006062 -354.35032) (xy 271.869662 -354.35032)
			(xy 271.896933 -354.350817) (xy 271.950922 -354.358574) (xy 272.003257 -354.373936) (xy 272.052872 -354.396591)
			(xy 272.098759 -354.426076) (xy 272.139981 -354.461792) (xy 272.175701 -354.503011) (xy 272.205191 -354.548894)
			(xy 272.22785 -354.598508) (xy 272.243218 -354.650841) (xy 272.25098 -354.704829) (xy 272.25098 -354.759371)
			(xy 272.25098 -354.759373) (xy 273.733684 -354.759373) (xy 273.733684 -354.704827) (xy 273.741447 -354.650835)
			(xy 273.756815 -354.598498) (xy 273.779475 -354.548882) (xy 273.808966 -354.502995) (xy 273.844688 -354.461772)
			(xy 273.885912 -354.426053) (xy 273.931801 -354.396564) (xy 273.981419 -354.373907) (xy 274.033757 -354.358542)
			(xy 274.087749 -354.350782) (xy 274.115022 -354.35032) (xy 274.978622 -354.35032) (xy 275.005889 -354.350844)
			(xy 275.059868 -354.358608) (xy 275.112192 -354.373974) (xy 275.161797 -354.396631) (xy 275.207673 -354.426116)
			(xy 275.248886 -354.461829) (xy 275.284597 -354.503044) (xy 275.31408 -354.548922) (xy 275.336733 -354.598528)
			(xy 275.352097 -354.650854) (xy 275.359858 -354.704833) (xy 275.359858 -354.759367) (xy 275.359858 -354.75937)
			(xy 276.842706 -354.75937) (xy 276.842706 -354.70483) (xy 276.850468 -354.650846) (xy 276.865833 -354.598515)
			(xy 276.888489 -354.548904) (xy 276.917975 -354.503022) (xy 276.95369 -354.461802) (xy 276.994907 -354.426085)
			(xy 277.040788 -354.396598) (xy 277.090398 -354.373939) (xy 277.142728 -354.358572) (xy 277.196712 -354.350808)
			(xy 277.223982 -354.35032) (xy 278.087582 -354.35032) (xy 278.114853 -354.350818) (xy 278.168839 -354.358578)
			(xy 278.221171 -354.373942) (xy 278.270784 -354.396597) (xy 278.316668 -354.426083) (xy 278.357888 -354.461799)
			(xy 278.393606 -354.503018) (xy 278.423094 -354.5489) (xy 278.445752 -354.598512) (xy 278.461118 -354.650844)
			(xy 278.468881 -354.704829) (xy 278.468881 -354.759371) (xy 278.468881 -354.759374) (xy 279.951584 -354.759374)
			(xy 279.951584 -354.704826) (xy 279.959347 -354.650833) (xy 279.974716 -354.598494) (xy 279.997378 -354.548876)
			(xy 280.026871 -354.502988) (xy 280.062595 -354.461765) (xy 280.103822 -354.426046) (xy 280.149713 -354.396558)
			(xy 280.199334 -354.373902) (xy 280.251674 -354.358538) (xy 280.305668 -354.350781) (xy 280.332942 -354.35032)
			(xy 281.196542 -354.35032) (xy 281.223808 -354.350845) (xy 281.277785 -354.358611) (xy 281.330107 -354.37398)
			(xy 281.379709 -354.396637) (xy 281.425583 -354.426123) (xy 281.466793 -354.461836) (xy 281.502502 -354.503051)
			(xy 281.531983 -354.548928) (xy 281.554635 -354.598533) (xy 281.569998 -354.650856) (xy 281.577758 -354.704834)
			(xy 281.577758 -354.759366) (xy 281.577757 -354.759372) (xy 283.060584 -354.759372) (xy 283.060584 -354.704828)
			(xy 283.068346 -354.650838) (xy 283.083713 -354.598503) (xy 283.106372 -354.548887) (xy 283.135861 -354.503001)
			(xy 283.171581 -354.461779) (xy 283.212803 -354.42606) (xy 283.258689 -354.396571) (xy 283.308305 -354.373912)
			(xy 283.36064 -354.358546) (xy 283.41463 -354.350783) (xy 283.441902 -354.35032) (xy 284.305502 -354.35032)
			(xy 284.33277 -354.350843) (xy 284.386751 -354.358604) (xy 284.439078 -354.373969) (xy 284.488685 -354.396624)
			(xy 284.534564 -354.426109) (xy 284.575779 -354.461822) (xy 284.611493 -354.503038) (xy 284.640977 -354.548917)
			(xy 284.663632 -354.598524) (xy 284.678996 -354.650851) (xy 284.686758 -354.704832) (xy 284.686758 -354.759368)
			(xy 284.686758 -354.759369) (xy 286.169606 -354.759369) (xy 286.169606 -354.704831) (xy 286.177367 -354.650848)
			(xy 286.192732 -354.598519) (xy 286.215386 -354.548909) (xy 286.24487 -354.503028) (xy 286.280583 -354.46181)
			(xy 286.321798 -354.426093) (xy 286.367676 -354.396604) (xy 286.417284 -354.373945) (xy 286.469611 -354.358575)
			(xy 286.523593 -354.350809) (xy 286.550862 -354.35032) (xy 287.414462 -354.35032) (xy 287.441733 -354.350817)
			(xy 287.495722 -354.358574) (xy 287.548057 -354.373936) (xy 287.597672 -354.396591) (xy 287.643559 -354.426076)
			(xy 287.684781 -354.461792) (xy 287.720501 -354.503011) (xy 287.749991 -354.548894) (xy 287.77265 -354.598508)
			(xy 287.788018 -354.650841) (xy 287.79578 -354.704829) (xy 287.79578 -354.759371) (xy 287.79578 -354.759373)
			(xy 289.278484 -354.759373) (xy 289.278484 -354.704827) (xy 289.286247 -354.650835) (xy 289.301615 -354.598498)
			(xy 289.324275 -354.548882) (xy 289.353766 -354.502995) (xy 289.389488 -354.461772) (xy 289.430712 -354.426053)
			(xy 289.476601 -354.396564) (xy 289.526219 -354.373907) (xy 289.578557 -354.358542) (xy 289.632549 -354.350782)
			(xy 289.659822 -354.35032) (xy 290.523422 -354.35032) (xy 290.550689 -354.350844) (xy 290.604668 -354.358608)
			(xy 290.656992 -354.373974) (xy 290.706597 -354.396631) (xy 290.752473 -354.426116) (xy 290.793686 -354.461829)
			(xy 290.829397 -354.503044) (xy 290.85888 -354.548922) (xy 290.881533 -354.598528) (xy 290.896897 -354.650854)
			(xy 290.904658 -354.704833) (xy 290.904658 -354.759367) (xy 290.904658 -354.75937) (xy 292.387506 -354.75937)
			(xy 292.387506 -354.70483) (xy 292.395268 -354.650846) (xy 292.410633 -354.598515) (xy 292.433289 -354.548904)
			(xy 292.462775 -354.503022) (xy 292.49849 -354.461802) (xy 292.539707 -354.426085) (xy 292.585588 -354.396598)
			(xy 292.635198 -354.373939) (xy 292.687528 -354.358572) (xy 292.741512 -354.350808) (xy 292.768782 -354.35032)
			(xy 293.632382 -354.35032) (xy 293.659653 -354.350818) (xy 293.713639 -354.358578) (xy 293.765971 -354.373942)
			(xy 293.815584 -354.396597) (xy 293.861468 -354.426083) (xy 293.902688 -354.461799) (xy 293.938406 -354.503018)
			(xy 293.967894 -354.5489) (xy 293.990552 -354.598512) (xy 294.005918 -354.650844) (xy 294.013681 -354.704829)
			(xy 294.013681 -354.759371) (xy 294.013681 -354.759374) (xy 295.496384 -354.759374) (xy 295.496384 -354.704826)
			(xy 295.504147 -354.650833) (xy 295.519516 -354.598494) (xy 295.542178 -354.548876) (xy 295.571671 -354.502988)
			(xy 295.607395 -354.461765) (xy 295.648622 -354.426046) (xy 295.694513 -354.396558) (xy 295.744134 -354.373902)
			(xy 295.796474 -354.358538) (xy 295.850468 -354.350781) (xy 295.877742 -354.35032) (xy 296.741342 -354.35032)
			(xy 296.768608 -354.350845) (xy 296.822585 -354.358611) (xy 296.874907 -354.37398) (xy 296.924509 -354.396637)
			(xy 296.970383 -354.426123) (xy 297.011593 -354.461836) (xy 297.047302 -354.503051) (xy 297.076783 -354.548928)
			(xy 297.099435 -354.598533) (xy 297.114798 -354.650856) (xy 297.122558 -354.704834) (xy 297.122558 -354.759366)
			(xy 297.122557 -354.759372) (xy 298.605384 -354.759372) (xy 298.605384 -354.704828) (xy 298.613146 -354.650838)
			(xy 298.628513 -354.598503) (xy 298.651172 -354.548887) (xy 298.680661 -354.503001) (xy 298.716381 -354.461779)
			(xy 298.757603 -354.42606) (xy 298.803489 -354.396571) (xy 298.853105 -354.373912) (xy 298.90544 -354.358546)
			(xy 298.95943 -354.350783) (xy 298.986702 -354.35032) (xy 299.850302 -354.35032) (xy 299.87757 -354.350843)
			(xy 299.931551 -354.358604) (xy 299.983878 -354.373969) (xy 300.033485 -354.396624) (xy 300.079364 -354.426109)
			(xy 300.120579 -354.461822) (xy 300.156293 -354.503038) (xy 300.185777 -354.548917) (xy 300.208432 -354.598524)
			(xy 300.223796 -354.650851) (xy 300.231558 -354.704832) (xy 300.231558 -354.759368) (xy 300.231558 -354.759369)
			(xy 315.230506 -354.759369) (xy 315.230506 -354.704831) (xy 315.238267 -354.650848) (xy 315.253632 -354.598519)
			(xy 315.276286 -354.548909) (xy 315.30577 -354.503027) (xy 315.341483 -354.461809) (xy 315.382699 -354.426092)
			(xy 315.428577 -354.396604) (xy 315.478185 -354.373944) (xy 315.530513 -354.358575) (xy 315.584495 -354.350809)
			(xy 315.611764 -354.35032) (xy 316.475364 -354.35032) (xy 316.502635 -354.350817) (xy 316.556624 -354.358575)
			(xy 316.608958 -354.373937) (xy 316.658574 -354.396591) (xy 316.70446 -354.426077) (xy 316.745682 -354.461793)
			(xy 316.781402 -354.503012) (xy 316.810891 -354.548895) (xy 316.83355 -354.598508) (xy 316.848918 -354.650841)
			(xy 316.85668 -354.704829) (xy 316.85668 -354.759371) (xy 316.85668 -354.759373) (xy 318.339384 -354.759373)
			(xy 318.339384 -354.704827) (xy 318.347147 -354.650835) (xy 318.362515 -354.598498) (xy 318.385175 -354.548881)
			(xy 318.414667 -354.502994) (xy 318.450388 -354.461771) (xy 318.491613 -354.426052) (xy 318.537502 -354.396564)
			(xy 318.587121 -354.373907) (xy 318.639459 -354.358542) (xy 318.693451 -354.350782) (xy 318.720724 -354.35032)
			(xy 319.584324 -354.35032) (xy 319.611591 -354.350844) (xy 319.665569 -354.358608) (xy 319.717894 -354.373975)
			(xy 319.767498 -354.396631) (xy 319.813374 -354.426116) (xy 319.854587 -354.46183) (xy 319.890298 -354.503045)
			(xy 319.91978 -354.548923) (xy 319.942434 -354.598529) (xy 319.957797 -354.650854) (xy 319.965558 -354.704833)
			(xy 319.965558 -354.759367) (xy 319.965558 -354.75937) (xy 321.448406 -354.75937) (xy 321.448406 -354.70483)
			(xy 321.456168 -354.650845) (xy 321.471533 -354.598515) (xy 321.494189 -354.548903) (xy 321.523675 -354.503021)
			(xy 321.55939 -354.461802) (xy 321.600608 -354.426085) (xy 321.646489 -354.396597) (xy 321.6961 -354.373939)
			(xy 321.74843 -354.358571) (xy 321.802414 -354.350808) (xy 321.829684 -354.35032) (xy 322.693284 -354.35032)
			(xy 322.720554 -354.350818) (xy 322.774541 -354.358578) (xy 322.826873 -354.373942) (xy 322.876485 -354.396598)
			(xy 322.922369 -354.426084) (xy 322.963589 -354.4618) (xy 322.999307 -354.503018) (xy 323.028794 -354.5489)
			(xy 323.051452 -354.598512) (xy 323.066818 -354.650844) (xy 323.074581 -354.70483) (xy 323.074581 -354.75937)
			(xy 323.07458 -354.759374) (xy 324.557284 -354.759374) (xy 324.557284 -354.704826) (xy 324.565047 -354.650832)
			(xy 324.580417 -354.598494) (xy 324.603078 -354.548875) (xy 324.632571 -354.502987) (xy 324.668295 -354.461764)
			(xy 324.709523 -354.426045) (xy 324.755414 -354.396557) (xy 324.805035 -354.373901) (xy 324.857375 -354.358538)
			(xy 324.91137 -354.350781) (xy 324.938644 -354.35032) (xy 325.802244 -354.35032) (xy 325.82951 -354.350845)
			(xy 325.883486 -354.358612) (xy 325.935808 -354.37398) (xy 325.98541 -354.396638) (xy 326.031284 -354.426124)
			(xy 326.072494 -354.461837) (xy 326.108203 -354.503052) (xy 326.137683 -354.548928) (xy 326.160335 -354.598533)
			(xy 326.175698 -354.650857) (xy 326.183458 -354.704834) (xy 326.183458 -354.759366) (xy 326.183457 -354.759372)
			(xy 327.666284 -354.759372) (xy 327.666284 -354.704828) (xy 327.674046 -354.650838) (xy 327.689413 -354.598502)
			(xy 327.712072 -354.548887) (xy 327.741562 -354.503001) (xy 327.777281 -354.461778) (xy 327.818504 -354.426059)
			(xy 327.86439 -354.39657) (xy 327.914006 -354.373912) (xy 327.966342 -354.358545) (xy 328.020332 -354.350783)
			(xy 328.047604 -354.35032) (xy 328.911204 -354.35032) (xy 328.938472 -354.350843) (xy 328.992453 -354.358604)
			(xy 329.044779 -354.373969) (xy 329.094386 -354.396625) (xy 329.140265 -354.426109) (xy 329.18148 -354.461823)
			(xy 329.217193 -354.503039) (xy 329.246677 -354.548917) (xy 329.269332 -354.598525) (xy 329.284696 -354.650851)
			(xy 329.292458 -354.704832) (xy 329.292458 -354.759368) (xy 329.292458 -354.759369) (xy 330.775306 -354.759369)
			(xy 330.775306 -354.704831) (xy 330.783067 -354.650848) (xy 330.798432 -354.598519) (xy 330.821086 -354.548909)
			(xy 330.85057 -354.503027) (xy 330.886283 -354.461809) (xy 330.927499 -354.426092) (xy 330.973377 -354.396604)
			(xy 331.022985 -354.373944) (xy 331.075313 -354.358575) (xy 331.129295 -354.350809) (xy 331.156564 -354.35032)
			(xy 332.020164 -354.35032) (xy 332.047435 -354.350817) (xy 332.101424 -354.358575) (xy 332.153758 -354.373937)
			(xy 332.203374 -354.396591) (xy 332.24926 -354.426077) (xy 332.290482 -354.461793) (xy 332.326202 -354.503012)
			(xy 332.355691 -354.548895) (xy 332.37835 -354.598508) (xy 332.393718 -354.650841) (xy 332.40148 -354.704829)
			(xy 332.40148 -354.759371) (xy 332.40148 -354.759373) (xy 333.884184 -354.759373) (xy 333.884184 -354.704827)
			(xy 333.891947 -354.650835) (xy 333.907315 -354.598498) (xy 333.929975 -354.548881) (xy 333.959467 -354.502994)
			(xy 333.995188 -354.461771) (xy 334.036413 -354.426052) (xy 334.082302 -354.396564) (xy 334.131921 -354.373907)
			(xy 334.184259 -354.358542) (xy 334.238251 -354.350782) (xy 334.265524 -354.35032) (xy 335.129124 -354.35032)
			(xy 335.156391 -354.350844) (xy 335.210369 -354.358608) (xy 335.262694 -354.373975) (xy 335.312298 -354.396631)
			(xy 335.358174 -354.426116) (xy 335.399387 -354.46183) (xy 335.435098 -354.503045) (xy 335.46458 -354.548923)
			(xy 335.487234 -354.598529) (xy 335.502597 -354.650854) (xy 335.510358 -354.704833) (xy 335.510358 -354.759367)
			(xy 335.510358 -354.75937) (xy 336.993206 -354.75937) (xy 336.993206 -354.70483) (xy 337.000968 -354.650845)
			(xy 337.016333 -354.598515) (xy 337.038989 -354.548903) (xy 337.068475 -354.503021) (xy 337.10419 -354.461802)
			(xy 337.145408 -354.426085) (xy 337.191289 -354.396597) (xy 337.2409 -354.373939) (xy 337.29323 -354.358571)
			(xy 337.347214 -354.350808) (xy 337.374484 -354.35032) (xy 338.238084 -354.35032) (xy 338.265354 -354.350818)
			(xy 338.319341 -354.358578) (xy 338.371673 -354.373942) (xy 338.421285 -354.396598) (xy 338.467169 -354.426084)
			(xy 338.508389 -354.4618) (xy 338.544107 -354.503018) (xy 338.573594 -354.5489) (xy 338.596252 -354.598512)
			(xy 338.611618 -354.650844) (xy 338.619381 -354.70483) (xy 338.619381 -354.75937) (xy 338.61938 -354.759374)
			(xy 340.102084 -354.759374) (xy 340.102084 -354.704826) (xy 340.109847 -354.650832) (xy 340.125217 -354.598494)
			(xy 340.147878 -354.548875) (xy 340.177371 -354.502987) (xy 340.213095 -354.461764) (xy 340.254323 -354.426045)
			(xy 340.300214 -354.396557) (xy 340.349835 -354.373901) (xy 340.402175 -354.358538) (xy 340.45617 -354.350781)
			(xy 340.483444 -354.35032) (xy 341.347044 -354.35032) (xy 341.37431 -354.350845) (xy 341.428286 -354.358612)
			(xy 341.480608 -354.37398) (xy 341.53021 -354.396638) (xy 341.576084 -354.426124) (xy 341.617294 -354.461837)
			(xy 341.653003 -354.503052) (xy 341.682483 -354.548928) (xy 341.705135 -354.598533) (xy 341.720498 -354.650857)
			(xy 341.728258 -354.704834) (xy 341.728258 -354.759366) (xy 341.728257 -354.759372) (xy 343.211084 -354.759372)
			(xy 343.211084 -354.704828) (xy 343.218846 -354.650838) (xy 343.234213 -354.598502) (xy 343.256872 -354.548887)
			(xy 343.286362 -354.503001) (xy 343.322081 -354.461778) (xy 343.363304 -354.426059) (xy 343.40919 -354.39657)
			(xy 343.458806 -354.373912) (xy 343.511142 -354.358545) (xy 343.565132 -354.350783) (xy 343.592404 -354.35032)
			(xy 344.456004 -354.35032) (xy 344.483272 -354.350843) (xy 344.537253 -354.358604) (xy 344.589579 -354.373969)
			(xy 344.639186 -354.396625) (xy 344.685065 -354.426109) (xy 344.72628 -354.461823) (xy 344.761993 -354.503039)
			(xy 344.791477 -354.548917) (xy 344.814132 -354.598525) (xy 344.829496 -354.650851) (xy 344.837258 -354.704832)
			(xy 344.837258 -354.759368) (xy 344.837257 -354.759374) (xy 373.915584 -354.759374) (xy 373.915584 -354.704826)
			(xy 373.923347 -354.650833) (xy 373.938716 -354.598495) (xy 373.961378 -354.548876) (xy 373.990871 -354.502989)
			(xy 374.026594 -354.461766) (xy 374.067821 -354.426047) (xy 374.113712 -354.396559) (xy 374.163332 -354.373902)
			(xy 374.215672 -354.358539) (xy 374.269666 -354.350781) (xy 374.29694 -354.35032) (xy 375.16054 -354.35032)
			(xy 375.187806 -354.350845) (xy 375.241783 -354.358611) (xy 375.294105 -354.373979) (xy 375.343708 -354.396637)
			(xy 375.389582 -354.426122) (xy 375.430793 -354.461836) (xy 375.466502 -354.50305) (xy 375.495983 -354.548927)
			(xy 375.518635 -354.598532) (xy 375.533997 -354.650856) (xy 375.541758 -354.704834) (xy 375.541758 -354.759366)
			(xy 375.541757 -354.759371) (xy 377.024606 -354.759371) (xy 377.024606 -354.704829) (xy 377.032369 -354.650843)
			(xy 377.047735 -354.598511) (xy 377.070392 -354.548899) (xy 377.099879 -354.503016) (xy 377.135596 -354.461796)
			(xy 377.176816 -354.426079) (xy 377.222699 -354.396592) (xy 377.272311 -354.373935) (xy 377.324643 -354.358569)
			(xy 377.378629 -354.350806) (xy 377.4059 -354.35032) (xy 378.2695 -354.35032) (xy 378.296768 -354.350842)
			(xy 378.350749 -354.358604) (xy 378.403076 -354.373968) (xy 378.452684 -354.396623) (xy 378.498563 -354.426108)
			(xy 378.539778 -354.461822) (xy 378.575492 -354.503037) (xy 378.604977 -354.548916) (xy 378.627632 -354.598524)
			(xy 378.642996 -354.650851) (xy 378.650758 -354.704832) (xy 378.650758 -354.759368) (xy 378.650758 -354.759369)
			(xy 380.133606 -354.759369) (xy 380.133606 -354.704831) (xy 380.141367 -354.650849) (xy 380.156731 -354.59852)
			(xy 380.179386 -354.54891) (xy 380.208869 -354.503029) (xy 380.244582 -354.46181) (xy 380.285797 -354.426093)
			(xy 380.331675 -354.396605) (xy 380.381282 -354.373945) (xy 380.433609 -354.358576) (xy 380.487591 -354.350809)
			(xy 380.51486 -354.35032) (xy 381.37846 -354.35032) (xy 381.405732 -354.350817) (xy 381.45972 -354.358574)
			(xy 381.512055 -354.373936) (xy 381.561671 -354.39659) (xy 381.607558 -354.426075) (xy 381.648781 -354.461791)
			(xy 381.684501 -354.50301) (xy 381.713991 -354.548894) (xy 381.73665 -354.598507) (xy 381.752018 -354.650841)
			(xy 381.75978 -354.704828) (xy 381.75978 -354.759372) (xy 381.75978 -354.759373) (xy 383.242484 -354.759373)
			(xy 383.242484 -354.704827) (xy 383.250247 -354.650836) (xy 383.265615 -354.598499) (xy 383.288275 -354.548882)
			(xy 383.317766 -354.502995) (xy 383.353487 -354.461773) (xy 383.394711 -354.426054) (xy 383.4406 -354.396565)
			(xy 383.490218 -354.373908) (xy 383.542555 -354.358542) (xy 383.596547 -354.350782) (xy 383.62382 -354.35032)
			(xy 384.48742 -354.35032) (xy 384.514687 -354.350844) (xy 384.568666 -354.358607) (xy 384.620991 -354.373974)
			(xy 384.670596 -354.39663) (xy 384.716472 -354.426115) (xy 384.757686 -354.461829) (xy 384.793397 -354.503044)
			(xy 384.82288 -354.548922) (xy 384.845533 -354.598528) (xy 384.860897 -354.650854) (xy 384.868658 -354.704833)
			(xy 384.868658 -354.759367) (xy 384.868658 -354.75937) (xy 386.351506 -354.75937) (xy 386.351506 -354.70483)
			(xy 386.359268 -354.650846) (xy 386.374633 -354.598515) (xy 386.397289 -354.548904) (xy 386.426774 -354.503022)
			(xy 386.462489 -354.461803) (xy 386.503706 -354.426086) (xy 386.549587 -354.396598) (xy 386.599197 -354.37394)
			(xy 386.651526 -354.358572) (xy 386.70551 -354.350808) (xy 386.73278 -354.35032) (xy 387.59638 -354.35032)
			(xy 387.623651 -354.350818) (xy 387.677637 -354.358578) (xy 387.72997 -354.373941) (xy 387.779583 -354.396597)
			(xy 387.825467 -354.426082) (xy 387.866688 -354.461798) (xy 387.902406 -354.503017) (xy 387.931894 -354.548899)
			(xy 387.954552 -354.598511) (xy 387.969918 -354.650843) (xy 387.97768 -354.704829) (xy 387.97768 -354.759371)
			(xy 387.97768 -354.759374) (xy 389.460384 -354.759374) (xy 389.460384 -354.704826) (xy 389.468147 -354.650833)
			(xy 389.483516 -354.598495) (xy 389.506178 -354.548876) (xy 389.535671 -354.502989) (xy 389.571394 -354.461766)
			(xy 389.612621 -354.426047) (xy 389.658512 -354.396559) (xy 389.708132 -354.373902) (xy 389.760472 -354.358539)
			(xy 389.814466 -354.350781) (xy 389.84174 -354.35032) (xy 390.70534 -354.35032) (xy 390.732606 -354.350845)
			(xy 390.786583 -354.358611) (xy 390.838905 -354.373979) (xy 390.888508 -354.396637) (xy 390.934382 -354.426122)
			(xy 390.975593 -354.461836) (xy 391.011302 -354.50305) (xy 391.040783 -354.548927) (xy 391.063435 -354.598532)
			(xy 391.078797 -354.650856) (xy 391.086558 -354.704834) (xy 391.086558 -354.759366) (xy 391.086557 -354.759371)
			(xy 392.569406 -354.759371) (xy 392.569406 -354.704829) (xy 392.577169 -354.650843) (xy 392.592535 -354.598511)
			(xy 392.615192 -354.548899) (xy 392.644679 -354.503016) (xy 392.680396 -354.461796) (xy 392.721616 -354.426079)
			(xy 392.767499 -354.396592) (xy 392.817111 -354.373935) (xy 392.869443 -354.358569) (xy 392.923429 -354.350806)
			(xy 392.9507 -354.35032) (xy 393.8143 -354.35032) (xy 393.841568 -354.350842) (xy 393.895549 -354.358604)
			(xy 393.947876 -354.373968) (xy 393.997484 -354.396623) (xy 394.043363 -354.426108) (xy 394.084578 -354.461822)
			(xy 394.120292 -354.503037) (xy 394.149777 -354.548916) (xy 394.172432 -354.598524) (xy 394.187796 -354.650851)
			(xy 394.195558 -354.704832) (xy 394.195558 -354.759368) (xy 394.195558 -354.759369) (xy 395.678406 -354.759369)
			(xy 395.678406 -354.704831) (xy 395.686167 -354.650849) (xy 395.701531 -354.59852) (xy 395.724186 -354.54891)
			(xy 395.753669 -354.503029) (xy 395.789382 -354.46181) (xy 395.830597 -354.426093) (xy 395.876475 -354.396605)
			(xy 395.926082 -354.373945) (xy 395.978409 -354.358576) (xy 396.032391 -354.350809) (xy 396.05966 -354.35032)
			(xy 396.92326 -354.35032) (xy 396.950532 -354.350817) (xy 397.00452 -354.358574) (xy 397.056855 -354.373936)
			(xy 397.106471 -354.39659) (xy 397.152358 -354.426075) (xy 397.193581 -354.461791) (xy 397.229301 -354.50301)
			(xy 397.258791 -354.548894) (xy 397.28145 -354.598507) (xy 397.296818 -354.650841) (xy 397.30458 -354.704828)
			(xy 397.30458 -354.759372) (xy 397.30458 -354.759373) (xy 398.787284 -354.759373) (xy 398.787284 -354.704827)
			(xy 398.795047 -354.650836) (xy 398.810415 -354.598499) (xy 398.833075 -354.548882) (xy 398.862566 -354.502995)
			(xy 398.898287 -354.461773) (xy 398.939511 -354.426054) (xy 398.9854 -354.396565) (xy 399.035018 -354.373908)
			(xy 399.087355 -354.358542) (xy 399.141347 -354.350782) (xy 399.16862 -354.35032) (xy 400.03222 -354.35032)
			(xy 400.059487 -354.350844) (xy 400.113466 -354.358607) (xy 400.165791 -354.373974) (xy 400.215396 -354.39663)
			(xy 400.261272 -354.426115) (xy 400.302486 -354.461829) (xy 400.338197 -354.503044) (xy 400.36768 -354.548922)
			(xy 400.390333 -354.598528) (xy 400.405697 -354.650854) (xy 400.413458 -354.704833) (xy 400.413458 -354.759367)
			(xy 400.413458 -354.75937) (xy 401.896306 -354.75937) (xy 401.896306 -354.70483) (xy 401.904068 -354.650846)
			(xy 401.919433 -354.598515) (xy 401.942089 -354.548904) (xy 401.971574 -354.503022) (xy 402.007289 -354.461803)
			(xy 402.048506 -354.426086) (xy 402.094387 -354.396598) (xy 402.143997 -354.37394) (xy 402.196326 -354.358572)
			(xy 402.25031 -354.350808) (xy 402.27758 -354.35032) (xy 403.14118 -354.35032) (xy 403.168451 -354.350818)
			(xy 403.222437 -354.358578) (xy 403.27477 -354.373941) (xy 403.324383 -354.396597) (xy 403.370267 -354.426082)
			(xy 403.411488 -354.461798) (xy 403.447206 -354.503017) (xy 403.476694 -354.548899) (xy 403.499352 -354.598511)
			(xy 403.514718 -354.650843) (xy 403.52248 -354.704829) (xy 403.52248 -354.759368) (xy 412.022806 -354.759368)
			(xy 412.022806 -354.704832) (xy 412.030567 -354.65085) (xy 412.045931 -354.598521) (xy 412.068585 -354.548912)
			(xy 412.098067 -354.503031) (xy 412.133779 -354.461813) (xy 412.174993 -354.426096) (xy 412.22087 -354.396608)
			(xy 412.270476 -354.373948) (xy 412.322803 -354.358577) (xy 412.376784 -354.35081) (xy 412.404052 -354.35032)
			(xy 413.267652 -354.35032) (xy 413.294924 -354.350816) (xy 413.348913 -354.358572) (xy 413.401249 -354.373934)
			(xy 413.450866 -354.396588) (xy 413.496754 -354.426072) (xy 413.537978 -354.461788) (xy 413.573699 -354.503008)
			(xy 413.603189 -354.548891) (xy 413.625849 -354.598506) (xy 413.641217 -354.65084) (xy 413.64898 -354.704828)
			(xy 413.64898 -354.759372) (xy 413.64898 -354.759373) (xy 415.131684 -354.759373) (xy 415.131684 -354.704827)
			(xy 415.139446 -354.650837) (xy 415.154814 -354.598501) (xy 415.177473 -354.548884) (xy 415.206964 -354.502998)
			(xy 415.242684 -354.461776) (xy 415.283908 -354.426056) (xy 415.329795 -354.396568) (xy 415.379412 -354.37391)
			(xy 415.431748 -354.358544) (xy 415.485739 -354.350783) (xy 415.513012 -354.35032) (xy 416.376612 -354.35032)
			(xy 416.40388 -354.350843) (xy 416.457859 -354.358606) (xy 416.510185 -354.373972) (xy 416.559791 -354.396627)
			(xy 416.605668 -354.426112) (xy 416.646883 -354.461826) (xy 416.682595 -354.503041) (xy 416.712078 -354.548919)
			(xy 416.734733 -354.598526) (xy 416.750097 -354.650852) (xy 416.757858 -354.704832) (xy 416.757858 -354.759368)
			(xy 416.757858 -354.759369) (xy 418.240706 -354.759369) (xy 418.240706 -354.704831) (xy 418.248468 -354.650847)
			(xy 418.263832 -354.598517) (xy 418.286488 -354.548907) (xy 418.315972 -354.503025) (xy 418.351686 -354.461806)
			(xy 418.392902 -354.426089) (xy 418.438782 -354.396601) (xy 418.488391 -354.373942) (xy 418.54072 -354.358574)
			(xy 418.594703 -354.350808) (xy 418.621972 -354.35032) (xy 419.485572 -354.35032) (xy 419.512843 -354.350818)
			(xy 419.56683 -354.358576) (xy 419.619164 -354.373939) (xy 419.668778 -354.396594) (xy 419.714663 -354.42608)
			(xy 419.755885 -354.461795) (xy 419.791604 -354.503014) (xy 419.821092 -354.548897) (xy 419.843751 -354.59851)
			(xy 419.859118 -354.650842) (xy 419.86688 -354.704829) (xy 419.86688 -354.759371) (xy 419.86688 -354.759374)
			(xy 421.349584 -354.759374) (xy 421.349584 -354.704826) (xy 421.357347 -354.650834) (xy 421.372716 -354.598496)
			(xy 421.395377 -354.548879) (xy 421.424869 -354.502991) (xy 421.460591 -354.461768) (xy 421.501817 -354.426049)
			(xy 421.547707 -354.396561) (xy 421.597326 -354.373904) (xy 421.649665 -354.35854) (xy 421.703658 -354.350781)
			(xy 421.730932 -354.35032) (xy 422.594532 -354.35032) (xy 422.621799 -354.350845) (xy 422.675776 -354.35861)
			(xy 422.728099 -354.373977) (xy 422.777703 -354.396634) (xy 422.823578 -354.426119) (xy 422.86479 -354.461833)
			(xy 422.9005 -354.503048) (xy 422.929981 -354.548925) (xy 422.952634 -354.598531) (xy 422.967997 -354.650855)
			(xy 422.975758 -354.704833) (xy 422.975758 -354.759367) (xy 422.975758 -354.75937) (xy 424.458606 -354.75937)
			(xy 424.458606 -354.70483) (xy 424.466368 -354.650844) (xy 424.481734 -354.598513) (xy 424.504391 -354.548901)
			(xy 424.533877 -354.503018) (xy 424.569593 -354.461799) (xy 424.610812 -354.426082) (xy 424.656694 -354.396594)
			(xy 424.706305 -354.373937) (xy 424.758636 -354.35857) (xy 424.812622 -354.350807) (xy 424.839892 -354.35032)
			(xy 425.703492 -354.35032) (xy 425.730762 -354.350819) (xy 425.784747 -354.35858) (xy 425.837078 -354.373945)
			(xy 425.88669 -354.396601) (xy 425.932573 -354.426087) (xy 425.973792 -354.461802) (xy 426.009509 -354.503021)
			(xy 426.038996 -354.548903) (xy 426.061653 -354.598514) (xy 426.077019 -354.650845) (xy 426.084781 -354.70483)
			(xy 426.084781 -354.759368) (xy 427.567606 -354.759368) (xy 427.567606 -354.704832) (xy 427.575367 -354.65085)
			(xy 427.590731 -354.598521) (xy 427.613385 -354.548912) (xy 427.642867 -354.503031) (xy 427.678579 -354.461813)
			(xy 427.719793 -354.426096) (xy 427.76567 -354.396608) (xy 427.815276 -354.373948) (xy 427.867603 -354.358577)
			(xy 427.921584 -354.35081) (xy 427.948852 -354.35032) (xy 428.812452 -354.35032) (xy 428.839724 -354.350816)
			(xy 428.893713 -354.358572) (xy 428.946049 -354.373934) (xy 428.995666 -354.396588) (xy 429.041554 -354.426072)
			(xy 429.082778 -354.461788) (xy 429.118499 -354.503008) (xy 429.147989 -354.548891) (xy 429.170649 -354.598506)
			(xy 429.186017 -354.65084) (xy 429.19378 -354.704828) (xy 429.19378 -354.759372) (xy 429.19378 -354.759373)
			(xy 430.676484 -354.759373) (xy 430.676484 -354.704827) (xy 430.684246 -354.650837) (xy 430.699614 -354.598501)
			(xy 430.722273 -354.548884) (xy 430.751764 -354.502998) (xy 430.787484 -354.461776) (xy 430.828708 -354.426056)
			(xy 430.874595 -354.396568) (xy 430.924212 -354.37391) (xy 430.976548 -354.358544) (xy 431.030539 -354.350783)
			(xy 431.057812 -354.35032) (xy 431.921412 -354.35032) (xy 431.94868 -354.350843) (xy 432.002659 -354.358606)
			(xy 432.054985 -354.373972) (xy 432.104591 -354.396627) (xy 432.150468 -354.426112) (xy 432.191683 -354.461826)
			(xy 432.227395 -354.503041) (xy 432.256878 -354.548919) (xy 432.279533 -354.598526) (xy 432.294897 -354.650852)
			(xy 432.302658 -354.704832) (xy 432.302658 -354.759368) (xy 432.302658 -354.759369) (xy 433.785506 -354.759369)
			(xy 433.785506 -354.704831) (xy 433.793268 -354.650847) (xy 433.808632 -354.598517) (xy 433.831288 -354.548907)
			(xy 433.860772 -354.503025) (xy 433.896486 -354.461806) (xy 433.937702 -354.426089) (xy 433.983582 -354.396601)
			(xy 434.033191 -354.373942) (xy 434.08552 -354.358574) (xy 434.139503 -354.350808) (xy 434.166772 -354.35032)
			(xy 435.030372 -354.35032) (xy 435.057643 -354.350818) (xy 435.11163 -354.358576) (xy 435.163964 -354.373939)
			(xy 435.213578 -354.396594) (xy 435.259463 -354.42608) (xy 435.300685 -354.461795) (xy 435.336404 -354.503014)
			(xy 435.365892 -354.548897) (xy 435.388551 -354.59851) (xy 435.403918 -354.650842) (xy 435.41168 -354.704829)
			(xy 435.41168 -354.759371) (xy 435.41168 -354.759374) (xy 436.894384 -354.759374) (xy 436.894384 -354.704826)
			(xy 436.902147 -354.650834) (xy 436.917516 -354.598496) (xy 436.940177 -354.548879) (xy 436.969669 -354.502991)
			(xy 437.005391 -354.461768) (xy 437.046617 -354.426049) (xy 437.092507 -354.396561) (xy 437.142126 -354.373904)
			(xy 437.194465 -354.35854) (xy 437.248458 -354.350781) (xy 437.275732 -354.35032) (xy 438.139332 -354.35032)
			(xy 438.166599 -354.350845) (xy 438.220576 -354.35861) (xy 438.272899 -354.373977) (xy 438.322503 -354.396634)
			(xy 438.368378 -354.426119) (xy 438.40959 -354.461833) (xy 438.4453 -354.503048) (xy 438.474781 -354.548925)
			(xy 438.497434 -354.598531) (xy 438.512797 -354.650855) (xy 438.520558 -354.704833) (xy 438.520558 -354.759367)
			(xy 438.520558 -354.75937) (xy 440.003406 -354.75937) (xy 440.003406 -354.70483) (xy 440.011168 -354.650844)
			(xy 440.026534 -354.598513) (xy 440.049191 -354.548901) (xy 440.078677 -354.503018) (xy 440.114393 -354.461799)
			(xy 440.155612 -354.426082) (xy 440.201494 -354.396594) (xy 440.251105 -354.373937) (xy 440.303436 -354.35857)
			(xy 440.357422 -354.350807) (xy 440.384692 -354.35032) (xy 441.248292 -354.35032) (xy 441.275562 -354.350819)
			(xy 441.329547 -354.35858) (xy 441.381878 -354.373945) (xy 441.43149 -354.396601) (xy 441.477373 -354.426087)
			(xy 441.518592 -354.461802) (xy 441.554309 -354.503021) (xy 441.583796 -354.548903) (xy 441.606453 -354.598514)
			(xy 441.621819 -354.650845) (xy 441.629581 -354.70483) (xy 441.629581 -354.75937) (xy 441.621819 -354.813355)
			(xy 441.606453 -354.865686) (xy 441.583796 -354.915297) (xy 441.554309 -354.961179) (xy 441.518592 -355.002398)
			(xy 441.477373 -355.038113) (xy 441.43149 -355.067599) (xy 441.381878 -355.090255) (xy 441.329547 -355.10562)
			(xy 441.275562 -355.113381) (xy 441.248292 -355.113844) (xy 440.384692 -355.113844) (xy 440.357422 -355.113393)
			(xy 440.303436 -355.10563) (xy 440.251105 -355.090263) (xy 440.201494 -355.067606) (xy 440.155612 -355.038118)
			(xy 440.114393 -355.002401) (xy 440.078677 -354.961182) (xy 440.049191 -354.915299) (xy 440.026534 -354.865687)
			(xy 440.011168 -354.813356) (xy 440.003406 -354.75937) (xy 438.520558 -354.75937) (xy 438.512797 -354.813345)
			(xy 438.497434 -354.865669) (xy 438.474781 -354.915275) (xy 438.4453 -354.961152) (xy 438.40959 -355.002367)
			(xy 438.368378 -355.038081) (xy 438.322503 -355.067566) (xy 438.272899 -355.090223) (xy 438.220576 -355.10559)
			(xy 438.166599 -355.113355) (xy 438.139332 -355.113844) (xy 437.275732 -355.113844) (xy 437.248458 -355.113419)
			(xy 437.194465 -355.10566) (xy 437.142126 -355.090296) (xy 437.092507 -355.067639) (xy 437.046617 -355.038151)
			(xy 437.005391 -355.002432) (xy 436.969669 -354.961209) (xy 436.940177 -354.915321) (xy 436.917516 -354.865704)
			(xy 436.902147 -354.813366) (xy 436.894384 -354.759374) (xy 435.41168 -354.759374) (xy 435.403918 -354.813358)
			(xy 435.388551 -354.86569) (xy 435.365892 -354.915303) (xy 435.336404 -354.961186) (xy 435.300685 -355.002405)
			(xy 435.259463 -355.03812) (xy 435.213578 -355.067606) (xy 435.163964 -355.090261) (xy 435.11163 -355.105624)
			(xy 435.057643 -355.113382) (xy 435.030372 -355.113844) (xy 434.166772 -355.113844) (xy 434.139503 -355.113392)
			(xy 434.08552 -355.105626) (xy 434.033191 -355.090258) (xy 433.983582 -355.067599) (xy 433.937702 -355.038111)
			(xy 433.896486 -355.002394) (xy 433.860772 -354.961175) (xy 433.831288 -354.915293) (xy 433.808632 -354.865683)
			(xy 433.793268 -354.813353) (xy 433.785506 -354.759369) (xy 432.302658 -354.759369) (xy 432.294897 -354.813348)
			(xy 432.279533 -354.865674) (xy 432.256878 -354.915281) (xy 432.227395 -354.961159) (xy 432.191683 -355.002374)
			(xy 432.150468 -355.038088) (xy 432.104591 -355.067573) (xy 432.054985 -355.090228) (xy 432.002659 -355.105594)
			(xy 431.94868 -355.113357) (xy 431.921412 -355.113844) (xy 431.057812 -355.113844) (xy 431.030539 -355.113417)
			(xy 430.976548 -355.105656) (xy 430.924212 -355.09029) (xy 430.874595 -355.067632) (xy 430.828708 -355.038144)
			(xy 430.787484 -355.002424) (xy 430.751764 -354.961202) (xy 430.722273 -354.915316) (xy 430.699614 -354.865699)
			(xy 430.684246 -354.813363) (xy 430.676484 -354.759373) (xy 429.19378 -354.759373) (xy 429.186017 -354.81336)
			(xy 429.170649 -354.865694) (xy 429.147989 -354.915309) (xy 429.118499 -354.961192) (xy 429.082778 -355.002412)
			(xy 429.041554 -355.038128) (xy 428.995666 -355.067612) (xy 428.946049 -355.090266) (xy 428.893713 -355.105628)
			(xy 428.839724 -355.113384) (xy 428.812452 -355.113844) (xy 427.948852 -355.113844) (xy 427.921584 -355.11339)
			(xy 427.867603 -355.105623) (xy 427.815276 -355.090252) (xy 427.76567 -355.067592) (xy 427.719793 -355.038104)
			(xy 427.678579 -355.002387) (xy 427.642867 -354.961169) (xy 427.613385 -354.915288) (xy 427.590731 -354.865679)
			(xy 427.575367 -354.81335) (xy 427.567606 -354.759368) (xy 426.084781 -354.759368) (xy 426.084781 -354.75937)
			(xy 426.077019 -354.813355) (xy 426.061653 -354.865686) (xy 426.038996 -354.915297) (xy 426.009509 -354.961179)
			(xy 425.973792 -355.002398) (xy 425.932573 -355.038113) (xy 425.88669 -355.067599) (xy 425.837078 -355.090255)
			(xy 425.784747 -355.10562) (xy 425.730762 -355.113381) (xy 425.703492 -355.113844) (xy 424.839892 -355.113844)
			(xy 424.812622 -355.113393) (xy 424.758636 -355.10563) (xy 424.706305 -355.090263) (xy 424.656694 -355.067606)
			(xy 424.610812 -355.038118) (xy 424.569593 -355.002401) (xy 424.533877 -354.961182) (xy 424.504391 -354.915299)
			(xy 424.481734 -354.865687) (xy 424.466368 -354.813356) (xy 424.458606 -354.75937) (xy 422.975758 -354.75937)
			(xy 422.967997 -354.813345) (xy 422.952634 -354.865669) (xy 422.929981 -354.915275) (xy 422.9005 -354.961152)
			(xy 422.86479 -355.002367) (xy 422.823578 -355.038081) (xy 422.777703 -355.067566) (xy 422.728099 -355.090223)
			(xy 422.675776 -355.10559) (xy 422.621799 -355.113355) (xy 422.594532 -355.113844) (xy 421.730932 -355.113844)
			(xy 421.703658 -355.113419) (xy 421.649665 -355.10566) (xy 421.597326 -355.090296) (xy 421.547707 -355.067639)
			(xy 421.501817 -355.038151) (xy 421.460591 -355.002432) (xy 421.424869 -354.961209) (xy 421.395377 -354.915321)
			(xy 421.372716 -354.865704) (xy 421.357347 -354.813366) (xy 421.349584 -354.759374) (xy 419.86688 -354.759374)
			(xy 419.859118 -354.813358) (xy 419.843751 -354.86569) (xy 419.821092 -354.915303) (xy 419.791604 -354.961186)
			(xy 419.755885 -355.002405) (xy 419.714663 -355.03812) (xy 419.668778 -355.067606) (xy 419.619164 -355.090261)
			(xy 419.56683 -355.105624) (xy 419.512843 -355.113382) (xy 419.485572 -355.113844) (xy 418.621972 -355.113844)
			(xy 418.594703 -355.113392) (xy 418.54072 -355.105626) (xy 418.488391 -355.090258) (xy 418.438782 -355.067599)
			(xy 418.392902 -355.038111) (xy 418.351686 -355.002394) (xy 418.315972 -354.961175) (xy 418.286488 -354.915293)
			(xy 418.263832 -354.865683) (xy 418.248468 -354.813353) (xy 418.240706 -354.759369) (xy 416.757858 -354.759369)
			(xy 416.750097 -354.813348) (xy 416.734733 -354.865674) (xy 416.712078 -354.915281) (xy 416.682595 -354.961159)
			(xy 416.646883 -355.002374) (xy 416.605668 -355.038088) (xy 416.559791 -355.067573) (xy 416.510185 -355.090228)
			(xy 416.457859 -355.105594) (xy 416.40388 -355.113357) (xy 416.376612 -355.113844) (xy 415.513012 -355.113844)
			(xy 415.485739 -355.113417) (xy 415.431748 -355.105656) (xy 415.379412 -355.09029) (xy 415.329795 -355.067632)
			(xy 415.283908 -355.038144) (xy 415.242684 -355.002424) (xy 415.206964 -354.961202) (xy 415.177473 -354.915316)
			(xy 415.154814 -354.865699) (xy 415.139446 -354.813363) (xy 415.131684 -354.759373) (xy 413.64898 -354.759373)
			(xy 413.641217 -354.81336) (xy 413.625849 -354.865694) (xy 413.603189 -354.915309) (xy 413.573699 -354.961192)
			(xy 413.537978 -355.002412) (xy 413.496754 -355.038128) (xy 413.450866 -355.067612) (xy 413.401249 -355.090266)
			(xy 413.348913 -355.105628) (xy 413.294924 -355.113384) (xy 413.267652 -355.113844) (xy 412.404052 -355.113844)
			(xy 412.376784 -355.11339) (xy 412.322803 -355.105623) (xy 412.270476 -355.090252) (xy 412.22087 -355.067592)
			(xy 412.174993 -355.038104) (xy 412.133779 -355.002387) (xy 412.098067 -354.961169) (xy 412.068585 -354.915288)
			(xy 412.045931 -354.865679) (xy 412.030567 -354.81335) (xy 412.022806 -354.759368) (xy 403.52248 -354.759368)
			(xy 403.52248 -354.759371) (xy 403.514718 -354.813357) (xy 403.499352 -354.865689) (xy 403.476694 -354.915301)
			(xy 403.447206 -354.961183) (xy 403.411488 -355.002402) (xy 403.370267 -355.038118) (xy 403.324383 -355.067603)
			(xy 403.27477 -355.090259) (xy 403.222437 -355.105622) (xy 403.168451 -355.113382) (xy 403.14118 -355.113844)
			(xy 402.27758 -355.113844) (xy 402.25031 -355.113392) (xy 402.196326 -355.105628) (xy 402.143997 -355.09026)
			(xy 402.094387 -355.067602) (xy 402.048506 -355.038114) (xy 402.007289 -355.002397) (xy 401.971574 -354.961178)
			(xy 401.942089 -354.915296) (xy 401.919433 -354.865685) (xy 401.904068 -354.813354) (xy 401.896306 -354.75937)
			(xy 400.413458 -354.75937) (xy 400.405697 -354.813346) (xy 400.390333 -354.865672) (xy 400.36768 -354.915278)
			(xy 400.338197 -354.961156) (xy 400.302486 -355.002371) (xy 400.261272 -355.038085) (xy 400.215396 -355.06757)
			(xy 400.165791 -355.090226) (xy 400.113466 -355.105593) (xy 400.059487 -355.113356) (xy 400.03222 -355.113844)
			(xy 399.16862 -355.113844) (xy 399.141347 -355.113418) (xy 399.087355 -355.105658) (xy 399.035018 -355.090292)
			(xy 398.9854 -355.067635) (xy 398.939511 -355.038146) (xy 398.898287 -355.002427) (xy 398.862566 -354.961205)
			(xy 398.833075 -354.915318) (xy 398.810415 -354.865701) (xy 398.795047 -354.813364) (xy 398.787284 -354.759373)
			(xy 397.30458 -354.759373) (xy 397.296818 -354.813359) (xy 397.28145 -354.865693) (xy 397.258791 -354.915306)
			(xy 397.229301 -354.96119) (xy 397.193581 -355.002409) (xy 397.152358 -355.038125) (xy 397.106471 -355.06761)
			(xy 397.056855 -355.090264) (xy 397.00452 -355.105626) (xy 396.950532 -355.113383) (xy 396.92326 -355.113844)
			(xy 396.05966 -355.113844) (xy 396.032391 -355.113391) (xy 395.978409 -355.105624) (xy 395.926082 -355.090255)
			(xy 395.876475 -355.067595) (xy 395.830597 -355.038107) (xy 395.789382 -355.00239) (xy 395.753669 -354.961171)
			(xy 395.724186 -354.91529) (xy 395.701531 -354.86568) (xy 395.686167 -354.813351) (xy 395.678406 -354.759369)
			(xy 394.195558 -354.759369) (xy 394.187796 -354.813349) (xy 394.172432 -354.865676) (xy 394.149777 -354.915284)
			(xy 394.120292 -354.961163) (xy 394.084578 -355.002378) (xy 394.043363 -355.038092) (xy 393.997484 -355.067577)
			(xy 393.947876 -355.090232) (xy 393.895549 -355.105596) (xy 393.841568 -355.113358) (xy 393.8143 -355.113844)
			(xy 392.9507 -355.113844) (xy 392.923429 -355.113394) (xy 392.869443 -355.105631) (xy 392.817111 -355.090265)
			(xy 392.767499 -355.067608) (xy 392.721616 -355.038121) (xy 392.680396 -355.002404) (xy 392.644679 -354.961184)
			(xy 392.615192 -354.915301) (xy 392.592535 -354.865689) (xy 392.577169 -354.813357) (xy 392.569406 -354.759371)
			(xy 391.086557 -354.759371) (xy 391.078797 -354.813344) (xy 391.063435 -354.865668) (xy 391.040783 -354.915273)
			(xy 391.011302 -354.96115) (xy 390.975593 -355.002364) (xy 390.934382 -355.038078) (xy 390.888508 -355.067563)
			(xy 390.838905 -355.090221) (xy 390.786583 -355.105589) (xy 390.732606 -355.113355) (xy 390.70534 -355.113844)
			(xy 389.84174 -355.113844) (xy 389.814466 -355.113419) (xy 389.760472 -355.105661) (xy 389.708132 -355.090298)
			(xy 389.658512 -355.067641) (xy 389.612621 -355.038153) (xy 389.571394 -355.002434) (xy 389.535671 -354.961211)
			(xy 389.506178 -354.915324) (xy 389.483516 -354.865705) (xy 389.468147 -354.813367) (xy 389.460384 -354.759374)
			(xy 387.97768 -354.759374) (xy 387.969918 -354.813357) (xy 387.954552 -354.865689) (xy 387.931894 -354.915301)
			(xy 387.902406 -354.961183) (xy 387.866688 -355.002402) (xy 387.825467 -355.038118) (xy 387.779583 -355.067603)
			(xy 387.72997 -355.090259) (xy 387.677637 -355.105622) (xy 387.623651 -355.113382) (xy 387.59638 -355.113844)
			(xy 386.73278 -355.113844) (xy 386.70551 -355.113392) (xy 386.651526 -355.105628) (xy 386.599197 -355.09026)
			(xy 386.549587 -355.067602) (xy 386.503706 -355.038114) (xy 386.462489 -355.002397) (xy 386.426774 -354.961178)
			(xy 386.397289 -354.915296) (xy 386.374633 -354.865685) (xy 386.359268 -354.813354) (xy 386.351506 -354.75937)
			(xy 384.868658 -354.75937) (xy 384.860897 -354.813346) (xy 384.845533 -354.865672) (xy 384.82288 -354.915278)
			(xy 384.793397 -354.961156) (xy 384.757686 -355.002371) (xy 384.716472 -355.038085) (xy 384.670596 -355.06757)
			(xy 384.620991 -355.090226) (xy 384.568666 -355.105593) (xy 384.514687 -355.113356) (xy 384.48742 -355.113844)
			(xy 383.62382 -355.113844) (xy 383.596547 -355.113418) (xy 383.542555 -355.105658) (xy 383.490218 -355.090292)
			(xy 383.4406 -355.067635) (xy 383.394711 -355.038146) (xy 383.353487 -355.002427) (xy 383.317766 -354.961205)
			(xy 383.288275 -354.915318) (xy 383.265615 -354.865701) (xy 383.250247 -354.813364) (xy 383.242484 -354.759373)
			(xy 381.75978 -354.759373) (xy 381.752018 -354.813359) (xy 381.73665 -354.865693) (xy 381.713991 -354.915306)
			(xy 381.684501 -354.96119) (xy 381.648781 -355.002409) (xy 381.607558 -355.038125) (xy 381.561671 -355.06761)
			(xy 381.512055 -355.090264) (xy 381.45972 -355.105626) (xy 381.405732 -355.113383) (xy 381.37846 -355.113844)
			(xy 380.51486 -355.113844) (xy 380.487591 -355.113391) (xy 380.433609 -355.105624) (xy 380.381282 -355.090255)
			(xy 380.331675 -355.067595) (xy 380.285797 -355.038107) (xy 380.244582 -355.00239) (xy 380.208869 -354.961171)
			(xy 380.179386 -354.91529) (xy 380.156731 -354.86568) (xy 380.141367 -354.813351) (xy 380.133606 -354.759369)
			(xy 378.650758 -354.759369) (xy 378.642996 -354.813349) (xy 378.627632 -354.865676) (xy 378.604977 -354.915284)
			(xy 378.575492 -354.961163) (xy 378.539778 -355.002378) (xy 378.498563 -355.038092) (xy 378.452684 -355.067577)
			(xy 378.403076 -355.090232) (xy 378.350749 -355.105596) (xy 378.296768 -355.113358) (xy 378.2695 -355.113844)
			(xy 377.4059 -355.113844) (xy 377.378629 -355.113394) (xy 377.324643 -355.105631) (xy 377.272311 -355.090265)
			(xy 377.222699 -355.067608) (xy 377.176816 -355.038121) (xy 377.135596 -355.002404) (xy 377.099879 -354.961184)
			(xy 377.070392 -354.915301) (xy 377.047735 -354.865689) (xy 377.032369 -354.813357) (xy 377.024606 -354.759371)
			(xy 375.541757 -354.759371) (xy 375.533997 -354.813344) (xy 375.518635 -354.865668) (xy 375.495983 -354.915273)
			(xy 375.466502 -354.96115) (xy 375.430793 -355.002364) (xy 375.389582 -355.038078) (xy 375.343708 -355.067563)
			(xy 375.294105 -355.090221) (xy 375.241783 -355.105589) (xy 375.187806 -355.113355) (xy 375.16054 -355.113844)
			(xy 374.29694 -355.113844) (xy 374.269666 -355.113419) (xy 374.215672 -355.105661) (xy 374.163332 -355.090298)
			(xy 374.113712 -355.067641) (xy 374.067821 -355.038153) (xy 374.026594 -355.002434) (xy 373.990871 -354.961211)
			(xy 373.961378 -354.915324) (xy 373.938716 -354.865705) (xy 373.923347 -354.813367) (xy 373.915584 -354.759374)
			(xy 344.837257 -354.759374) (xy 344.829496 -354.813349) (xy 344.814132 -354.865675) (xy 344.791477 -354.915283)
			(xy 344.761993 -354.961161) (xy 344.72628 -355.002377) (xy 344.685065 -355.038091) (xy 344.639186 -355.067575)
			(xy 344.589579 -355.090231) (xy 344.537253 -355.105596) (xy 344.483272 -355.113357) (xy 344.456004 -355.113844)
			(xy 343.592404 -355.113844) (xy 343.565132 -355.113417) (xy 343.511142 -355.105655) (xy 343.458806 -355.090288)
			(xy 343.40919 -355.06763) (xy 343.363304 -355.038141) (xy 343.322081 -355.002422) (xy 343.286362 -354.961199)
			(xy 343.256872 -354.915313) (xy 343.234213 -354.865698) (xy 343.218846 -354.813362) (xy 343.211084 -354.759372)
			(xy 341.728257 -354.759372) (xy 341.720498 -354.813343) (xy 341.705135 -354.865667) (xy 341.682483 -354.915272)
			(xy 341.653003 -354.961148) (xy 341.617294 -355.002363) (xy 341.576084 -355.038076) (xy 341.53021 -355.067562)
			(xy 341.480608 -355.09022) (xy 341.428286 -355.105588) (xy 341.37431 -355.113355) (xy 341.347044 -355.113844)
			(xy 340.483444 -355.113844) (xy 340.45617 -355.113419) (xy 340.402175 -355.105662) (xy 340.349835 -355.090299)
			(xy 340.300214 -355.067643) (xy 340.254323 -355.038155) (xy 340.213095 -355.002436) (xy 340.177371 -354.961213)
			(xy 340.147878 -354.915325) (xy 340.125217 -354.865706) (xy 340.109847 -354.813368) (xy 340.102084 -354.759374)
			(xy 338.61938 -354.759374) (xy 338.611618 -354.813356) (xy 338.596252 -354.865688) (xy 338.573594 -354.9153)
			(xy 338.544107 -354.961182) (xy 338.508389 -355.0024) (xy 338.467169 -355.038116) (xy 338.421285 -355.067602)
			(xy 338.371673 -355.090258) (xy 338.319341 -355.105622) (xy 338.265354 -355.113382) (xy 338.238084 -355.113844)
			(xy 337.374484 -355.113844) (xy 337.347214 -355.113392) (xy 337.29323 -355.105629) (xy 337.2409 -355.090261)
			(xy 337.191289 -355.067603) (xy 337.145408 -355.038115) (xy 337.10419 -355.002398) (xy 337.068475 -354.961179)
			(xy 337.038989 -354.915297) (xy 337.016333 -354.865685) (xy 337.000968 -354.813355) (xy 336.993206 -354.75937)
			(xy 335.510358 -354.75937) (xy 335.502597 -354.813346) (xy 335.487234 -354.865671) (xy 335.46458 -354.915277)
			(xy 335.435098 -354.961155) (xy 335.399387 -355.00237) (xy 335.358174 -355.038084) (xy 335.312298 -355.067569)
			(xy 335.262694 -355.090225) (xy 335.210369 -355.105592) (xy 335.156391 -355.113356) (xy 335.129124 -355.113844)
			(xy 334.265524 -355.113844) (xy 334.238251 -355.113418) (xy 334.184259 -355.105658) (xy 334.131921 -355.090293)
			(xy 334.082302 -355.067636) (xy 334.036413 -355.038148) (xy 333.995188 -355.002429) (xy 333.959467 -354.961206)
			(xy 333.929975 -354.915319) (xy 333.907315 -354.865702) (xy 333.891947 -354.813365) (xy 333.884184 -354.759373)
			(xy 332.40148 -354.759373) (xy 332.393718 -354.813359) (xy 332.37835 -354.865692) (xy 332.355691 -354.915305)
			(xy 332.326202 -354.961188) (xy 332.290482 -355.002407) (xy 332.24926 -355.038123) (xy 332.203374 -355.067609)
			(xy 332.153758 -355.090263) (xy 332.101424 -355.105625) (xy 332.047435 -355.113383) (xy 332.020164 -355.113844)
			(xy 331.156564 -355.113844) (xy 331.129295 -355.113391) (xy 331.075313 -355.105625) (xy 331.022985 -355.090256)
			(xy 330.973377 -355.067596) (xy 330.927499 -355.038108) (xy 330.886283 -355.002391) (xy 330.85057 -354.961173)
			(xy 330.821086 -354.915291) (xy 330.798432 -354.865681) (xy 330.783067 -354.813352) (xy 330.775306 -354.759369)
			(xy 329.292458 -354.759369) (xy 329.284696 -354.813349) (xy 329.269332 -354.865675) (xy 329.246677 -354.915283)
			(xy 329.217193 -354.961161) (xy 329.18148 -355.002377) (xy 329.140265 -355.038091) (xy 329.094386 -355.067575)
			(xy 329.044779 -355.090231) (xy 328.992453 -355.105596) (xy 328.938472 -355.113357) (xy 328.911204 -355.113844)
			(xy 328.047604 -355.113844) (xy 328.020332 -355.113417) (xy 327.966342 -355.105655) (xy 327.914006 -355.090288)
			(xy 327.86439 -355.06763) (xy 327.818504 -355.038141) (xy 327.777281 -355.002422) (xy 327.741562 -354.961199)
			(xy 327.712072 -354.915313) (xy 327.689413 -354.865698) (xy 327.674046 -354.813362) (xy 327.666284 -354.759372)
			(xy 326.183457 -354.759372) (xy 326.175698 -354.813343) (xy 326.160335 -354.865667) (xy 326.137683 -354.915272)
			(xy 326.108203 -354.961148) (xy 326.072494 -355.002363) (xy 326.031284 -355.038076) (xy 325.98541 -355.067562)
			(xy 325.935808 -355.09022) (xy 325.883486 -355.105588) (xy 325.82951 -355.113355) (xy 325.802244 -355.113844)
			(xy 324.938644 -355.113844) (xy 324.91137 -355.113419) (xy 324.857375 -355.105662) (xy 324.805035 -355.090299)
			(xy 324.755414 -355.067643) (xy 324.709523 -355.038155) (xy 324.668295 -355.002436) (xy 324.632571 -354.961213)
			(xy 324.603078 -354.915325) (xy 324.580417 -354.865706) (xy 324.565047 -354.813368) (xy 324.557284 -354.759374)
			(xy 323.07458 -354.759374) (xy 323.066818 -354.813356) (xy 323.051452 -354.865688) (xy 323.028794 -354.9153)
			(xy 322.999307 -354.961182) (xy 322.963589 -355.0024) (xy 322.922369 -355.038116) (xy 322.876485 -355.067602)
			(xy 322.826873 -355.090258) (xy 322.774541 -355.105622) (xy 322.720554 -355.113382) (xy 322.693284 -355.113844)
			(xy 321.829684 -355.113844) (xy 321.802414 -355.113392) (xy 321.74843 -355.105629) (xy 321.6961 -355.090261)
			(xy 321.646489 -355.067603) (xy 321.600608 -355.038115) (xy 321.55939 -355.002398) (xy 321.523675 -354.961179)
			(xy 321.494189 -354.915297) (xy 321.471533 -354.865685) (xy 321.456168 -354.813355) (xy 321.448406 -354.75937)
			(xy 319.965558 -354.75937) (xy 319.957797 -354.813346) (xy 319.942434 -354.865671) (xy 319.91978 -354.915277)
			(xy 319.890298 -354.961155) (xy 319.854587 -355.00237) (xy 319.813374 -355.038084) (xy 319.767498 -355.067569)
			(xy 319.717894 -355.090225) (xy 319.665569 -355.105592) (xy 319.611591 -355.113356) (xy 319.584324 -355.113844)
			(xy 318.720724 -355.113844) (xy 318.693451 -355.113418) (xy 318.639459 -355.105658) (xy 318.587121 -355.090293)
			(xy 318.537502 -355.067636) (xy 318.491613 -355.038148) (xy 318.450388 -355.002429) (xy 318.414667 -354.961206)
			(xy 318.385175 -354.915319) (xy 318.362515 -354.865702) (xy 318.347147 -354.813365) (xy 318.339384 -354.759373)
			(xy 316.85668 -354.759373) (xy 316.848918 -354.813359) (xy 316.83355 -354.865692) (xy 316.810891 -354.915305)
			(xy 316.781402 -354.961188) (xy 316.745682 -355.002407) (xy 316.70446 -355.038123) (xy 316.658574 -355.067609)
			(xy 316.608958 -355.090263) (xy 316.556624 -355.105625) (xy 316.502635 -355.113383) (xy 316.475364 -355.113844)
			(xy 315.611764 -355.113844) (xy 315.584495 -355.113391) (xy 315.530513 -355.105625) (xy 315.478185 -355.090256)
			(xy 315.428577 -355.067596) (xy 315.382699 -355.038108) (xy 315.341483 -355.002391) (xy 315.30577 -354.961173)
			(xy 315.276286 -354.915291) (xy 315.253632 -354.865681) (xy 315.238267 -354.813352) (xy 315.230506 -354.759369)
			(xy 300.231558 -354.759369) (xy 300.223796 -354.813349) (xy 300.208432 -354.865676) (xy 300.185777 -354.915283)
			(xy 300.156293 -354.961162) (xy 300.120579 -355.002378) (xy 300.079364 -355.038091) (xy 300.033485 -355.067576)
			(xy 299.983878 -355.090231) (xy 299.931551 -355.105596) (xy 299.87757 -355.113357) (xy 299.850302 -355.113844)
			(xy 298.986702 -355.113844) (xy 298.95943 -355.113417) (xy 298.90544 -355.105654) (xy 298.853105 -355.090288)
			(xy 298.803489 -355.067629) (xy 298.757603 -355.03814) (xy 298.716381 -355.002421) (xy 298.680661 -354.961199)
			(xy 298.651172 -354.915313) (xy 298.628513 -354.865697) (xy 298.613146 -354.813362) (xy 298.605384 -354.759372)
			(xy 297.122557 -354.759372) (xy 297.114798 -354.813344) (xy 297.099435 -354.865667) (xy 297.076783 -354.915272)
			(xy 297.047302 -354.961149) (xy 297.011593 -355.002364) (xy 296.970383 -355.038077) (xy 296.924509 -355.067563)
			(xy 296.874907 -355.09022) (xy 296.822585 -355.105589) (xy 296.768608 -355.113355) (xy 296.741342 -355.113844)
			(xy 295.877742 -355.113844) (xy 295.850468 -355.113419) (xy 295.796474 -355.105662) (xy 295.744134 -355.090298)
			(xy 295.694513 -355.067642) (xy 295.648622 -355.038154) (xy 295.607395 -355.002435) (xy 295.571671 -354.961212)
			(xy 295.542178 -354.915324) (xy 295.519516 -354.865706) (xy 295.504147 -354.813367) (xy 295.496384 -354.759374)
			(xy 294.013681 -354.759374) (xy 294.005918 -354.813356) (xy 293.990552 -354.865688) (xy 293.967894 -354.9153)
			(xy 293.938406 -354.961182) (xy 293.902688 -355.002401) (xy 293.861468 -355.038117) (xy 293.815584 -355.067603)
			(xy 293.765971 -355.090258) (xy 293.713639 -355.105622) (xy 293.659653 -355.113382) (xy 293.632382 -355.113844)
			(xy 292.768782 -355.113844) (xy 292.741512 -355.113392) (xy 292.687528 -355.105628) (xy 292.635198 -355.090261)
			(xy 292.585588 -355.067602) (xy 292.539707 -355.038115) (xy 292.49849 -355.002398) (xy 292.462775 -354.961178)
			(xy 292.433289 -354.915296) (xy 292.410633 -354.865685) (xy 292.395268 -354.813354) (xy 292.387506 -354.75937)
			(xy 290.904658 -354.75937) (xy 290.896897 -354.813346) (xy 290.881533 -354.865672) (xy 290.85888 -354.915278)
			(xy 290.829397 -354.961156) (xy 290.793686 -355.002371) (xy 290.752473 -355.038084) (xy 290.706597 -355.067569)
			(xy 290.656992 -355.090226) (xy 290.604668 -355.105592) (xy 290.550689 -355.113356) (xy 290.523422 -355.113844)
			(xy 289.659822 -355.113844) (xy 289.632549 -355.113418) (xy 289.578557 -355.105658) (xy 289.526219 -355.090293)
			(xy 289.476601 -355.067636) (xy 289.430712 -355.038147) (xy 289.389488 -355.002428) (xy 289.353766 -354.961205)
			(xy 289.324275 -354.915318) (xy 289.301615 -354.865702) (xy 289.286247 -354.813365) (xy 289.278484 -354.759373)
			(xy 287.79578 -354.759373) (xy 287.788018 -354.813359) (xy 287.77265 -354.865692) (xy 287.749991 -354.915306)
			(xy 287.720501 -354.961189) (xy 287.684781 -355.002408) (xy 287.643559 -355.038124) (xy 287.597672 -355.067609)
			(xy 287.548057 -355.090264) (xy 287.495722 -355.105626) (xy 287.441733 -355.113383) (xy 287.414462 -355.113844)
			(xy 286.550862 -355.113844) (xy 286.523593 -355.113391) (xy 286.469611 -355.105625) (xy 286.417284 -355.090255)
			(xy 286.367676 -355.067596) (xy 286.321798 -355.038107) (xy 286.280583 -355.00239) (xy 286.24487 -354.961172)
			(xy 286.215386 -354.915291) (xy 286.192732 -354.865681) (xy 286.177367 -354.813352) (xy 286.169606 -354.759369)
			(xy 284.686758 -354.759369) (xy 284.678996 -354.813349) (xy 284.663632 -354.865676) (xy 284.640977 -354.915283)
			(xy 284.611493 -354.961162) (xy 284.575779 -355.002378) (xy 284.534564 -355.038091) (xy 284.488685 -355.067576)
			(xy 284.439078 -355.090231) (xy 284.386751 -355.105596) (xy 284.33277 -355.113357) (xy 284.305502 -355.113844)
			(xy 283.441902 -355.113844) (xy 283.41463 -355.113417) (xy 283.36064 -355.105654) (xy 283.308305 -355.090288)
			(xy 283.258689 -355.067629) (xy 283.212803 -355.03814) (xy 283.171581 -355.002421) (xy 283.135861 -354.961199)
			(xy 283.106372 -354.915313) (xy 283.083713 -354.865697) (xy 283.068346 -354.813362) (xy 283.060584 -354.759372)
			(xy 281.577757 -354.759372) (xy 281.569998 -354.813344) (xy 281.554635 -354.865667) (xy 281.531983 -354.915272)
			(xy 281.502502 -354.961149) (xy 281.466793 -355.002364) (xy 281.425583 -355.038077) (xy 281.379709 -355.067563)
			(xy 281.330107 -355.09022) (xy 281.277785 -355.105589) (xy 281.223808 -355.113355) (xy 281.196542 -355.113844)
			(xy 280.332942 -355.113844) (xy 280.305668 -355.113419) (xy 280.251674 -355.105662) (xy 280.199334 -355.090298)
			(xy 280.149713 -355.067642) (xy 280.103822 -355.038154) (xy 280.062595 -355.002435) (xy 280.026871 -354.961212)
			(xy 279.997378 -354.915324) (xy 279.974716 -354.865706) (xy 279.959347 -354.813367) (xy 279.951584 -354.759374)
			(xy 278.468881 -354.759374) (xy 278.461118 -354.813356) (xy 278.445752 -354.865688) (xy 278.423094 -354.9153)
			(xy 278.393606 -354.961182) (xy 278.357888 -355.002401) (xy 278.316668 -355.038117) (xy 278.270784 -355.067603)
			(xy 278.221171 -355.090258) (xy 278.168839 -355.105622) (xy 278.114853 -355.113382) (xy 278.087582 -355.113844)
			(xy 277.223982 -355.113844) (xy 277.196712 -355.113392) (xy 277.142728 -355.105628) (xy 277.090398 -355.090261)
			(xy 277.040788 -355.067602) (xy 276.994907 -355.038115) (xy 276.95369 -355.002398) (xy 276.917975 -354.961178)
			(xy 276.888489 -354.915296) (xy 276.865833 -354.865685) (xy 276.850468 -354.813354) (xy 276.842706 -354.75937)
			(xy 275.359858 -354.75937) (xy 275.352097 -354.813346) (xy 275.336733 -354.865672) (xy 275.31408 -354.915278)
			(xy 275.284597 -354.961156) (xy 275.248886 -355.002371) (xy 275.207673 -355.038084) (xy 275.161797 -355.067569)
			(xy 275.112192 -355.090226) (xy 275.059868 -355.105592) (xy 275.005889 -355.113356) (xy 274.978622 -355.113844)
			(xy 274.115022 -355.113844) (xy 274.087749 -355.113418) (xy 274.033757 -355.105658) (xy 273.981419 -355.090293)
			(xy 273.931801 -355.067636) (xy 273.885912 -355.038147) (xy 273.844688 -355.002428) (xy 273.808966 -354.961205)
			(xy 273.779475 -354.915318) (xy 273.756815 -354.865702) (xy 273.741447 -354.813365) (xy 273.733684 -354.759373)
			(xy 272.25098 -354.759373) (xy 272.243218 -354.813359) (xy 272.22785 -354.865692) (xy 272.205191 -354.915306)
			(xy 272.175701 -354.961189) (xy 272.139981 -355.002408) (xy 272.098759 -355.038124) (xy 272.052872 -355.067609)
			(xy 272.003257 -355.090264) (xy 271.950922 -355.105626) (xy 271.896933 -355.113383) (xy 271.869662 -355.113844)
			(xy 271.006062 -355.113844) (xy 270.978793 -355.113391) (xy 270.924811 -355.105625) (xy 270.872484 -355.090255)
			(xy 270.822876 -355.067596) (xy 270.776998 -355.038107) (xy 270.735783 -355.00239) (xy 270.70007 -354.961172)
			(xy 270.670586 -354.915291) (xy 270.647932 -354.865681) (xy 270.632567 -354.813352) (xy 270.624806 -354.759369)
			(xy 188.299268 -354.759369) (xy 188.294942 -354.78946) (xy 188.279575 -354.841794) (xy 188.256917 -354.891409)
			(xy 188.227428 -354.937294) (xy 188.191709 -354.978515) (xy 188.150487 -355.014233) (xy 188.104602 -355.04372)
			(xy 188.054987 -355.066378) (xy 188.002652 -355.081744) (xy 187.948664 -355.089505) (xy 187.921392 -355.089968)
			(xy 187.057792 -355.089968) (xy 187.030523 -355.089469) (xy 186.976542 -355.081707) (xy 186.924214 -355.066341)
			(xy 186.874605 -355.043684) (xy 186.828726 -355.014199) (xy 186.78751 -354.978484) (xy 186.751796 -354.937267)
			(xy 186.722312 -354.891388) (xy 186.699656 -354.841779) (xy 186.684292 -354.789451) (xy 186.67653 -354.735469)
			(xy 185.193682 -354.735469) (xy 185.185921 -354.78945) (xy 185.170557 -354.841778) (xy 185.147903 -354.891387)
			(xy 185.118419 -354.937267) (xy 185.082707 -354.978484) (xy 185.041492 -355.0142) (xy 184.995615 -355.043687)
			(xy 184.946008 -355.066346) (xy 184.893681 -355.081714) (xy 184.8397 -355.089479) (xy 184.812432 -355.089968)
			(xy 183.948832 -355.089968) (xy 183.92156 -355.089495) (xy 183.86757 -355.081736) (xy 183.815235 -355.066373)
			(xy 183.765618 -355.043718) (xy 183.719731 -355.014231) (xy 183.678508 -354.978515) (xy 183.642788 -354.937294)
			(xy 183.613298 -354.89141) (xy 183.590638 -354.841795) (xy 183.57527 -354.789461) (xy 183.567508 -354.735472)
			(xy 182.08478 -354.735472) (xy 182.08478 -354.759371) (xy 182.077018 -354.813358) (xy 182.061651 -354.86569)
			(xy 182.038992 -354.915303) (xy 182.009504 -354.961186) (xy 181.973785 -355.002405) (xy 181.932563 -355.03812)
			(xy 181.886678 -355.067606) (xy 181.837064 -355.090261) (xy 181.78473 -355.105624) (xy 181.730743 -355.113382)
			(xy 181.703472 -355.113844) (xy 180.839872 -355.113844) (xy 180.812603 -355.113392) (xy 180.75862 -355.105626)
			(xy 180.706291 -355.090258) (xy 180.656682 -355.067599) (xy 180.610802 -355.038111) (xy 180.569586 -355.002394)
			(xy 180.533872 -354.961175) (xy 180.504388 -354.915293) (xy 180.481732 -354.865683) (xy 180.466368 -354.813353)
			(xy 180.458606 -354.759369) (xy 178.975758 -354.759369) (xy 178.967997 -354.813348) (xy 178.952633 -354.865674)
			(xy 178.929978 -354.915281) (xy 178.900495 -354.961159) (xy 178.864783 -355.002374) (xy 178.823568 -355.038088)
			(xy 178.777691 -355.067573) (xy 178.728085 -355.090228) (xy 178.675759 -355.105594) (xy 178.62178 -355.113357)
			(xy 178.594512 -355.113844) (xy 177.730912 -355.113844) (xy 177.703639 -355.113417) (xy 177.649648 -355.105656)
			(xy 177.597312 -355.09029) (xy 177.547695 -355.067632) (xy 177.501808 -355.038144) (xy 177.460584 -355.002424)
			(xy 177.424864 -354.961202) (xy 177.395373 -354.915316) (xy 177.372714 -354.865699) (xy 177.357346 -354.813363)
			(xy 177.349584 -354.759373) (xy 175.86688 -354.759373) (xy 175.859117 -354.81336) (xy 175.843749 -354.865694)
			(xy 175.821089 -354.915309) (xy 175.791599 -354.961192) (xy 175.755878 -355.002412) (xy 175.714654 -355.038128)
			(xy 175.668766 -355.067612) (xy 175.619149 -355.090266) (xy 175.566813 -355.105628) (xy 175.512824 -355.113384)
			(xy 175.485552 -355.113844) (xy 174.621952 -355.113844) (xy 174.594684 -355.11339) (xy 174.540703 -355.105623)
			(xy 174.488376 -355.090252) (xy 174.43877 -355.067592) (xy 174.392893 -355.038104) (xy 174.351679 -355.002387)
			(xy 174.315967 -354.961169) (xy 174.286485 -354.915288) (xy 174.263831 -354.865679) (xy 174.248467 -354.81335)
			(xy 174.240706 -354.759368) (xy 172.757881 -354.759368) (xy 172.757881 -354.75937) (xy 172.750119 -354.813355)
			(xy 172.734753 -354.865686) (xy 172.712096 -354.915297) (xy 172.682609 -354.961179) (xy 172.646892 -355.002398)
			(xy 172.605673 -355.038113) (xy 172.55979 -355.067599) (xy 172.510178 -355.090255) (xy 172.457847 -355.10562)
			(xy 172.403862 -355.113381) (xy 172.376592 -355.113844) (xy 171.512992 -355.113844) (xy 171.485722 -355.113393)
			(xy 171.431736 -355.10563) (xy 171.379405 -355.090263) (xy 171.329794 -355.067606) (xy 171.283912 -355.038118)
			(xy 171.242693 -355.002401) (xy 171.206977 -354.961182) (xy 171.177491 -354.915299) (xy 171.154834 -354.865687)
			(xy 171.139468 -354.813356) (xy 171.131706 -354.75937) (xy 169.648858 -354.75937) (xy 169.641097 -354.813345)
			(xy 169.625734 -354.865669) (xy 169.603081 -354.915275) (xy 169.5736 -354.961152) (xy 169.53789 -355.002367)
			(xy 169.496678 -355.038081) (xy 169.450803 -355.067566) (xy 169.401199 -355.090223) (xy 169.348876 -355.10559)
			(xy 169.294899 -355.113355) (xy 169.267632 -355.113844) (xy 168.404032 -355.113844) (xy 168.376758 -355.113419)
			(xy 168.322765 -355.10566) (xy 168.270426 -355.090296) (xy 168.220807 -355.067639) (xy 168.174917 -355.038151)
			(xy 168.133691 -355.002432) (xy 168.097969 -354.961209) (xy 168.068477 -354.915321) (xy 168.045816 -354.865704)
			(xy 168.030447 -354.813366) (xy 168.022684 -354.759374) (xy 166.53998 -354.759374) (xy 166.532218 -354.813358)
			(xy 166.516851 -354.86569) (xy 166.494192 -354.915303) (xy 166.464704 -354.961186) (xy 166.428985 -355.002405)
			(xy 166.387763 -355.03812) (xy 166.341878 -355.067606) (xy 166.292264 -355.090261) (xy 166.23993 -355.105624)
			(xy 166.185943 -355.113382) (xy 166.158672 -355.113844) (xy 165.295072 -355.113844) (xy 165.267803 -355.113392)
			(xy 165.21382 -355.105626) (xy 165.161491 -355.090258) (xy 165.111882 -355.067599) (xy 165.066002 -355.038111)
			(xy 165.024786 -355.002394) (xy 164.989072 -354.961175) (xy 164.959588 -354.915293) (xy 164.936932 -354.865683)
			(xy 164.921568 -354.813353) (xy 164.913806 -354.759369) (xy 163.430958 -354.759369) (xy 163.423197 -354.813348)
			(xy 163.407833 -354.865674) (xy 163.385178 -354.915281) (xy 163.355695 -354.961159) (xy 163.319983 -355.002374)
			(xy 163.278768 -355.038088) (xy 163.232891 -355.067573) (xy 163.183285 -355.090228) (xy 163.130959 -355.105594)
			(xy 163.07698 -355.113357) (xy 163.049712 -355.113844) (xy 162.186112 -355.113844) (xy 162.158839 -355.113417)
			(xy 162.104848 -355.105656) (xy 162.052512 -355.09029) (xy 162.002895 -355.067632) (xy 161.957008 -355.038144)
			(xy 161.915784 -355.002424) (xy 161.880064 -354.961202) (xy 161.850573 -354.915316) (xy 161.827914 -354.865699)
			(xy 161.812546 -354.813363) (xy 161.804784 -354.759373) (xy 160.32208 -354.759373) (xy 160.314317 -354.81336)
			(xy 160.298949 -354.865694) (xy 160.276289 -354.915309) (xy 160.246799 -354.961192) (xy 160.211078 -355.002412)
			(xy 160.169854 -355.038128) (xy 160.123966 -355.067612) (xy 160.074349 -355.090266) (xy 160.022013 -355.105628)
			(xy 159.968024 -355.113384) (xy 159.940752 -355.113844) (xy 159.077152 -355.113844) (xy 159.049884 -355.11339)
			(xy 158.995903 -355.105623) (xy 158.943576 -355.090252) (xy 158.89397 -355.067592) (xy 158.848093 -355.038104)
			(xy 158.806879 -355.002387) (xy 158.771167 -354.961169) (xy 158.741685 -354.915288) (xy 158.719031 -354.865679)
			(xy 158.703667 -354.81335) (xy 158.695906 -354.759368) (xy 144.196558 -354.759368) (xy 144.188797 -354.813348)
			(xy 144.173432 -354.865675) (xy 144.150778 -354.915282) (xy 144.121294 -354.96116) (xy 144.085581 -355.002376)
			(xy 144.044367 -355.038089) (xy 143.998489 -355.067574) (xy 143.948882 -355.09023) (xy 143.896556 -355.105595)
			(xy 143.842576 -355.113357) (xy 143.815308 -355.113844) (xy 142.951708 -355.113844) (xy 142.924435 -355.113417)
			(xy 142.870445 -355.105655) (xy 142.818109 -355.090289) (xy 142.768492 -355.067631) (xy 142.722606 -355.038142)
			(xy 142.681383 -355.002423) (xy 142.645663 -354.961201) (xy 142.616173 -354.915315) (xy 142.593514 -354.865699)
			(xy 142.578146 -354.813363) (xy 142.570384 -354.759373) (xy 141.087557 -354.759373) (xy 141.079798 -354.813343)
			(xy 141.064436 -354.865666) (xy 141.041784 -354.915271) (xy 141.012304 -354.961147) (xy 140.976595 -355.002361)
			(xy 140.935386 -355.038075) (xy 140.889513 -355.067561) (xy 140.839911 -355.090219) (xy 140.78759 -355.105587)
			(xy 140.733614 -355.113354) (xy 140.706348 -355.113844) (xy 139.842748 -355.113844) (xy 139.815473 -355.11342)
			(xy 139.761479 -355.105663) (xy 139.709138 -355.0903) (xy 139.659516 -355.067644) (xy 139.613625 -355.038156)
			(xy 139.572397 -355.002437) (xy 139.536672 -354.961214) (xy 139.507179 -354.915326) (xy 139.484517 -354.865707)
			(xy 139.469147 -354.813368) (xy 139.461384 -354.759374) (xy 137.97868 -354.759374) (xy 137.970918 -354.813356)
			(xy 137.955552 -354.865687) (xy 137.932895 -354.915298) (xy 137.903408 -354.961181) (xy 137.867691 -355.002399)
			(xy 137.826471 -355.038115) (xy 137.780588 -355.067601) (xy 137.730976 -355.090256) (xy 137.678644 -355.105621)
			(xy 137.624658 -355.113381) (xy 137.597388 -355.113844) (xy 136.733788 -355.113844) (xy 136.706518 -355.113393)
			(xy 136.652533 -355.105629) (xy 136.600203 -355.090262) (xy 136.550591 -355.067604) (xy 136.50471 -355.038117)
			(xy 136.463492 -355.0024) (xy 136.427776 -354.96118) (xy 136.39829 -354.915298) (xy 136.375634 -354.865686)
			(xy 136.360268 -354.813355) (xy 136.352506 -354.75937) (xy 134.869658 -354.75937) (xy 134.861897 -354.813345)
			(xy 134.846534 -354.86567) (xy 134.823881 -354.915276) (xy 134.794399 -354.961154) (xy 134.758688 -355.002369)
			(xy 134.717476 -355.038082) (xy 134.671601 -355.067567) (xy 134.621997 -355.090224) (xy 134.569673 -355.105591)
			(xy 134.515695 -355.113356) (xy 134.488428 -355.113844) (xy 133.624828 -355.113844) (xy 133.597554 -355.113418)
			(xy 133.543562 -355.105659) (xy 133.491223 -355.090295) (xy 133.441604 -355.067638) (xy 133.395715 -355.038149)
			(xy 133.35449 -355.00243) (xy 133.318768 -354.961207) (xy 133.289276 -354.91532) (xy 133.266615 -354.865703)
			(xy 133.251247 -354.813365) (xy 133.243484 -354.759374) (xy 131.76078 -354.759374) (xy 131.753018 -354.813358)
			(xy 131.737651 -354.865691) (xy 131.714992 -354.915304) (xy 131.685503 -354.961187) (xy 131.649783 -355.002406)
			(xy 131.608561 -355.038122) (xy 131.562676 -355.067607) (xy 131.513061 -355.090262) (xy 131.460727 -355.105625)
			(xy 131.406739 -355.113383) (xy 131.379468 -355.113844) (xy 130.515868 -355.113844) (xy 130.488599 -355.113391)
			(xy 130.434616 -355.105626) (xy 130.382288 -355.090257) (xy 130.33268 -355.067598) (xy 130.2868 -355.03811)
			(xy 130.245585 -355.002393) (xy 130.209871 -354.961174) (xy 130.180387 -354.915292) (xy 130.157732 -354.865682)
			(xy 130.142368 -354.813353) (xy 130.134606 -354.759369) (xy 128.651758 -354.759369) (xy 128.643997 -354.813348)
			(xy 128.628632 -354.865675) (xy 128.605978 -354.915282) (xy 128.576494 -354.96116) (xy 128.540781 -355.002376)
			(xy 128.499567 -355.038089) (xy 128.453689 -355.067574) (xy 128.404082 -355.09023) (xy 128.351756 -355.105595)
			(xy 128.297776 -355.113357) (xy 128.270508 -355.113844) (xy 127.406908 -355.113844) (xy 127.379635 -355.113417)
			(xy 127.325645 -355.105655) (xy 127.273309 -355.090289) (xy 127.223692 -355.067631) (xy 127.177806 -355.038142)
			(xy 127.136583 -355.002423) (xy 127.100863 -354.961201) (xy 127.071373 -354.915315) (xy 127.048714 -354.865699)
			(xy 127.033346 -354.813363) (xy 127.025584 -354.759373) (xy 125.542757 -354.759373) (xy 125.534998 -354.813343)
			(xy 125.519636 -354.865666) (xy 125.496984 -354.915271) (xy 125.467504 -354.961147) (xy 125.431795 -355.002361)
			(xy 125.390586 -355.038075) (xy 125.344713 -355.067561) (xy 125.295111 -355.090219) (xy 125.24279 -355.105587)
			(xy 125.188814 -355.113354) (xy 125.161548 -355.113844) (xy 124.297948 -355.113844) (xy 124.270673 -355.11342)
			(xy 124.216679 -355.105663) (xy 124.164338 -355.0903) (xy 124.114716 -355.067644) (xy 124.068825 -355.038156)
			(xy 124.027597 -355.002437) (xy 123.991872 -354.961214) (xy 123.962379 -354.915326) (xy 123.939717 -354.865707)
			(xy 123.924347 -354.813368) (xy 123.916584 -354.759374) (xy 122.43388 -354.759374) (xy 122.426118 -354.813356)
			(xy 122.410752 -354.865687) (xy 122.388095 -354.915298) (xy 122.358608 -354.961181) (xy 122.322891 -355.002399)
			(xy 122.281671 -355.038115) (xy 122.235788 -355.067601) (xy 122.186176 -355.090256) (xy 122.133844 -355.105621)
			(xy 122.079858 -355.113381) (xy 122.052588 -355.113844) (xy 121.188988 -355.113844) (xy 121.161718 -355.113393)
			(xy 121.107733 -355.105629) (xy 121.055403 -355.090262) (xy 121.005791 -355.067604) (xy 120.95991 -355.038117)
			(xy 120.918692 -355.0024) (xy 120.882976 -354.96118) (xy 120.85349 -354.915298) (xy 120.830834 -354.865686)
			(xy 120.815468 -354.813355) (xy 120.807706 -354.75937) (xy 119.324858 -354.75937) (xy 119.317097 -354.813345)
			(xy 119.301734 -354.86567) (xy 119.279081 -354.915276) (xy 119.249599 -354.961154) (xy 119.213888 -355.002369)
			(xy 119.172676 -355.038082) (xy 119.126801 -355.067567) (xy 119.077197 -355.090224) (xy 119.024873 -355.105591)
			(xy 118.970895 -355.113356) (xy 118.943628 -355.113844) (xy 118.080028 -355.113844) (xy 118.052754 -355.113418)
			(xy 117.998762 -355.105659) (xy 117.946423 -355.090295) (xy 117.896804 -355.067638) (xy 117.850915 -355.038149)
			(xy 117.80969 -355.00243) (xy 117.773968 -354.961207) (xy 117.744476 -354.91532) (xy 117.721815 -354.865703)
			(xy 117.706447 -354.813365) (xy 117.698684 -354.759374) (xy 116.21598 -354.759374) (xy 116.208218 -354.813358)
			(xy 116.192851 -354.865691) (xy 116.170192 -354.915304) (xy 116.140703 -354.961187) (xy 116.104983 -355.002406)
			(xy 116.063761 -355.038122) (xy 116.017876 -355.067607) (xy 115.968261 -355.090262) (xy 115.915927 -355.105625)
			(xy 115.861939 -355.113383) (xy 115.834668 -355.113844) (xy 114.971068 -355.113844) (xy 114.943799 -355.113391)
			(xy 114.889816 -355.105626) (xy 114.837488 -355.090257) (xy 114.78788 -355.067598) (xy 114.742 -355.03811)
			(xy 114.700785 -355.002393) (xy 114.665071 -354.961174) (xy 114.635587 -354.915292) (xy 114.612932 -354.865682)
			(xy 114.597568 -354.813353) (xy 114.589806 -354.759369) (xy 93.706658 -354.759369) (xy 93.698898 -354.813344)
			(xy 93.683535 -354.865667) (xy 93.660883 -354.915272) (xy 93.631402 -354.961149) (xy 93.595693 -355.002364)
			(xy 93.554483 -355.038077) (xy 93.508609 -355.067563) (xy 93.459007 -355.09022) (xy 93.406685 -355.105589)
			(xy 93.352708 -355.113355) (xy 93.325442 -355.113844) (xy 92.461842 -355.113844) (xy 92.434568 -355.113419)
			(xy 92.380574 -355.105662) (xy 92.328234 -355.090298) (xy 92.278613 -355.067642) (xy 92.232722 -355.038154)
			(xy 92.191495 -355.002435) (xy 92.155771 -354.961212) (xy 92.126278 -354.915324) (xy 92.103616 -354.865706)
			(xy 92.088247 -354.813367) (xy 92.080484 -354.759374) (xy 90.597781 -354.759374) (xy 90.590018 -354.813356)
			(xy 90.574652 -354.865688) (xy 90.551994 -354.9153) (xy 90.522506 -354.961182) (xy 90.486788 -355.002401)
			(xy 90.445568 -355.038117) (xy 90.399684 -355.067603) (xy 90.350071 -355.090258) (xy 90.297739 -355.105622)
			(xy 90.243753 -355.113382) (xy 90.216482 -355.113844) (xy 89.352882 -355.113844) (xy 89.325612 -355.113392)
			(xy 89.271628 -355.105628) (xy 89.219298 -355.090261) (xy 89.169688 -355.067602) (xy 89.123807 -355.038115)
			(xy 89.08259 -355.002398) (xy 89.046875 -354.961178) (xy 89.017389 -354.915296) (xy 88.994733 -354.865685)
			(xy 88.979368 -354.813354) (xy 88.971606 -354.75937) (xy 87.488758 -354.75937) (xy 87.480997 -354.813346)
			(xy 87.465633 -354.865672) (xy 87.44298 -354.915278) (xy 87.413497 -354.961156) (xy 87.377786 -355.002371)
			(xy 87.336573 -355.038084) (xy 87.290697 -355.067569) (xy 87.241092 -355.090226) (xy 87.188768 -355.105592)
			(xy 87.134789 -355.113356) (xy 87.107522 -355.113844) (xy 86.243922 -355.113844) (xy 86.216649 -355.113418)
			(xy 86.162657 -355.105658) (xy 86.110319 -355.090293) (xy 86.060701 -355.067636) (xy 86.014812 -355.038147)
			(xy 85.973588 -355.002428) (xy 85.937866 -354.961205) (xy 85.908375 -354.915318) (xy 85.885715 -354.865702)
			(xy 85.870347 -354.813365) (xy 85.862584 -354.759373) (xy 84.37988 -354.759373) (xy 84.372118 -354.813359)
			(xy 84.35675 -354.865692) (xy 84.334091 -354.915306) (xy 84.304601 -354.961189) (xy 84.268881 -355.002408)
			(xy 84.227659 -355.038124) (xy 84.181772 -355.067609) (xy 84.132157 -355.090264) (xy 84.079822 -355.105626)
			(xy 84.025833 -355.113383) (xy 83.998562 -355.113844) (xy 83.134962 -355.113844) (xy 83.107693 -355.113391)
			(xy 83.053711 -355.105625) (xy 83.001384 -355.090255) (xy 82.951776 -355.067596) (xy 82.905898 -355.038107)
			(xy 82.864683 -355.00239) (xy 82.82897 -354.961172) (xy 82.799486 -354.915291) (xy 82.776832 -354.865681)
			(xy 82.761467 -354.813352) (xy 82.753706 -354.759369) (xy 81.270858 -354.759369) (xy 81.263096 -354.813349)
			(xy 81.247732 -354.865676) (xy 81.225077 -354.915283) (xy 81.195593 -354.961162) (xy 81.159879 -355.002378)
			(xy 81.118664 -355.038091) (xy 81.072785 -355.067576) (xy 81.023178 -355.090231) (xy 80.970851 -355.105596)
			(xy 80.91687 -355.113357) (xy 80.889602 -355.113844) (xy 80.026002 -355.113844) (xy 79.99873 -355.113417)
			(xy 79.94474 -355.105654) (xy 79.892405 -355.090288) (xy 79.842789 -355.067629) (xy 79.796903 -355.03814)
			(xy 79.755681 -355.002421) (xy 79.719961 -354.961199) (xy 79.690472 -354.915313) (xy 79.667813 -354.865697)
			(xy 79.652446 -354.813362) (xy 79.644684 -354.759372) (xy 78.161857 -354.759372) (xy 78.154098 -354.813344)
			(xy 78.138735 -354.865667) (xy 78.116083 -354.915272) (xy 78.086602 -354.961149) (xy 78.050893 -355.002364)
			(xy 78.009683 -355.038077) (xy 77.963809 -355.067563) (xy 77.914207 -355.09022) (xy 77.861885 -355.105589)
			(xy 77.807908 -355.113355) (xy 77.780642 -355.113844) (xy 76.917042 -355.113844) (xy 76.889768 -355.113419)
			(xy 76.835774 -355.105662) (xy 76.783434 -355.090298) (xy 76.733813 -355.067642) (xy 76.687922 -355.038154)
			(xy 76.646695 -355.002435) (xy 76.610971 -354.961212) (xy 76.581478 -354.915324) (xy 76.558816 -354.865706)
			(xy 76.543447 -354.813367) (xy 76.535684 -354.759374) (xy 75.052981 -354.759374) (xy 75.045218 -354.813356)
			(xy 75.029852 -354.865688) (xy 75.007194 -354.9153) (xy 74.977706 -354.961182) (xy 74.941988 -355.002401)
			(xy 74.900768 -355.038117) (xy 74.854884 -355.067603) (xy 74.805271 -355.090258) (xy 74.752939 -355.105622)
			(xy 74.698953 -355.113382) (xy 74.671682 -355.113844) (xy 73.808082 -355.113844) (xy 73.780812 -355.113392)
			(xy 73.726828 -355.105628) (xy 73.674498 -355.090261) (xy 73.624888 -355.067602) (xy 73.579007 -355.038115)
			(xy 73.53779 -355.002398) (xy 73.502075 -354.961178) (xy 73.472589 -354.915296) (xy 73.449933 -354.865685)
			(xy 73.434568 -354.813354) (xy 73.426806 -354.75937) (xy 71.943958 -354.75937) (xy 71.936197 -354.813346)
			(xy 71.920833 -354.865672) (xy 71.89818 -354.915278) (xy 71.868697 -354.961156) (xy 71.832986 -355.002371)
			(xy 71.791773 -355.038084) (xy 71.745897 -355.067569) (xy 71.696292 -355.090226) (xy 71.643968 -355.105592)
			(xy 71.589989 -355.113356) (xy 71.562722 -355.113844) (xy 70.699122 -355.113844) (xy 70.671849 -355.113418)
			(xy 70.617857 -355.105658) (xy 70.565519 -355.090293) (xy 70.515901 -355.067636) (xy 70.470012 -355.038147)
			(xy 70.428788 -355.002428) (xy 70.393066 -354.961205) (xy 70.363575 -354.915318) (xy 70.340915 -354.865702)
			(xy 70.325547 -354.813365) (xy 70.317784 -354.759373) (xy 68.83508 -354.759373) (xy 68.827318 -354.813359)
			(xy 68.81195 -354.865692) (xy 68.789291 -354.915306) (xy 68.759801 -354.961189) (xy 68.724081 -355.002408)
			(xy 68.682859 -355.038124) (xy 68.636972 -355.067609) (xy 68.587357 -355.090264) (xy 68.535022 -355.105626)
			(xy 68.481033 -355.113383) (xy 68.453762 -355.113844) (xy 67.590162 -355.113844) (xy 67.562893 -355.113391)
			(xy 67.508911 -355.105625) (xy 67.456584 -355.090255) (xy 67.406976 -355.067596) (xy 67.361098 -355.038107)
			(xy 67.319883 -355.00239) (xy 67.28417 -354.961172) (xy 67.254686 -354.915291) (xy 67.232032 -354.865681)
			(xy 67.216667 -354.813352) (xy 67.208906 -354.759369) (xy 65.726058 -354.759369) (xy 65.718296 -354.813349)
			(xy 65.702932 -354.865676) (xy 65.680277 -354.915283) (xy 65.650793 -354.961162) (xy 65.615079 -355.002378)
			(xy 65.573864 -355.038091) (xy 65.527985 -355.067576) (xy 65.478378 -355.090231) (xy 65.426051 -355.105596)
			(xy 65.37207 -355.113357) (xy 65.344802 -355.113844) (xy 64.481202 -355.113844) (xy 64.45393 -355.113417)
			(xy 64.39994 -355.105654) (xy 64.347605 -355.090288) (xy 64.297989 -355.067629) (xy 64.252103 -355.03814)
			(xy 64.210881 -355.002421) (xy 64.175161 -354.961199) (xy 64.145672 -354.915313) (xy 64.123013 -354.865697)
			(xy 64.107646 -354.813362) (xy 64.099884 -354.759372) (xy 51.666857 -354.759372) (xy 51.659098 -354.813343)
			(xy 51.643736 -354.865666) (xy 51.621084 -354.915271) (xy 51.591604 -354.961147) (xy 51.555895 -355.002361)
			(xy 51.514686 -355.038075) (xy 51.468813 -355.067561) (xy 51.419211 -355.090219) (xy 51.36689 -355.105587)
			(xy 51.312914 -355.113354) (xy 51.285648 -355.113844) (xy 50.422048 -355.113844) (xy 50.394773 -355.11342)
			(xy 50.340779 -355.105663) (xy 50.288438 -355.0903) (xy 50.238816 -355.067644) (xy 50.192925 -355.038156)
			(xy 50.151697 -355.002437) (xy 50.115972 -354.961214) (xy 50.086479 -354.915326) (xy 50.063817 -354.865707)
			(xy 50.048447 -354.813368) (xy 50.040684 -354.759374) (xy 48.55798 -354.759374) (xy 48.550218 -354.813356)
			(xy 48.534852 -354.865687) (xy 48.512195 -354.915298) (xy 48.482708 -354.961181) (xy 48.446991 -355.002399)
			(xy 48.405771 -355.038115) (xy 48.359888 -355.067601) (xy 48.310276 -355.090256) (xy 48.257944 -355.105621)
			(xy 48.203958 -355.113381) (xy 48.176688 -355.113844) (xy 47.313088 -355.113844) (xy 47.285818 -355.113393)
			(xy 47.231833 -355.105629) (xy 47.179503 -355.090262) (xy 47.129891 -355.067604) (xy 47.08401 -355.038117)
			(xy 47.042792 -355.0024) (xy 47.007076 -354.96118) (xy 46.97759 -354.915298) (xy 46.954934 -354.865686)
			(xy 46.939568 -354.813355) (xy 46.931806 -354.75937) (xy 45.448958 -354.75937) (xy 45.441197 -354.813345)
			(xy 45.425834 -354.86567) (xy 45.403181 -354.915276) (xy 45.373699 -354.961154) (xy 45.337988 -355.002369)
			(xy 45.296776 -355.038082) (xy 45.250901 -355.067567) (xy 45.201297 -355.090224) (xy 45.148973 -355.105591)
			(xy 45.094995 -355.113356) (xy 45.067728 -355.113844) (xy 44.204128 -355.113844) (xy 44.176854 -355.113418)
			(xy 44.122862 -355.105659) (xy 44.070523 -355.090295) (xy 44.020904 -355.067638) (xy 43.975015 -355.038149)
			(xy 43.93379 -355.00243) (xy 43.898068 -354.961207) (xy 43.868576 -354.91532) (xy 43.845915 -354.865703)
			(xy 43.830547 -354.813365) (xy 43.822784 -354.759374) (xy 42.34008 -354.759374) (xy 42.332318 -354.813358)
			(xy 42.316951 -354.865691) (xy 42.294292 -354.915304) (xy 42.264803 -354.961187) (xy 42.229083 -355.002406)
			(xy 42.187861 -355.038122) (xy 42.141976 -355.067607) (xy 42.092361 -355.090262) (xy 42.040027 -355.105625)
			(xy 41.986039 -355.113383) (xy 41.958768 -355.113844) (xy 41.095168 -355.113844) (xy 41.067899 -355.113391)
			(xy 41.013916 -355.105626) (xy 40.961588 -355.090257) (xy 40.91198 -355.067598) (xy 40.8661 -355.03811)
			(xy 40.824885 -355.002393) (xy 40.789171 -354.961174) (xy 40.759687 -354.915292) (xy 40.737032 -354.865682)
			(xy 40.721668 -354.813353) (xy 40.713906 -354.759369) (xy 39.231058 -354.759369) (xy 39.223297 -354.813348)
			(xy 39.207932 -354.865675) (xy 39.185278 -354.915282) (xy 39.155794 -354.96116) (xy 39.120081 -355.002376)
			(xy 39.078867 -355.038089) (xy 39.032989 -355.067574) (xy 38.983382 -355.09023) (xy 38.931056 -355.105595)
			(xy 38.877076 -355.113357) (xy 38.849808 -355.113844) (xy 37.986208 -355.113844) (xy 37.958935 -355.113417)
			(xy 37.904945 -355.105655) (xy 37.852609 -355.090289) (xy 37.802992 -355.067631) (xy 37.757106 -355.038142)
			(xy 37.715883 -355.002423) (xy 37.680163 -354.961201) (xy 37.650673 -354.915315) (xy 37.628014 -354.865699)
			(xy 37.612646 -354.813363) (xy 37.604884 -354.759373) (xy 36.122057 -354.759373) (xy 36.114298 -354.813343)
			(xy 36.098936 -354.865666) (xy 36.076284 -354.915271) (xy 36.046804 -354.961147) (xy 36.011095 -355.002361)
			(xy 35.969886 -355.038075) (xy 35.924013 -355.067561) (xy 35.874411 -355.090219) (xy 35.82209 -355.105587)
			(xy 35.768114 -355.113354) (xy 35.740848 -355.113844) (xy 34.877248 -355.113844) (xy 34.849973 -355.11342)
			(xy 34.795979 -355.105663) (xy 34.743638 -355.0903) (xy 34.694016 -355.067644) (xy 34.648125 -355.038156)
			(xy 34.606897 -355.002437) (xy 34.571172 -354.961214) (xy 34.541679 -354.915326) (xy 34.519017 -354.865707)
			(xy 34.503647 -354.813368) (xy 34.495884 -354.759374) (xy 33.01318 -354.759374) (xy 33.005418 -354.813356)
			(xy 32.990052 -354.865687) (xy 32.967395 -354.915298) (xy 32.937908 -354.961181) (xy 32.902191 -355.002399)
			(xy 32.860971 -355.038115) (xy 32.815088 -355.067601) (xy 32.765476 -355.090256) (xy 32.713144 -355.105621)
			(xy 32.659158 -355.113381) (xy 32.631888 -355.113844) (xy 31.768288 -355.113844) (xy 31.741018 -355.113393)
			(xy 31.687033 -355.105629) (xy 31.634703 -355.090262) (xy 31.585091 -355.067604) (xy 31.53921 -355.038117)
			(xy 31.497992 -355.0024) (xy 31.462276 -354.96118) (xy 31.43279 -354.915298) (xy 31.410134 -354.865686)
			(xy 31.394768 -354.813355) (xy 31.387006 -354.75937) (xy 29.904158 -354.75937) (xy 29.896397 -354.813345)
			(xy 29.881034 -354.86567) (xy 29.858381 -354.915276) (xy 29.828899 -354.961154) (xy 29.793188 -355.002369)
			(xy 29.751976 -355.038082) (xy 29.706101 -355.067567) (xy 29.656497 -355.090224) (xy 29.604173 -355.105591)
			(xy 29.550195 -355.113356) (xy 29.522928 -355.113844) (xy 28.659328 -355.113844) (xy 28.632054 -355.113418)
			(xy 28.578062 -355.105659) (xy 28.525723 -355.090295) (xy 28.476104 -355.067638) (xy 28.430215 -355.038149)
			(xy 28.38899 -355.00243) (xy 28.353268 -354.961207) (xy 28.323776 -354.91532) (xy 28.301115 -354.865703)
			(xy 28.285747 -354.813365) (xy 28.277984 -354.759374) (xy 26.79528 -354.759374) (xy 26.787518 -354.813358)
			(xy 26.772151 -354.865691) (xy 26.749492 -354.915304) (xy 26.720003 -354.961187) (xy 26.684283 -355.002406)
			(xy 26.643061 -355.038122) (xy 26.597176 -355.067607) (xy 26.547561 -355.090262) (xy 26.495227 -355.105625)
			(xy 26.441239 -355.113383) (xy 26.413968 -355.113844) (xy 25.550368 -355.113844) (xy 25.523099 -355.113391)
			(xy 25.469116 -355.105626) (xy 25.416788 -355.090257) (xy 25.36718 -355.067598) (xy 25.3213 -355.03811)
			(xy 25.280085 -355.002393) (xy 25.244371 -354.961174) (xy 25.214887 -354.915292) (xy 25.192232 -354.865682)
			(xy 25.176868 -354.813353) (xy 25.169106 -354.759369) (xy 23.686258 -354.759369) (xy 23.678497 -354.813348)
			(xy 23.663132 -354.865675) (xy 23.640478 -354.915282) (xy 23.610994 -354.96116) (xy 23.575281 -355.002376)
			(xy 23.534067 -355.038089) (xy 23.488189 -355.067574) (xy 23.438582 -355.09023) (xy 23.386256 -355.105595)
			(xy 23.332276 -355.113357) (xy 23.305008 -355.113844) (xy 22.441408 -355.113844) (xy 22.414135 -355.113417)
			(xy 22.360145 -355.105655) (xy 22.307809 -355.090289) (xy 22.258192 -355.067631) (xy 22.212306 -355.038142)
			(xy 22.171083 -355.002423) (xy 22.135363 -354.961201) (xy 22.105873 -354.915315) (xy 22.083214 -354.865699)
			(xy 22.067846 -354.813363) (xy 22.060084 -354.759373) (xy 0.508 -354.759373) (xy 0.508 -357.784969)
			(xy 22.060131 -357.784969) (xy 22.060131 -357.730431) (xy 22.067893 -357.676447) (xy 22.083259 -357.624118)
			(xy 22.105915 -357.574508) (xy 22.135401 -357.528628) (xy 22.171117 -357.487411) (xy 22.212334 -357.451696)
			(xy 22.258215 -357.422211) (xy 22.307826 -357.399556) (xy 22.360155 -357.384191) (xy 22.414139 -357.376431)
			(xy 22.441408 -357.375968) (xy 23.305008 -357.375968) (xy 23.332279 -357.376395) (xy 23.386266 -357.384158)
			(xy 23.438599 -357.399525) (xy 23.488212 -357.422184) (xy 23.534095 -357.451672) (xy 23.575315 -357.48739)
			(xy 23.611032 -357.528611) (xy 23.64052 -357.574495) (xy 23.663177 -357.624109) (xy 23.678543 -357.676442)
			(xy 23.686306 -357.730429) (xy 23.686306 -357.784966) (xy 25.169154 -357.784966) (xy 25.169154 -357.730434)
			(xy 25.176914 -357.676458) (xy 25.192277 -357.624135) (xy 25.214929 -357.574531) (xy 25.24441 -357.528655)
			(xy 25.280119 -357.487441) (xy 25.321329 -357.451729) (xy 25.367203 -357.422244) (xy 25.416805 -357.399588)
			(xy 25.469126 -357.384221) (xy 25.523102 -357.376457) (xy 25.550368 -357.375968) (xy 26.413968 -357.375968)
			(xy 26.441243 -357.376369) (xy 26.495237 -357.384128) (xy 26.547578 -357.399493) (xy 26.597199 -357.422151)
			(xy 26.64309 -357.45164) (xy 26.684317 -357.48736) (xy 26.720041 -357.528584) (xy 26.749534 -357.574473)
			(xy 26.772196 -357.624092) (xy 26.787565 -357.676431) (xy 26.795328 -357.730425) (xy 26.795328 -357.78497)
			(xy 28.278031 -357.78497) (xy 28.278032 -357.73043) (xy 28.285794 -357.676445) (xy 28.30116 -357.624114)
			(xy 28.323818 -357.574503) (xy 28.353306 -357.528621) (xy 28.389024 -357.487404) (xy 28.430244 -357.451689)
			(xy 28.476127 -357.422205) (xy 28.52574 -357.39955) (xy 28.578072 -357.384188) (xy 28.632058 -357.37643)
			(xy 28.659328 -357.375968) (xy 29.522928 -357.375968) (xy 29.550198 -357.376396) (xy 29.604183 -357.384162)
			(xy 29.656513 -357.399531) (xy 29.706124 -357.42219) (xy 29.752005 -357.451679) (xy 29.793222 -357.487397)
			(xy 29.828937 -357.528618) (xy 29.858423 -357.574501) (xy 29.881079 -357.624113) (xy 29.896444 -357.676444)
			(xy 29.904206 -357.73043) (xy 29.904206 -357.784967) (xy 31.387054 -357.784967) (xy 31.387054 -357.730433)
			(xy 31.394815 -357.676455) (xy 31.410179 -357.624131) (xy 31.432832 -357.574525) (xy 31.462315 -357.528648)
			(xy 31.498026 -357.487434) (xy 31.539239 -357.451722) (xy 31.585115 -357.422238) (xy 31.634719 -357.399583)
			(xy 31.687043 -357.384218) (xy 31.741021 -357.376455) (xy 31.768288 -357.375968) (xy 32.631888 -357.375968)
			(xy 32.659162 -357.376371) (xy 32.713154 -357.384132) (xy 32.765492 -357.399499) (xy 32.815111 -357.422157)
			(xy 32.861 -357.451647) (xy 32.902224 -357.487367) (xy 32.937946 -357.528591) (xy 32.967437 -357.574479)
			(xy 32.990097 -357.624096) (xy 33.005465 -357.676434) (xy 33.013228 -357.730426) (xy 33.013228 -357.784971)
			(xy 34.495932 -357.784971) (xy 34.495932 -357.730429) (xy 34.503694 -357.676442) (xy 34.519062 -357.62411)
			(xy 34.541721 -357.574497) (xy 34.571211 -357.528615) (xy 34.606931 -357.487397) (xy 34.648153 -357.451682)
			(xy 34.694039 -357.422198) (xy 34.743655 -357.399545) (xy 34.795989 -357.384184) (xy 34.849977 -357.376428)
			(xy 34.877248 -357.375968) (xy 35.740848 -357.375968) (xy 35.768117 -357.376398) (xy 35.8221 -357.384166)
			(xy 35.874428 -357.399536) (xy 35.924036 -357.422197) (xy 35.969914 -357.451687) (xy 36.011129 -357.487405)
			(xy 36.046842 -357.528624) (xy 36.076326 -357.574506) (xy 36.09898 -357.624117) (xy 36.114345 -357.676447)
			(xy 36.122106 -357.730431) (xy 36.122106 -357.784969) (xy 37.604931 -357.784969) (xy 37.604931 -357.730431)
			(xy 37.612693 -357.676447) (xy 37.628059 -357.624118) (xy 37.650715 -357.574508) (xy 37.680201 -357.528628)
			(xy 37.715917 -357.487411) (xy 37.757134 -357.451696) (xy 37.803015 -357.422211) (xy 37.852626 -357.399556)
			(xy 37.904955 -357.384191) (xy 37.958939 -357.376431) (xy 37.986208 -357.375968) (xy 38.849808 -357.375968)
			(xy 38.877079 -357.376395) (xy 38.931066 -357.384158) (xy 38.983399 -357.399525) (xy 39.033012 -357.422184)
			(xy 39.078895 -357.451672) (xy 39.120115 -357.48739) (xy 39.155832 -357.528611) (xy 39.18532 -357.574495)
			(xy 39.207977 -357.624109) (xy 39.223343 -357.676442) (xy 39.231106 -357.730429) (xy 39.231106 -357.784966)
			(xy 40.713954 -357.784966) (xy 40.713954 -357.730434) (xy 40.721714 -357.676458) (xy 40.737077 -357.624135)
			(xy 40.759729 -357.574531) (xy 40.78921 -357.528655) (xy 40.824919 -357.487441) (xy 40.866129 -357.451729)
			(xy 40.912003 -357.422244) (xy 40.961605 -357.399588) (xy 41.013926 -357.384221) (xy 41.067902 -357.376457)
			(xy 41.095168 -357.375968) (xy 41.958768 -357.375968) (xy 41.986043 -357.376369) (xy 42.040037 -357.384128)
			(xy 42.092378 -357.399493) (xy 42.141999 -357.422151) (xy 42.18789 -357.45164) (xy 42.229117 -357.48736)
			(xy 42.264841 -357.528584) (xy 42.294334 -357.574473) (xy 42.316996 -357.624092) (xy 42.332365 -357.676431)
			(xy 42.340128 -357.730425) (xy 42.340128 -357.78497) (xy 43.822831 -357.78497) (xy 43.822832 -357.73043)
			(xy 43.830594 -357.676445) (xy 43.84596 -357.624114) (xy 43.868618 -357.574503) (xy 43.898106 -357.528621)
			(xy 43.933824 -357.487404) (xy 43.975044 -357.451689) (xy 44.020927 -357.422205) (xy 44.07054 -357.39955)
			(xy 44.122872 -357.384188) (xy 44.176858 -357.37643) (xy 44.204128 -357.375968) (xy 45.067728 -357.375968)
			(xy 45.094998 -357.376396) (xy 45.148983 -357.384162) (xy 45.201313 -357.399531) (xy 45.250924 -357.42219)
			(xy 45.296805 -357.451679) (xy 45.338022 -357.487397) (xy 45.373737 -357.528618) (xy 45.403223 -357.574501)
			(xy 45.425879 -357.624113) (xy 45.441244 -357.676444) (xy 45.449006 -357.73043) (xy 45.449006 -357.784967)
			(xy 46.931854 -357.784967) (xy 46.931854 -357.730433) (xy 46.939615 -357.676455) (xy 46.954979 -357.624131)
			(xy 46.977632 -357.574525) (xy 47.007115 -357.528648) (xy 47.042826 -357.487434) (xy 47.084039 -357.451722)
			(xy 47.129915 -357.422238) (xy 47.179519 -357.399583) (xy 47.231843 -357.384218) (xy 47.285821 -357.376455)
			(xy 47.313088 -357.375968) (xy 48.176688 -357.375968) (xy 48.203962 -357.376371) (xy 48.257954 -357.384132)
			(xy 48.310292 -357.399499) (xy 48.359911 -357.422157) (xy 48.4058 -357.451647) (xy 48.447024 -357.487367)
			(xy 48.482746 -357.528591) (xy 48.512237 -357.574479) (xy 48.534897 -357.624096) (xy 48.550265 -357.676434)
			(xy 48.558028 -357.730426) (xy 48.558028 -357.784971) (xy 50.040732 -357.784971) (xy 50.040732 -357.730429)
			(xy 50.048494 -357.676442) (xy 50.063862 -357.62411) (xy 50.086521 -357.574497) (xy 50.116011 -357.528615)
			(xy 50.151731 -357.487397) (xy 50.192953 -357.451682) (xy 50.238839 -357.422198) (xy 50.288455 -357.399545)
			(xy 50.340789 -357.384184) (xy 50.394777 -357.376428) (xy 50.422048 -357.375968) (xy 51.285648 -357.375968)
			(xy 51.312917 -357.376398) (xy 51.3669 -357.384166) (xy 51.419228 -357.399536) (xy 51.468836 -357.422197)
			(xy 51.514714 -357.451687) (xy 51.555929 -357.487405) (xy 51.591642 -357.528624) (xy 51.621126 -357.574506)
			(xy 51.64378 -357.624117) (xy 51.659145 -357.676447) (xy 51.666906 -357.730431) (xy 51.666906 -357.784969)
			(xy 64.099931 -357.784969) (xy 64.099931 -357.730431) (xy 64.107693 -357.676448) (xy 64.123058 -357.62412)
			(xy 64.145714 -357.57451) (xy 64.1752 -357.52863) (xy 64.210914 -357.487413) (xy 64.252132 -357.451698)
			(xy 64.298012 -357.422213) (xy 64.347621 -357.399557) (xy 64.39995 -357.384193) (xy 64.453933 -357.376431)
			(xy 64.481202 -357.375968) (xy 65.344802 -357.375968) (xy 65.372073 -357.376395) (xy 65.426061 -357.384157)
			(xy 65.478394 -357.399524) (xy 65.528008 -357.422182) (xy 65.573893 -357.45167) (xy 65.615113 -357.487388)
			(xy 65.650831 -357.528609) (xy 65.680319 -357.574493) (xy 65.702977 -357.624107) (xy 65.718343 -357.676441)
			(xy 65.726106 -357.730429) (xy 65.726106 -357.784966) (xy 67.208954 -357.784966) (xy 67.208954 -357.730435)
			(xy 67.216714 -357.676458) (xy 67.232077 -357.624136) (xy 67.254728 -357.574532) (xy 67.284208 -357.528657)
			(xy 67.319917 -357.487443) (xy 67.361126 -357.451731) (xy 67.406999 -357.422246) (xy 67.4566 -357.39959)
			(xy 67.508921 -357.384222) (xy 67.562897 -357.376457) (xy 67.590162 -357.375968) (xy 68.453762 -357.375968)
			(xy 68.481037 -357.376369) (xy 68.535032 -357.384127) (xy 68.587373 -357.399491) (xy 68.636995 -357.422149)
			(xy 68.682887 -357.451638) (xy 68.724115 -357.487358) (xy 68.75984 -357.528582) (xy 68.789333 -357.574471)
			(xy 68.811995 -357.624091) (xy 68.827365 -357.676431) (xy 68.835128 -357.730425) (xy 68.835128 -357.78497)
			(xy 70.317831 -357.78497) (xy 70.317831 -357.73043) (xy 70.325594 -357.676446) (xy 70.34096 -357.624115)
			(xy 70.363617 -357.574505) (xy 70.393105 -357.528623) (xy 70.428822 -357.487406) (xy 70.470041 -357.451691)
			(xy 70.515924 -357.422207) (xy 70.565536 -357.399552) (xy 70.617867 -357.384189) (xy 70.671852 -357.37643)
			(xy 70.699122 -357.375968) (xy 71.562722 -357.375968) (xy 71.589992 -357.376396) (xy 71.643978 -357.384161)
			(xy 71.696309 -357.399529) (xy 71.74592 -357.422189) (xy 71.791802 -357.451677) (xy 71.83302 -357.487395)
			(xy 71.868736 -357.528616) (xy 71.898222 -357.574499) (xy 71.920878 -357.624112) (xy 71.936244 -357.676444)
			(xy 71.944006 -357.730429) (xy 71.944006 -357.784966) (xy 73.426854 -357.784966) (xy 73.426854 -357.730434)
			(xy 73.434615 -357.676456) (xy 73.449978 -357.624132) (xy 73.472631 -357.574527) (xy 73.502113 -357.52865)
			(xy 73.537824 -357.487436) (xy 73.579036 -357.451724) (xy 73.624911 -357.42224) (xy 73.674515 -357.399584)
			(xy 73.726838 -357.384219) (xy 73.780816 -357.376456) (xy 73.808082 -357.375968) (xy 74.671682 -357.375968)
			(xy 74.698956 -357.37637) (xy 74.752949 -357.384131) (xy 74.805288 -357.399497) (xy 74.854907 -357.422155)
			(xy 74.900797 -357.451645) (xy 74.942022 -357.487365) (xy 74.977744 -357.528589) (xy 75.007236 -357.574477)
			(xy 75.029897 -357.624095) (xy 75.045265 -357.676433) (xy 75.053028 -357.730426) (xy 75.053028 -357.784971)
			(xy 76.535732 -357.784971) (xy 76.535732 -357.730429) (xy 76.543494 -357.676443) (xy 76.558861 -357.624111)
			(xy 76.58152 -357.574499) (xy 76.611009 -357.528617) (xy 76.646729 -357.487399) (xy 76.687951 -357.451684)
			(xy 76.733836 -357.4222) (xy 76.78345 -357.399547) (xy 76.835784 -357.384185) (xy 76.889771 -357.376429)
			(xy 76.917042 -357.375968) (xy 77.780642 -357.375968) (xy 77.807912 -357.376397) (xy 77.861895 -357.384165)
			(xy 77.914223 -357.399535) (xy 77.963832 -357.422195) (xy 78.009711 -357.451684) (xy 78.050927 -357.487402)
			(xy 78.086641 -357.528622) (xy 78.116125 -357.574505) (xy 78.13878 -357.624116) (xy 78.154144 -357.676446)
			(xy 78.161906 -357.73043) (xy 78.161906 -357.784969) (xy 79.644731 -357.784969) (xy 79.644731 -357.730431)
			(xy 79.652493 -357.676448) (xy 79.667858 -357.62412) (xy 79.690514 -357.57451) (xy 79.72 -357.52863)
			(xy 79.755714 -357.487413) (xy 79.796932 -357.451698) (xy 79.842812 -357.422213) (xy 79.892421 -357.399557)
			(xy 79.94475 -357.384193) (xy 79.998733 -357.376431) (xy 80.026002 -357.375968) (xy 80.889602 -357.375968)
			(xy 80.916873 -357.376395) (xy 80.970861 -357.384157) (xy 81.023194 -357.399524) (xy 81.072808 -357.422182)
			(xy 81.118693 -357.45167) (xy 81.159913 -357.487388) (xy 81.195631 -357.528609) (xy 81.225119 -357.574493)
			(xy 81.247777 -357.624107) (xy 81.263143 -357.676441) (xy 81.270906 -357.730429) (xy 81.270906 -357.784966)
			(xy 82.753754 -357.784966) (xy 82.753754 -357.730435) (xy 82.761514 -357.676458) (xy 82.776877 -357.624136)
			(xy 82.799528 -357.574532) (xy 82.829008 -357.528657) (xy 82.864717 -357.487443) (xy 82.905926 -357.451731)
			(xy 82.951799 -357.422246) (xy 83.0014 -357.39959) (xy 83.053721 -357.384222) (xy 83.107697 -357.376457)
			(xy 83.134962 -357.375968) (xy 83.998562 -357.375968) (xy 84.025837 -357.376369) (xy 84.079832 -357.384127)
			(xy 84.132173 -357.399491) (xy 84.181795 -357.422149) (xy 84.227687 -357.451638) (xy 84.268915 -357.487358)
			(xy 84.30464 -357.528582) (xy 84.334133 -357.574471) (xy 84.356795 -357.624091) (xy 84.372165 -357.676431)
			(xy 84.379928 -357.730425) (xy 84.379928 -357.78497) (xy 85.862631 -357.78497) (xy 85.862631 -357.73043)
			(xy 85.870394 -357.676446) (xy 85.88576 -357.624115) (xy 85.908417 -357.574505) (xy 85.937905 -357.528623)
			(xy 85.973622 -357.487406) (xy 86.014841 -357.451691) (xy 86.060724 -357.422207) (xy 86.110336 -357.399552)
			(xy 86.162667 -357.384189) (xy 86.216652 -357.37643) (xy 86.243922 -357.375968) (xy 87.107522 -357.375968)
			(xy 87.134792 -357.376396) (xy 87.188778 -357.384161) (xy 87.241109 -357.399529) (xy 87.29072 -357.422189)
			(xy 87.336602 -357.451677) (xy 87.37782 -357.487395) (xy 87.413536 -357.528616) (xy 87.443022 -357.574499)
			(xy 87.465678 -357.624112) (xy 87.481044 -357.676444) (xy 87.488806 -357.730429) (xy 87.488806 -357.784966)
			(xy 88.971654 -357.784966) (xy 88.971654 -357.730434) (xy 88.979415 -357.676456) (xy 88.994778 -357.624132)
			(xy 89.017431 -357.574527) (xy 89.046913 -357.52865) (xy 89.082624 -357.487436) (xy 89.123836 -357.451724)
			(xy 89.169711 -357.42224) (xy 89.219315 -357.399584) (xy 89.271638 -357.384219) (xy 89.325616 -357.376456)
			(xy 89.352882 -357.375968) (xy 90.216482 -357.375968) (xy 90.243756 -357.37637) (xy 90.297749 -357.384131)
			(xy 90.350088 -357.399497) (xy 90.399707 -357.422155) (xy 90.445597 -357.451645) (xy 90.486822 -357.487365)
			(xy 90.522544 -357.528589) (xy 90.552036 -357.574477) (xy 90.574697 -357.624095) (xy 90.590065 -357.676433)
			(xy 90.597828 -357.730426) (xy 90.597828 -357.784971) (xy 92.080532 -357.784971) (xy 92.080532 -357.730429)
			(xy 92.088294 -357.676443) (xy 92.103661 -357.624111) (xy 92.12632 -357.574499) (xy 92.155809 -357.528617)
			(xy 92.191529 -357.487399) (xy 92.232751 -357.451684) (xy 92.278636 -357.4222) (xy 92.32825 -357.399547)
			(xy 92.380584 -357.384185) (xy 92.434571 -357.376429) (xy 92.461842 -357.375968) (xy 93.325442 -357.375968)
			(xy 93.352712 -357.376397) (xy 93.406695 -357.384165) (xy 93.459023 -357.399535) (xy 93.508632 -357.422195)
			(xy 93.554511 -357.451684) (xy 93.595727 -357.487402) (xy 93.631441 -357.528622) (xy 93.660925 -357.574505)
			(xy 93.68358 -357.624116) (xy 93.698944 -357.676446) (xy 93.706706 -357.73043) (xy 93.706706 -357.784966)
			(xy 114.589854 -357.784966) (xy 114.589854 -357.730434) (xy 114.597614 -357.676458) (xy 114.612977 -357.624135)
			(xy 114.635629 -357.574531) (xy 114.66511 -357.528655) (xy 114.700819 -357.487441) (xy 114.742029 -357.451729)
			(xy 114.787903 -357.422244) (xy 114.837505 -357.399588) (xy 114.889826 -357.384221) (xy 114.943802 -357.376457)
			(xy 114.971068 -357.375968) (xy 115.834668 -357.375968) (xy 115.861943 -357.376369) (xy 115.915937 -357.384128)
			(xy 115.968278 -357.399493) (xy 116.017899 -357.422151) (xy 116.06379 -357.45164) (xy 116.105017 -357.48736)
			(xy 116.140741 -357.528584) (xy 116.170234 -357.574473) (xy 116.192896 -357.624092) (xy 116.208265 -357.676431)
			(xy 116.216028 -357.730425) (xy 116.216028 -357.78497) (xy 117.698731 -357.78497) (xy 117.698732 -357.73043)
			(xy 117.706494 -357.676445) (xy 117.72186 -357.624114) (xy 117.744518 -357.574503) (xy 117.774006 -357.528621)
			(xy 117.809724 -357.487404) (xy 117.850944 -357.451689) (xy 117.896827 -357.422205) (xy 117.94644 -357.39955)
			(xy 117.998772 -357.384188) (xy 118.052758 -357.37643) (xy 118.080028 -357.375968) (xy 118.943628 -357.375968)
			(xy 118.970898 -357.376396) (xy 119.024883 -357.384162) (xy 119.077213 -357.399531) (xy 119.126824 -357.42219)
			(xy 119.172705 -357.451679) (xy 119.213922 -357.487397) (xy 119.249637 -357.528618) (xy 119.279123 -357.574501)
			(xy 119.301779 -357.624113) (xy 119.317144 -357.676444) (xy 119.324906 -357.73043) (xy 119.324906 -357.784967)
			(xy 120.807754 -357.784967) (xy 120.807754 -357.730433) (xy 120.815515 -357.676455) (xy 120.830879 -357.624131)
			(xy 120.853532 -357.574525) (xy 120.883015 -357.528648) (xy 120.918726 -357.487434) (xy 120.959939 -357.451722)
			(xy 121.005815 -357.422238) (xy 121.055419 -357.399583) (xy 121.107743 -357.384218) (xy 121.161721 -357.376455)
			(xy 121.188988 -357.375968) (xy 122.052588 -357.375968) (xy 122.079862 -357.376371) (xy 122.133854 -357.384132)
			(xy 122.186192 -357.399499) (xy 122.235811 -357.422157) (xy 122.2817 -357.451647) (xy 122.322924 -357.487367)
			(xy 122.358646 -357.528591) (xy 122.388137 -357.574479) (xy 122.410797 -357.624096) (xy 122.426165 -357.676434)
			(xy 122.433928 -357.730426) (xy 122.433928 -357.784971) (xy 123.916632 -357.784971) (xy 123.916632 -357.730429)
			(xy 123.924394 -357.676442) (xy 123.939762 -357.62411) (xy 123.962421 -357.574497) (xy 123.991911 -357.528615)
			(xy 124.027631 -357.487397) (xy 124.068853 -357.451682) (xy 124.114739 -357.422198) (xy 124.164355 -357.399545)
			(xy 124.216689 -357.384184) (xy 124.270677 -357.376428) (xy 124.297948 -357.375968) (xy 125.161548 -357.375968)
			(xy 125.188817 -357.376398) (xy 125.2428 -357.384166) (xy 125.295128 -357.399536) (xy 125.344736 -357.422197)
			(xy 125.390614 -357.451687) (xy 125.431829 -357.487405) (xy 125.467542 -357.528624) (xy 125.497026 -357.574506)
			(xy 125.51968 -357.624117) (xy 125.535045 -357.676447) (xy 125.542806 -357.730431) (xy 125.542806 -357.784969)
			(xy 127.025631 -357.784969) (xy 127.025631 -357.730431) (xy 127.033393 -357.676447) (xy 127.048759 -357.624118)
			(xy 127.071415 -357.574508) (xy 127.100901 -357.528628) (xy 127.136617 -357.487411) (xy 127.177834 -357.451696)
			(xy 127.223715 -357.422211) (xy 127.273326 -357.399556) (xy 127.325655 -357.384191) (xy 127.379639 -357.376431)
			(xy 127.406908 -357.375968) (xy 128.270508 -357.375968) (xy 128.297779 -357.376395) (xy 128.351766 -357.384158)
			(xy 128.404099 -357.399525) (xy 128.453712 -357.422184) (xy 128.499595 -357.451672) (xy 128.540815 -357.48739)
			(xy 128.576532 -357.528611) (xy 128.60602 -357.574495) (xy 128.628677 -357.624109) (xy 128.644043 -357.676442)
			(xy 128.651806 -357.730429) (xy 128.651806 -357.784966) (xy 130.134654 -357.784966) (xy 130.134654 -357.730434)
			(xy 130.142414 -357.676458) (xy 130.157777 -357.624135) (xy 130.180429 -357.574531) (xy 130.20991 -357.528655)
			(xy 130.245619 -357.487441) (xy 130.286829 -357.451729) (xy 130.332703 -357.422244) (xy 130.382305 -357.399588)
			(xy 130.434626 -357.384221) (xy 130.488602 -357.376457) (xy 130.515868 -357.375968) (xy 131.379468 -357.375968)
			(xy 131.406743 -357.376369) (xy 131.460737 -357.384128) (xy 131.513078 -357.399493) (xy 131.562699 -357.422151)
			(xy 131.60859 -357.45164) (xy 131.649817 -357.48736) (xy 131.685541 -357.528584) (xy 131.715034 -357.574473)
			(xy 131.737696 -357.624092) (xy 131.753065 -357.676431) (xy 131.760828 -357.730425) (xy 131.760828 -357.78497)
			(xy 133.243531 -357.78497) (xy 133.243532 -357.73043) (xy 133.251294 -357.676445) (xy 133.26666 -357.624114)
			(xy 133.289318 -357.574503) (xy 133.318806 -357.528621) (xy 133.354524 -357.487404) (xy 133.395744 -357.451689)
			(xy 133.441627 -357.422205) (xy 133.49124 -357.39955) (xy 133.543572 -357.384188) (xy 133.597558 -357.37643)
			(xy 133.624828 -357.375968) (xy 134.488428 -357.375968) (xy 134.515698 -357.376396) (xy 134.569683 -357.384162)
			(xy 134.622013 -357.399531) (xy 134.671624 -357.42219) (xy 134.717505 -357.451679) (xy 134.758722 -357.487397)
			(xy 134.794437 -357.528618) (xy 134.823923 -357.574501) (xy 134.846579 -357.624113) (xy 134.861944 -357.676444)
			(xy 134.869706 -357.73043) (xy 134.869706 -357.784967) (xy 136.352554 -357.784967) (xy 136.352554 -357.730433)
			(xy 136.360315 -357.676455) (xy 136.375679 -357.624131) (xy 136.398332 -357.574525) (xy 136.427815 -357.528648)
			(xy 136.463526 -357.487434) (xy 136.504739 -357.451722) (xy 136.550615 -357.422238) (xy 136.600219 -357.399583)
			(xy 136.652543 -357.384218) (xy 136.706521 -357.376455) (xy 136.733788 -357.375968) (xy 137.597388 -357.375968)
			(xy 137.624662 -357.376371) (xy 137.678654 -357.384132) (xy 137.730992 -357.399499) (xy 137.780611 -357.422157)
			(xy 137.8265 -357.451647) (xy 137.867724 -357.487367) (xy 137.903446 -357.528591) (xy 137.932937 -357.574479)
			(xy 137.955597 -357.624096) (xy 137.970965 -357.676434) (xy 137.978728 -357.730426) (xy 137.978728 -357.784971)
			(xy 139.461432 -357.784971) (xy 139.461432 -357.730429) (xy 139.469194 -357.676442) (xy 139.484562 -357.62411)
			(xy 139.507221 -357.574497) (xy 139.536711 -357.528615) (xy 139.572431 -357.487397) (xy 139.613653 -357.451682)
			(xy 139.659539 -357.422198) (xy 139.709155 -357.399545) (xy 139.761489 -357.384184) (xy 139.815477 -357.376428)
			(xy 139.842748 -357.375968) (xy 140.706348 -357.375968) (xy 140.733617 -357.376398) (xy 140.7876 -357.384166)
			(xy 140.839928 -357.399536) (xy 140.889536 -357.422197) (xy 140.935414 -357.451687) (xy 140.976629 -357.487405)
			(xy 141.012342 -357.528624) (xy 141.041826 -357.574506) (xy 141.06448 -357.624117) (xy 141.079845 -357.676447)
			(xy 141.087606 -357.730431) (xy 141.087606 -357.784969) (xy 142.570431 -357.784969) (xy 142.570431 -357.730431)
			(xy 142.578193 -357.676447) (xy 142.593559 -357.624118) (xy 142.616215 -357.574508) (xy 142.645701 -357.528628)
			(xy 142.681417 -357.487411) (xy 142.722634 -357.451696) (xy 142.768515 -357.422211) (xy 142.818126 -357.399556)
			(xy 142.870455 -357.384191) (xy 142.924439 -357.376431) (xy 142.951708 -357.375968) (xy 143.815308 -357.375968)
			(xy 143.842579 -357.376395) (xy 143.896566 -357.384158) (xy 143.948899 -357.399525) (xy 143.998512 -357.422184)
			(xy 144.044395 -357.451672) (xy 144.085615 -357.48739) (xy 144.121332 -357.528611) (xy 144.15082 -357.574495)
			(xy 144.173477 -357.624109) (xy 144.188843 -357.676442) (xy 144.196606 -357.730429) (xy 144.196606 -357.784965)
			(xy 158.695954 -357.784965) (xy 158.695954 -357.730435) (xy 158.703714 -357.67646) (xy 158.719076 -357.624138)
			(xy 158.741727 -357.574535) (xy 158.771206 -357.52866) (xy 158.806913 -357.487447) (xy 158.848122 -357.451735)
			(xy 158.893993 -357.42225) (xy 158.943593 -357.399593) (xy 158.995913 -357.384224) (xy 159.049887 -357.376458)
			(xy 159.077152 -357.375968) (xy 159.940752 -357.375968) (xy 159.968027 -357.376368) (xy 160.022024 -357.384125)
			(xy 160.074366 -357.399489) (xy 160.123989 -357.422145) (xy 160.169883 -357.451634) (xy 160.211112 -357.487354)
			(xy 160.246837 -357.528579) (xy 160.276332 -357.574468) (xy 160.298994 -357.624089) (xy 160.314364 -357.676429)
			(xy 160.322128 -357.730425) (xy 160.322128 -357.784969) (xy 161.804831 -357.784969) (xy 161.804831 -357.730431)
			(xy 161.812593 -357.676447) (xy 161.827959 -357.624117) (xy 161.850616 -357.574507) (xy 161.880102 -357.528627)
			(xy 161.915818 -357.487409) (xy 161.957036 -357.451695) (xy 162.002918 -357.42221) (xy 162.052529 -357.399555)
			(xy 162.104859 -357.384191) (xy 162.158843 -357.376431) (xy 162.186112 -357.375968) (xy 163.049712 -357.375968)
			(xy 163.076983 -357.376395) (xy 163.130969 -357.384159) (xy 163.183302 -357.399527) (xy 163.232914 -357.422185)
			(xy 163.278797 -357.451674) (xy 163.320017 -357.487392) (xy 163.355733 -357.528612) (xy 163.385221 -357.574496)
			(xy 163.407878 -357.62411) (xy 163.423244 -357.676442) (xy 163.431006 -357.730429) (xy 163.431006 -357.784966)
			(xy 164.913854 -357.784966) (xy 164.913854 -357.730434) (xy 164.921615 -357.676457) (xy 164.936977 -357.624134)
			(xy 164.95963 -357.57453) (xy 164.989111 -357.528654) (xy 165.02482 -357.48744) (xy 165.066031 -357.451727)
			(xy 165.111905 -357.422243) (xy 165.161508 -357.399587) (xy 165.21383 -357.384221) (xy 165.267806 -357.376456)
			(xy 165.295072 -357.375968) (xy 166.158672 -357.375968) (xy 166.185946 -357.37637) (xy 166.239941 -357.384129)
			(xy 166.292281 -357.399494) (xy 166.341901 -357.422152) (xy 166.387792 -357.451641) (xy 166.429019 -357.487361)
			(xy 166.464742 -357.528585) (xy 166.494235 -357.574474) (xy 166.516896 -357.624093) (xy 166.532265 -357.676432)
			(xy 166.540028 -357.730426) (xy 166.540028 -357.78497) (xy 168.022732 -357.78497) (xy 168.022732 -357.73043)
			(xy 168.030494 -357.676444) (xy 168.045861 -357.624113) (xy 168.068519 -357.574502) (xy 168.098007 -357.52862)
			(xy 168.133725 -357.487402) (xy 168.174946 -357.451688) (xy 168.22083 -357.422203) (xy 168.270443 -357.399549)
			(xy 168.322776 -357.384187) (xy 168.376762 -357.376429) (xy 168.404032 -357.375968) (xy 169.267632 -357.375968)
			(xy 169.294902 -357.376397) (xy 169.348886 -357.384163) (xy 169.401216 -357.399532) (xy 169.450826 -357.422192)
			(xy 169.496707 -357.451681) (xy 169.537924 -357.487399) (xy 169.573638 -357.528619) (xy 169.603124 -357.574502)
			(xy 169.625779 -357.624114) (xy 169.641144 -357.676445) (xy 169.648906 -357.73043) (xy 169.648906 -357.784967)
			(xy 171.131754 -357.784967) (xy 171.131754 -357.730433) (xy 171.139515 -357.676454) (xy 171.154879 -357.62413)
			(xy 171.177533 -357.574524) (xy 171.207016 -357.528647) (xy 171.242727 -357.487433) (xy 171.283941 -357.45172)
			(xy 171.329817 -357.422237) (xy 171.379422 -357.399582) (xy 171.431747 -357.384217) (xy 171.485725 -357.376455)
			(xy 171.512992 -357.375968) (xy 172.376592 -357.375968) (xy 172.403866 -357.376371) (xy 172.457857 -357.384133)
			(xy 172.510195 -357.3995) (xy 172.559813 -357.422159) (xy 172.605702 -357.451648) (xy 172.646926 -357.487368)
			(xy 172.682647 -357.528592) (xy 172.712138 -357.57448) (xy 172.734798 -357.624097) (xy 172.750165 -357.676435)
			(xy 172.757928 -357.730426) (xy 172.757928 -357.784965) (xy 174.240754 -357.784965) (xy 174.240754 -357.730435)
			(xy 174.248514 -357.67646) (xy 174.263876 -357.624138) (xy 174.286527 -357.574535) (xy 174.316006 -357.52866)
			(xy 174.351713 -357.487447) (xy 174.392922 -357.451735) (xy 174.438793 -357.42225) (xy 174.488393 -357.399593)
			(xy 174.540713 -357.384224) (xy 174.594687 -357.376458) (xy 174.621952 -357.375968) (xy 175.485552 -357.375968)
			(xy 175.512827 -357.376368) (xy 175.566824 -357.384125) (xy 175.619166 -357.399489) (xy 175.668789 -357.422145)
			(xy 175.714683 -357.451634) (xy 175.755912 -357.487354) (xy 175.791637 -357.528579) (xy 175.821132 -357.574468)
			(xy 175.843794 -357.624089) (xy 175.859164 -357.676429) (xy 175.866928 -357.730425) (xy 175.866928 -357.784969)
			(xy 177.349631 -357.784969) (xy 177.349631 -357.730431) (xy 177.357393 -357.676447) (xy 177.372759 -357.624117)
			(xy 177.395416 -357.574507) (xy 177.424902 -357.528627) (xy 177.460618 -357.487409) (xy 177.501836 -357.451695)
			(xy 177.547718 -357.42221) (xy 177.597329 -357.399555) (xy 177.649659 -357.384191) (xy 177.703643 -357.376431)
			(xy 177.730912 -357.375968) (xy 178.594512 -357.375968) (xy 178.621783 -357.376395) (xy 178.675769 -357.384159)
			(xy 178.728102 -357.399527) (xy 178.777714 -357.422185) (xy 178.823597 -357.451674) (xy 178.864817 -357.487392)
			(xy 178.900533 -357.528612) (xy 178.930021 -357.574496) (xy 178.952678 -357.62411) (xy 178.968044 -357.676442)
			(xy 178.975806 -357.730429) (xy 178.975806 -357.784966) (xy 180.458654 -357.784966) (xy 180.458654 -357.730434)
			(xy 180.466415 -357.676457) (xy 180.481777 -357.624134) (xy 180.50443 -357.57453) (xy 180.533911 -357.528654)
			(xy 180.56962 -357.48744) (xy 180.610831 -357.451727) (xy 180.656705 -357.422243) (xy 180.706308 -357.399587)
			(xy 180.75863 -357.384221) (xy 180.812606 -357.376456) (xy 180.839872 -357.375968) (xy 181.703472 -357.375968)
			(xy 181.730746 -357.37637) (xy 181.784741 -357.384129) (xy 181.837081 -357.399494) (xy 181.886701 -357.422152)
			(xy 181.932592 -357.451641) (xy 181.973819 -357.487361) (xy 182.009542 -357.528585) (xy 182.039035 -357.574474)
			(xy 182.061696 -357.624093) (xy 182.077065 -357.676432) (xy 182.084828 -357.730426) (xy 182.084828 -357.761176)
			(xy 183.567456 -357.761176) (xy 183.567456 -357.706624) (xy 183.57522 -357.652628) (xy 183.590589 -357.600287)
			(xy 183.613252 -357.550665) (xy 183.642746 -357.504775) (xy 183.678471 -357.463549) (xy 183.7197 -357.427827)
			(xy 183.765593 -357.398337) (xy 183.815217 -357.375678) (xy 183.867559 -357.360313) (xy 183.921556 -357.352553)
			(xy 183.948832 -357.352092) (xy 184.812432 -357.352092) (xy 184.839697 -357.352672) (xy 184.89367 -357.360437)
			(xy 184.94599 -357.375803) (xy 184.99559 -357.398458) (xy 185.041461 -357.427942) (xy 185.08267 -357.463653)
			(xy 185.118378 -357.504864) (xy 185.147857 -357.550738) (xy 185.170508 -357.60034) (xy 185.18587 -357.652661)
			(xy 185.19363 -357.706635) (xy 185.19363 -357.761165) (xy 185.193629 -357.761172) (xy 186.676479 -357.761172)
			(xy 186.676479 -357.706628) (xy 186.684241 -357.652638) (xy 186.699608 -357.600303) (xy 186.722266 -357.550688)
			(xy 186.751755 -357.504801) (xy 186.787473 -357.463579) (xy 186.828695 -357.42786) (xy 186.87458 -357.39837)
			(xy 186.924196 -357.37571) (xy 186.97653 -357.360343) (xy 187.03052 -357.352579) (xy 187.057792 -357.352092)
			(xy 187.921392 -357.352092) (xy 187.94866 -357.352647) (xy 188.002641 -357.360407) (xy 188.054969 -357.375771)
			(xy 188.104577 -357.398425) (xy 188.150456 -357.427909) (xy 188.191672 -357.463622) (xy 188.227386 -357.504838)
			(xy 188.256871 -357.550716) (xy 188.279526 -357.600324) (xy 188.294891 -357.652651) (xy 188.302653 -357.706632)
			(xy 188.302653 -357.761168) (xy 188.294891 -357.815149) (xy 188.279526 -357.867476) (xy 188.256871 -357.917084)
			(xy 188.227386 -357.962962) (xy 188.223925 -357.966956) (xy 245.50903 -357.966956) (xy 245.50903 -357.88226)
			(xy 245.517081 -357.797946) (xy 245.53311 -357.71478) (xy 245.556971 -357.633513) (xy 245.58845 -357.554883)
			(xy 245.627261 -357.479602) (xy 245.673051 -357.40835) (xy 245.725407 -357.341774) (xy 245.783855 -357.280476)
			(xy 245.847865 -357.225011) (xy 245.916857 -357.175882) (xy 245.990207 -357.133533) (xy 246.06725 -357.098349)
			(xy 246.147289 -357.070647) (xy 246.229598 -357.050679) (xy 246.313433 -357.038626) (xy 246.398034 -357.034596)
			(xy 246.482635 -357.038626) (xy 246.56647 -357.050679) (xy 246.648779 -357.070647) (xy 246.728818 -357.098349)
			(xy 246.805861 -357.133533) (xy 246.879211 -357.175882) (xy 246.948203 -357.225011) (xy 247.012213 -357.280476)
			(xy 247.070661 -357.341774) (xy 247.123017 -357.40835) (xy 247.168807 -357.479602) (xy 247.207618 -357.554883)
			(xy 247.239097 -357.633513) (xy 247.262958 -357.71478) (xy 247.276485 -357.784966) (xy 270.624854 -357.784966)
			(xy 270.624854 -357.730435) (xy 270.632614 -357.676458) (xy 270.647977 -357.624136) (xy 270.670628 -357.574532)
			(xy 270.700108 -357.528657) (xy 270.735817 -357.487443) (xy 270.777026 -357.451731) (xy 270.822899 -357.422246)
			(xy 270.8725 -357.39959) (xy 270.924821 -357.384222) (xy 270.978797 -357.376457) (xy 271.006062 -357.375968)
			(xy 271.869662 -357.375968) (xy 271.896937 -357.376369) (xy 271.950932 -357.384127) (xy 272.003273 -357.399491)
			(xy 272.052895 -357.422149) (xy 272.098787 -357.451638) (xy 272.140015 -357.487358) (xy 272.17574 -357.528582)
			(xy 272.205233 -357.574471) (xy 272.227895 -357.624091) (xy 272.243265 -357.676431) (xy 272.251028 -357.730425)
			(xy 272.251028 -357.78497) (xy 273.733731 -357.78497) (xy 273.733731 -357.73043) (xy 273.741494 -357.676446)
			(xy 273.75686 -357.624115) (xy 273.779517 -357.574505) (xy 273.809005 -357.528623) (xy 273.844722 -357.487406)
			(xy 273.885941 -357.451691) (xy 273.931824 -357.422207) (xy 273.981436 -357.399552) (xy 274.033767 -357.384189)
			(xy 274.087752 -357.37643) (xy 274.115022 -357.375968) (xy 274.978622 -357.375968) (xy 275.005892 -357.376396)
			(xy 275.059878 -357.384161) (xy 275.112209 -357.399529) (xy 275.16182 -357.422189) (xy 275.207702 -357.451677)
			(xy 275.24892 -357.487395) (xy 275.284636 -357.528616) (xy 275.314122 -357.574499) (xy 275.336778 -357.624112)
			(xy 275.352144 -357.676444) (xy 275.359906 -357.730429) (xy 275.359906 -357.784966) (xy 276.842754 -357.784966)
			(xy 276.842754 -357.730434) (xy 276.850515 -357.676456) (xy 276.865878 -357.624132) (xy 276.888531 -357.574527)
			(xy 276.918013 -357.52865) (xy 276.953724 -357.487436) (xy 276.994936 -357.451724) (xy 277.040811 -357.42224)
			(xy 277.090415 -357.399584) (xy 277.142738 -357.384219) (xy 277.196716 -357.376456) (xy 277.223982 -357.375968)
			(xy 278.087582 -357.375968) (xy 278.114856 -357.37637) (xy 278.168849 -357.384131) (xy 278.221188 -357.399497)
			(xy 278.270807 -357.422155) (xy 278.316697 -357.451645) (xy 278.357922 -357.487365) (xy 278.393644 -357.528589)
			(xy 278.423136 -357.574477) (xy 278.445797 -357.624095) (xy 278.461165 -357.676433) (xy 278.468928 -357.730426)
			(xy 278.468928 -357.784971) (xy 279.951632 -357.784971) (xy 279.951632 -357.730429) (xy 279.959394 -357.676443)
			(xy 279.974761 -357.624111) (xy 279.99742 -357.574499) (xy 280.026909 -357.528617) (xy 280.062629 -357.487399)
			(xy 280.103851 -357.451684) (xy 280.149736 -357.4222) (xy 280.19935 -357.399547) (xy 280.251684 -357.384185)
			(xy 280.305671 -357.376429) (xy 280.332942 -357.375968) (xy 281.196542 -357.375968) (xy 281.223812 -357.376397)
			(xy 281.277795 -357.384165) (xy 281.330123 -357.399535) (xy 281.379732 -357.422195) (xy 281.425611 -357.451684)
			(xy 281.466827 -357.487402) (xy 281.502541 -357.528622) (xy 281.532025 -357.574505) (xy 281.55468 -357.624116)
			(xy 281.570044 -357.676446) (xy 281.577806 -357.73043) (xy 281.577806 -357.784969) (xy 283.060631 -357.784969)
			(xy 283.060631 -357.730431) (xy 283.068393 -357.676448) (xy 283.083758 -357.62412) (xy 283.106414 -357.57451)
			(xy 283.1359 -357.52863) (xy 283.171614 -357.487413) (xy 283.212832 -357.451698) (xy 283.258712 -357.422213)
			(xy 283.308321 -357.399557) (xy 283.36065 -357.384193) (xy 283.414633 -357.376431) (xy 283.441902 -357.375968)
			(xy 284.305502 -357.375968) (xy 284.332773 -357.376395) (xy 284.386761 -357.384157) (xy 284.439094 -357.399524)
			(xy 284.488708 -357.422182) (xy 284.534593 -357.45167) (xy 284.575813 -357.487388) (xy 284.611531 -357.528609)
			(xy 284.641019 -357.574493) (xy 284.663677 -357.624107) (xy 284.679043 -357.676441) (xy 284.686806 -357.730429)
			(xy 284.686806 -357.784966) (xy 286.169654 -357.784966) (xy 286.169654 -357.730435) (xy 286.177414 -357.676458)
			(xy 286.192777 -357.624136) (xy 286.215428 -357.574532) (xy 286.244908 -357.528657) (xy 286.280617 -357.487443)
			(xy 286.321826 -357.451731) (xy 286.367699 -357.422246) (xy 286.4173 -357.39959) (xy 286.469621 -357.384222)
			(xy 286.523597 -357.376457) (xy 286.550862 -357.375968) (xy 287.414462 -357.375968) (xy 287.441737 -357.376369)
			(xy 287.495732 -357.384127) (xy 287.548073 -357.399491) (xy 287.597695 -357.422149) (xy 287.643587 -357.451638)
			(xy 287.684815 -357.487358) (xy 287.72054 -357.528582) (xy 287.750033 -357.574471) (xy 287.772695 -357.624091)
			(xy 287.788065 -357.676431) (xy 287.795828 -357.730425) (xy 287.795828 -357.78497) (xy 289.278531 -357.78497)
			(xy 289.278531 -357.73043) (xy 289.286294 -357.676446) (xy 289.30166 -357.624115) (xy 289.324317 -357.574505)
			(xy 289.353805 -357.528623) (xy 289.389522 -357.487406) (xy 289.430741 -357.451691) (xy 289.476624 -357.422207)
			(xy 289.526236 -357.399552) (xy 289.578567 -357.384189) (xy 289.632552 -357.37643) (xy 289.659822 -357.375968)
			(xy 290.523422 -357.375968) (xy 290.550692 -357.376396) (xy 290.604678 -357.384161) (xy 290.657009 -357.399529)
			(xy 290.70662 -357.422189) (xy 290.752502 -357.451677) (xy 290.79372 -357.487395) (xy 290.829436 -357.528616)
			(xy 290.858922 -357.574499) (xy 290.881578 -357.624112) (xy 290.896944 -357.676444) (xy 290.904706 -357.730429)
			(xy 290.904706 -357.784966) (xy 292.387554 -357.784966) (xy 292.387554 -357.730434) (xy 292.395315 -357.676456)
			(xy 292.410678 -357.624132) (xy 292.433331 -357.574527) (xy 292.462813 -357.52865) (xy 292.498524 -357.487436)
			(xy 292.539736 -357.451724) (xy 292.585611 -357.42224) (xy 292.635215 -357.399584) (xy 292.687538 -357.384219)
			(xy 292.741516 -357.376456) (xy 292.768782 -357.375968) (xy 293.632382 -357.375968) (xy 293.659656 -357.37637)
			(xy 293.713649 -357.384131) (xy 293.765988 -357.399497) (xy 293.815607 -357.422155) (xy 293.861497 -357.451645)
			(xy 293.902722 -357.487365) (xy 293.938444 -357.528589) (xy 293.967936 -357.574477) (xy 293.990597 -357.624095)
			(xy 294.005965 -357.676433) (xy 294.013728 -357.730426) (xy 294.013728 -357.784971) (xy 295.496432 -357.784971)
			(xy 295.496432 -357.730429) (xy 295.504194 -357.676443) (xy 295.519561 -357.624111) (xy 295.54222 -357.574499)
			(xy 295.571709 -357.528617) (xy 295.607429 -357.487399) (xy 295.648651 -357.451684) (xy 295.694536 -357.4222)
			(xy 295.74415 -357.399547) (xy 295.796484 -357.384185) (xy 295.850471 -357.376429) (xy 295.877742 -357.375968)
			(xy 296.741342 -357.375968) (xy 296.768612 -357.376397) (xy 296.822595 -357.384165) (xy 296.874923 -357.399535)
			(xy 296.924532 -357.422195) (xy 296.970411 -357.451684) (xy 297.011627 -357.487402) (xy 297.047341 -357.528622)
			(xy 297.076825 -357.574505) (xy 297.09948 -357.624116) (xy 297.114844 -357.676446) (xy 297.122606 -357.73043)
			(xy 297.122606 -357.784969) (xy 298.605431 -357.784969) (xy 298.605431 -357.730431) (xy 298.613193 -357.676448)
			(xy 298.628558 -357.62412) (xy 298.651214 -357.57451) (xy 298.6807 -357.52863) (xy 298.716414 -357.487413)
			(xy 298.757632 -357.451698) (xy 298.803512 -357.422213) (xy 298.853121 -357.399557) (xy 298.90545 -357.384193)
			(xy 298.959433 -357.376431) (xy 298.986702 -357.375968) (xy 299.850302 -357.375968) (xy 299.877573 -357.376395)
			(xy 299.931561 -357.384157) (xy 299.983894 -357.399524) (xy 300.033508 -357.422182) (xy 300.079393 -357.45167)
			(xy 300.120613 -357.487388) (xy 300.156331 -357.528609) (xy 300.185819 -357.574493) (xy 300.208477 -357.624107)
			(xy 300.223843 -357.676441) (xy 300.231606 -357.730429) (xy 300.231606 -357.784966) (xy 315.230554 -357.784966)
			(xy 315.230554 -357.730434) (xy 315.238314 -357.676458) (xy 315.253677 -357.624136) (xy 315.276328 -357.574532)
			(xy 315.305809 -357.528656) (xy 315.341517 -357.487443) (xy 315.382727 -357.45173) (xy 315.4286 -357.422246)
			(xy 315.478202 -357.399589) (xy 315.530523 -357.384222) (xy 315.584498 -357.376457) (xy 315.611764 -357.375968)
			(xy 316.475364 -357.375968) (xy 316.502639 -357.376369) (xy 316.556634 -357.384128) (xy 316.608975 -357.399492)
			(xy 316.658597 -357.422149) (xy 316.704488 -357.451638) (xy 316.745716 -357.487359) (xy 316.78144 -357.528583)
			(xy 316.810933 -357.574472) (xy 316.833595 -357.624091) (xy 316.848965 -357.676431) (xy 316.856728 -357.730425)
			(xy 316.856728 -357.78497) (xy 318.339431 -357.78497) (xy 318.339431 -357.73043) (xy 318.347194 -357.676445)
			(xy 318.36256 -357.624115) (xy 318.385217 -357.574504) (xy 318.414705 -357.528623) (xy 318.450422 -357.487405)
			(xy 318.491642 -357.451691) (xy 318.537525 -357.422206) (xy 318.587137 -357.399552) (xy 318.639469 -357.384189)
			(xy 318.693454 -357.37643) (xy 318.720724 -357.375968) (xy 319.584324 -357.375968) (xy 319.611594 -357.376396)
			(xy 319.66558 -357.384161) (xy 319.71791 -357.39953) (xy 319.767521 -357.422189) (xy 319.813403 -357.451678)
			(xy 319.854621 -357.487396) (xy 319.890336 -357.528616) (xy 319.919822 -357.5745) (xy 319.942479 -357.624112)
			(xy 319.957844 -357.676444) (xy 319.965606 -357.73043) (xy 319.965606 -357.784967) (xy 321.448454 -357.784967)
			(xy 321.448454 -357.730434) (xy 321.456215 -357.676456) (xy 321.471578 -357.624131) (xy 321.494232 -357.574526)
			(xy 321.523714 -357.52865) (xy 321.559424 -357.487436) (xy 321.600637 -357.451723) (xy 321.646512 -357.422239)
			(xy 321.696116 -357.399584) (xy 321.74844 -357.384218) (xy 321.802418 -357.376455) (xy 321.829684 -357.375968)
			(xy 322.693284 -357.375968) (xy 322.720558 -357.37637) (xy 322.774551 -357.384131) (xy 322.826889 -357.399497)
			(xy 322.876508 -357.422156) (xy 322.922398 -357.451645) (xy 322.963623 -357.487366) (xy 322.999345 -357.528589)
			(xy 323.028836 -357.574477) (xy 323.051497 -357.624096) (xy 323.066865 -357.676434) (xy 323.074628 -357.730426)
			(xy 323.074628 -357.784971) (xy 324.557332 -357.784971) (xy 324.557332 -357.730429) (xy 324.565094 -357.676443)
			(xy 324.580461 -357.624111) (xy 324.603121 -357.574498) (xy 324.63261 -357.528616) (xy 324.668329 -357.487398)
			(xy 324.709551 -357.451684) (xy 324.755437 -357.422199) (xy 324.805052 -357.399546) (xy 324.857386 -357.384185)
			(xy 324.911373 -357.376428) (xy 324.938644 -357.375968) (xy 325.802244 -357.375968) (xy 325.829513 -357.376398)
			(xy 325.883497 -357.384165) (xy 325.935825 -357.399535) (xy 325.985433 -357.422196) (xy 326.031312 -357.451685)
			(xy 326.072528 -357.487403) (xy 326.108241 -357.528623) (xy 326.137725 -357.574505) (xy 326.16038 -357.624116)
			(xy 326.175744 -357.676447) (xy 326.183506 -357.73043) (xy 326.183506 -357.784969) (xy 327.666331 -357.784969)
			(xy 327.666331 -357.730431) (xy 327.674093 -357.676448) (xy 327.689458 -357.624119) (xy 327.712114 -357.57451)
			(xy 327.7416 -357.528629) (xy 327.777315 -357.487412) (xy 327.818533 -357.451698) (xy 327.864413 -357.422212)
			(xy 327.914023 -357.399557) (xy 327.966352 -357.384192) (xy 328.020335 -357.376431) (xy 328.047604 -357.375968)
			(xy 328.911204 -357.375968) (xy 328.938475 -357.376395) (xy 328.992463 -357.384158) (xy 329.044796 -357.399524)
			(xy 329.094409 -357.422183) (xy 329.140293 -357.451671) (xy 329.181514 -357.487389) (xy 329.217231 -357.52861)
			(xy 329.246719 -357.574494) (xy 329.269377 -357.624108) (xy 329.284743 -357.676441) (xy 329.292506 -357.730429)
			(xy 329.292506 -357.784966) (xy 330.775354 -357.784966) (xy 330.775354 -357.730434) (xy 330.783114 -357.676458)
			(xy 330.798477 -357.624136) (xy 330.821128 -357.574532) (xy 330.850609 -357.528656) (xy 330.886317 -357.487443)
			(xy 330.927527 -357.45173) (xy 330.9734 -357.422246) (xy 331.023002 -357.399589) (xy 331.075323 -357.384222)
			(xy 331.129298 -357.376457) (xy 331.156564 -357.375968) (xy 332.020164 -357.375968) (xy 332.047439 -357.376369)
			(xy 332.101434 -357.384128) (xy 332.153775 -357.399492) (xy 332.203397 -357.422149) (xy 332.249288 -357.451638)
			(xy 332.290516 -357.487359) (xy 332.32624 -357.528583) (xy 332.355733 -357.574472) (xy 332.378395 -357.624091)
			(xy 332.393765 -357.676431) (xy 332.401528 -357.730425) (xy 332.401528 -357.78497) (xy 333.884231 -357.78497)
			(xy 333.884231 -357.73043) (xy 333.891994 -357.676445) (xy 333.90736 -357.624115) (xy 333.930017 -357.574504)
			(xy 333.959505 -357.528623) (xy 333.995222 -357.487405) (xy 334.036442 -357.451691) (xy 334.082325 -357.422206)
			(xy 334.131937 -357.399552) (xy 334.184269 -357.384189) (xy 334.238254 -357.37643) (xy 334.265524 -357.375968)
			(xy 335.129124 -357.375968) (xy 335.156394 -357.376396) (xy 335.21038 -357.384161) (xy 335.26271 -357.39953)
			(xy 335.312321 -357.422189) (xy 335.358203 -357.451678) (xy 335.399421 -357.487396) (xy 335.435136 -357.528616)
			(xy 335.464622 -357.5745) (xy 335.487279 -357.624112) (xy 335.502644 -357.676444) (xy 335.510406 -357.73043)
			(xy 335.510406 -357.784967) (xy 336.993254 -357.784967) (xy 336.993254 -357.730434) (xy 337.001015 -357.676456)
			(xy 337.016378 -357.624131) (xy 337.039032 -357.574526) (xy 337.068514 -357.52865) (xy 337.104224 -357.487436)
			(xy 337.145437 -357.451723) (xy 337.191312 -357.422239) (xy 337.240916 -357.399584) (xy 337.29324 -357.384218)
			(xy 337.347218 -357.376455) (xy 337.374484 -357.375968) (xy 338.238084 -357.375968) (xy 338.265358 -357.37637)
			(xy 338.319351 -357.384131) (xy 338.371689 -357.399497) (xy 338.421308 -357.422156) (xy 338.467198 -357.451645)
			(xy 338.508423 -357.487366) (xy 338.544145 -357.528589) (xy 338.573636 -357.574477) (xy 338.596297 -357.624096)
			(xy 338.611665 -357.676434) (xy 338.619428 -357.730426) (xy 338.619428 -357.784971) (xy 340.102132 -357.784971)
			(xy 340.102132 -357.730429) (xy 340.109894 -357.676443) (xy 340.125261 -357.624111) (xy 340.147921 -357.574498)
			(xy 340.17741 -357.528616) (xy 340.213129 -357.487398) (xy 340.254351 -357.451684) (xy 340.300237 -357.422199)
			(xy 340.349852 -357.399546) (xy 340.402186 -357.384185) (xy 340.456173 -357.376428) (xy 340.483444 -357.375968)
			(xy 341.347044 -357.375968) (xy 341.374313 -357.376398) (xy 341.428297 -357.384165) (xy 341.480625 -357.399535)
			(xy 341.530233 -357.422196) (xy 341.576112 -357.451685) (xy 341.617328 -357.487403) (xy 341.653041 -357.528623)
			(xy 341.682525 -357.574505) (xy 341.70518 -357.624116) (xy 341.720544 -357.676447) (xy 341.728306 -357.73043)
			(xy 341.728306 -357.784969) (xy 343.211131 -357.784969) (xy 343.211131 -357.730431) (xy 343.218893 -357.676448)
			(xy 343.234258 -357.624119) (xy 343.256914 -357.57451) (xy 343.2864 -357.528629) (xy 343.322115 -357.487412)
			(xy 343.363333 -357.451698) (xy 343.409213 -357.422212) (xy 343.458823 -357.399557) (xy 343.511152 -357.384192)
			(xy 343.565135 -357.376431) (xy 343.592404 -357.375968) (xy 344.456004 -357.375968) (xy 344.483275 -357.376395)
			(xy 344.537263 -357.384158) (xy 344.589596 -357.399524) (xy 344.639209 -357.422183) (xy 344.685093 -357.451671)
			(xy 344.726314 -357.487389) (xy 344.762031 -357.52861) (xy 344.791519 -357.574494) (xy 344.814177 -357.624108)
			(xy 344.829543 -357.676441) (xy 344.837306 -357.730429) (xy 344.837306 -357.784971) (xy 373.915632 -357.784971)
			(xy 373.915632 -357.730429) (xy 373.923394 -357.676443) (xy 373.938761 -357.624111) (xy 373.96142 -357.574499)
			(xy 373.990909 -357.528617) (xy 374.026628 -357.4874) (xy 374.06785 -357.451685) (xy 374.113735 -357.422201)
			(xy 374.163349 -357.399547) (xy 374.215682 -357.384186) (xy 374.269669 -357.376429) (xy 374.29694 -357.375968)
			(xy 375.16054 -357.375968) (xy 375.18781 -357.376397) (xy 375.241793 -357.384164) (xy 375.294122 -357.399534)
			(xy 375.343731 -357.422194) (xy 375.389611 -357.451684) (xy 375.430827 -357.487402) (xy 375.46654 -357.528622)
			(xy 375.496025 -357.574504) (xy 375.51868 -357.624116) (xy 375.534044 -357.676446) (xy 375.541806 -357.73043)
			(xy 375.541806 -357.784967) (xy 377.024654 -357.784967) (xy 377.024654 -357.730433) (xy 377.032415 -357.676453)
			(xy 377.04778 -357.624128) (xy 377.070434 -357.574522) (xy 377.099918 -357.528644) (xy 377.13563 -357.48743)
			(xy 377.176844 -357.451718) (xy 377.222722 -357.422234) (xy 377.272328 -357.39958) (xy 377.324653 -357.384215)
			(xy 377.378633 -357.376454) (xy 377.4059 -357.375968) (xy 378.2695 -357.375968) (xy 378.296772 -357.376395)
			(xy 378.350759 -357.384157) (xy 378.403093 -357.399523) (xy 378.452707 -357.422181) (xy 378.498592 -357.451669)
			(xy 378.539812 -357.487388) (xy 378.575531 -357.528608) (xy 378.605019 -357.574493) (xy 378.627677 -357.624107)
			(xy 378.643043 -357.676441) (xy 378.650805 -357.730428) (xy 378.650805 -357.784965) (xy 380.133654 -357.784965)
			(xy 380.133654 -357.730435) (xy 380.141414 -357.676459) (xy 380.156776 -357.624137) (xy 380.179428 -357.574533)
			(xy 380.208908 -357.528658) (xy 380.244616 -357.487444) (xy 380.285825 -357.451732) (xy 380.331698 -357.422247)
			(xy 380.381299 -357.39959) (xy 380.43362 -357.384223) (xy 380.487595 -357.376457) (xy 380.51486 -357.375968)
			(xy 381.37846 -357.375968) (xy 381.405735 -357.376369) (xy 381.45973 -357.384127) (xy 381.512072 -357.399491)
			(xy 381.561694 -357.422148) (xy 381.607586 -357.451637) (xy 381.648815 -357.487357) (xy 381.684539 -357.528582)
			(xy 381.714033 -357.574471) (xy 381.736695 -357.62409) (xy 381.752065 -357.67643) (xy 381.759828 -357.730425)
			(xy 381.759828 -357.78497) (xy 383.242531 -357.78497) (xy 383.242531 -357.73043) (xy 383.250294 -357.676446)
			(xy 383.26566 -357.624116) (xy 383.288317 -357.574505) (xy 383.317804 -357.528624) (xy 383.353521 -357.487407)
			(xy 383.39474 -357.451692) (xy 383.440623 -357.422207) (xy 383.490234 -357.399553) (xy 383.542565 -357.384189)
			(xy 383.59655 -357.37643) (xy 383.62382 -357.375968) (xy 384.48742 -357.375968) (xy 384.514691 -357.376396)
			(xy 384.568676 -357.38416) (xy 384.621007 -357.399529) (xy 384.670619 -357.422188) (xy 384.716501 -357.451677)
			(xy 384.75772 -357.487395) (xy 384.793435 -357.528615) (xy 384.822922 -357.574499) (xy 384.845578 -357.624111)
			(xy 384.860944 -357.676443) (xy 384.868706 -357.730429) (xy 384.868706 -357.784966) (xy 386.351554 -357.784966)
			(xy 386.351554 -357.730434) (xy 386.359315 -357.676456) (xy 386.374678 -357.624132) (xy 386.397331 -357.574527)
			(xy 386.426813 -357.528651) (xy 386.462523 -357.487437) (xy 386.503735 -357.451725) (xy 386.54961 -357.422241)
			(xy 386.599213 -357.399585) (xy 386.651537 -357.384219) (xy 386.705514 -357.376456) (xy 386.73278 -357.375968)
			(xy 387.59638 -357.375968) (xy 387.623654 -357.37637) (xy 387.677647 -357.384131) (xy 387.729987 -357.399496)
			(xy 387.779606 -357.422155) (xy 387.825496 -357.451644) (xy 387.866722 -357.487364) (xy 387.902444 -357.528588)
			(xy 387.931936 -357.574476) (xy 387.954597 -357.624095) (xy 387.969965 -357.676433) (xy 387.977728 -357.730426)
			(xy 387.977728 -357.784971) (xy 389.460432 -357.784971) (xy 389.460432 -357.730429) (xy 389.468194 -357.676443)
			(xy 389.483561 -357.624111) (xy 389.50622 -357.574499) (xy 389.535709 -357.528617) (xy 389.571428 -357.4874)
			(xy 389.61265 -357.451685) (xy 389.658535 -357.422201) (xy 389.708149 -357.399547) (xy 389.760482 -357.384186)
			(xy 389.814469 -357.376429) (xy 389.84174 -357.375968) (xy 390.70534 -357.375968) (xy 390.73261 -357.376397)
			(xy 390.786593 -357.384164) (xy 390.838922 -357.399534) (xy 390.888531 -357.422194) (xy 390.934411 -357.451684)
			(xy 390.975627 -357.487402) (xy 391.01134 -357.528622) (xy 391.040825 -357.574504) (xy 391.06348 -357.624116)
			(xy 391.078844 -357.676446) (xy 391.086606 -357.73043) (xy 391.086606 -357.784967) (xy 392.569454 -357.784967)
			(xy 392.569454 -357.730433) (xy 392.577215 -357.676453) (xy 392.59258 -357.624128) (xy 392.615234 -357.574522)
			(xy 392.644718 -357.528644) (xy 392.68043 -357.48743) (xy 392.721644 -357.451718) (xy 392.767522 -357.422234)
			(xy 392.817128 -357.39958) (xy 392.869453 -357.384215) (xy 392.923433 -357.376454) (xy 392.9507 -357.375968)
			(xy 393.8143 -357.375968) (xy 393.841572 -357.376395) (xy 393.895559 -357.384157) (xy 393.947893 -357.399523)
			(xy 393.997507 -357.422181) (xy 394.043392 -357.451669) (xy 394.084612 -357.487388) (xy 394.120331 -357.528608)
			(xy 394.149819 -357.574493) (xy 394.172477 -357.624107) (xy 394.187843 -357.676441) (xy 394.195605 -357.730428)
			(xy 394.195605 -357.784965) (xy 395.678454 -357.784965) (xy 395.678454 -357.730435) (xy 395.686214 -357.676459)
			(xy 395.701576 -357.624137) (xy 395.724228 -357.574533) (xy 395.753708 -357.528658) (xy 395.789416 -357.487444)
			(xy 395.830625 -357.451732) (xy 395.876498 -357.422247) (xy 395.926099 -357.39959) (xy 395.97842 -357.384223)
			(xy 396.032395 -357.376457) (xy 396.05966 -357.375968) (xy 396.92326 -357.375968) (xy 396.950535 -357.376369)
			(xy 397.00453 -357.384127) (xy 397.056872 -357.399491) (xy 397.106494 -357.422148) (xy 397.152386 -357.451637)
			(xy 397.193615 -357.487357) (xy 397.229339 -357.528582) (xy 397.258833 -357.574471) (xy 397.281495 -357.62409)
			(xy 397.296865 -357.67643) (xy 397.304628 -357.730425) (xy 397.304628 -357.78497) (xy 398.787331 -357.78497)
			(xy 398.787331 -357.73043) (xy 398.795094 -357.676446) (xy 398.81046 -357.624116) (xy 398.833117 -357.574505)
			(xy 398.862604 -357.528624) (xy 398.898321 -357.487407) (xy 398.93954 -357.451692) (xy 398.985423 -357.422207)
			(xy 399.035034 -357.399553) (xy 399.087365 -357.384189) (xy 399.14135 -357.37643) (xy 399.16862 -357.375968)
			(xy 400.03222 -357.375968) (xy 400.059491 -357.376396) (xy 400.113476 -357.38416) (xy 400.165807 -357.399529)
			(xy 400.215419 -357.422188) (xy 400.261301 -357.451677) (xy 400.30252 -357.487395) (xy 400.338235 -357.528615)
			(xy 400.367722 -357.574499) (xy 400.390378 -357.624111) (xy 400.405744 -357.676443) (xy 400.413506 -357.730429)
			(xy 400.413506 -357.784966) (xy 401.896354 -357.784966) (xy 401.896354 -357.730434) (xy 401.904115 -357.676456)
			(xy 401.919478 -357.624132) (xy 401.942131 -357.574527) (xy 401.971613 -357.528651) (xy 402.007323 -357.487437)
			(xy 402.048535 -357.451725) (xy 402.09441 -357.422241) (xy 402.144013 -357.399585) (xy 402.196337 -357.384219)
			(xy 402.250314 -357.376456) (xy 402.27758 -357.375968) (xy 403.14118 -357.375968) (xy 403.168454 -357.37637)
			(xy 403.222447 -357.384131) (xy 403.274787 -357.399496) (xy 403.324406 -357.422155) (xy 403.370296 -357.451644)
			(xy 403.411522 -357.487364) (xy 403.447244 -357.528588) (xy 403.476736 -357.574476) (xy 403.499397 -357.624095)
			(xy 403.514765 -357.676433) (xy 403.522528 -357.730426) (xy 403.522528 -357.784965) (xy 412.022854 -357.784965)
			(xy 412.022854 -357.730435) (xy 412.030614 -357.67646) (xy 412.045976 -357.624138) (xy 412.068627 -357.574535)
			(xy 412.098106 -357.52866) (xy 412.133813 -357.487447) (xy 412.175022 -357.451735) (xy 412.220893 -357.42225)
			(xy 412.270493 -357.399593) (xy 412.322813 -357.384224) (xy 412.376787 -357.376458) (xy 412.404052 -357.375968)
			(xy 413.267652 -357.375968) (xy 413.294927 -357.376368) (xy 413.348924 -357.384125) (xy 413.401266 -357.399489)
			(xy 413.450889 -357.422145) (xy 413.496783 -357.451634) (xy 413.538012 -357.487354) (xy 413.573737 -357.528579)
			(xy 413.603232 -357.574468) (xy 413.625894 -357.624089) (xy 413.641264 -357.676429) (xy 413.649028 -357.730425)
			(xy 413.649028 -357.784969) (xy 415.131731 -357.784969) (xy 415.131731 -357.730431) (xy 415.139493 -357.676447)
			(xy 415.154859 -357.624117) (xy 415.177516 -357.574507) (xy 415.207002 -357.528627) (xy 415.242718 -357.487409)
			(xy 415.283936 -357.451695) (xy 415.329818 -357.42221) (xy 415.379429 -357.399555) (xy 415.431759 -357.384191)
			(xy 415.485743 -357.376431) (xy 415.513012 -357.375968) (xy 416.376612 -357.375968) (xy 416.403883 -357.376395)
			(xy 416.457869 -357.384159) (xy 416.510202 -357.399527) (xy 416.559814 -357.422185) (xy 416.605697 -357.451674)
			(xy 416.646917 -357.487392) (xy 416.682633 -357.528612) (xy 416.712121 -357.574496) (xy 416.734778 -357.62411)
			(xy 416.750144 -357.676442) (xy 416.757906 -357.730429) (xy 416.757906 -357.784966) (xy 418.240754 -357.784966)
			(xy 418.240754 -357.730434) (xy 418.248515 -357.676457) (xy 418.263877 -357.624134) (xy 418.28653 -357.57453)
			(xy 418.316011 -357.528654) (xy 418.35172 -357.48744) (xy 418.392931 -357.451727) (xy 418.438805 -357.422243)
			(xy 418.488408 -357.399587) (xy 418.54073 -357.384221) (xy 418.594706 -357.376456) (xy 418.621972 -357.375968)
			(xy 419.485572 -357.375968) (xy 419.512846 -357.37637) (xy 419.566841 -357.384129) (xy 419.619181 -357.399494)
			(xy 419.668801 -357.422152) (xy 419.714692 -357.451641) (xy 419.755919 -357.487361) (xy 419.791642 -357.528585)
			(xy 419.821135 -357.574474) (xy 419.843796 -357.624093) (xy 419.859165 -357.676432) (xy 419.866928 -357.730426)
			(xy 419.866928 -357.78497) (xy 421.349632 -357.78497) (xy 421.349632 -357.73043) (xy 421.357394 -357.676444)
			(xy 421.372761 -357.624113) (xy 421.395419 -357.574502) (xy 421.424907 -357.52862) (xy 421.460625 -357.487402)
			(xy 421.501846 -357.451688) (xy 421.54773 -357.422203) (xy 421.597343 -357.399549) (xy 421.649676 -357.384187)
			(xy 421.703662 -357.376429) (xy 421.730932 -357.375968) (xy 422.594532 -357.375968) (xy 422.621802 -357.376397)
			(xy 422.675786 -357.384163) (xy 422.728116 -357.399532) (xy 422.777726 -357.422192) (xy 422.823607 -357.451681)
			(xy 422.864824 -357.487399) (xy 422.900538 -357.528619) (xy 422.930024 -357.574502) (xy 422.952679 -357.624114)
			(xy 422.968044 -357.676445) (xy 422.975806 -357.73043) (xy 422.975806 -357.784967) (xy 424.458654 -357.784967)
			(xy 424.458654 -357.730433) (xy 424.466415 -357.676454) (xy 424.481779 -357.62413) (xy 424.504433 -357.574524)
			(xy 424.533916 -357.528647) (xy 424.569627 -357.487433) (xy 424.610841 -357.45172) (xy 424.656717 -357.422237)
			(xy 424.706322 -357.399582) (xy 424.758647 -357.384217) (xy 424.812625 -357.376455) (xy 424.839892 -357.375968)
			(xy 425.703492 -357.375968) (xy 425.730766 -357.376371) (xy 425.784757 -357.384133) (xy 425.837095 -357.3995)
			(xy 425.886713 -357.422159) (xy 425.932602 -357.451648) (xy 425.973826 -357.487368) (xy 426.009547 -357.528592)
			(xy 426.039038 -357.57448) (xy 426.061698 -357.624097) (xy 426.077065 -357.676435) (xy 426.084828 -357.730426)
			(xy 426.084828 -357.784965) (xy 427.567654 -357.784965) (xy 427.567654 -357.730435) (xy 427.575414 -357.67646)
			(xy 427.590776 -357.624138) (xy 427.613427 -357.574535) (xy 427.642906 -357.52866) (xy 427.678613 -357.487447)
			(xy 427.719822 -357.451735) (xy 427.765693 -357.42225) (xy 427.815293 -357.399593) (xy 427.867613 -357.384224)
			(xy 427.921587 -357.376458) (xy 427.948852 -357.375968) (xy 428.812452 -357.375968) (xy 428.839727 -357.376368)
			(xy 428.893724 -357.384125) (xy 428.946066 -357.399489) (xy 428.995689 -357.422145) (xy 429.041583 -357.451634)
			(xy 429.082812 -357.487354) (xy 429.118537 -357.528579) (xy 429.148032 -357.574468) (xy 429.170694 -357.624089)
			(xy 429.186064 -357.676429) (xy 429.193828 -357.730425) (xy 429.193828 -357.784969) (xy 430.676531 -357.784969)
			(xy 430.676531 -357.730431) (xy 430.684293 -357.676447) (xy 430.699659 -357.624117) (xy 430.722316 -357.574507)
			(xy 430.751802 -357.528627) (xy 430.787518 -357.487409) (xy 430.828736 -357.451695) (xy 430.874618 -357.42221)
			(xy 430.924229 -357.399555) (xy 430.976559 -357.384191) (xy 431.030543 -357.376431) (xy 431.057812 -357.375968)
			(xy 431.921412 -357.375968) (xy 431.948683 -357.376395) (xy 432.002669 -357.384159) (xy 432.055002 -357.399527)
			(xy 432.104614 -357.422185) (xy 432.150497 -357.451674) (xy 432.191717 -357.487392) (xy 432.227433 -357.528612)
			(xy 432.256921 -357.574496) (xy 432.279578 -357.62411) (xy 432.294944 -357.676442) (xy 432.302706 -357.730429)
			(xy 432.302706 -357.784966) (xy 433.785554 -357.784966) (xy 433.785554 -357.730434) (xy 433.793315 -357.676457)
			(xy 433.808677 -357.624134) (xy 433.83133 -357.57453) (xy 433.860811 -357.528654) (xy 433.89652 -357.48744)
			(xy 433.937731 -357.451727) (xy 433.983605 -357.422243) (xy 434.033208 -357.399587) (xy 434.08553 -357.384221)
			(xy 434.139506 -357.376456) (xy 434.166772 -357.375968) (xy 435.030372 -357.375968) (xy 435.057646 -357.37637)
			(xy 435.111641 -357.384129) (xy 435.163981 -357.399494) (xy 435.213601 -357.422152) (xy 435.259492 -357.451641)
			(xy 435.300719 -357.487361) (xy 435.336442 -357.528585) (xy 435.365935 -357.574474) (xy 435.388596 -357.624093)
			(xy 435.403965 -357.676432) (xy 435.411728 -357.730426) (xy 435.411728 -357.78497) (xy 436.894432 -357.78497)
			(xy 436.894432 -357.73043) (xy 436.902194 -357.676444) (xy 436.917561 -357.624113) (xy 436.940219 -357.574502)
			(xy 436.969707 -357.52862) (xy 437.005425 -357.487402) (xy 437.046646 -357.451688) (xy 437.09253 -357.422203)
			(xy 437.142143 -357.399549) (xy 437.194476 -357.384187) (xy 437.248462 -357.376429) (xy 437.275732 -357.375968)
			(xy 438.139332 -357.375968) (xy 438.166602 -357.376397) (xy 438.220586 -357.384163) (xy 438.272916 -357.399532)
			(xy 438.322526 -357.422192) (xy 438.368407 -357.451681) (xy 438.409624 -357.487399) (xy 438.445338 -357.528619)
			(xy 438.474824 -357.574502) (xy 438.497479 -357.624114) (xy 438.512844 -357.676445) (xy 438.520606 -357.73043)
			(xy 438.520606 -357.784967) (xy 440.003454 -357.784967) (xy 440.003454 -357.730433) (xy 440.011215 -357.676454)
			(xy 440.026579 -357.62413) (xy 440.049233 -357.574524) (xy 440.078716 -357.528647) (xy 440.114427 -357.487433)
			(xy 440.155641 -357.45172) (xy 440.201517 -357.422237) (xy 440.251122 -357.399582) (xy 440.303447 -357.384217)
			(xy 440.357425 -357.376455) (xy 440.384692 -357.375968) (xy 441.248292 -357.375968) (xy 441.275566 -357.376371)
			(xy 441.329557 -357.384133) (xy 441.381895 -357.3995) (xy 441.431513 -357.422159) (xy 441.477402 -357.451648)
			(xy 441.518626 -357.487368) (xy 441.554347 -357.528592) (xy 441.583838 -357.57448) (xy 441.606498 -357.624097)
			(xy 441.621865 -357.676435) (xy 441.629628 -357.730426) (xy 441.629628 -357.784974) (xy 441.621865 -357.838965)
			(xy 441.606498 -357.891303) (xy 441.583838 -357.94092) (xy 441.554347 -357.986808) (xy 441.518626 -358.028032)
			(xy 441.477402 -358.063752) (xy 441.431513 -358.093241) (xy 441.381895 -358.1159) (xy 441.329557 -358.131267)
			(xy 441.275566 -358.139029) (xy 441.248292 -358.139492) (xy 440.384692 -358.139492) (xy 440.357425 -358.138945)
			(xy 440.303447 -358.131183) (xy 440.251122 -358.115818) (xy 440.201517 -358.093163) (xy 440.155641 -358.06368)
			(xy 440.114427 -358.027967) (xy 440.078716 -357.986753) (xy 440.049233 -357.940876) (xy 440.026579 -357.89127)
			(xy 440.011215 -357.838946) (xy 440.003454 -357.784967) (xy 438.520606 -357.784967) (xy 438.520606 -357.78497)
			(xy 438.512844 -357.838955) (xy 438.497479 -357.891286) (xy 438.474824 -357.940898) (xy 438.445338 -357.986781)
			(xy 438.409624 -358.028001) (xy 438.368407 -358.063719) (xy 438.322526 -358.093208) (xy 438.272916 -358.115868)
			(xy 438.220586 -358.131237) (xy 438.166602 -358.139003) (xy 438.139332 -358.139492) (xy 437.275732 -358.139492)
			(xy 437.248462 -358.138971) (xy 437.194476 -358.131213) (xy 437.142143 -358.115851) (xy 437.09253 -358.093197)
			(xy 437.046646 -358.063712) (xy 437.005425 -358.027998) (xy 436.969707 -357.98678) (xy 436.940219 -357.940898)
			(xy 436.917561 -357.891287) (xy 436.902194 -357.838956) (xy 436.894432 -357.78497) (xy 435.411728 -357.78497)
			(xy 435.411728 -357.784974) (xy 435.403965 -357.838968) (xy 435.388596 -357.891307) (xy 435.365935 -357.940926)
			(xy 435.336442 -357.986815) (xy 435.300719 -358.028039) (xy 435.259492 -358.063759) (xy 435.213601 -358.093248)
			(xy 435.163981 -358.115906) (xy 435.111641 -358.131271) (xy 435.057646 -358.13903) (xy 435.030372 -358.139492)
			(xy 434.166772 -358.139492) (xy 434.139506 -358.138944) (xy 434.08553 -358.131179) (xy 434.033208 -358.115813)
			(xy 433.983605 -358.093157) (xy 433.937731 -358.063673) (xy 433.89652 -358.02796) (xy 433.860811 -357.986746)
			(xy 433.83133 -357.94087) (xy 433.808677 -357.891266) (xy 433.793315 -357.838943) (xy 433.785554 -357.784966)
			(xy 432.302706 -357.784966) (xy 432.302706 -357.784971) (xy 432.294944 -357.838958) (xy 432.279578 -357.89129)
			(xy 432.256921 -357.940904) (xy 432.227433 -357.986788) (xy 432.191717 -358.028008) (xy 432.150497 -358.063726)
			(xy 432.104614 -358.093215) (xy 432.055002 -358.115873) (xy 432.002669 -358.131241) (xy 431.948683 -358.139005)
			(xy 431.921412 -358.139492) (xy 431.057812 -358.139492) (xy 431.030543 -358.138969) (xy 430.976559 -358.131209)
			(xy 430.924229 -358.115845) (xy 430.874618 -358.09319) (xy 430.828736 -358.063705) (xy 430.787518 -358.027991)
			(xy 430.751802 -357.986773) (xy 430.722316 -357.940893) (xy 430.699659 -357.891283) (xy 430.684293 -357.838953)
			(xy 430.676531 -357.784969) (xy 429.193828 -357.784969) (xy 429.193828 -357.784975) (xy 429.186064 -357.838971)
			(xy 429.170694 -357.891311) (xy 429.148032 -357.940932) (xy 429.118537 -357.986821) (xy 429.082812 -358.028046)
			(xy 429.041583 -358.063766) (xy 428.995689 -358.093255) (xy 428.946066 -358.115911) (xy 428.893724 -358.131275)
			(xy 428.839727 -358.139032) (xy 428.812452 -358.139492) (xy 427.948852 -358.139492) (xy 427.921587 -358.138942)
			(xy 427.867613 -358.131176) (xy 427.815293 -358.115807) (xy 427.765693 -358.09315) (xy 427.719822 -358.063665)
			(xy 427.678613 -358.027953) (xy 427.642906 -357.98674) (xy 427.613427 -357.940865) (xy 427.590776 -357.891262)
			(xy 427.575414 -357.83894) (xy 427.567654 -357.784965) (xy 426.084828 -357.784965) (xy 426.084828 -357.784974)
			(xy 426.077065 -357.838965) (xy 426.061698 -357.891303) (xy 426.039038 -357.94092) (xy 426.009547 -357.986808)
			(xy 425.973826 -358.028032) (xy 425.932602 -358.063752) (xy 425.886713 -358.093241) (xy 425.837095 -358.1159)
			(xy 425.784757 -358.131267) (xy 425.730766 -358.139029) (xy 425.703492 -358.139492) (xy 424.839892 -358.139492)
			(xy 424.812625 -358.138945) (xy 424.758647 -358.131183) (xy 424.706322 -358.115818) (xy 424.656717 -358.093163)
			(xy 424.610841 -358.06368) (xy 424.569627 -358.027967) (xy 424.533916 -357.986753) (xy 424.504433 -357.940876)
			(xy 424.481779 -357.89127) (xy 424.466415 -357.838946) (xy 424.458654 -357.784967) (xy 422.975806 -357.784967)
			(xy 422.975806 -357.78497) (xy 422.968044 -357.838955) (xy 422.952679 -357.891286) (xy 422.930024 -357.940898)
			(xy 422.900538 -357.986781) (xy 422.864824 -358.028001) (xy 422.823607 -358.063719) (xy 422.777726 -358.093208)
			(xy 422.728116 -358.115868) (xy 422.675786 -358.131237) (xy 422.621802 -358.139003) (xy 422.594532 -358.139492)
			(xy 421.730932 -358.139492) (xy 421.703662 -358.138971) (xy 421.649676 -358.131213) (xy 421.597343 -358.115851)
			(xy 421.54773 -358.093197) (xy 421.501846 -358.063712) (xy 421.460625 -358.027998) (xy 421.424907 -357.98678)
			(xy 421.395419 -357.940898) (xy 421.372761 -357.891287) (xy 421.357394 -357.838956) (xy 421.349632 -357.78497)
			(xy 419.866928 -357.78497) (xy 419.866928 -357.784974) (xy 419.859165 -357.838968) (xy 419.843796 -357.891307)
			(xy 419.821135 -357.940926) (xy 419.791642 -357.986815) (xy 419.755919 -358.028039) (xy 419.714692 -358.063759)
			(xy 419.668801 -358.093248) (xy 419.619181 -358.115906) (xy 419.566841 -358.131271) (xy 419.512846 -358.13903)
			(xy 419.485572 -358.139492) (xy 418.621972 -358.139492) (xy 418.594706 -358.138944) (xy 418.54073 -358.131179)
			(xy 418.488408 -358.115813) (xy 418.438805 -358.093157) (xy 418.392931 -358.063673) (xy 418.35172 -358.02796)
			(xy 418.316011 -357.986746) (xy 418.28653 -357.94087) (xy 418.263877 -357.891266) (xy 418.248515 -357.838943)
			(xy 418.240754 -357.784966) (xy 416.757906 -357.784966) (xy 416.757906 -357.784971) (xy 416.750144 -357.838958)
			(xy 416.734778 -357.89129) (xy 416.712121 -357.940904) (xy 416.682633 -357.986788) (xy 416.646917 -358.028008)
			(xy 416.605697 -358.063726) (xy 416.559814 -358.093215) (xy 416.510202 -358.115873) (xy 416.457869 -358.131241)
			(xy 416.403883 -358.139005) (xy 416.376612 -358.139492) (xy 415.513012 -358.139492) (xy 415.485743 -358.138969)
			(xy 415.431759 -358.131209) (xy 415.379429 -358.115845) (xy 415.329818 -358.09319) (xy 415.283936 -358.063705)
			(xy 415.242718 -358.027991) (xy 415.207002 -357.986773) (xy 415.177516 -357.940893) (xy 415.154859 -357.891283)
			(xy 415.139493 -357.838953) (xy 415.131731 -357.784969) (xy 413.649028 -357.784969) (xy 413.649028 -357.784975)
			(xy 413.641264 -357.838971) (xy 413.625894 -357.891311) (xy 413.603232 -357.940932) (xy 413.573737 -357.986821)
			(xy 413.538012 -358.028046) (xy 413.496783 -358.063766) (xy 413.450889 -358.093255) (xy 413.401266 -358.115911)
			(xy 413.348924 -358.131275) (xy 413.294927 -358.139032) (xy 413.267652 -358.139492) (xy 412.404052 -358.139492)
			(xy 412.376787 -358.138942) (xy 412.322813 -358.131176) (xy 412.270493 -358.115807) (xy 412.220893 -358.09315)
			(xy 412.175022 -358.063665) (xy 412.133813 -358.027953) (xy 412.098106 -357.98674) (xy 412.068627 -357.940865)
			(xy 412.045976 -357.891262) (xy 412.030614 -357.83894) (xy 412.022854 -357.784965) (xy 403.522528 -357.784965)
			(xy 403.522528 -357.784974) (xy 403.514765 -357.838967) (xy 403.499397 -357.891305) (xy 403.476736 -357.940924)
			(xy 403.447244 -357.986812) (xy 403.411522 -358.028036) (xy 403.370296 -358.063756) (xy 403.324406 -358.093245)
			(xy 403.274787 -358.115904) (xy 403.222447 -358.131269) (xy 403.168454 -358.13903) (xy 403.14118 -358.139492)
			(xy 402.27758 -358.139492) (xy 402.250314 -358.138944) (xy 402.196337 -358.131181) (xy 402.144013 -358.115815)
			(xy 402.09441 -358.093159) (xy 402.048535 -358.063675) (xy 402.007323 -358.027963) (xy 401.971613 -357.986749)
			(xy 401.942131 -357.940873) (xy 401.919478 -357.891268) (xy 401.904115 -357.838944) (xy 401.896354 -357.784966)
			(xy 400.413506 -357.784966) (xy 400.413506 -357.784971) (xy 400.405744 -357.838957) (xy 400.390378 -357.891289)
			(xy 400.367722 -357.940901) (xy 400.338235 -357.986785) (xy 400.30252 -358.028005) (xy 400.261301 -358.063723)
			(xy 400.215419 -358.093212) (xy 400.165807 -358.115871) (xy 400.113476 -358.13124) (xy 400.059491 -358.139004)
			(xy 400.03222 -358.139492) (xy 399.16862 -358.139492) (xy 399.14135 -358.13897) (xy 399.087365 -358.131211)
			(xy 399.035034 -358.115847) (xy 398.985423 -358.093193) (xy 398.93954 -358.063708) (xy 398.898321 -358.027993)
			(xy 398.862604 -357.986776) (xy 398.833117 -357.940895) (xy 398.81046 -357.891284) (xy 398.795094 -357.838954)
			(xy 398.787331 -357.78497) (xy 397.304628 -357.78497) (xy 397.304628 -357.784975) (xy 397.296865 -357.83897)
			(xy 397.281495 -357.89131) (xy 397.258833 -357.940929) (xy 397.229339 -357.986818) (xy 397.193615 -358.028043)
			(xy 397.152386 -358.063763) (xy 397.106494 -358.093252) (xy 397.056872 -358.115909) (xy 397.00453 -358.131273)
			(xy 396.950535 -358.139031) (xy 396.92326 -358.139492) (xy 396.05966 -358.139492) (xy 396.032395 -358.138943)
			(xy 395.97842 -358.131177) (xy 395.926099 -358.11581) (xy 395.876498 -358.093153) (xy 395.830625 -358.063668)
			(xy 395.789416 -358.027956) (xy 395.753708 -357.986742) (xy 395.724228 -357.940867) (xy 395.701576 -357.891263)
			(xy 395.686214 -357.838941) (xy 395.678454 -357.784965) (xy 394.195605 -357.784965) (xy 394.195605 -357.784972)
			(xy 394.187843 -357.838959) (xy 394.172477 -357.891293) (xy 394.149819 -357.940907) (xy 394.120331 -357.986792)
			(xy 394.084612 -358.028012) (xy 394.043392 -358.063731) (xy 393.997507 -358.093219) (xy 393.947893 -358.115877)
			(xy 393.895559 -358.131243) (xy 393.841572 -358.139005) (xy 393.8143 -358.139492) (xy 392.9507 -358.139492)
			(xy 392.923433 -358.138946) (xy 392.869453 -358.131185) (xy 392.817128 -358.11582) (xy 392.767522 -358.093166)
			(xy 392.721644 -358.063682) (xy 392.68043 -358.02797) (xy 392.644718 -357.986756) (xy 392.615234 -357.940878)
			(xy 392.59258 -357.891272) (xy 392.577215 -357.838947) (xy 392.569454 -357.784967) (xy 391.086606 -357.784967)
			(xy 391.086606 -357.78497) (xy 391.078844 -357.838954) (xy 391.06348 -357.891284) (xy 391.040825 -357.940896)
			(xy 391.01134 -357.986778) (xy 390.975627 -358.027998) (xy 390.934411 -358.063716) (xy 390.888531 -358.093206)
			(xy 390.838922 -358.115866) (xy 390.786593 -358.131236) (xy 390.73261 -358.139003) (xy 390.70534 -358.139492)
			(xy 389.84174 -358.139492) (xy 389.814469 -358.138971) (xy 389.760482 -358.131214) (xy 389.708149 -358.115853)
			(xy 389.658535 -358.093199) (xy 389.61265 -358.063715) (xy 389.571428 -358.028) (xy 389.535709 -357.986783)
			(xy 389.50622 -357.940901) (xy 389.483561 -357.891289) (xy 389.468194 -357.838957) (xy 389.460432 -357.784971)
			(xy 387.977728 -357.784971) (xy 387.977728 -357.784974) (xy 387.969965 -357.838967) (xy 387.954597 -357.891305)
			(xy 387.931936 -357.940924) (xy 387.902444 -357.986812) (xy 387.866722 -358.028036) (xy 387.825496 -358.063756)
			(xy 387.779606 -358.093245) (xy 387.729987 -358.115904) (xy 387.677647 -358.131269) (xy 387.623654 -358.13903)
			(xy 387.59638 -358.139492) (xy 386.73278 -358.139492) (xy 386.705514 -358.138944) (xy 386.651537 -358.131181)
			(xy 386.599213 -358.115815) (xy 386.54961 -358.093159) (xy 386.503735 -358.063675) (xy 386.462523 -358.027963)
			(xy 386.426813 -357.986749) (xy 386.397331 -357.940873) (xy 386.374678 -357.891268) (xy 386.359315 -357.838944)
			(xy 386.351554 -357.784966) (xy 384.868706 -357.784966) (xy 384.868706 -357.784971) (xy 384.860944 -357.838957)
			(xy 384.845578 -357.891289) (xy 384.822922 -357.940901) (xy 384.793435 -357.986785) (xy 384.75772 -358.028005)
			(xy 384.716501 -358.063723) (xy 384.670619 -358.093212) (xy 384.621007 -358.115871) (xy 384.568676 -358.13124)
			(xy 384.514691 -358.139004) (xy 384.48742 -358.139492) (xy 383.62382 -358.139492) (xy 383.59655 -358.13897)
			(xy 383.542565 -358.131211) (xy 383.490234 -358.115847) (xy 383.440623 -358.093193) (xy 383.39474 -358.063708)
			(xy 383.353521 -358.027993) (xy 383.317804 -357.986776) (xy 383.288317 -357.940895) (xy 383.26566 -357.891284)
			(xy 383.250294 -357.838954) (xy 383.242531 -357.78497) (xy 381.759828 -357.78497) (xy 381.759828 -357.784975)
			(xy 381.752065 -357.83897) (xy 381.736695 -357.89131) (xy 381.714033 -357.940929) (xy 381.684539 -357.986818)
			(xy 381.648815 -358.028043) (xy 381.607586 -358.063763) (xy 381.561694 -358.093252) (xy 381.512072 -358.115909)
			(xy 381.45973 -358.131273) (xy 381.405735 -358.139031) (xy 381.37846 -358.139492) (xy 380.51486 -358.139492)
			(xy 380.487595 -358.138943) (xy 380.43362 -358.131177) (xy 380.381299 -358.11581) (xy 380.331698 -358.093153)
			(xy 380.285825 -358.063668) (xy 380.244616 -358.027956) (xy 380.208908 -357.986742) (xy 380.179428 -357.940867)
			(xy 380.156776 -357.891263) (xy 380.141414 -357.838941) (xy 380.133654 -357.784965) (xy 378.650805 -357.784965)
			(xy 378.650805 -357.784972) (xy 378.643043 -357.838959) (xy 378.627677 -357.891293) (xy 378.605019 -357.940907)
			(xy 378.575531 -357.986792) (xy 378.539812 -358.028012) (xy 378.498592 -358.063731) (xy 378.452707 -358.093219)
			(xy 378.403093 -358.115877) (xy 378.350759 -358.131243) (xy 378.296772 -358.139005) (xy 378.2695 -358.139492)
			(xy 377.4059 -358.139492) (xy 377.378633 -358.138946) (xy 377.324653 -358.131185) (xy 377.272328 -358.11582)
			(xy 377.222722 -358.093166) (xy 377.176844 -358.063682) (xy 377.13563 -358.02797) (xy 377.099918 -357.986756)
			(xy 377.070434 -357.940878) (xy 377.04778 -357.891272) (xy 377.032415 -357.838947) (xy 377.024654 -357.784967)
			(xy 375.541806 -357.784967) (xy 375.541806 -357.78497) (xy 375.534044 -357.838954) (xy 375.51868 -357.891284)
			(xy 375.496025 -357.940896) (xy 375.46654 -357.986778) (xy 375.430827 -358.027998) (xy 375.389611 -358.063716)
			(xy 375.343731 -358.093206) (xy 375.294122 -358.115866) (xy 375.241793 -358.131236) (xy 375.18781 -358.139003)
			(xy 375.16054 -358.139492) (xy 374.29694 -358.139492) (xy 374.269669 -358.138971) (xy 374.215682 -358.131214)
			(xy 374.163349 -358.115853) (xy 374.113735 -358.093199) (xy 374.06785 -358.063715) (xy 374.026628 -358.028)
			(xy 373.990909 -357.986783) (xy 373.96142 -357.940901) (xy 373.938761 -357.891289) (xy 373.923394 -357.838957)
			(xy 373.915632 -357.784971) (xy 344.837306 -357.784971) (xy 344.829543 -357.838959) (xy 344.814177 -357.891292)
			(xy 344.791519 -357.940906) (xy 344.762031 -357.98679) (xy 344.726314 -358.028011) (xy 344.685093 -358.063729)
			(xy 344.639209 -358.093217) (xy 344.589596 -358.115876) (xy 344.537263 -358.131242) (xy 344.483275 -358.139005)
			(xy 344.456004 -358.139492) (xy 343.592404 -358.139492) (xy 343.565135 -358.138969) (xy 343.511152 -358.131208)
			(xy 343.458823 -358.115843) (xy 343.409213 -358.093188) (xy 343.363333 -358.063702) (xy 343.322115 -358.027988)
			(xy 343.2864 -357.986771) (xy 343.256914 -357.94089) (xy 343.234258 -357.891281) (xy 343.218893 -357.838952)
			(xy 343.211131 -357.784969) (xy 341.728306 -357.784969) (xy 341.728306 -357.78497) (xy 341.720544 -357.838953)
			(xy 341.70518 -357.891284) (xy 341.682525 -357.940895) (xy 341.653041 -357.986777) (xy 341.617328 -358.027997)
			(xy 341.576112 -358.063715) (xy 341.530233 -358.093204) (xy 341.480625 -358.115865) (xy 341.428297 -358.131235)
			(xy 341.374313 -358.139002) (xy 341.347044 -358.139492) (xy 340.483444 -358.139492) (xy 340.456173 -358.138972)
			(xy 340.402186 -358.131215) (xy 340.349852 -358.115854) (xy 340.300237 -358.093201) (xy 340.254351 -358.063716)
			(xy 340.213129 -358.028002) (xy 340.17741 -357.986784) (xy 340.147921 -357.940902) (xy 340.125261 -357.891289)
			(xy 340.109894 -357.838957) (xy 340.102132 -357.784971) (xy 338.619428 -357.784971) (xy 338.619428 -357.784974)
			(xy 338.611665 -357.838966) (xy 338.596297 -357.891304) (xy 338.573636 -357.940923) (xy 338.544145 -357.986811)
			(xy 338.508423 -358.028034) (xy 338.467198 -358.063755) (xy 338.421308 -358.093244) (xy 338.371689 -358.115903)
			(xy 338.319351 -358.131269) (xy 338.265358 -358.13903) (xy 338.238084 -358.139492) (xy 337.374484 -358.139492)
			(xy 337.347218 -358.138945) (xy 337.29324 -358.131182) (xy 337.240916 -358.115816) (xy 337.191312 -358.093161)
			(xy 337.145437 -358.063677) (xy 337.104224 -358.027964) (xy 337.068514 -357.98675) (xy 337.039032 -357.940874)
			(xy 337.016378 -357.891269) (xy 337.001015 -357.838944) (xy 336.993254 -357.784967) (xy 335.510406 -357.784967)
			(xy 335.510406 -357.78497) (xy 335.502644 -357.838956) (xy 335.487279 -357.891288) (xy 335.464622 -357.9409)
			(xy 335.435136 -357.986784) (xy 335.399421 -358.028004) (xy 335.358203 -358.063722) (xy 335.312321 -358.093211)
			(xy 335.26271 -358.11587) (xy 335.21038 -358.131239) (xy 335.156394 -358.139004) (xy 335.129124 -358.139492)
			(xy 334.265524 -358.139492) (xy 334.238254 -358.13897) (xy 334.184269 -358.131211) (xy 334.131937 -358.115848)
			(xy 334.082325 -358.093194) (xy 334.036442 -358.063709) (xy 333.995222 -358.027995) (xy 333.959505 -357.986777)
			(xy 333.930017 -357.940896) (xy 333.90736 -357.891285) (xy 333.891994 -357.838955) (xy 333.884231 -357.78497)
			(xy 332.401528 -357.78497) (xy 332.401528 -357.784975) (xy 332.393765 -357.838969) (xy 332.378395 -357.891309)
			(xy 332.355733 -357.940928) (xy 332.32624 -357.986817) (xy 332.290516 -358.028041) (xy 332.249288 -358.063762)
			(xy 332.203397 -358.093251) (xy 332.153775 -358.115908) (xy 332.101434 -358.131272) (xy 332.047439 -358.139031)
			(xy 332.020164 -358.139492) (xy 331.156564 -358.139492) (xy 331.129298 -358.138943) (xy 331.075323 -358.131178)
			(xy 331.023002 -358.115811) (xy 330.9734 -358.093154) (xy 330.927527 -358.06367) (xy 330.886317 -358.027957)
			(xy 330.850609 -357.986744) (xy 330.821128 -357.940868) (xy 330.798477 -357.891264) (xy 330.783114 -357.838942)
			(xy 330.775354 -357.784966) (xy 329.292506 -357.784966) (xy 329.292506 -357.784971) (xy 329.284743 -357.838959)
			(xy 329.269377 -357.891292) (xy 329.246719 -357.940906) (xy 329.217231 -357.98679) (xy 329.181514 -358.028011)
			(xy 329.140293 -358.063729) (xy 329.094409 -358.093217) (xy 329.044796 -358.115876) (xy 328.992463 -358.131242)
			(xy 328.938475 -358.139005) (xy 328.911204 -358.139492) (xy 328.047604 -358.139492) (xy 328.020335 -358.138969)
			(xy 327.966352 -358.131208) (xy 327.914023 -358.115843) (xy 327.864413 -358.093188) (xy 327.818533 -358.063702)
			(xy 327.777315 -358.027988) (xy 327.7416 -357.986771) (xy 327.712114 -357.94089) (xy 327.689458 -357.891281)
			(xy 327.674093 -357.838952) (xy 327.666331 -357.784969) (xy 326.183506 -357.784969) (xy 326.183506 -357.78497)
			(xy 326.175744 -357.838953) (xy 326.16038 -357.891284) (xy 326.137725 -357.940895) (xy 326.108241 -357.986777)
			(xy 326.072528 -358.027997) (xy 326.031312 -358.063715) (xy 325.985433 -358.093204) (xy 325.935825 -358.115865)
			(xy 325.883497 -358.131235) (xy 325.829513 -358.139002) (xy 325.802244 -358.139492) (xy 324.938644 -358.139492)
			(xy 324.911373 -358.138972) (xy 324.857386 -358.131215) (xy 324.805052 -358.115854) (xy 324.755437 -358.093201)
			(xy 324.709551 -358.063716) (xy 324.668329 -358.028002) (xy 324.63261 -357.986784) (xy 324.603121 -357.940902)
			(xy 324.580461 -357.891289) (xy 324.565094 -357.838957) (xy 324.557332 -357.784971) (xy 323.074628 -357.784971)
			(xy 323.074628 -357.784974) (xy 323.066865 -357.838966) (xy 323.051497 -357.891304) (xy 323.028836 -357.940923)
			(xy 322.999345 -357.986811) (xy 322.963623 -358.028034) (xy 322.922398 -358.063755) (xy 322.876508 -358.093244)
			(xy 322.826889 -358.115903) (xy 322.774551 -358.131269) (xy 322.720558 -358.13903) (xy 322.693284 -358.139492)
			(xy 321.829684 -358.139492) (xy 321.802418 -358.138945) (xy 321.74844 -358.131182) (xy 321.696116 -358.115816)
			(xy 321.646512 -358.093161) (xy 321.600637 -358.063677) (xy 321.559424 -358.027964) (xy 321.523714 -357.98675)
			(xy 321.494232 -357.940874) (xy 321.471578 -357.891269) (xy 321.456215 -357.838944) (xy 321.448454 -357.784967)
			(xy 319.965606 -357.784967) (xy 319.965606 -357.78497) (xy 319.957844 -357.838956) (xy 319.942479 -357.891288)
			(xy 319.919822 -357.9409) (xy 319.890336 -357.986784) (xy 319.854621 -358.028004) (xy 319.813403 -358.063722)
			(xy 319.767521 -358.093211) (xy 319.71791 -358.11587) (xy 319.66558 -358.131239) (xy 319.611594 -358.139004)
			(xy 319.584324 -358.139492) (xy 318.720724 -358.139492) (xy 318.693454 -358.13897) (xy 318.639469 -358.131211)
			(xy 318.587137 -358.115848) (xy 318.537525 -358.093194) (xy 318.491642 -358.063709) (xy 318.450422 -358.027995)
			(xy 318.414705 -357.986777) (xy 318.385217 -357.940896) (xy 318.36256 -357.891285) (xy 318.347194 -357.838955)
			(xy 318.339431 -357.78497) (xy 316.856728 -357.78497) (xy 316.856728 -357.784975) (xy 316.848965 -357.838969)
			(xy 316.833595 -357.891309) (xy 316.810933 -357.940928) (xy 316.78144 -357.986817) (xy 316.745716 -358.028041)
			(xy 316.704488 -358.063762) (xy 316.658597 -358.093251) (xy 316.608975 -358.115908) (xy 316.556634 -358.131272)
			(xy 316.502639 -358.139031) (xy 316.475364 -358.139492) (xy 315.611764 -358.139492) (xy 315.584498 -358.138943)
			(xy 315.530523 -358.131178) (xy 315.478202 -358.115811) (xy 315.4286 -358.093154) (xy 315.382727 -358.06367)
			(xy 315.341517 -358.027957) (xy 315.305809 -357.986744) (xy 315.276328 -357.940868) (xy 315.253677 -357.891264)
			(xy 315.238314 -357.838942) (xy 315.230554 -357.784966) (xy 300.231606 -357.784966) (xy 300.231606 -357.784971)
			(xy 300.223843 -357.838959) (xy 300.208477 -357.891293) (xy 300.185819 -357.940907) (xy 300.156331 -357.986791)
			(xy 300.120613 -358.028012) (xy 300.079393 -358.06373) (xy 300.033508 -358.093218) (xy 299.983894 -358.115876)
			(xy 299.931561 -358.131243) (xy 299.877573 -358.139005) (xy 299.850302 -358.139492) (xy 298.986702 -358.139492)
			(xy 298.959433 -358.138969) (xy 298.90545 -358.131207) (xy 298.853121 -358.115843) (xy 298.803512 -358.093187)
			(xy 298.757632 -358.063702) (xy 298.716414 -358.027987) (xy 298.6807 -357.98677) (xy 298.651214 -357.94089)
			(xy 298.628558 -357.89128) (xy 298.613193 -357.838952) (xy 298.605431 -357.784969) (xy 297.122606 -357.784969)
			(xy 297.122606 -357.78497) (xy 297.114844 -357.838954) (xy 297.09948 -357.891284) (xy 297.076825 -357.940895)
			(xy 297.047341 -357.986778) (xy 297.011627 -358.027998) (xy 296.970411 -358.063716) (xy 296.924532 -358.093205)
			(xy 296.874923 -358.115865) (xy 296.822595 -358.131235) (xy 296.768612 -358.139003) (xy 296.741342 -358.139492)
			(xy 295.877742 -358.139492) (xy 295.850471 -358.138971) (xy 295.796484 -358.131215) (xy 295.74415 -358.115853)
			(xy 295.694536 -358.0932) (xy 295.64865 -358.063716) (xy 295.607429 -358.028001) (xy 295.571709 -357.986783)
			(xy 295.54222 -357.940901) (xy 295.519561 -357.891289) (xy 295.504194 -357.838957) (xy 295.496432 -357.784971)
			(xy 294.013728 -357.784971) (xy 294.013728 -357.784974) (xy 294.005965 -357.838967) (xy 293.990597 -357.891305)
			(xy 293.967936 -357.940923) (xy 293.938444 -357.986811) (xy 293.902722 -358.028035) (xy 293.861497 -358.063755)
			(xy 293.815607 -358.093245) (xy 293.765988 -358.115903) (xy 293.713649 -358.131269) (xy 293.659656 -358.13903)
			(xy 293.632382 -358.139492) (xy 292.768782 -358.139492) (xy 292.741516 -358.138944) (xy 292.687538 -358.131181)
			(xy 292.635215 -358.115816) (xy 292.585611 -358.09316) (xy 292.539736 -358.063676) (xy 292.498524 -358.027964)
			(xy 292.462813 -357.98675) (xy 292.433331 -357.940873) (xy 292.410678 -357.891268) (xy 292.395315 -357.838944)
			(xy 292.387554 -357.784966) (xy 290.904706 -357.784966) (xy 290.904706 -357.784971) (xy 290.896944 -357.838956)
			(xy 290.881578 -357.891288) (xy 290.858922 -357.940901) (xy 290.829436 -357.986784) (xy 290.79372 -358.028005)
			(xy 290.752502 -358.063723) (xy 290.70662 -358.093211) (xy 290.657009 -358.115871) (xy 290.604678 -358.131239)
			(xy 290.550692 -358.139004) (xy 290.523422 -358.139492) (xy 289.659822 -358.139492) (xy 289.632552 -358.13897)
			(xy 289.578567 -358.131211) (xy 289.526236 -358.115848) (xy 289.476624 -358.093193) (xy 289.430741 -358.063709)
			(xy 289.389522 -358.027994) (xy 289.353805 -357.986777) (xy 289.324317 -357.940895) (xy 289.30166 -357.891285)
			(xy 289.286294 -357.838954) (xy 289.278531 -357.78497) (xy 287.795828 -357.78497) (xy 287.795828 -357.784975)
			(xy 287.788065 -357.838969) (xy 287.772695 -357.891309) (xy 287.750033 -357.940929) (xy 287.72054 -357.986818)
			(xy 287.684815 -358.028042) (xy 287.643587 -358.063762) (xy 287.597695 -358.093251) (xy 287.548073 -358.115908)
			(xy 287.495732 -358.131273) (xy 287.441737 -358.139031) (xy 287.414462 -358.139492) (xy 286.550862 -358.139492)
			(xy 286.523597 -358.138943) (xy 286.469621 -358.131178) (xy 286.4173 -358.11581) (xy 286.367699 -358.093154)
			(xy 286.321826 -358.063669) (xy 286.280617 -358.027957) (xy 286.244908 -357.986743) (xy 286.215428 -357.940868)
			(xy 286.192777 -357.891264) (xy 286.177414 -357.838942) (xy 286.169654 -357.784966) (xy 284.686806 -357.784966)
			(xy 284.686806 -357.784971) (xy 284.679043 -357.838959) (xy 284.663677 -357.891293) (xy 284.641019 -357.940907)
			(xy 284.611531 -357.986791) (xy 284.575813 -358.028012) (xy 284.534593 -358.06373) (xy 284.488708 -358.093218)
			(xy 284.439094 -358.115876) (xy 284.386761 -358.131243) (xy 284.332773 -358.139005) (xy 284.305502 -358.139492)
			(xy 283.441902 -358.139492) (xy 283.414633 -358.138969) (xy 283.36065 -358.131207) (xy 283.308321 -358.115843)
			(xy 283.258712 -358.093187) (xy 283.212832 -358.063702) (xy 283.171614 -358.027987) (xy 283.1359 -357.98677)
			(xy 283.106414 -357.94089) (xy 283.083758 -357.89128) (xy 283.068393 -357.838952) (xy 283.060631 -357.784969)
			(xy 281.577806 -357.784969) (xy 281.577806 -357.78497) (xy 281.570044 -357.838954) (xy 281.55468 -357.891284)
			(xy 281.532025 -357.940895) (xy 281.502541 -357.986778) (xy 281.466827 -358.027998) (xy 281.425611 -358.063716)
			(xy 281.379732 -358.093205) (xy 281.330123 -358.115865) (xy 281.277795 -358.131235) (xy 281.223812 -358.139003)
			(xy 281.196542 -358.139492) (xy 280.332942 -358.139492) (xy 280.305671 -358.138971) (xy 280.251684 -358.131215)
			(xy 280.19935 -358.115853) (xy 280.149736 -358.0932) (xy 280.10385 -358.063716) (xy 280.062629 -358.028001)
			(xy 280.026909 -357.986783) (xy 279.99742 -357.940901) (xy 279.974761 -357.891289) (xy 279.959394 -357.838957)
			(xy 279.951632 -357.784971) (xy 278.468928 -357.784971) (xy 278.468928 -357.784974) (xy 278.461165 -357.838967)
			(xy 278.445797 -357.891305) (xy 278.423136 -357.940923) (xy 278.393644 -357.986811) (xy 278.357922 -358.028035)
			(xy 278.316697 -358.063755) (xy 278.270807 -358.093245) (xy 278.221188 -358.115903) (xy 278.168849 -358.131269)
			(xy 278.114856 -358.13903) (xy 278.087582 -358.139492) (xy 277.223982 -358.139492) (xy 277.196716 -358.138944)
			(xy 277.142738 -358.131181) (xy 277.090415 -358.115816) (xy 277.040811 -358.09316) (xy 276.994936 -358.063676)
			(xy 276.953724 -358.027964) (xy 276.918013 -357.98675) (xy 276.888531 -357.940873) (xy 276.865878 -357.891268)
			(xy 276.850515 -357.838944) (xy 276.842754 -357.784966) (xy 275.359906 -357.784966) (xy 275.359906 -357.784971)
			(xy 275.352144 -357.838956) (xy 275.336778 -357.891288) (xy 275.314122 -357.940901) (xy 275.284636 -357.986784)
			(xy 275.24892 -358.028005) (xy 275.207702 -358.063723) (xy 275.16182 -358.093211) (xy 275.112209 -358.115871)
			(xy 275.059878 -358.131239) (xy 275.005892 -358.139004) (xy 274.978622 -358.139492) (xy 274.115022 -358.139492)
			(xy 274.087752 -358.13897) (xy 274.033767 -358.131211) (xy 273.981436 -358.115848) (xy 273.931824 -358.093193)
			(xy 273.885941 -358.063709) (xy 273.844722 -358.027994) (xy 273.809005 -357.986777) (xy 273.779517 -357.940895)
			(xy 273.75686 -357.891285) (xy 273.741494 -357.838954) (xy 273.733731 -357.78497) (xy 272.251028 -357.78497)
			(xy 272.251028 -357.784975) (xy 272.243265 -357.838969) (xy 272.227895 -357.891309) (xy 272.205233 -357.940929)
			(xy 272.17574 -357.986818) (xy 272.140015 -358.028042) (xy 272.098787 -358.063762) (xy 272.052895 -358.093251)
			(xy 272.003273 -358.115908) (xy 271.950932 -358.131273) (xy 271.896937 -358.139031) (xy 271.869662 -358.139492)
			(xy 271.006062 -358.139492) (xy 270.978797 -358.138943) (xy 270.924821 -358.131178) (xy 270.8725 -358.11581)
			(xy 270.822899 -358.093154) (xy 270.777026 -358.063669) (xy 270.735817 -358.027957) (xy 270.700108 -357.986743)
			(xy 270.670628 -357.940868) (xy 270.647977 -357.891264) (xy 270.632614 -357.838942) (xy 270.624854 -357.784966)
			(xy 247.276485 -357.784966) (xy 247.278987 -357.797946) (xy 247.287038 -357.88226) (xy 247.287542 -357.924608)
			(xy 247.287038 -357.966956) (xy 247.278987 -358.05127) (xy 247.262958 -358.134436) (xy 247.239097 -358.215703)
			(xy 247.207618 -358.294333) (xy 247.168807 -358.369614) (xy 247.123017 -358.440866) (xy 247.070661 -358.507442)
			(xy 247.012213 -358.56874) (xy 246.948203 -358.624205) (xy 246.879211 -358.673334) (xy 246.805861 -358.715683)
			(xy 246.728818 -358.750867) (xy 246.648779 -358.778569) (xy 246.56647 -358.798537) (xy 246.482635 -358.81059)
			(xy 246.398034 -358.814621) (xy 246.313433 -358.81059) (xy 246.229598 -358.798537) (xy 246.147289 -358.778569)
			(xy 246.06725 -358.750867) (xy 245.990207 -358.715683) (xy 245.916857 -358.673334) (xy 245.847865 -358.624205)
			(xy 245.783855 -358.56874) (xy 245.725407 -358.507442) (xy 245.673051 -358.440866) (xy 245.627261 -358.369614)
			(xy 245.58845 -358.294333) (xy 245.556971 -358.215703) (xy 245.53311 -358.134436) (xy 245.517081 -358.05127)
			(xy 245.50903 -357.966956) (xy 188.223925 -357.966956) (xy 188.191672 -358.004178) (xy 188.150456 -358.039891)
			(xy 188.104577 -358.069375) (xy 188.054969 -358.092029) (xy 188.002641 -358.107393) (xy 187.94866 -358.115153)
			(xy 187.921392 -358.115616) (xy 187.057792 -358.115616) (xy 187.03052 -358.115221) (xy 186.97653 -358.107457)
			(xy 186.924196 -358.092089) (xy 186.87458 -358.06943) (xy 186.828695 -358.03994) (xy 186.787473 -358.004221)
			(xy 186.751755 -357.962999) (xy 186.722266 -357.917112) (xy 186.699608 -357.867497) (xy 186.684241 -357.815162)
			(xy 186.676479 -357.761172) (xy 185.193629 -357.761172) (xy 185.18587 -357.815139) (xy 185.170508 -357.86746)
			(xy 185.147857 -357.917062) (xy 185.118378 -357.962936) (xy 185.08267 -358.004147) (xy 185.041461 -358.039858)
			(xy 184.99559 -358.069342) (xy 184.94599 -358.091997) (xy 184.89367 -358.107363) (xy 184.839697 -358.115128)
			(xy 184.812432 -358.115616) (xy 183.948832 -358.115616) (xy 183.921556 -358.115247) (xy 183.867559 -358.107487)
			(xy 183.815217 -358.092122) (xy 183.765593 -358.069463) (xy 183.7197 -358.039973) (xy 183.678471 -358.004251)
			(xy 183.642746 -357.963025) (xy 183.613252 -357.917135) (xy 183.590589 -357.867513) (xy 183.57522 -357.815172)
			(xy 183.567456 -357.761176) (xy 182.084828 -357.761176) (xy 182.084828 -357.784974) (xy 182.077065 -357.838968)
			(xy 182.061696 -357.891307) (xy 182.039035 -357.940926) (xy 182.009542 -357.986815) (xy 181.973819 -358.028039)
			(xy 181.932592 -358.063759) (xy 181.886701 -358.093248) (xy 181.837081 -358.115906) (xy 181.784741 -358.131271)
			(xy 181.730746 -358.13903) (xy 181.703472 -358.139492) (xy 180.839872 -358.139492) (xy 180.812606 -358.138944)
			(xy 180.75863 -358.131179) (xy 180.706308 -358.115813) (xy 180.656705 -358.093157) (xy 180.610831 -358.063673)
			(xy 180.56962 -358.02796) (xy 180.533911 -357.986746) (xy 180.50443 -357.94087) (xy 180.481777 -357.891266)
			(xy 180.466415 -357.838943) (xy 180.458654 -357.784966) (xy 178.975806 -357.784966) (xy 178.975806 -357.784971)
			(xy 178.968044 -357.838958) (xy 178.952678 -357.89129) (xy 178.930021 -357.940904) (xy 178.900533 -357.986788)
			(xy 178.864817 -358.028008) (xy 178.823597 -358.063726) (xy 178.777714 -358.093215) (xy 178.728102 -358.115873)
			(xy 178.675769 -358.131241) (xy 178.621783 -358.139005) (xy 178.594512 -358.139492) (xy 177.730912 -358.139492)
			(xy 177.703643 -358.138969) (xy 177.649659 -358.131209) (xy 177.597329 -358.115845) (xy 177.547718 -358.09319)
			(xy 177.501836 -358.063705) (xy 177.460618 -358.027991) (xy 177.424902 -357.986773) (xy 177.395416 -357.940893)
			(xy 177.372759 -357.891283) (xy 177.357393 -357.838953) (xy 177.349631 -357.784969) (xy 175.866928 -357.784969)
			(xy 175.866928 -357.784975) (xy 175.859164 -357.838971) (xy 175.843794 -357.891311) (xy 175.821132 -357.940932)
			(xy 175.791637 -357.986821) (xy 175.755912 -358.028046) (xy 175.714683 -358.063766) (xy 175.668789 -358.093255)
			(xy 175.619166 -358.115911) (xy 175.566824 -358.131275) (xy 175.512827 -358.139032) (xy 175.485552 -358.139492)
			(xy 174.621952 -358.139492) (xy 174.594687 -358.138942) (xy 174.540713 -358.131176) (xy 174.488393 -358.115807)
			(xy 174.438793 -358.09315) (xy 174.392922 -358.063665) (xy 174.351713 -358.027953) (xy 174.316006 -357.98674)
			(xy 174.286527 -357.940865) (xy 174.263876 -357.891262) (xy 174.248514 -357.83894) (xy 174.240754 -357.784965)
			(xy 172.757928 -357.784965) (xy 172.757928 -357.784974) (xy 172.750165 -357.838965) (xy 172.734798 -357.891303)
			(xy 172.712138 -357.94092) (xy 172.682647 -357.986808) (xy 172.646926 -358.028032) (xy 172.605702 -358.063752)
			(xy 172.559813 -358.093241) (xy 172.510195 -358.1159) (xy 172.457857 -358.131267) (xy 172.403866 -358.139029)
			(xy 172.376592 -358.139492) (xy 171.512992 -358.139492) (xy 171.485725 -358.138945) (xy 171.431747 -358.131183)
			(xy 171.379422 -358.115818) (xy 171.329817 -358.093163) (xy 171.283941 -358.06368) (xy 171.242727 -358.027967)
			(xy 171.207016 -357.986753) (xy 171.177533 -357.940876) (xy 171.154879 -357.89127) (xy 171.139515 -357.838946)
			(xy 171.131754 -357.784967) (xy 169.648906 -357.784967) (xy 169.648906 -357.78497) (xy 169.641144 -357.838955)
			(xy 169.625779 -357.891286) (xy 169.603124 -357.940898) (xy 169.573638 -357.986781) (xy 169.537924 -358.028001)
			(xy 169.496707 -358.063719) (xy 169.450826 -358.093208) (xy 169.401216 -358.115868) (xy 169.348886 -358.131237)
			(xy 169.294902 -358.139003) (xy 169.267632 -358.139492) (xy 168.404032 -358.139492) (xy 168.376762 -358.138971)
			(xy 168.322776 -358.131213) (xy 168.270443 -358.115851) (xy 168.22083 -358.093197) (xy 168.174946 -358.063712)
			(xy 168.133725 -358.027998) (xy 168.098007 -357.98678) (xy 168.068519 -357.940898) (xy 168.045861 -357.891287)
			(xy 168.030494 -357.838956) (xy 168.022732 -357.78497) (xy 166.540028 -357.78497) (xy 166.540028 -357.784974)
			(xy 166.532265 -357.838968) (xy 166.516896 -357.891307) (xy 166.494235 -357.940926) (xy 166.464742 -357.986815)
			(xy 166.429019 -358.028039) (xy 166.387792 -358.063759) (xy 166.341901 -358.093248) (xy 166.292281 -358.115906)
			(xy 166.239941 -358.131271) (xy 166.185946 -358.13903) (xy 166.158672 -358.139492) (xy 165.295072 -358.139492)
			(xy 165.267806 -358.138944) (xy 165.21383 -358.131179) (xy 165.161508 -358.115813) (xy 165.111905 -358.093157)
			(xy 165.066031 -358.063673) (xy 165.02482 -358.02796) (xy 164.989111 -357.986746) (xy 164.95963 -357.94087)
			(xy 164.936977 -357.891266) (xy 164.921615 -357.838943) (xy 164.913854 -357.784966) (xy 163.431006 -357.784966)
			(xy 163.431006 -357.784971) (xy 163.423244 -357.838958) (xy 163.407878 -357.89129) (xy 163.385221 -357.940904)
			(xy 163.355733 -357.986788) (xy 163.320017 -358.028008) (xy 163.278797 -358.063726) (xy 163.232914 -358.093215)
			(xy 163.183302 -358.115873) (xy 163.130969 -358.131241) (xy 163.076983 -358.139005) (xy 163.049712 -358.139492)
			(xy 162.186112 -358.139492) (xy 162.158843 -358.138969) (xy 162.104859 -358.131209) (xy 162.052529 -358.115845)
			(xy 162.002918 -358.09319) (xy 161.957036 -358.063705) (xy 161.915818 -358.027991) (xy 161.880102 -357.986773)
			(xy 161.850616 -357.940893) (xy 161.827959 -357.891283) (xy 161.812593 -357.838953) (xy 161.804831 -357.784969)
			(xy 160.322128 -357.784969) (xy 160.322128 -357.784975) (xy 160.314364 -357.838971) (xy 160.298994 -357.891311)
			(xy 160.276332 -357.940932) (xy 160.246837 -357.986821) (xy 160.211112 -358.028046) (xy 160.169883 -358.063766)
			(xy 160.123989 -358.093255) (xy 160.074366 -358.115911) (xy 160.022024 -358.131275) (xy 159.968027 -358.139032)
			(xy 159.940752 -358.139492) (xy 159.077152 -358.139492) (xy 159.049887 -358.138942) (xy 158.995913 -358.131176)
			(xy 158.943593 -358.115807) (xy 158.893993 -358.09315) (xy 158.848122 -358.063665) (xy 158.806913 -358.027953)
			(xy 158.771206 -357.98674) (xy 158.741727 -357.940865) (xy 158.719076 -357.891262) (xy 158.703714 -357.83894)
			(xy 158.695954 -357.784965) (xy 144.196606 -357.784965) (xy 144.196606 -357.784971) (xy 144.188843 -357.838958)
			(xy 144.173477 -357.891291) (xy 144.15082 -357.940905) (xy 144.121332 -357.986789) (xy 144.085615 -358.02801)
			(xy 144.044395 -358.063728) (xy 143.998512 -358.093216) (xy 143.948899 -358.115875) (xy 143.896566 -358.131242)
			(xy 143.842579 -358.139005) (xy 143.815308 -358.139492) (xy 142.951708 -358.139492) (xy 142.924439 -358.138969)
			(xy 142.870455 -358.131209) (xy 142.818126 -358.115844) (xy 142.768515 -358.093189) (xy 142.722634 -358.063704)
			(xy 142.681417 -358.027989) (xy 142.645701 -357.986772) (xy 142.616215 -357.940892) (xy 142.593559 -357.891282)
			(xy 142.578193 -357.838953) (xy 142.570431 -357.784969) (xy 141.087606 -357.784969) (xy 141.079845 -357.838953)
			(xy 141.06448 -357.891283) (xy 141.041826 -357.940894) (xy 141.012342 -357.986776) (xy 140.976629 -358.027995)
			(xy 140.935414 -358.063713) (xy 140.889536 -358.093203) (xy 140.839928 -358.115864) (xy 140.7876 -358.131234)
			(xy 140.733617 -358.139002) (xy 140.706348 -358.139492) (xy 139.842748 -358.139492) (xy 139.815477 -358.138972)
			(xy 139.761489 -358.131216) (xy 139.709155 -358.115855) (xy 139.659539 -358.093202) (xy 139.613653 -358.063718)
			(xy 139.572431 -358.028003) (xy 139.536711 -357.986785) (xy 139.507221 -357.940903) (xy 139.484562 -357.89129)
			(xy 139.469194 -357.838958) (xy 139.461432 -357.784971) (xy 137.978728 -357.784971) (xy 137.978728 -357.784974)
			(xy 137.970965 -357.838966) (xy 137.955597 -357.891304) (xy 137.932937 -357.940921) (xy 137.903446 -357.986809)
			(xy 137.867724 -358.028033) (xy 137.8265 -358.063753) (xy 137.780611 -358.093243) (xy 137.730992 -358.115901)
			(xy 137.678654 -358.131268) (xy 137.624662 -358.139029) (xy 137.597388 -358.139492) (xy 136.733788 -358.139492)
			(xy 136.706521 -358.138945) (xy 136.652543 -358.131182) (xy 136.600219 -358.115817) (xy 136.550615 -358.093162)
			(xy 136.504739 -358.063678) (xy 136.463526 -358.027966) (xy 136.427815 -357.986752) (xy 136.398332 -357.940875)
			(xy 136.375679 -357.891269) (xy 136.360315 -357.838945) (xy 136.352554 -357.784967) (xy 134.869706 -357.784967)
			(xy 134.869706 -357.78497) (xy 134.861944 -357.838956) (xy 134.846579 -357.891287) (xy 134.823923 -357.940899)
			(xy 134.794437 -357.986782) (xy 134.758722 -358.028003) (xy 134.717505 -358.063721) (xy 134.671624 -358.09321)
			(xy 134.622013 -358.115869) (xy 134.569683 -358.131238) (xy 134.515698 -358.139004) (xy 134.488428 -358.139492)
			(xy 133.624828 -358.139492) (xy 133.597558 -358.13897) (xy 133.543572 -358.131212) (xy 133.49124 -358.11585)
			(xy 133.441627 -358.093195) (xy 133.395744 -358.063711) (xy 133.354524 -358.027996) (xy 133.318806 -357.986779)
			(xy 133.289318 -357.940897) (xy 133.26666 -357.891286) (xy 133.251294 -357.838955) (xy 133.243531 -357.78497)
			(xy 131.760828 -357.78497) (xy 131.760828 -357.784975) (xy 131.753065 -357.838969) (xy 131.737696 -357.891308)
			(xy 131.715034 -357.940927) (xy 131.685541 -357.986816) (xy 131.649817 -358.02804) (xy 131.60859 -358.06376)
			(xy 131.562699 -358.093249) (xy 131.513078 -358.115907) (xy 131.460737 -358.131272) (xy 131.406743 -358.139031)
			(xy 131.379468 -358.139492) (xy 130.515868 -358.139492) (xy 130.488602 -358.138943) (xy 130.434626 -358.131179)
			(xy 130.382305 -358.115812) (xy 130.332703 -358.093156) (xy 130.286829 -358.063671) (xy 130.245619 -358.027959)
			(xy 130.20991 -357.986745) (xy 130.180429 -357.940869) (xy 130.157777 -357.891265) (xy 130.142414 -357.838942)
			(xy 130.134654 -357.784966) (xy 128.651806 -357.784966) (xy 128.651806 -357.784971) (xy 128.644043 -357.838958)
			(xy 128.628677 -357.891291) (xy 128.60602 -357.940905) (xy 128.576532 -357.986789) (xy 128.540815 -358.02801)
			(xy 128.499595 -358.063728) (xy 128.453712 -358.093216) (xy 128.404099 -358.115875) (xy 128.351766 -358.131242)
			(xy 128.297779 -358.139005) (xy 128.270508 -358.139492) (xy 127.406908 -358.139492) (xy 127.379639 -358.138969)
			(xy 127.325655 -358.131209) (xy 127.273326 -358.115844) (xy 127.223715 -358.093189) (xy 127.177834 -358.063704)
			(xy 127.136617 -358.027989) (xy 127.100901 -357.986772) (xy 127.071415 -357.940892) (xy 127.048759 -357.891282)
			(xy 127.033393 -357.838953) (xy 127.025631 -357.784969) (xy 125.542806 -357.784969) (xy 125.535045 -357.838953)
			(xy 125.51968 -357.891283) (xy 125.497026 -357.940894) (xy 125.467542 -357.986776) (xy 125.431829 -358.027995)
			(xy 125.390614 -358.063713) (xy 125.344736 -358.093203) (xy 125.295128 -358.115864) (xy 125.2428 -358.131234)
			(xy 125.188817 -358.139002) (xy 125.161548 -358.139492) (xy 124.297948 -358.139492) (xy 124.270677 -358.138972)
			(xy 124.216689 -358.131216) (xy 124.164355 -358.115855) (xy 124.114739 -358.093202) (xy 124.068853 -358.063718)
			(xy 124.027631 -358.028003) (xy 123.991911 -357.986785) (xy 123.962421 -357.940903) (xy 123.939762 -357.89129)
			(xy 123.924394 -357.838958) (xy 123.916632 -357.784971) (xy 122.433928 -357.784971) (xy 122.433928 -357.784974)
			(xy 122.426165 -357.838966) (xy 122.410797 -357.891304) (xy 122.388137 -357.940921) (xy 122.358646 -357.986809)
			(xy 122.322924 -358.028033) (xy 122.2817 -358.063753) (xy 122.235811 -358.093243) (xy 122.186192 -358.115901)
			(xy 122.133854 -358.131268) (xy 122.079862 -358.139029) (xy 122.052588 -358.139492) (xy 121.188988 -358.139492)
			(xy 121.161721 -358.138945) (xy 121.107743 -358.131182) (xy 121.055419 -358.115817) (xy 121.005815 -358.093162)
			(xy 120.959939 -358.063678) (xy 120.918726 -358.027966) (xy 120.883015 -357.986752) (xy 120.853532 -357.940875)
			(xy 120.830879 -357.891269) (xy 120.815515 -357.838945) (xy 120.807754 -357.784967) (xy 119.324906 -357.784967)
			(xy 119.324906 -357.78497) (xy 119.317144 -357.838956) (xy 119.301779 -357.891287) (xy 119.279123 -357.940899)
			(xy 119.249637 -357.986782) (xy 119.213922 -358.028003) (xy 119.172705 -358.063721) (xy 119.126824 -358.09321)
			(xy 119.077213 -358.115869) (xy 119.024883 -358.131238) (xy 118.970898 -358.139004) (xy 118.943628 -358.139492)
			(xy 118.080028 -358.139492) (xy 118.052758 -358.13897) (xy 117.998772 -358.131212) (xy 117.94644 -358.11585)
			(xy 117.896827 -358.093195) (xy 117.850944 -358.063711) (xy 117.809724 -358.027996) (xy 117.774006 -357.986779)
			(xy 117.744518 -357.940897) (xy 117.72186 -357.891286) (xy 117.706494 -357.838955) (xy 117.698731 -357.78497)
			(xy 116.216028 -357.78497) (xy 116.216028 -357.784975) (xy 116.208265 -357.838969) (xy 116.192896 -357.891308)
			(xy 116.170234 -357.940927) (xy 116.140741 -357.986816) (xy 116.105017 -358.02804) (xy 116.06379 -358.06376)
			(xy 116.017899 -358.093249) (xy 115.968278 -358.115907) (xy 115.915937 -358.131272) (xy 115.861943 -358.139031)
			(xy 115.834668 -358.139492) (xy 114.971068 -358.139492) (xy 114.943802 -358.138943) (xy 114.889826 -358.131179)
			(xy 114.837505 -358.115812) (xy 114.787903 -358.093156) (xy 114.742029 -358.063671) (xy 114.700819 -358.027959)
			(xy 114.66511 -357.986745) (xy 114.635629 -357.940869) (xy 114.612977 -357.891265) (xy 114.597614 -357.838942)
			(xy 114.589854 -357.784966) (xy 93.706706 -357.784966) (xy 93.706706 -357.78497) (xy 93.698944 -357.838954)
			(xy 93.68358 -357.891284) (xy 93.660925 -357.940895) (xy 93.631441 -357.986778) (xy 93.595727 -358.027998)
			(xy 93.554511 -358.063716) (xy 93.508632 -358.093205) (xy 93.459023 -358.115865) (xy 93.406695 -358.131235)
			(xy 93.352712 -358.139003) (xy 93.325442 -358.139492) (xy 92.461842 -358.139492) (xy 92.434571 -358.138971)
			(xy 92.380584 -358.131215) (xy 92.32825 -358.115853) (xy 92.278636 -358.0932) (xy 92.23275 -358.063716)
			(xy 92.191529 -358.028001) (xy 92.155809 -357.986783) (xy 92.12632 -357.940901) (xy 92.103661 -357.891289)
			(xy 92.088294 -357.838957) (xy 92.080532 -357.784971) (xy 90.597828 -357.784971) (xy 90.597828 -357.784974)
			(xy 90.590065 -357.838967) (xy 90.574697 -357.891305) (xy 90.552036 -357.940923) (xy 90.522544 -357.986811)
			(xy 90.486822 -358.028035) (xy 90.445597 -358.063755) (xy 90.399707 -358.093245) (xy 90.350088 -358.115903)
			(xy 90.297749 -358.131269) (xy 90.243756 -358.13903) (xy 90.216482 -358.139492) (xy 89.352882 -358.139492)
			(xy 89.325616 -358.138944) (xy 89.271638 -358.131181) (xy 89.219315 -358.115816) (xy 89.169711 -358.09316)
			(xy 89.123836 -358.063676) (xy 89.082624 -358.027964) (xy 89.046913 -357.98675) (xy 89.017431 -357.940873)
			(xy 88.994778 -357.891268) (xy 88.979415 -357.838944) (xy 88.971654 -357.784966) (xy 87.488806 -357.784966)
			(xy 87.488806 -357.784971) (xy 87.481044 -357.838956) (xy 87.465678 -357.891288) (xy 87.443022 -357.940901)
			(xy 87.413536 -357.986784) (xy 87.37782 -358.028005) (xy 87.336602 -358.063723) (xy 87.29072 -358.093211)
			(xy 87.241109 -358.115871) (xy 87.188778 -358.131239) (xy 87.134792 -358.139004) (xy 87.107522 -358.139492)
			(xy 86.243922 -358.139492) (xy 86.216652 -358.13897) (xy 86.162667 -358.131211) (xy 86.110336 -358.115848)
			(xy 86.060724 -358.093193) (xy 86.014841 -358.063709) (xy 85.973622 -358.027994) (xy 85.937905 -357.986777)
			(xy 85.908417 -357.940895) (xy 85.88576 -357.891285) (xy 85.870394 -357.838954) (xy 85.862631 -357.78497)
			(xy 84.379928 -357.78497) (xy 84.379928 -357.784975) (xy 84.372165 -357.838969) (xy 84.356795 -357.891309)
			(xy 84.334133 -357.940929) (xy 84.30464 -357.986818) (xy 84.268915 -358.028042) (xy 84.227687 -358.063762)
			(xy 84.181795 -358.093251) (xy 84.132173 -358.115908) (xy 84.079832 -358.131273) (xy 84.025837 -358.139031)
			(xy 83.998562 -358.139492) (xy 83.134962 -358.139492) (xy 83.107697 -358.138943) (xy 83.053721 -358.131178)
			(xy 83.0014 -358.11581) (xy 82.951799 -358.093154) (xy 82.905926 -358.063669) (xy 82.864717 -358.027957)
			(xy 82.829008 -357.986743) (xy 82.799528 -357.940868) (xy 82.776877 -357.891264) (xy 82.761514 -357.838942)
			(xy 82.753754 -357.784966) (xy 81.270906 -357.784966) (xy 81.270906 -357.784971) (xy 81.263143 -357.838959)
			(xy 81.247777 -357.891293) (xy 81.225119 -357.940907) (xy 81.195631 -357.986791) (xy 81.159913 -358.028012)
			(xy 81.118693 -358.06373) (xy 81.072808 -358.093218) (xy 81.023194 -358.115876) (xy 80.970861 -358.131243)
			(xy 80.916873 -358.139005) (xy 80.889602 -358.139492) (xy 80.026002 -358.139492) (xy 79.998733 -358.138969)
			(xy 79.94475 -358.131207) (xy 79.892421 -358.115843) (xy 79.842812 -358.093187) (xy 79.796932 -358.063702)
			(xy 79.755714 -358.027987) (xy 79.72 -357.98677) (xy 79.690514 -357.94089) (xy 79.667858 -357.89128)
			(xy 79.652493 -357.838952) (xy 79.644731 -357.784969) (xy 78.161906 -357.784969) (xy 78.161906 -357.78497)
			(xy 78.154144 -357.838954) (xy 78.13878 -357.891284) (xy 78.116125 -357.940895) (xy 78.086641 -357.986778)
			(xy 78.050927 -358.027998) (xy 78.009711 -358.063716) (xy 77.963832 -358.093205) (xy 77.914223 -358.115865)
			(xy 77.861895 -358.131235) (xy 77.807912 -358.139003) (xy 77.780642 -358.139492) (xy 76.917042 -358.139492)
			(xy 76.889771 -358.138971) (xy 76.835784 -358.131215) (xy 76.78345 -358.115853) (xy 76.733836 -358.0932)
			(xy 76.68795 -358.063716) (xy 76.646729 -358.028001) (xy 76.611009 -357.986783) (xy 76.58152 -357.940901)
			(xy 76.558861 -357.891289) (xy 76.543494 -357.838957) (xy 76.535732 -357.784971) (xy 75.053028 -357.784971)
			(xy 75.053028 -357.784974) (xy 75.045265 -357.838967) (xy 75.029897 -357.891305) (xy 75.007236 -357.940923)
			(xy 74.977744 -357.986811) (xy 74.942022 -358.028035) (xy 74.900797 -358.063755) (xy 74.854907 -358.093245)
			(xy 74.805288 -358.115903) (xy 74.752949 -358.131269) (xy 74.698956 -358.13903) (xy 74.671682 -358.139492)
			(xy 73.808082 -358.139492) (xy 73.780816 -358.138944) (xy 73.726838 -358.131181) (xy 73.674515 -358.115816)
			(xy 73.624911 -358.09316) (xy 73.579036 -358.063676) (xy 73.537824 -358.027964) (xy 73.502113 -357.98675)
			(xy 73.472631 -357.940873) (xy 73.449978 -357.891268) (xy 73.434615 -357.838944) (xy 73.426854 -357.784966)
			(xy 71.944006 -357.784966) (xy 71.944006 -357.784971) (xy 71.936244 -357.838956) (xy 71.920878 -357.891288)
			(xy 71.898222 -357.940901) (xy 71.868736 -357.986784) (xy 71.83302 -358.028005) (xy 71.791802 -358.063723)
			(xy 71.74592 -358.093211) (xy 71.696309 -358.115871) (xy 71.643978 -358.131239) (xy 71.589992 -358.139004)
			(xy 71.562722 -358.139492) (xy 70.699122 -358.139492) (xy 70.671852 -358.13897) (xy 70.617867 -358.131211)
			(xy 70.565536 -358.115848) (xy 70.515924 -358.093193) (xy 70.470041 -358.063709) (xy 70.428822 -358.027994)
			(xy 70.393105 -357.986777) (xy 70.363617 -357.940895) (xy 70.34096 -357.891285) (xy 70.325594 -357.838954)
			(xy 70.317831 -357.78497) (xy 68.835128 -357.78497) (xy 68.835128 -357.784975) (xy 68.827365 -357.838969)
			(xy 68.811995 -357.891309) (xy 68.789333 -357.940929) (xy 68.75984 -357.986818) (xy 68.724115 -358.028042)
			(xy 68.682887 -358.063762) (xy 68.636995 -358.093251) (xy 68.587373 -358.115908) (xy 68.535032 -358.131273)
			(xy 68.481037 -358.139031) (xy 68.453762 -358.139492) (xy 67.590162 -358.139492) (xy 67.562897 -358.138943)
			(xy 67.508921 -358.131178) (xy 67.4566 -358.11581) (xy 67.406999 -358.093154) (xy 67.361126 -358.063669)
			(xy 67.319917 -358.027957) (xy 67.284208 -357.986743) (xy 67.254728 -357.940868) (xy 67.232077 -357.891264)
			(xy 67.216714 -357.838942) (xy 67.208954 -357.784966) (xy 65.726106 -357.784966) (xy 65.726106 -357.784971)
			(xy 65.718343 -357.838959) (xy 65.702977 -357.891293) (xy 65.680319 -357.940907) (xy 65.650831 -357.986791)
			(xy 65.615113 -358.028012) (xy 65.573893 -358.06373) (xy 65.528008 -358.093218) (xy 65.478394 -358.115876)
			(xy 65.426061 -358.131243) (xy 65.372073 -358.139005) (xy 65.344802 -358.139492) (xy 64.481202 -358.139492)
			(xy 64.453933 -358.138969) (xy 64.39995 -358.131207) (xy 64.347621 -358.115843) (xy 64.298012 -358.093187)
			(xy 64.252132 -358.063702) (xy 64.210914 -358.027987) (xy 64.1752 -357.98677) (xy 64.145714 -357.94089)
			(xy 64.123058 -357.89128) (xy 64.107693 -357.838952) (xy 64.099931 -357.784969) (xy 51.666906 -357.784969)
			(xy 51.659145 -357.838953) (xy 51.64378 -357.891283) (xy 51.621126 -357.940894) (xy 51.591642 -357.986776)
			(xy 51.555929 -358.027995) (xy 51.514714 -358.063713) (xy 51.468836 -358.093203) (xy 51.419228 -358.115864)
			(xy 51.3669 -358.131234) (xy 51.312917 -358.139002) (xy 51.285648 -358.139492) (xy 50.422048 -358.139492)
			(xy 50.394777 -358.138972) (xy 50.340789 -358.131216) (xy 50.288455 -358.115855) (xy 50.238839 -358.093202)
			(xy 50.192953 -358.063718) (xy 50.151731 -358.028003) (xy 50.116011 -357.986785) (xy 50.086521 -357.940903)
			(xy 50.063862 -357.89129) (xy 50.048494 -357.838958) (xy 50.040732 -357.784971) (xy 48.558028 -357.784971)
			(xy 48.558028 -357.784974) (xy 48.550265 -357.838966) (xy 48.534897 -357.891304) (xy 48.512237 -357.940921)
			(xy 48.482746 -357.986809) (xy 48.447024 -358.028033) (xy 48.4058 -358.063753) (xy 48.359911 -358.093243)
			(xy 48.310292 -358.115901) (xy 48.257954 -358.131268) (xy 48.203962 -358.139029) (xy 48.176688 -358.139492)
			(xy 47.313088 -358.139492) (xy 47.285821 -358.138945) (xy 47.231843 -358.131182) (xy 47.179519 -358.115817)
			(xy 47.129915 -358.093162) (xy 47.084039 -358.063678) (xy 47.042826 -358.027966) (xy 47.007115 -357.986752)
			(xy 46.977632 -357.940875) (xy 46.954979 -357.891269) (xy 46.939615 -357.838945) (xy 46.931854 -357.784967)
			(xy 45.449006 -357.784967) (xy 45.449006 -357.78497) (xy 45.441244 -357.838956) (xy 45.425879 -357.891287)
			(xy 45.403223 -357.940899) (xy 45.373737 -357.986782) (xy 45.338022 -358.028003) (xy 45.296805 -358.063721)
			(xy 45.250924 -358.09321) (xy 45.201313 -358.115869) (xy 45.148983 -358.131238) (xy 45.094998 -358.139004)
			(xy 45.067728 -358.139492) (xy 44.204128 -358.139492) (xy 44.176858 -358.13897) (xy 44.122872 -358.131212)
			(xy 44.07054 -358.11585) (xy 44.020927 -358.093195) (xy 43.975044 -358.063711) (xy 43.933824 -358.027996)
			(xy 43.898106 -357.986779) (xy 43.868618 -357.940897) (xy 43.84596 -357.891286) (xy 43.830594 -357.838955)
			(xy 43.822831 -357.78497) (xy 42.340128 -357.78497) (xy 42.340128 -357.784975) (xy 42.332365 -357.838969)
			(xy 42.316996 -357.891308) (xy 42.294334 -357.940927) (xy 42.264841 -357.986816) (xy 42.229117 -358.02804)
			(xy 42.18789 -358.06376) (xy 42.141999 -358.093249) (xy 42.092378 -358.115907) (xy 42.040037 -358.131272)
			(xy 41.986043 -358.139031) (xy 41.958768 -358.139492) (xy 41.095168 -358.139492) (xy 41.067902 -358.138943)
			(xy 41.013926 -358.131179) (xy 40.961605 -358.115812) (xy 40.912003 -358.093156) (xy 40.866129 -358.063671)
			(xy 40.824919 -358.027959) (xy 40.78921 -357.986745) (xy 40.759729 -357.940869) (xy 40.737077 -357.891265)
			(xy 40.721714 -357.838942) (xy 40.713954 -357.784966) (xy 39.231106 -357.784966) (xy 39.231106 -357.784971)
			(xy 39.223343 -357.838958) (xy 39.207977 -357.891291) (xy 39.18532 -357.940905) (xy 39.155832 -357.986789)
			(xy 39.120115 -358.02801) (xy 39.078895 -358.063728) (xy 39.033012 -358.093216) (xy 38.983399 -358.115875)
			(xy 38.931066 -358.131242) (xy 38.877079 -358.139005) (xy 38.849808 -358.139492) (xy 37.986208 -358.139492)
			(xy 37.958939 -358.138969) (xy 37.904955 -358.131209) (xy 37.852626 -358.115844) (xy 37.803015 -358.093189)
			(xy 37.757134 -358.063704) (xy 37.715917 -358.027989) (xy 37.680201 -357.986772) (xy 37.650715 -357.940892)
			(xy 37.628059 -357.891282) (xy 37.612693 -357.838953) (xy 37.604931 -357.784969) (xy 36.122106 -357.784969)
			(xy 36.114345 -357.838953) (xy 36.09898 -357.891283) (xy 36.076326 -357.940894) (xy 36.046842 -357.986776)
			(xy 36.011129 -358.027995) (xy 35.969914 -358.063713) (xy 35.924036 -358.093203) (xy 35.874428 -358.115864)
			(xy 35.8221 -358.131234) (xy 35.768117 -358.139002) (xy 35.740848 -358.139492) (xy 34.877248 -358.139492)
			(xy 34.849977 -358.138972) (xy 34.795989 -358.131216) (xy 34.743655 -358.115855) (xy 34.694039 -358.093202)
			(xy 34.648153 -358.063718) (xy 34.606931 -358.028003) (xy 34.571211 -357.986785) (xy 34.541721 -357.940903)
			(xy 34.519062 -357.89129) (xy 34.503694 -357.838958) (xy 34.495932 -357.784971) (xy 33.013228 -357.784971)
			(xy 33.013228 -357.784974) (xy 33.005465 -357.838966) (xy 32.990097 -357.891304) (xy 32.967437 -357.940921)
			(xy 32.937946 -357.986809) (xy 32.902224 -358.028033) (xy 32.861 -358.063753) (xy 32.815111 -358.093243)
			(xy 32.765492 -358.115901) (xy 32.713154 -358.131268) (xy 32.659162 -358.139029) (xy 32.631888 -358.139492)
			(xy 31.768288 -358.139492) (xy 31.741021 -358.138945) (xy 31.687043 -358.131182) (xy 31.634719 -358.115817)
			(xy 31.585115 -358.093162) (xy 31.539239 -358.063678) (xy 31.498026 -358.027966) (xy 31.462315 -357.986752)
			(xy 31.432832 -357.940875) (xy 31.410179 -357.891269) (xy 31.394815 -357.838945) (xy 31.387054 -357.784967)
			(xy 29.904206 -357.784967) (xy 29.904206 -357.78497) (xy 29.896444 -357.838956) (xy 29.881079 -357.891287)
			(xy 29.858423 -357.940899) (xy 29.828937 -357.986782) (xy 29.793222 -358.028003) (xy 29.752005 -358.063721)
			(xy 29.706124 -358.09321) (xy 29.656513 -358.115869) (xy 29.604183 -358.131238) (xy 29.550198 -358.139004)
			(xy 29.522928 -358.139492) (xy 28.659328 -358.139492) (xy 28.632058 -358.13897) (xy 28.578072 -358.131212)
			(xy 28.52574 -358.11585) (xy 28.476127 -358.093195) (xy 28.430244 -358.063711) (xy 28.389024 -358.027996)
			(xy 28.353306 -357.986779) (xy 28.323818 -357.940897) (xy 28.30116 -357.891286) (xy 28.285794 -357.838955)
			(xy 28.278031 -357.78497) (xy 26.795328 -357.78497) (xy 26.795328 -357.784975) (xy 26.787565 -357.838969)
			(xy 26.772196 -357.891308) (xy 26.749534 -357.940927) (xy 26.720041 -357.986816) (xy 26.684317 -358.02804)
			(xy 26.64309 -358.06376) (xy 26.597199 -358.093249) (xy 26.547578 -358.115907) (xy 26.495237 -358.131272)
			(xy 26.441243 -358.139031) (xy 26.413968 -358.139492) (xy 25.550368 -358.139492) (xy 25.523102 -358.138943)
			(xy 25.469126 -358.131179) (xy 25.416805 -358.115812) (xy 25.367203 -358.093156) (xy 25.321329 -358.063671)
			(xy 25.280119 -358.027959) (xy 25.24441 -357.986745) (xy 25.214929 -357.940869) (xy 25.192277 -357.891265)
			(xy 25.176914 -357.838942) (xy 25.169154 -357.784966) (xy 23.686306 -357.784966) (xy 23.686306 -357.784971)
			(xy 23.678543 -357.838958) (xy 23.663177 -357.891291) (xy 23.64052 -357.940905) (xy 23.611032 -357.986789)
			(xy 23.575315 -358.02801) (xy 23.534095 -358.063728) (xy 23.488212 -358.093216) (xy 23.438599 -358.115875)
			(xy 23.386266 -358.131242) (xy 23.332279 -358.139005) (xy 23.305008 -358.139492) (xy 22.441408 -358.139492)
			(xy 22.414139 -358.138969) (xy 22.360155 -358.131209) (xy 22.307826 -358.115844) (xy 22.258215 -358.093189)
			(xy 22.212334 -358.063704) (xy 22.171117 -358.027989) (xy 22.135401 -357.986772) (xy 22.105915 -357.940892)
			(xy 22.083259 -357.891282) (xy 22.067893 -357.838953) (xy 22.060131 -357.784969) (xy 0.508 -357.784969)
			(xy 0.508 -360.017783) (xy 101.774757 -360.017783) (xy 101.774757 -359.957817) (xy 101.782584 -359.898365)
			(xy 101.798104 -359.840443) (xy 101.821052 -359.785042) (xy 101.851035 -359.733111) (xy 101.88754 -359.685538)
			(xy 101.929942 -359.643136) (xy 101.977516 -359.606632) (xy 102.029448 -359.57665) (xy 102.084849 -359.553703)
			(xy 102.142771 -359.538183) (xy 102.202223 -359.530357) (xy 102.232206 -359.529888) (xy 103.095806 -359.529888)
			(xy 103.125793 -359.530279) (xy 103.185255 -359.538108) (xy 103.243186 -359.553631) (xy 103.298595 -359.576583)
			(xy 103.350534 -359.60657) (xy 103.398115 -359.643081) (xy 103.440523 -359.68549) (xy 103.477033 -359.733071)
			(xy 103.50702 -359.785011) (xy 103.529971 -359.84042) (xy 103.545494 -359.898351) (xy 103.553322 -359.957813)
			(xy 103.553322 -360.017787) (xy 103.545494 -360.077249) (xy 103.529971 -360.13518) (xy 103.50702 -360.190589)
			(xy 103.477033 -360.242529) (xy 103.440523 -360.29011) (xy 103.398115 -360.332519) (xy 103.350534 -360.36903)
			(xy 103.298595 -360.399017) (xy 103.243186 -360.421969) (xy 103.185255 -360.437492) (xy 103.125793 -360.445321)
			(xy 103.095806 -360.445812) (xy 102.232206 -360.445812) (xy 102.202223 -360.445243) (xy 102.142771 -360.437417)
			(xy 102.084849 -360.421897) (xy 102.029448 -360.39895) (xy 101.977516 -360.368968) (xy 101.929942 -360.332464)
			(xy 101.88754 -360.290062) (xy 101.851035 -360.242489) (xy 101.821052 -360.190558) (xy 101.798104 -360.135157)
			(xy 101.782584 -360.077235) (xy 101.774757 -360.017783) (xy 0.508 -360.017783) (xy 0.508 -363.334808)
			(xy 54.890416 -363.334808) (xy 54.890416 -362.471208) (xy 54.890906 -362.441224) (xy 54.898734 -362.381768)
			(xy 54.914255 -362.323843) (xy 54.937204 -362.268439) (xy 54.967188 -362.216505) (xy 55.003694 -362.168929)
			(xy 55.046099 -362.126524) (xy 55.093675 -362.090018) (xy 55.145609 -362.060034) (xy 55.201013 -362.037085)
			(xy 55.258938 -362.021564) (xy 55.318394 -362.013736) (xy 55.378362 -362.013736) (xy 55.437818 -362.021564)
			(xy 55.495743 -362.037085) (xy 55.551147 -362.060034) (xy 55.603081 -362.090018) (xy 55.650657 -362.126524)
			(xy 55.693062 -362.168929) (xy 55.729568 -362.216505) (xy 55.759552 -362.268439) (xy 55.782501 -362.323843)
			(xy 55.798022 -362.381768) (xy 55.80585 -362.441224) (xy 55.80634 -362.471208) (xy 55.80634 -363.334808)
			(xy 55.80585 -363.364792) (xy 55.798022 -363.424248) (xy 55.782501 -363.482173) (xy 55.759552 -363.537577)
			(xy 55.729568 -363.589511) (xy 55.693062 -363.637087) (xy 55.650657 -363.679492) (xy 55.603081 -363.715998)
			(xy 55.551147 -363.745982) (xy 55.495743 -363.768931) (xy 55.437818 -363.784452) (xy 55.378362 -363.79228)
			(xy 55.318394 -363.79228) (xy 55.258938 -363.784452) (xy 55.201013 -363.768931) (xy 55.145609 -363.745982)
			(xy 55.093675 -363.715998) (xy 55.046099 -363.679492) (xy 55.003694 -363.637087) (xy 54.967188 -363.589511)
			(xy 54.937204 -363.537577) (xy 54.914255 -363.482173) (xy 54.898734 -363.424248) (xy 54.890906 -363.364792)
			(xy 54.890416 -363.334808) (xy 0.508 -363.334808) (xy 0.508 -365.797384) (xy 54.438294 -365.797384)
			(xy 54.438294 -365.737416) (xy 54.446121 -365.67796) (xy 54.461641 -365.620034) (xy 54.484589 -365.564629)
			(xy 54.514571 -365.512694) (xy 54.551076 -365.465115) (xy 54.593478 -365.422709) (xy 54.641052 -365.386199)
			(xy 54.692984 -365.356211) (xy 54.748387 -365.333257) (xy 54.806311 -365.317731) (xy 54.865766 -365.309897)
			(xy 54.89575 -365.309404) (xy 55.75935 -365.309404) (xy 55.789336 -365.309938) (xy 55.848794 -365.31776)
			(xy 55.906723 -365.333276) (xy 55.962131 -365.356222) (xy 56.01407 -365.386203) (xy 56.06165 -365.422708)
			(xy 56.104059 -365.465112) (xy 56.140569 -365.512689) (xy 56.170556 -365.564624) (xy 56.193508 -365.620029)
			(xy 56.20903 -365.677957) (xy 56.216859 -365.737414) (xy 56.216859 -365.797386) (xy 56.20903 -365.856843)
			(xy 56.193508 -365.914771) (xy 56.170556 -365.970176) (xy 56.140569 -366.022112) (xy 56.104059 -366.069688)
			(xy 56.06165 -366.112092) (xy 56.01407 -366.148597) (xy 55.962131 -366.178578) (xy 55.906723 -366.201524)
			(xy 55.848794 -366.21704) (xy 55.789336 -366.224862) (xy 55.75935 -366.225328) (xy 54.89575 -366.225328)
			(xy 54.865766 -366.224903) (xy 54.806311 -366.217069) (xy 54.748386 -366.201543) (xy 54.692984 -366.178589)
			(xy 54.641052 -366.148601) (xy 54.593478 -366.112091) (xy 54.551076 -366.069685) (xy 54.514571 -366.022106)
			(xy 54.484589 -365.970171) (xy 54.461641 -365.914766) (xy 54.446121 -365.85684) (xy 54.438294 -365.797384)
			(xy 0.508 -365.797384) (xy 0.508 -368.516662) (xy 53.966364 -368.516662) (xy 53.966364 -367.653062)
			(xy 53.96685 -367.625793) (xy 53.974612 -367.571809) (xy 53.989977 -367.519479) (xy 54.012634 -367.469869)
			(xy 54.04212 -367.423988) (xy 54.077835 -367.382771) (xy 54.119052 -367.347056) (xy 54.164933 -367.31757)
			(xy 54.214543 -367.294913) (xy 54.266873 -367.279548) (xy 54.320857 -367.271786) (xy 54.375395 -367.271786)
			(xy 54.429379 -367.279548) (xy 54.481709 -367.294913) (xy 54.531319 -367.31757) (xy 54.5772 -367.347056)
			(xy 54.618417 -367.382771) (xy 54.654132 -367.423988) (xy 54.683618 -367.469869) (xy 54.706275 -367.519479)
			(xy 54.72164 -367.571809) (xy 54.729402 -367.625793) (xy 54.729888 -367.653062) (xy 54.729888 -368.516662)
			(xy 57.339484 -368.516662) (xy 57.339484 -367.653062) (xy 57.33997 -367.625793) (xy 57.347732 -367.571809)
			(xy 57.363097 -367.519479) (xy 57.385754 -367.469869) (xy 57.41524 -367.423988) (xy 57.450955 -367.382771)
			(xy 57.492172 -367.347056) (xy 57.538053 -367.31757) (xy 57.587663 -367.294913) (xy 57.639993 -367.279548)
			(xy 57.693977 -367.271786) (xy 57.748515 -367.271786) (xy 57.802499 -367.279548) (xy 57.854829 -367.294913)
			(xy 57.904439 -367.31757) (xy 57.95032 -367.347056) (xy 57.991537 -367.382771) (xy 58.027252 -367.423988)
			(xy 58.056738 -367.469869) (xy 58.079395 -367.519479) (xy 58.09476 -367.571809) (xy 58.102522 -367.625793)
			(xy 58.103008 -367.653062) (xy 58.103008 -368.516662) (xy 58.102522 -368.543931) (xy 58.09476 -368.597915)
			(xy 58.079395 -368.650245) (xy 58.056738 -368.699855) (xy 58.027252 -368.745736) (xy 57.991537 -368.786953)
			(xy 57.95032 -368.822668) (xy 57.904439 -368.852154) (xy 57.854829 -368.874811) (xy 57.802499 -368.890176)
			(xy 57.748515 -368.897938) (xy 57.693977 -368.897938) (xy 57.639993 -368.890176) (xy 57.587663 -368.874811)
			(xy 57.538053 -368.852154) (xy 57.492172 -368.822668) (xy 57.450955 -368.786953) (xy 57.41524 -368.745736)
			(xy 57.385754 -368.699855) (xy 57.363097 -368.650245) (xy 57.347732 -368.597915) (xy 57.33997 -368.543931)
			(xy 57.339484 -368.516662) (xy 54.729888 -368.516662) (xy 54.729402 -368.543931) (xy 54.72164 -368.597915)
			(xy 54.706275 -368.650245) (xy 54.683618 -368.699855) (xy 54.654132 -368.745736) (xy 54.618417 -368.786953)
			(xy 54.5772 -368.822668) (xy 54.531319 -368.852154) (xy 54.481709 -368.874811) (xy 54.429379 -368.890176)
			(xy 54.375395 -368.897938) (xy 54.320857 -368.897938) (xy 54.266873 -368.890176) (xy 54.214543 -368.874811)
			(xy 54.164933 -368.852154) (xy 54.119052 -368.822668) (xy 54.077835 -368.786953) (xy 54.04212 -368.745736)
			(xy 54.012634 -368.699855) (xy 53.989977 -368.650245) (xy 53.974612 -368.597915) (xy 53.96685 -368.543931)
			(xy 53.966364 -368.516662) (xy 0.508 -368.516662) (xy 0.508 -370.523703) (xy 27.348898 -370.523703)
			(xy 27.348899 -370.456279) (xy 27.356975 -370.38934) (xy 27.373012 -370.323851) (xy 27.396776 -370.260753)
			(xy 27.427927 -370.200957) (xy 27.466016 -370.145322) (xy 27.48788 -370.119656) (xy 27.493675 -370.11251)
			(xy 27.500191 -370.09532) (xy 27.50058 -370.086128) (xy 27.50058 -369.928902) (xy 27.501029 -369.918771)
			(xy 27.508764 -369.900042) (xy 27.523062 -369.885684) (xy 27.541759 -369.877872) (xy 27.551888 -369.87734)
			(xy 28.268168 -369.87734) (xy 28.278293 -369.877743) (xy 28.297004 -369.885488) (xy 28.311321 -369.899809)
			(xy 28.31906 -369.918522) (xy 28.319476 -369.928648) (xy 28.319476 -370.086128) (xy 28.319878 -370.095316)
			(xy 28.326398 -370.1125) (xy 28.332176 -370.119656) (xy 28.354029 -370.145331) (xy 28.39212 -370.200963)
			(xy 28.423272 -370.260758) (xy 28.447038 -370.323854) (xy 28.463075 -370.389342) (xy 28.471152 -370.456279)
			(xy 28.471153 -370.523644) (xy 31.749193 -370.523644) (xy 31.749194 -370.456338) (xy 31.75724 -370.389514)
			(xy 31.773215 -370.324131) (xy 31.79689 -370.261126) (xy 31.827927 -370.201402) (xy 31.865879 -370.145816)
			(xy 31.887668 -370.120164) (xy 31.893471 -370.113023) (xy 31.89998 -370.095829) (xy 31.900368 -370.086636)
			(xy 31.900368 -369.928902) (xy 31.900766 -369.918727) (xy 31.908556 -369.899926) (xy 31.92295 -369.88554)
			(xy 31.941755 -369.877761) (xy 31.95193 -369.87734) (xy 32.66821 -369.87734) (xy 32.678369 -369.877825)
			(xy 32.697138 -369.885603) (xy 32.711503 -369.899972) (xy 32.719277 -369.918743) (xy 32.719772 -369.928902)
			(xy 32.719772 -370.086636) (xy 32.720171 -370.095824) (xy 32.726693 -370.113008) (xy 32.732472 -370.120164)
			(xy 32.754248 -370.145826) (xy 32.792196 -370.201411) (xy 32.823229 -370.261134) (xy 32.846902 -370.324137)
			(xy 32.862876 -370.389518) (xy 32.870921 -370.456339) (xy 32.870922 -370.523643) (xy 32.870915 -370.523703)
			(xy 36.148986 -370.523703) (xy 36.148987 -370.456279) (xy 36.157063 -370.389341) (xy 36.173099 -370.323851)
			(xy 36.196863 -370.260754) (xy 36.228013 -370.200957) (xy 36.266101 -370.145322) (xy 36.287964 -370.119656)
			(xy 36.29377 -370.112518) (xy 36.300277 -370.095322) (xy 36.300664 -370.086128) (xy 36.300664 -369.928902)
			(xy 36.301129 -369.918772) (xy 36.308861 -369.900047) (xy 36.323154 -369.88569) (xy 36.341845 -369.877875)
			(xy 36.351972 -369.87734) (xy 37.068252 -369.87734) (xy 37.078408 -369.877762) (xy 37.097167 -369.885549)
			(xy 37.111494 -369.899947) (xy 37.119188 -369.918744) (xy 37.11956 -369.928902) (xy 37.11956 -370.086128)
			(xy 37.119966 -370.095315) (xy 37.126483 -370.112499) (xy 37.13226 -370.119656) (xy 37.154114 -370.14533)
			(xy 37.192205 -370.200963) (xy 37.223359 -370.260757) (xy 37.247125 -370.323853) (xy 37.263163 -370.389341)
			(xy 37.27124 -370.456279) (xy 37.271241 -370.523703) (xy 37.271241 -370.523704) (xy 40.548752 -370.523704)
			(xy 40.548753 -370.456278) (xy 40.556831 -370.389338) (xy 40.572869 -370.323848) (xy 40.596637 -370.26075)
			(xy 40.627792 -370.200954) (xy 40.665885 -370.14532) (xy 40.687752 -370.119656) (xy 40.693556 -370.112516)
			(xy 40.700065 -370.095321) (xy 40.700452 -370.086128) (xy 40.700452 -369.928902) (xy 40.700929 -369.918774)
			(xy 40.708658 -369.900051) (xy 40.722947 -369.885694) (xy 40.741634 -369.877877) (xy 40.75176 -369.87734)
			(xy 41.46804 -369.87734) (xy 41.478202 -369.87769) (xy 41.496963 -369.885506) (xy 41.511286 -369.899925)
			(xy 41.518977 -369.918738) (xy 41.519348 -369.928902) (xy 41.519348 -370.086128) (xy 41.519756 -370.095315)
			(xy 41.526273 -370.112499) (xy 41.532048 -370.119656) (xy 41.553902 -370.14533) (xy 41.591994 -370.200962)
			(xy 41.623149 -370.260757) (xy 41.646916 -370.323852) (xy 41.662954 -370.389341) (xy 41.671031 -370.456279)
			(xy 41.671032 -370.523644) (xy 44.949071 -370.523644) (xy 44.949073 -370.456338) (xy 44.957118 -370.389515)
			(xy 44.973092 -370.324132) (xy 44.996766 -370.261127) (xy 45.027801 -370.201403) (xy 45.065751 -370.145816)
			(xy 45.08754 -370.120164) (xy 45.093339 -370.113021) (xy 45.099851 -370.095829) (xy 45.10024 -370.086636)
			(xy 45.10024 -369.928902) (xy 45.100665 -369.91873) (xy 45.10845 -369.899935) (xy 45.122835 -369.88555)
			(xy 45.14163 -369.877765) (xy 45.151802 -369.87734) (xy 45.868082 -369.87734) (xy 45.878253 -369.877778)
			(xy 45.897047 -369.885558) (xy 45.911433 -369.899939) (xy 45.919218 -369.918731) (xy 45.919644 -369.928902)
			(xy 45.919644 -370.086636) (xy 45.92005 -370.095823) (xy 45.926568 -370.113007) (xy 45.932344 -370.120164)
			(xy 45.95412 -370.145826) (xy 45.992071 -370.20141) (xy 46.023105 -370.261132) (xy 46.046779 -370.324136)
			(xy 46.062754 -370.389517) (xy 46.070799 -370.456339) (xy 46.0708 -370.523643) (xy 46.062757 -370.590465)
			(xy 46.046785 -370.655847) (xy 46.023113 -370.718851) (xy 45.99208 -370.778574) (xy 45.954131 -370.83416)
			(xy 45.932344 -370.859812) (xy 45.926553 -370.866961) (xy 45.920036 -370.884149) (xy 45.919644 -370.89334)
			(xy 45.919644 -371.386862) (xy 45.920085 -371.396046) (xy 45.926578 -371.41323) (xy 45.932344 -371.42039)
			(xy 45.954146 -371.44603) (xy 45.992096 -371.501618) (xy 46.023129 -371.561343) (xy 46.046568 -371.623726)
			(xy 47.14919 -371.623726) (xy 47.149193 -371.556417) (xy 47.157242 -371.489591) (xy 47.17322 -371.424206)
			(xy 47.1969 -371.3612) (xy 47.22794 -371.301475) (xy 47.265897 -371.24589) (xy 47.287688 -371.220238)
			(xy 47.293492 -371.213098) (xy 47.300003 -371.195904) (xy 47.300388 -371.18671) (xy 47.300388 -371.028722)
			(xy 47.300783 -371.018546) (xy 47.30857 -370.999742) (xy 47.322966 -370.985355) (xy 47.341773 -370.977578)
			(xy 47.35195 -370.97716) (xy 48.06823 -370.97716) (xy 48.078392 -370.977609) (xy 48.097167 -370.985398)
			(xy 48.111532 -370.999777) (xy 48.119301 -371.018559) (xy 48.119792 -371.028722) (xy 48.119792 -371.18671)
			(xy 48.120199 -371.195898) (xy 48.126715 -371.213082) (xy 48.132492 -371.220238) (xy 48.154241 -371.245921)
			(xy 48.192189 -371.301504) (xy 48.196948 -371.310662) (xy 53.966364 -371.310662) (xy 53.966364 -370.447062)
			(xy 53.96685 -370.419793) (xy 53.974612 -370.365809) (xy 53.989977 -370.313479) (xy 54.012634 -370.263869)
			(xy 54.04212 -370.217988) (xy 54.077835 -370.176771) (xy 54.119052 -370.141056) (xy 54.164933 -370.11157)
			(xy 54.214543 -370.088913) (xy 54.266873 -370.073548) (xy 54.320857 -370.065786) (xy 54.375395 -370.065786)
			(xy 54.429379 -370.073548) (xy 54.481709 -370.088913) (xy 54.531319 -370.11157) (xy 54.5772 -370.141056)
			(xy 54.618417 -370.176771) (xy 54.654132 -370.217988) (xy 54.683618 -370.263869) (xy 54.706275 -370.313479)
			(xy 54.72164 -370.365809) (xy 54.729402 -370.419793) (xy 54.729888 -370.447062) (xy 54.729888 -371.310662)
			(xy 57.339484 -371.310662) (xy 57.339484 -370.447062) (xy 57.33997 -370.419793) (xy 57.347732 -370.365809)
			(xy 57.363097 -370.313479) (xy 57.385754 -370.263869) (xy 57.41524 -370.217988) (xy 57.450955 -370.176771)
			(xy 57.492172 -370.141056) (xy 57.538053 -370.11157) (xy 57.587663 -370.088913) (xy 57.639993 -370.073548)
			(xy 57.693977 -370.065786) (xy 57.748515 -370.065786) (xy 57.802499 -370.073548) (xy 57.854829 -370.088913)
			(xy 57.904439 -370.11157) (xy 57.95032 -370.141056) (xy 57.991537 -370.176771) (xy 58.027252 -370.217988)
			(xy 58.056738 -370.263869) (xy 58.079395 -370.313479) (xy 58.09476 -370.365809) (xy 58.102522 -370.419793)
			(xy 58.103008 -370.447062) (xy 58.103008 -370.523703) (xy 71.348807 -370.523703) (xy 71.348808 -370.456279)
			(xy 71.356885 -370.38934) (xy 71.372921 -370.32385) (xy 71.396686 -370.260753) (xy 71.427838 -370.200956)
			(xy 71.465928 -370.145321) (xy 71.487792 -370.119656) (xy 71.493589 -370.112511) (xy 71.500104 -370.09532)
			(xy 71.500492 -370.086128) (xy 71.500492 -369.928902) (xy 71.501027 -369.918781) (xy 71.508745 -369.900069)
			(xy 71.523016 -369.885715) (xy 71.541682 -369.877887) (xy 71.5518 -369.87734) (xy 72.26808 -369.87734)
			(xy 72.278238 -369.877739) (xy 72.296998 -369.885535) (xy 72.311323 -369.89994) (xy 72.319016 -369.918742)
			(xy 72.319388 -369.928902) (xy 72.319388 -370.086128) (xy 72.319787 -370.095316) (xy 72.326309 -370.1125)
			(xy 72.332088 -370.119656) (xy 72.353941 -370.145331) (xy 72.39203 -370.200964) (xy 72.423182 -370.260758)
			(xy 72.446948 -370.323854) (xy 72.462984 -370.389342) (xy 72.471061 -370.45628) (xy 72.471063 -370.523644)
			(xy 75.749102 -370.523644) (xy 75.749103 -370.456338) (xy 75.757149 -370.389513) (xy 75.773125 -370.32413)
			(xy 75.796801 -370.261125) (xy 75.827837 -370.201401) (xy 75.86579 -370.145816) (xy 75.88758 -370.120164)
			(xy 75.893372 -370.113015) (xy 75.89989 -370.095828) (xy 75.90028 -370.086636) (xy 75.90028 -369.928902)
			(xy 75.900666 -369.918725) (xy 75.908459 -369.899923) (xy 75.922856 -369.885536) (xy 75.941665 -369.877759)
			(xy 75.951842 -369.87734) (xy 76.668122 -369.87734) (xy 76.678281 -369.877815) (xy 76.697052 -369.885597)
			(xy 76.711416 -369.899969) (xy 76.71919 -369.918742) (xy 76.719684 -369.928902) (xy 76.719684 -370.086636)
			(xy 76.72008 -370.095825) (xy 76.726604 -370.113009) (xy 76.732384 -370.120164) (xy 76.754159 -370.145826)
			(xy 76.792107 -370.201412) (xy 76.82314 -370.261134) (xy 76.846812 -370.324137) (xy 76.862785 -370.389518)
			(xy 76.87083 -370.456339) (xy 76.870831 -370.523643) (xy 76.870824 -370.523703) (xy 80.148895 -370.523703)
			(xy 80.148896 -370.456279) (xy 80.156972 -370.38934) (xy 80.173008 -370.323851) (xy 80.196773 -370.260754)
			(xy 80.227924 -370.200957) (xy 80.266012 -370.145322) (xy 80.287876 -370.119656) (xy 80.293671 -370.112509)
			(xy 80.300187 -370.09532) (xy 80.300576 -370.086128) (xy 80.300576 -369.928902) (xy 80.301029 -369.918771)
			(xy 80.308763 -369.900043) (xy 80.32306 -369.885685) (xy 80.341755 -369.877873) (xy 80.351884 -369.87734)
			(xy 81.068164 -369.87734) (xy 81.078289 -369.877747) (xy 81.096999 -369.88549) (xy 81.111316 -369.899811)
			(xy 81.119056 -369.918523) (xy 81.119472 -369.928648) (xy 81.119472 -370.086128) (xy 81.119875 -370.095316)
			(xy 81.126394 -370.1125) (xy 81.132172 -370.119656) (xy 81.154025 -370.14533) (xy 81.192116 -370.200963)
			(xy 81.223269 -370.260758) (xy 81.247035 -370.323853) (xy 81.263072 -370.389342) (xy 81.271149 -370.456279)
			(xy 81.27115 -370.523703) (xy 84.548686 -370.523703) (xy 84.548687 -370.456279) (xy 84.556763 -370.389341)
			(xy 84.572799 -370.323851) (xy 84.596563 -370.260754) (xy 84.627713 -370.200957) (xy 84.665801 -370.145322)
			(xy 84.687664 -370.119656) (xy 84.69347 -370.112518) (xy 84.699977 -370.095322) (xy 84.700364 -370.086128)
			(xy 84.700364 -369.928902) (xy 84.700829 -369.918772) (xy 84.708561 -369.900047) (xy 84.722854 -369.88569)
			(xy 84.741545 -369.877875) (xy 84.751672 -369.87734) (xy 85.467952 -369.87734) (xy 85.478076 -369.877756)
			(xy 85.496787 -369.885496) (xy 85.511104 -369.899813) (xy 85.518844 -369.918524) (xy 85.51926 -369.928648)
			(xy 85.51926 -370.086128) (xy 85.519666 -370.095315) (xy 85.526183 -370.112499) (xy 85.53196 -370.119656)
			(xy 85.553814 -370.14533) (xy 85.591905 -370.200963) (xy 85.623059 -370.260757) (xy 85.646825 -370.323853)
			(xy 85.662863 -370.389341) (xy 85.67094 -370.456279) (xy 85.670941 -370.523644) (xy 115.349244 -370.523644)
			(xy 115.349245 -370.456338) (xy 115.35729 -370.389516) (xy 115.373263 -370.324133) (xy 115.396936 -370.261128)
			(xy 115.427969 -370.201404) (xy 115.465917 -370.145817) (xy 115.487704 -370.120164) (xy 115.493499 -370.113018)
			(xy 115.500014 -370.095828) (xy 115.500404 -370.086636) (xy 115.500404 -369.928902) (xy 115.500934 -369.918749)
			(xy 115.508702 -369.899986) (xy 115.523056 -369.885622) (xy 115.541813 -369.877841) (xy 115.551966 -369.87734)
			(xy 116.268246 -369.87734) (xy 116.278407 -369.877796) (xy 116.297177 -369.885586) (xy 116.311541 -369.899963)
			(xy 116.319314 -369.918741) (xy 116.319808 -369.928902) (xy 116.319808 -370.086636) (xy 116.320199 -370.095825)
			(xy 116.326726 -370.11301) (xy 116.332508 -370.120164) (xy 116.354286 -370.145825) (xy 116.392238 -370.201409)
			(xy 116.423275 -370.261131) (xy 116.446951 -370.324134) (xy 116.462926 -370.389516) (xy 116.470972 -370.456338)
			(xy 116.470973 -370.523644) (xy 116.470966 -370.523703) (xy 119.749013 -370.523703) (xy 119.749014 -370.456279)
			(xy 119.757091 -370.38934) (xy 119.773128 -370.32385) (xy 119.796893 -370.260752) (xy 119.828045 -370.200956)
			(xy 119.866135 -370.145321) (xy 119.888 -370.119656) (xy 119.893798 -370.112512) (xy 119.900312 -370.09532)
			(xy 119.9007 -370.086128) (xy 119.9007 -369.928902) (xy 119.901227 -369.91878) (xy 119.908947 -369.900067)
			(xy 119.92322 -369.885712) (xy 119.941889 -369.877886) (xy 119.952008 -369.87734) (xy 120.668288 -369.87734)
			(xy 120.678446 -369.877732) (xy 120.697206 -369.885531) (xy 120.711531 -369.899938) (xy 120.719224 -369.918741)
			(xy 120.719596 -369.928902) (xy 120.719596 -370.086128) (xy 120.719993 -370.095317) (xy 120.726516 -370.112501)
			(xy 120.732296 -370.119656) (xy 120.754148 -370.145331) (xy 120.792238 -370.200964) (xy 120.823389 -370.260759)
			(xy 120.847154 -370.323854) (xy 120.863191 -370.389342) (xy 120.871267 -370.45628) (xy 120.871269 -370.523644)
			(xy 124.149308 -370.523644) (xy 124.149309 -370.456338) (xy 124.157355 -370.389513) (xy 124.173331 -370.32413)
			(xy 124.197007 -370.261125) (xy 124.228045 -370.201401) (xy 124.265998 -370.145816) (xy 124.287788 -370.120164)
			(xy 124.293581 -370.113016) (xy 124.300098 -370.095828) (xy 124.300488 -370.086636) (xy 124.300488 -369.928902)
			(xy 124.300867 -369.918724) (xy 124.30866 -369.89992) (xy 124.32306 -369.885533) (xy 124.341872 -369.877757)
			(xy 124.35205 -369.87734) (xy 125.06833 -369.87734) (xy 125.07849 -369.877809) (xy 125.09726 -369.885593)
			(xy 125.111625 -369.899967) (xy 125.119398 -369.918742) (xy 125.119892 -369.928902) (xy 125.119892 -370.086636)
			(xy 125.120286 -370.095825) (xy 125.126811 -370.113009) (xy 125.132592 -370.120164) (xy 125.154367 -370.145826)
			(xy 125.192314 -370.201412) (xy 125.223346 -370.261134) (xy 125.247018 -370.324138) (xy 125.262991 -370.389518)
			(xy 125.271036 -370.456339) (xy 125.271037 -370.523643) (xy 125.271037 -370.523644) (xy 128.549099 -370.523644)
			(xy 128.5491 -370.456338) (xy 128.557146 -370.389514) (xy 128.573121 -370.32413) (xy 128.596797 -370.261125)
			(xy 128.627834 -370.201402) (xy 128.665787 -370.145816) (xy 128.687576 -370.120164) (xy 128.693368 -370.113015)
			(xy 128.699886 -370.095828) (xy 128.700276 -370.086636) (xy 128.700276 -369.928902) (xy 128.700666 -369.918726)
			(xy 128.708458 -369.899924) (xy 128.722854 -369.885538) (xy 128.741661 -369.877759) (xy 128.751838 -369.87734)
			(xy 129.468118 -369.87734) (xy 129.478277 -369.877818) (xy 129.497047 -369.885599) (xy 129.511412 -369.89997)
			(xy 129.519185 -369.918743) (xy 129.51968 -369.928902) (xy 129.51968 -370.086636) (xy 129.520077 -370.095824)
			(xy 129.5266 -370.113008) (xy 129.53238 -370.120164) (xy 129.554155 -370.145826) (xy 129.592103 -370.201412)
			(xy 129.623136 -370.261134) (xy 129.646809 -370.324137) (xy 129.662782 -370.389518) (xy 129.670827 -370.456339)
			(xy 129.670828 -370.523643) (xy 129.670828 -370.523644) (xy 159.349153 -370.523644) (xy 159.349154 -370.456338)
			(xy 159.357199 -370.389515) (xy 159.373173 -370.324133) (xy 159.396846 -370.261128) (xy 159.427879 -370.201404)
			(xy 159.465828 -370.145816) (xy 159.487616 -370.120164) (xy 159.493412 -370.113019) (xy 159.499927 -370.095828)
			(xy 159.500316 -370.086636) (xy 159.500316 -369.928902) (xy 159.500835 -369.918747) (xy 159.508604 -369.899982)
			(xy 159.522962 -369.885618) (xy 159.541723 -369.877839) (xy 159.551878 -369.87734) (xy 160.268158 -369.87734)
			(xy 160.278327 -369.877798) (xy 160.297121 -369.88557) (xy 160.311508 -369.899945) (xy 160.319294 -369.918733)
			(xy 160.31972 -369.928902) (xy 160.31972 -370.086636) (xy 160.320109 -370.095826) (xy 160.326637 -370.11301)
			(xy 160.33242 -370.120164) (xy 160.354197 -370.145825) (xy 160.392149 -370.20141) (xy 160.423185 -370.261131)
			(xy 160.44686 -370.324135) (xy 160.462835 -370.389516) (xy 160.470881 -370.456339) (xy 160.470882 -370.523643)
			(xy 160.470875 -370.523703) (xy 163.748922 -370.523703) (xy 163.748923 -370.456279) (xy 163.757 -370.389339)
			(xy 163.773037 -370.323849) (xy 163.796803 -370.260752) (xy 163.827956 -370.200955) (xy 163.866047 -370.145321)
			(xy 163.887912 -370.119656) (xy 163.893711 -370.112513) (xy 163.900224 -370.095321) (xy 163.900612 -370.086128)
			(xy 163.900612 -369.928902) (xy 163.901127 -369.918779) (xy 163.908849 -369.900063) (xy 163.923126 -369.885708)
			(xy 163.9418 -369.877884) (xy 163.95192 -369.87734) (xy 164.6682 -369.87734) (xy 164.678359 -369.877722)
			(xy 164.697119 -369.885526) (xy 164.711444 -369.899935) (xy 164.719136 -369.918741) (xy 164.719508 -369.928902)
			(xy 164.719508 -370.086128) (xy 164.719903 -370.095317) (xy 164.726427 -370.112501) (xy 164.732208 -370.119656)
			(xy 164.75406 -370.145331) (xy 164.792148 -370.200964) (xy 164.823299 -370.260759) (xy 164.847064 -370.323855)
			(xy 164.8631 -370.389343) (xy 164.871176 -370.45628) (xy 164.871178 -370.523644) (xy 168.149241 -370.523644)
			(xy 168.149242 -370.456338) (xy 168.157287 -370.389516) (xy 168.17326 -370.324133) (xy 168.196933 -370.261128)
			(xy 168.227965 -370.201404) (xy 168.265913 -370.145817) (xy 168.2877 -370.120164) (xy 168.293494 -370.113017)
			(xy 168.30001 -370.095828) (xy 168.3004 -370.086636) (xy 168.3004 -369.928902) (xy 168.300934 -369.918749)
			(xy 168.308701 -369.899987) (xy 168.323054 -369.885623) (xy 168.341809 -369.877842) (xy 168.351962 -369.87734)
			(xy 169.068242 -369.87734) (xy 169.078403 -369.877799) (xy 169.097173 -369.885588) (xy 169.111537 -369.899964)
			(xy 169.11931 -369.918741) (xy 169.119804 -369.928902) (xy 169.119804 -370.086636) (xy 169.120196 -370.095825)
			(xy 169.126722 -370.113009) (xy 169.132504 -370.120164) (xy 169.154279 -370.145826) (xy 169.192225 -370.201412)
			(xy 169.223256 -370.261135) (xy 169.246928 -370.324138) (xy 169.2629 -370.389519) (xy 169.270945 -370.456339)
			(xy 169.270946 -370.523643) (xy 169.270946 -370.523644) (xy 172.549008 -370.523644) (xy 172.549009 -370.456338)
			(xy 172.557055 -370.389513) (xy 172.573031 -370.32413) (xy 172.596707 -370.261125) (xy 172.627745 -370.201401)
			(xy 172.665698 -370.145816) (xy 172.687488 -370.120164) (xy 172.693281 -370.113016) (xy 172.699798 -370.095828)
			(xy 172.700188 -370.086636) (xy 172.700188 -369.928902) (xy 172.700567 -369.918724) (xy 172.70836 -369.89992)
			(xy 172.72276 -369.885533) (xy 172.741572 -369.877757) (xy 172.75175 -369.87734) (xy 173.46803 -369.87734)
			(xy 173.47819 -369.877809) (xy 173.49696 -369.885593) (xy 173.511325 -369.899967) (xy 173.519098 -369.918742)
			(xy 173.519592 -369.928902) (xy 173.519592 -370.086636) (xy 173.519986 -370.095825) (xy 173.526511 -370.113009)
			(xy 173.532292 -370.120164) (xy 173.554067 -370.145826) (xy 173.592014 -370.201412) (xy 173.623046 -370.261134)
			(xy 173.646718 -370.324138) (xy 173.662691 -370.389518) (xy 173.670736 -370.456339) (xy 173.670737 -370.523643)
			(xy 173.662694 -370.590464) (xy 173.646724 -370.655845) (xy 173.623054 -370.718849) (xy 173.592023 -370.778573)
			(xy 173.554078 -370.834159) (xy 173.532292 -370.859812) (xy 173.526507 -370.866965) (xy 173.519986 -370.88415)
			(xy 173.519592 -370.89334) (xy 173.519592 -370.901722) (xy 204.470508 -370.901722) (xy 204.470508 -367.316004)
			(xy 204.470934 -367.305935) (xy 204.478654 -367.287337) (xy 204.485494 -367.279936) (xy 204.682344 -367.083086)
			(xy 204.689733 -367.076232) (xy 204.708341 -367.068521) (xy 204.718412 -367.0681) (xy 208.051146 -367.0681)
			(xy 208.061216 -367.068527) (xy 208.079815 -367.076244) (xy 208.087214 -367.083086) (xy 208.263998 -367.25987)
			(xy 208.270817 -367.267287) (xy 208.278549 -367.285873) (xy 208.278984 -367.295938) (xy 208.278984 -370.103908)
			(xy 208.279552 -370.116248) (xy 208.288818 -370.13912) (xy 208.297018 -370.148358) (xy 208.297526 -370.148866)
			(xy 208.34985 -370.20119) (xy 208.35903 -370.209654) (xy 208.382078 -370.219214) (xy 208.394554 -370.219732)
			(xy 208.738724 -370.219732) (xy 208.748796 -370.220137) (xy 208.767394 -370.227871) (xy 208.774792 -370.234718)
			(xy 209.51444 -370.974366) (xy 209.523615 -370.982837) (xy 209.546667 -370.99239) (xy 209.559144 -370.992908)
			(xy 210.018376 -370.992908) (xy 210.028444 -370.993344) (xy 210.047042 -371.001057) (xy 210.054444 -371.007894)
			(xy 210.21421 -371.16766) (xy 210.221026 -371.175079) (xy 210.228759 -371.193664) (xy 210.229196 -371.203728)
			(xy 210.229196 -371.61724) (xy 210.229798 -371.629697) (xy 210.239356 -371.652707) (xy 210.247738 -371.661944)
			(xy 210.379056 -371.793262) (xy 210.379564 -371.79377) (xy 210.388781 -371.802003) (xy 210.411665 -371.811276)
			(xy 210.424014 -371.811804) (xy 216.605104 -371.811804) (xy 216.617445 -371.811237) (xy 216.640316 -371.801971)
			(xy 216.649554 -371.79377) (xy 216.650062 -371.793262) (xy 217.67927 -370.764054) (xy 217.679778 -370.763546)
			(xy 217.688008 -370.754327) (xy 217.697282 -370.731444) (xy 217.697812 -370.719096) (xy 217.697812 -367.36528)
			(xy 217.698224 -367.355209) (xy 217.705954 -367.336611) (xy 217.712798 -367.329212) (xy 217.96883 -367.073434)
			(xy 217.97623 -367.066593) (xy 217.994829 -367.058873) (xy 218.004898 -367.058448) (xy 221.295214 -367.058448)
			(xy 221.305259 -367.058823) (xy 221.323856 -367.066407) (xy 221.331282 -367.07318) (xy 221.508066 -367.249964)
			(xy 221.514878 -367.257386) (xy 221.522615 -367.275968) (xy 221.523052 -367.286032) (xy 221.523052 -370.745258)
			(xy 221.523577 -370.757603) (xy 221.532871 -370.780476) (xy 221.541086 -370.789708) (xy 221.541594 -370.790216)
			(xy 221.701614 -370.950236) (xy 221.708464 -370.957628) (xy 221.716177 -370.976233) (xy 221.7166 -370.986304)
			(xy 221.7166 -373.574564) (xy 221.71724 -373.587017) (xy 221.726771 -373.610028) (xy 221.735142 -373.619268)
			(xy 223.603312 -375.487438) (xy 223.6125 -375.495892) (xy 223.635542 -375.505456) (xy 223.648016 -375.50598)
			(xy 225.569526 -375.50598) (xy 225.581983 -375.505377) (xy 225.604994 -375.49582) (xy 225.61423 -375.487438)
			(xy 226.890326 -374.211342) (xy 226.890834 -374.210834) (xy 226.899064 -374.201614) (xy 226.90834 -374.178732)
			(xy 226.908868 -374.166384) (xy 226.908868 -372.704106) (xy 226.909279 -372.694035) (xy 226.917008 -372.675436)
			(xy 226.923854 -372.668038) (xy 228.193346 -371.3988) (xy 228.201796 -371.389609) (xy 228.211362 -371.366569)
			(xy 228.211888 -371.354096) (xy 228.211888 -370.983256) (xy 228.212267 -370.973181) (xy 228.220018 -370.954582)
			(xy 228.226874 -370.947188) (xy 228.380798 -370.793264) (xy 228.389257 -370.78408) (xy 228.398819 -370.761035)
			(xy 228.39934 -370.74856) (xy 228.39934 -367.292382) (xy 228.399715 -367.282337) (xy 228.4073 -367.263741)
			(xy 228.414072 -367.256314) (xy 228.600508 -367.069878) (xy 228.607909 -367.063039) (xy 228.626508 -367.055319)
			(xy 228.636576 -367.054892) (xy 231.959912 -367.054892) (xy 231.969985 -367.055287) (xy 231.988584 -367.063026)
			(xy 231.99598 -367.069878) (xy 232.182416 -367.256314) (xy 232.1891 -367.263803) (xy 232.196697 -367.282356)
			(xy 232.197148 -367.292382) (xy 232.197148 -370.755164) (xy 232.197775 -370.767618) (xy 232.207314 -370.79063)
			(xy 232.21569 -370.799868) (xy 232.35031 -370.934234) (xy 232.357159 -370.941627) (xy 232.364873 -370.960232)
			(xy 232.365296 -370.970302) (xy 232.365296 -371.212364) (xy 232.365833 -371.224708) (xy 232.37512 -371.247579)
			(xy 232.38333 -371.256814) (xy 232.383838 -371.257322) (xy 233.100118 -371.973602) (xy 233.106954 -371.981005)
			(xy 233.114675 -371.999602) (xy 233.115104 -372.00967) (xy 233.115104 -375.498868) (xy 233.115741 -375.511321)
			(xy 233.125274 -375.534332) (xy 233.133646 -375.543572) (xy 233.841798 -376.251724) (xy 235.85424 -376.251724)
			(xy 235.85424 -368.653314) (xy 235.854662 -368.643244) (xy 235.862384 -368.624646) (xy 235.869226 -368.617246)
			(xy 236.22889 -368.257582) (xy 236.236297 -368.250752) (xy 236.254891 -368.243027) (xy 236.264958 -368.242596)
			(xy 242.047014 -368.242596) (xy 242.057087 -368.242989) (xy 242.075686 -368.25073) (xy 242.083082 -368.257582)
			(xy 242.35029 -368.52479) (xy 242.357117 -368.532201) (xy 242.364845 -368.550792) (xy 242.365276 -368.560858)
			(xy 242.365276 -376.144028) (xy 242.364736 -376.155236) (xy 242.355238 -376.175537) (xy 242.346988 -376.183144)
			(xy 242.273836 -376.244104) (xy 242.269772 -376.247914) (xy 241.986816 -376.53087) (xy 241.986562 -376.531124)
			(xy 241.978942 -376.540522) (xy 241.91849 -376.631454) (xy 241.910997 -376.641545) (xy 241.888878 -376.653411)
			(xy 241.876326 -376.65406) (xy 236.25683 -376.65406) (xy 236.246761 -376.653629) (xy 236.228163 -376.645913)
			(xy 236.220762 -376.639074) (xy 235.869226 -376.287792) (xy 235.862394 -376.280386) (xy 235.854669 -376.261791)
			(xy 235.85424 -376.251724) (xy 233.841798 -376.251724) (xy 234.964478 -377.374404) (xy 242.49126 -377.374404)
			(xy 242.49126 -368.547142) (xy 242.491691 -368.537073) (xy 242.499406 -368.518474) (xy 242.506246 -368.511074)
			(xy 242.759738 -368.257582) (xy 242.767129 -368.25073) (xy 242.785735 -368.243018) (xy 242.795806 -368.242596)
			(xy 265.583924 -368.242596) (xy 265.593998 -368.242984) (xy 265.612597 -368.250728) (xy 265.619992 -368.257582)
			(xy 266.105894 -368.743484) (xy 266.112719 -368.750896) (xy 266.120448 -368.769486) (xy 266.12088 -368.779552)
			(xy 266.12088 -370.523704) (xy 286.928752 -370.523704) (xy 286.928753 -370.456278) (xy 286.936831 -370.389338)
			(xy 286.952869 -370.323848) (xy 286.976637 -370.26075) (xy 287.007792 -370.200954) (xy 287.045885 -370.14532)
			(xy 287.067752 -370.119656) (xy 287.073556 -370.112516) (xy 287.080065 -370.095321) (xy 287.080452 -370.086128)
			(xy 287.080452 -369.928902) (xy 287.080929 -369.918774) (xy 287.088658 -369.900051) (xy 287.102947 -369.885694)
			(xy 287.121634 -369.877877) (xy 287.13176 -369.87734) (xy 287.84804 -369.87734) (xy 287.85817 -369.877684)
			(xy 287.876882 -369.885453) (xy 287.891196 -369.899792) (xy 287.898933 -369.918517) (xy 287.899348 -369.928648)
			(xy 287.899348 -370.086128) (xy 287.899756 -370.095315) (xy 287.906273 -370.112499) (xy 287.912048 -370.119656)
			(xy 287.933902 -370.14533) (xy 287.971994 -370.200962) (xy 288.003149 -370.260757) (xy 288.026916 -370.323852)
			(xy 288.042954 -370.389341) (xy 288.051031 -370.456279) (xy 288.051032 -370.523644) (xy 291.329071 -370.523644)
			(xy 291.329073 -370.456338) (xy 291.337118 -370.389515) (xy 291.353092 -370.324132) (xy 291.376766 -370.261127)
			(xy 291.407801 -370.201403) (xy 291.445751 -370.145816) (xy 291.46754 -370.120164) (xy 291.473339 -370.113021)
			(xy 291.479851 -370.095829) (xy 291.48024 -370.086636) (xy 291.48024 -369.928902) (xy 291.480665 -369.91873)
			(xy 291.48845 -369.899935) (xy 291.502835 -369.88555) (xy 291.52163 -369.877765) (xy 291.531802 -369.87734)
			(xy 292.248082 -369.87734) (xy 292.258253 -369.877778) (xy 292.277047 -369.885558) (xy 292.291433 -369.899939)
			(xy 292.299218 -369.918731) (xy 292.299644 -369.928902) (xy 292.299644 -370.086636) (xy 292.30005 -370.095823)
			(xy 292.306568 -370.113007) (xy 292.312344 -370.120164) (xy 292.33412 -370.145826) (xy 292.372071 -370.20141)
			(xy 292.403105 -370.261132) (xy 292.426779 -370.324136) (xy 292.442754 -370.389517) (xy 292.450799 -370.456339)
			(xy 292.4508 -370.523643) (xy 292.450793 -370.523704) (xy 295.72884 -370.523704) (xy 295.728841 -370.456278)
			(xy 295.736918 -370.389339) (xy 295.752956 -370.323848) (xy 295.776723 -370.260751) (xy 295.807878 -370.200955)
			(xy 295.84597 -370.145321) (xy 295.867836 -370.119656) (xy 295.873638 -370.112515) (xy 295.880149 -370.095321)
			(xy 295.880536 -370.086128) (xy 295.880536 -369.928902) (xy 295.881028 -369.918776) (xy 295.888755 -369.900056)
			(xy 295.903039 -369.885699) (xy 295.92172 -369.877879) (xy 295.931844 -369.87734) (xy 296.648124 -369.87734)
			(xy 296.658285 -369.877703) (xy 296.677045 -369.885514) (xy 296.691369 -369.899929) (xy 296.699061 -369.918739)
			(xy 296.699432 -369.928902) (xy 296.699432 -370.086128) (xy 296.699844 -370.095315) (xy 296.706358 -370.112498)
			(xy 296.712132 -370.119656) (xy 296.733983 -370.145332) (xy 296.77207 -370.200965) (xy 296.803219 -370.26076)
			(xy 296.826983 -370.323856) (xy 296.843018 -370.389343) (xy 296.851095 -370.45628) (xy 296.851096 -370.523702)
			(xy 296.851096 -370.523704) (xy 300.128631 -370.523704) (xy 300.128632 -370.456278) (xy 300.136709 -370.389339)
			(xy 300.152747 -370.323849) (xy 300.176513 -370.260751) (xy 300.207667 -370.200955) (xy 300.245758 -370.145321)
			(xy 300.267624 -370.119656) (xy 300.273425 -370.112514) (xy 300.279936 -370.095321) (xy 300.280324 -370.086128)
			(xy 300.280324 -369.928902) (xy 300.280828 -369.918777) (xy 300.288552 -369.900059) (xy 300.302833 -369.885704)
			(xy 300.32151 -369.877882) (xy 300.331632 -369.87734) (xy 301.047912 -369.87734) (xy 301.058072 -369.877712)
			(xy 301.076832 -369.885519) (xy 301.091157 -369.899932) (xy 301.098849 -369.91874) (xy 301.09922 -369.928902)
			(xy 301.09922 -370.086128) (xy 301.099612 -370.095317) (xy 301.106138 -370.112502) (xy 301.11192 -370.119656)
			(xy 301.133771 -370.145331) (xy 301.171859 -370.200965) (xy 301.203009 -370.26076) (xy 301.226773 -370.323855)
			(xy 301.242809 -370.389343) (xy 301.250886 -370.45628) (xy 301.250887 -370.523644) (xy 330.92919 -370.523644)
			(xy 330.929191 -370.456338) (xy 330.937237 -370.389514) (xy 330.953212 -370.324131) (xy 330.976887 -370.261126)
			(xy 331.007923 -370.201402) (xy 331.045875 -370.145816) (xy 331.067664 -370.120164) (xy 331.073466 -370.113023)
			(xy 331.079976 -370.095829) (xy 331.080364 -370.086636) (xy 331.080364 -369.928902) (xy 331.080766 -369.918727)
			(xy 331.088555 -369.899928) (xy 331.102948 -369.885542) (xy 331.121751 -369.877761) (xy 331.131926 -369.87734)
			(xy 331.848206 -369.87734) (xy 331.858364 -369.877829) (xy 331.877134 -369.885605) (xy 331.891499 -369.899973)
			(xy 331.899273 -369.918744) (xy 331.899768 -369.928902) (xy 331.899768 -370.086636) (xy 331.900168 -370.095824)
			(xy 331.90669 -370.113008) (xy 331.912468 -370.120164) (xy 331.934244 -370.145826) (xy 331.972193 -370.201411)
			(xy 332.003226 -370.261133) (xy 332.026899 -370.324137) (xy 332.042873 -370.389518) (xy 332.050918 -370.456339)
			(xy 332.050919 -370.523643) (xy 332.050912 -370.523703) (xy 335.328983 -370.523703) (xy 335.328984 -370.456279)
			(xy 335.33706 -370.389341) (xy 335.353096 -370.323852) (xy 335.376859 -370.260754) (xy 335.408009 -370.200957)
			(xy 335.446097 -370.145322) (xy 335.46796 -370.119656) (xy 335.473765 -370.112517) (xy 335.480273 -370.095322)
			(xy 335.48066 -370.086128) (xy 335.48066 -369.928902) (xy 335.481129 -369.918773) (xy 335.48886 -369.900048)
			(xy 335.503152 -369.885691) (xy 335.521841 -369.877875) (xy 335.531968 -369.87734) (xy 336.248248 -369.87734)
			(xy 336.25841 -369.877683) (xy 336.277171 -369.885502) (xy 336.291494 -369.899923) (xy 336.299185 -369.918737)
			(xy 336.299556 -369.928902) (xy 336.299556 -370.086128) (xy 336.299963 -370.095315) (xy 336.30648 -370.112499)
			(xy 336.312256 -370.119656) (xy 336.33411 -370.14533) (xy 336.372202 -370.200962) (xy 336.403355 -370.260757)
			(xy 336.427122 -370.323853) (xy 336.44316 -370.389341) (xy 336.451237 -370.456279) (xy 336.451238 -370.523644)
			(xy 339.729277 -370.523644) (xy 339.729279 -370.456338) (xy 339.737324 -370.389514) (xy 339.753299 -370.324131)
			(xy 339.776973 -370.261126) (xy 339.808008 -370.201402) (xy 339.845959 -370.145816) (xy 339.867748 -370.120164)
			(xy 339.873548 -370.113022) (xy 339.880059 -370.095829) (xy 339.880448 -370.086636) (xy 339.880448 -369.928902)
			(xy 339.880866 -369.918729) (xy 339.888652 -369.899933) (xy 339.903039 -369.885547) (xy 339.921837 -369.877764)
			(xy 339.93201 -369.87734) (xy 340.64829 -369.87734) (xy 340.658461 -369.877772) (xy 340.677256 -369.885554)
			(xy 340.691641 -369.899937) (xy 340.699426 -369.918731) (xy 340.699852 -369.928902) (xy 340.699852 -370.086636)
			(xy 340.700256 -370.095824) (xy 340.706775 -370.113007) (xy 340.712552 -370.120164) (xy 340.734328 -370.145826)
			(xy 340.772278 -370.201411) (xy 340.803312 -370.261133) (xy 340.826986 -370.324136) (xy 340.84296 -370.389517)
			(xy 340.851005 -370.456339) (xy 340.851006 -370.523643) (xy 340.851006 -370.523644) (xy 344.129068 -370.523644)
			(xy 344.129069 -370.456338) (xy 344.137115 -370.389515) (xy 344.153089 -370.324132) (xy 344.176763 -370.261127)
			(xy 344.207797 -370.201403) (xy 344.245748 -370.145816) (xy 344.267536 -370.120164) (xy 344.273335 -370.113021)
			(xy 344.279847 -370.095829) (xy 344.280236 -370.086636) (xy 344.280236 -369.928902) (xy 344.280735 -369.918745)
			(xy 344.288508 -369.899976) (xy 344.302873 -369.885611) (xy 344.321641 -369.877836) (xy 344.331798 -369.87734)
			(xy 345.048078 -369.87734) (xy 345.058248 -369.877782) (xy 345.077043 -369.88556) (xy 345.091429 -369.89994)
			(xy 345.099214 -369.918732) (xy 345.09964 -369.928902) (xy 345.09964 -370.086636) (xy 345.100046 -370.095823)
			(xy 345.106564 -370.113007) (xy 345.11234 -370.120164) (xy 345.134116 -370.145826) (xy 345.172067 -370.20141)
			(xy 345.203102 -370.261132) (xy 345.226776 -370.324136) (xy 345.242751 -370.389517) (xy 345.250796 -370.456339)
			(xy 345.250797 -370.523643) (xy 345.250797 -370.523644) (xy 374.929099 -370.523644) (xy 374.9291 -370.456338)
			(xy 374.937146 -370.389514) (xy 374.953121 -370.32413) (xy 374.976797 -370.261125) (xy 375.007834 -370.201402)
			(xy 375.045787 -370.145816) (xy 375.067576 -370.120164) (xy 375.073368 -370.113015) (xy 375.079886 -370.095828)
			(xy 375.080276 -370.086636) (xy 375.080276 -369.928902) (xy 375.080666 -369.918726) (xy 375.088458 -369.899924)
			(xy 375.102854 -369.885538) (xy 375.121661 -369.877759) (xy 375.131838 -369.87734) (xy 375.848118 -369.87734)
			(xy 375.858277 -369.877818) (xy 375.877047 -369.885599) (xy 375.891412 -369.89997) (xy 375.899185 -369.918743)
			(xy 375.89968 -369.928902) (xy 375.89968 -370.086636) (xy 375.900077 -370.095824) (xy 375.9066 -370.113008)
			(xy 375.91238 -370.120164) (xy 375.934155 -370.145826) (xy 375.972103 -370.201412) (xy 376.003136 -370.261134)
			(xy 376.026809 -370.324137) (xy 376.042782 -370.389518) (xy 376.050827 -370.456339) (xy 376.050828 -370.523643)
			(xy 376.050821 -370.523703) (xy 379.328892 -370.523703) (xy 379.328893 -370.456279) (xy 379.336969 -370.38934)
			(xy 379.353005 -370.323851) (xy 379.376769 -370.260754) (xy 379.40792 -370.200957) (xy 379.446008 -370.145322)
			(xy 379.467872 -370.119656) (xy 379.473678 -370.112518) (xy 379.480185 -370.095322) (xy 379.480572 -370.086128)
			(xy 379.480572 -369.928902) (xy 379.481029 -369.918772) (xy 379.488762 -369.900044) (xy 379.503058 -369.885687)
			(xy 379.521752 -369.877873) (xy 379.53188 -369.87734) (xy 380.24816 -369.87734) (xy 380.258316 -369.877755)
			(xy 380.277076 -369.885545) (xy 380.291402 -369.899945) (xy 380.299096 -369.918743) (xy 380.299468 -369.928902)
			(xy 380.299468 -370.086128) (xy 380.299872 -370.095316) (xy 380.306391 -370.1125) (xy 380.312168 -370.119656)
			(xy 380.334021 -370.14533) (xy 380.372112 -370.200963) (xy 380.403265 -370.260758) (xy 380.427032 -370.323853)
			(xy 380.443069 -370.389342) (xy 380.451146 -370.456279) (xy 380.451147 -370.523644) (xy 383.729187 -370.523644)
			(xy 383.729188 -370.456338) (xy 383.737234 -370.389514) (xy 383.753209 -370.324131) (xy 383.776884 -370.261126)
			(xy 383.807919 -370.201402) (xy 383.845871 -370.145816) (xy 383.86766 -370.120164) (xy 383.873462 -370.113023)
			(xy 383.879972 -370.095829) (xy 383.88036 -370.086636) (xy 383.88036 -369.928902) (xy 383.880766 -369.918728)
			(xy 383.888554 -369.899929) (xy 383.902946 -369.885543) (xy 383.921748 -369.877762) (xy 383.931922 -369.87734)
			(xy 384.648202 -369.87734) (xy 384.65836 -369.877832) (xy 384.67713 -369.885607) (xy 384.691495 -369.899974)
			(xy 384.699269 -369.918744) (xy 384.699764 -369.928902) (xy 384.699764 -370.086636) (xy 384.700165 -370.095824)
			(xy 384.706686 -370.113008) (xy 384.712464 -370.120164) (xy 384.73424 -370.145826) (xy 384.772189 -370.201411)
			(xy 384.803222 -370.261133) (xy 384.826895 -370.324137) (xy 384.842869 -370.389518) (xy 384.850914 -370.456339)
			(xy 384.850915 -370.523643) (xy 384.850915 -370.523644) (xy 388.128977 -370.523644) (xy 388.128979 -370.456338)
			(xy 388.137024 -370.389514) (xy 388.152999 -370.324131) (xy 388.176673 -370.261126) (xy 388.207708 -370.201402)
			(xy 388.245659 -370.145816) (xy 388.267448 -370.120164) (xy 388.273248 -370.113022) (xy 388.279759 -370.095829)
			(xy 388.280148 -370.086636) (xy 388.280148 -369.928902) (xy 388.280566 -369.918729) (xy 388.288352 -369.899933)
			(xy 388.302739 -369.885547) (xy 388.321537 -369.877764) (xy 388.33171 -369.87734) (xy 389.04799 -369.87734)
			(xy 389.058161 -369.877772) (xy 389.076956 -369.885554) (xy 389.091341 -369.899937) (xy 389.099126 -369.918731)
			(xy 389.099552 -369.928902) (xy 389.099552 -370.086636) (xy 389.099956 -370.095824) (xy 389.106475 -370.113007)
			(xy 389.112252 -370.120164) (xy 389.134028 -370.145826) (xy 389.171978 -370.201411) (xy 389.203012 -370.261133)
			(xy 389.226686 -370.324136) (xy 389.24266 -370.389517) (xy 389.250705 -370.456339) (xy 389.250706 -370.523643)
			(xy 389.250706 -370.523644) (xy 418.929008 -370.523644) (xy 418.929009 -370.456338) (xy 418.937055 -370.389513)
			(xy 418.953031 -370.32413) (xy 418.976707 -370.261125) (xy 419.007745 -370.201401) (xy 419.045698 -370.145816)
			(xy 419.067488 -370.120164) (xy 419.073281 -370.113016) (xy 419.079798 -370.095828) (xy 419.080188 -370.086636)
			(xy 419.080188 -369.928902) (xy 419.080567 -369.918724) (xy 419.08836 -369.89992) (xy 419.10276 -369.885533)
			(xy 419.121572 -369.877757) (xy 419.13175 -369.87734) (xy 419.84803 -369.87734) (xy 419.85819 -369.877809)
			(xy 419.87696 -369.885593) (xy 419.891325 -369.899967) (xy 419.899098 -369.918742) (xy 419.899592 -369.928902)
			(xy 419.899592 -370.086636) (xy 419.899986 -370.095825) (xy 419.906511 -370.113009) (xy 419.912292 -370.120164)
			(xy 419.934067 -370.145826) (xy 419.972014 -370.201412) (xy 420.003046 -370.261134) (xy 420.026718 -370.324138)
			(xy 420.042691 -370.389518) (xy 420.050736 -370.456339) (xy 420.050737 -370.523643) (xy 420.05073 -370.523703)
			(xy 423.328801 -370.523703) (xy 423.328802 -370.456279) (xy 423.336878 -370.38934) (xy 423.352915 -370.323851)
			(xy 423.37668 -370.260753) (xy 423.407831 -370.200957) (xy 423.44592 -370.145322) (xy 423.467784 -370.119656)
			(xy 423.47358 -370.11251) (xy 423.480095 -370.09532) (xy 423.480484 -370.086128) (xy 423.480484 -369.928902)
			(xy 423.48093 -369.91877) (xy 423.488665 -369.900041) (xy 423.502964 -369.885683) (xy 423.521662 -369.877871)
			(xy 423.531792 -369.87734) (xy 424.248072 -369.87734) (xy 424.258198 -369.87774) (xy 424.276908 -369.885486)
			(xy 424.291225 -369.899808) (xy 424.298964 -369.918522) (xy 424.29938 -369.928648) (xy 424.29938 -370.086128)
			(xy 424.299781 -370.095316) (xy 424.306302 -370.1125) (xy 424.31208 -370.119656) (xy 424.333933 -370.145331)
			(xy 424.372023 -370.200963) (xy 424.403176 -370.260758) (xy 424.426941 -370.323854) (xy 424.442978 -370.389342)
			(xy 424.451055 -370.456279) (xy 424.451056 -370.523644) (xy 427.729096 -370.523644) (xy 427.729097 -370.456338)
			(xy 427.737143 -370.389514) (xy 427.753118 -370.32413) (xy 427.776794 -370.261125) (xy 427.80783 -370.201402)
			(xy 427.845783 -370.145816) (xy 427.867572 -370.120164) (xy 427.873375 -370.113024) (xy 427.879884 -370.095829)
			(xy 427.880272 -370.086636) (xy 427.880272 -369.928902) (xy 427.880666 -369.918726) (xy 427.888457 -369.899925)
			(xy 427.902852 -369.885539) (xy 427.921658 -369.87776) (xy 427.931834 -369.87734) (xy 428.648114 -369.87734)
			(xy 428.658273 -369.877822) (xy 428.677043 -369.885602) (xy 428.691407 -369.899971) (xy 428.699181 -369.918743)
			(xy 428.699676 -369.928902) (xy 428.699676 -370.086636) (xy 428.700074 -370.095824) (xy 428.706597 -370.113008)
			(xy 428.712376 -370.120164) (xy 428.734152 -370.145826) (xy 428.7721 -370.201411) (xy 428.803133 -370.261134)
			(xy 428.826806 -370.324137) (xy 428.842779 -370.389518) (xy 428.850824 -370.456339) (xy 428.850825 -370.523643)
			(xy 428.850825 -370.523644) (xy 432.128887 -370.523644) (xy 432.128888 -370.456338) (xy 432.136934 -370.389514)
			(xy 432.152909 -370.324131) (xy 432.176584 -370.261126) (xy 432.207619 -370.201402) (xy 432.245571 -370.145816)
			(xy 432.26736 -370.120164) (xy 432.273162 -370.113023) (xy 432.279672 -370.095829) (xy 432.28006 -370.086636)
			(xy 432.28006 -369.928902) (xy 432.280466 -369.918728) (xy 432.288254 -369.899929) (xy 432.302646 -369.885543)
			(xy 432.321448 -369.877762) (xy 432.331622 -369.87734) (xy 433.047902 -369.87734) (xy 433.05806 -369.877832)
			(xy 433.07683 -369.885607) (xy 433.091195 -369.899974) (xy 433.098969 -369.918744) (xy 433.099464 -369.928902)
			(xy 433.099464 -370.086636) (xy 433.099865 -370.095824) (xy 433.106386 -370.113008) (xy 433.112164 -370.120164)
			(xy 433.13394 -370.145826) (xy 433.171889 -370.201411) (xy 433.202922 -370.261133) (xy 433.226595 -370.324137)
			(xy 433.242569 -370.389518) (xy 433.250614 -370.456339) (xy 433.250615 -370.523643) (xy 433.242572 -370.590465)
			(xy 433.226601 -370.655846) (xy 433.20293 -370.71885) (xy 433.171898 -370.778573) (xy 433.133951 -370.83416)
			(xy 433.112164 -370.859812) (xy 433.106375 -370.866963) (xy 433.099857 -370.884149) (xy 433.099464 -370.89334)
			(xy 433.099464 -371.386862) (xy 433.099901 -371.396046) (xy 433.106397 -371.41323) (xy 433.112164 -371.42039)
			(xy 433.133966 -371.446031) (xy 433.171914 -371.501619) (xy 433.202946 -371.561344) (xy 433.226383 -371.623725)
			(xy 434.329029 -371.623725) (xy 434.329032 -371.556418) (xy 434.33708 -371.489593) (xy 434.353056 -371.424209)
			(xy 434.376732 -371.361203) (xy 434.407768 -371.301478) (xy 434.445719 -371.245891) (xy 434.467508 -371.220238)
			(xy 434.473314 -371.2131) (xy 434.479823 -371.195904) (xy 434.480208 -371.18671) (xy 434.480208 -371.028722)
			(xy 434.48075 -371.018569) (xy 434.488512 -370.999806) (xy 434.502863 -370.985441) (xy 434.521618 -370.977661)
			(xy 434.53177 -370.97716) (xy 435.24805 -370.97716) (xy 435.258221 -370.977605) (xy 435.277019 -370.985378)
			(xy 435.291406 -370.999758) (xy 435.299189 -371.018551) (xy 435.299612 -371.028722) (xy 435.299612 -371.18671)
			(xy 435.300015 -371.195898) (xy 435.306533 -371.213082) (xy 435.312312 -371.220238) (xy 435.334064 -371.24592)
			(xy 435.372017 -371.301501) (xy 435.403055 -371.36122) (xy 435.426732 -371.424221) (xy 435.442709 -371.4896)
			(xy 435.450757 -371.55642) (xy 435.45076 -371.623723) (xy 435.442719 -371.690544) (xy 435.426749 -371.755924)
			(xy 435.403078 -371.818928) (xy 435.372046 -371.87865) (xy 435.334099 -371.934235) (xy 435.312312 -371.959886)
			(xy 435.306498 -371.967019) (xy 435.299993 -371.984219) (xy 435.299612 -371.993414) (xy 435.299612 -372.486682)
			(xy 435.300028 -372.495869) (xy 435.306537 -372.513053) (xy 435.312312 -372.52021) (xy 435.334135 -372.545834)
			(xy 435.372086 -372.601423) (xy 435.40312 -372.66115) (xy 435.426793 -372.724159) (xy 435.442765 -372.789545)
			(xy 435.450807 -372.856371) (xy 435.450804 -372.92368) (xy 435.442756 -372.990506) (xy 435.426778 -373.05589)
			(xy 435.403099 -373.118896) (xy 435.372059 -373.178621) (xy 435.334103 -373.234206) (xy 435.312312 -373.259858)
			(xy 435.30651 -373.266999) (xy 435.299998 -373.284193) (xy 435.299612 -373.293386) (xy 435.299612 -373.451374)
			(xy 435.299213 -373.46155) (xy 435.291428 -373.480354) (xy 435.277034 -373.494741) (xy 435.258226 -373.502518)
			(xy 435.24805 -373.502936) (xy 434.53177 -373.502936) (xy 434.521607 -373.502491) (xy 434.502832 -373.494701)
			(xy 434.488467 -373.480321) (xy 434.480698 -373.461537) (xy 434.480208 -373.451374) (xy 434.480208 -373.293386)
			(xy 434.479803 -373.284198) (xy 434.473286 -373.267014) (xy 434.467508 -373.259858) (xy 434.445755 -373.234178)
			(xy 434.407807 -373.178595) (xy 434.376774 -373.118875) (xy 434.3531 -373.055874) (xy 434.337126 -372.990495)
			(xy 434.32908 -372.923676) (xy 434.329077 -372.856375) (xy 434.337117 -372.789555) (xy 434.353085 -372.724175)
			(xy 434.376753 -372.661172) (xy 434.40778 -372.601449) (xy 434.445723 -372.545863) (xy 434.467508 -372.52021)
			(xy 434.473326 -372.51308) (xy 434.479828 -372.495878) (xy 434.480208 -372.486682) (xy 434.480208 -371.993414)
			(xy 434.479789 -371.984228) (xy 434.473281 -371.967043) (xy 434.467508 -371.959886) (xy 434.445684 -371.934264)
			(xy 434.407738 -371.878673) (xy 434.376708 -371.818945) (xy 434.353039 -371.755936) (xy 434.33707 -371.690551)
			(xy 434.329029 -371.623725) (xy 433.226383 -371.623725) (xy 433.226618 -371.62435) (xy 433.24259 -371.689734)
			(xy 433.250633 -371.756557) (xy 433.250632 -371.823864) (xy 433.242586 -371.890687) (xy 433.226612 -371.95607)
			(xy 433.202938 -372.019075) (xy 433.171903 -372.078799) (xy 433.133953 -372.134386) (xy 433.112164 -372.160038)
			(xy 433.106364 -372.167181) (xy 433.099852 -372.184373) (xy 433.099464 -372.193566) (xy 433.099464 -372.351554)
			(xy 433.098999 -372.361722) (xy 433.091229 -372.380516) (xy 433.076856 -372.394902) (xy 433.05807 -372.402689)
			(xy 433.047902 -372.403116) (xy 432.331622 -372.403116) (xy 432.321446 -372.402717) (xy 432.302643 -372.394931)
			(xy 432.288256 -372.380537) (xy 432.280478 -372.36173) (xy 432.28006 -372.351554) (xy 432.28006 -372.193566)
			(xy 432.279653 -372.184379) (xy 432.273135 -372.167195) (xy 432.26736 -372.160038) (xy 432.245586 -372.134375)
			(xy 432.207635 -372.07879) (xy 432.1766 -372.019069) (xy 432.152925 -371.956065) (xy 432.136951 -371.890684)
			(xy 432.128905 -371.823863) (xy 432.128904 -371.756558) (xy 432.136947 -371.689736) (xy 432.152919 -371.624355)
			(xy 432.176591 -371.561351) (xy 432.207624 -371.501628) (xy 432.245573 -371.446042) (xy 432.26736 -371.42039)
			(xy 432.273151 -371.413241) (xy 432.279667 -371.396053) (xy 432.28006 -371.386862) (xy 432.28006 -370.89334)
			(xy 432.279617 -370.884157) (xy 432.273125 -370.866972) (xy 432.26736 -370.859812) (xy 432.24556 -370.83417)
			(xy 432.20761 -370.778582) (xy 432.176576 -370.718858) (xy 432.152903 -370.655852) (xy 432.136931 -370.590468)
			(xy 432.128887 -370.523644) (xy 428.850825 -370.523644) (xy 428.842782 -370.590464) (xy 428.826811 -370.655846)
			(xy 428.80314 -370.71885) (xy 428.772109 -370.778573) (xy 428.734163 -370.83416) (xy 428.712376 -370.859812)
			(xy 428.706589 -370.866964) (xy 428.700069 -370.884149) (xy 428.699676 -370.89334) (xy 428.699676 -371.386862)
			(xy 428.70011 -371.396047) (xy 428.706608 -371.413231) (xy 428.712376 -371.42039) (xy 428.734177 -371.446031)
			(xy 428.772125 -371.501619) (xy 428.803156 -371.561345) (xy 428.826615 -371.623785) (xy 429.928709 -371.623785)
			(xy 429.928713 -371.556358) (xy 429.936793 -371.489417) (xy 429.952833 -371.423925) (xy 429.976602 -371.360827)
			(xy 430.007759 -371.30103) (xy 430.045853 -371.245395) (xy 430.06772 -371.21973) (xy 430.073531 -371.212595)
			(xy 430.080036 -371.195397) (xy 430.08042 -371.186202) (xy 430.08042 -371.028722) (xy 430.080944 -371.018599)
			(xy 430.088661 -370.999882) (xy 430.102935 -370.985526) (xy 430.121608 -370.977702) (xy 430.131728 -370.97716)
			(xy 430.848008 -370.97716) (xy 430.858158 -370.977614) (xy 430.876902 -370.985405) (xy 430.891224 -370.999791)
			(xy 430.898931 -371.018571) (xy 430.899316 -371.028722) (xy 430.899316 -371.186202) (xy 430.899722 -371.19539)
			(xy 430.906238 -371.212574) (xy 430.912016 -371.21973) (xy 430.933842 -371.245426) (xy 430.971931 -371.301057)
			(xy 431.003082 -371.360849) (xy 431.026848 -371.423942) (xy 431.042886 -371.489427) (xy 431.050964 -371.556361)
			(xy 431.050968 -371.623782) (xy 431.042896 -371.690717) (xy 431.026865 -371.756204) (xy 431.003106 -371.819299)
			(xy 430.97196 -371.879094) (xy 430.933877 -371.934729) (xy 430.912016 -371.960394) (xy 430.906241 -371.967555)
			(xy 430.899713 -371.984733) (xy 430.899316 -371.993922) (xy 430.899316 -372.486174) (xy 430.899735 -372.49536)
			(xy 430.906242 -372.512545) (xy 430.912016 -372.519702) (xy 430.933913 -372.54534) (xy 430.971999 -372.600979)
			(xy 431.003148 -372.660779) (xy 431.026909 -372.723879) (xy 431.042942 -372.789371) (xy 431.051015 -372.856313)
			(xy 431.051012 -372.923739) (xy 431.042933 -372.990679) (xy 431.026894 -373.05617) (xy 431.003127 -373.119268)
			(xy 430.971973 -373.179065) (xy 430.933881 -373.2347) (xy 430.912016 -373.260366) (xy 430.906211 -373.267505)
			(xy 430.899701 -373.2847) (xy 430.899316 -373.293894) (xy 430.899316 -373.451374) (xy 430.898851 -373.461504)
			(xy 430.891124 -373.480233) (xy 430.87683 -373.494592) (xy 430.858136 -373.502405) (xy 430.848008 -373.502936)
			(xy 430.131728 -373.502936) (xy 430.12158 -373.502456) (xy 430.102835 -373.494677) (xy 430.088512 -373.480298)
			(xy 430.080805 -373.461523) (xy 430.08042 -373.451374) (xy 430.08042 -373.293894) (xy 430.080008 -373.284707)
			(xy 430.073495 -373.267523) (xy 430.06772 -373.260366) (xy 430.045889 -373.234674) (xy 430.007798 -373.179043)
			(xy 429.976644 -373.119251) (xy 429.952877 -373.056158) (xy 429.936839 -372.990672) (xy 429.92876 -372.923736)
			(xy 429.928757 -372.856315) (xy 429.93683 -372.789379) (xy 429.952862 -372.723891) (xy 429.976624 -372.660796)
			(xy 430.007771 -372.601) (xy 430.045857 -372.545367) (xy 430.06772 -372.519702) (xy 430.073501 -372.512546)
			(xy 430.080024 -372.495364) (xy 430.08042 -372.486174) (xy 430.08042 -371.993922) (xy 430.079995 -371.984737)
			(xy 430.073491 -371.967552) (xy 430.06772 -371.960394) (xy 430.045818 -371.93476) (xy 430.007729 -371.879121)
			(xy 429.976579 -371.819321) (xy 429.952816 -371.75622) (xy 429.936783 -371.690727) (xy 429.928709 -371.623785)
			(xy 428.826615 -371.623785) (xy 428.826828 -371.624351) (xy 428.842799 -371.689734) (xy 428.850842 -371.756558)
			(xy 428.850841 -371.823863) (xy 428.842795 -371.890687) (xy 428.826821 -371.95607) (xy 428.803148 -372.019075)
			(xy 428.772114 -372.078799) (xy 428.734164 -372.134386) (xy 428.712376 -372.160038) (xy 428.706578 -372.167182)
			(xy 428.700065 -372.184374) (xy 428.699676 -372.193566) (xy 428.699676 -372.351554) (xy 428.699199 -372.361721)
			(xy 428.691432 -372.380512) (xy 428.677062 -372.394898) (xy 428.65828 -372.402687) (xy 428.648114 -372.403116)
			(xy 427.931834 -372.403116) (xy 427.921659 -372.402707) (xy 427.902856 -372.394925) (xy 427.888469 -372.380534)
			(xy 427.880691 -372.361729) (xy 427.880272 -372.351554) (xy 427.880272 -372.193566) (xy 427.879884 -372.184376)
			(xy 427.873356 -372.167192) (xy 427.867572 -372.160038) (xy 427.845797 -372.134375) (xy 427.807846 -372.078791)
			(xy 427.77681 -372.019069) (xy 427.753135 -371.956066) (xy 427.73716 -371.890685) (xy 427.729114 -371.823863)
			(xy 427.729113 -371.756558) (xy 427.737156 -371.689736) (xy 427.753129 -371.624354) (xy 427.776801 -371.56135)
			(xy 427.807835 -371.501627) (xy 427.845784 -371.446042) (xy 427.867572 -371.42039) (xy 427.873364 -371.413242)
			(xy 427.879879 -371.396053) (xy 427.880272 -371.386862) (xy 427.880272 -370.89334) (xy 427.879849 -370.884154)
			(xy 427.873345 -370.866969) (xy 427.867572 -370.859812) (xy 427.845772 -370.83417) (xy 427.807821 -370.778583)
			(xy 427.776786 -370.718858) (xy 427.753113 -370.655852) (xy 427.73714 -370.590468) (xy 427.729096 -370.523644)
			(xy 424.451056 -370.523644) (xy 424.451056 -370.523703) (xy 424.442981 -370.59064) (xy 424.426947 -370.656129)
			(xy 424.403183 -370.719225) (xy 424.372033 -370.779021) (xy 424.333944 -370.834655) (xy 424.31208 -370.86032)
			(xy 424.30629 -370.86747) (xy 424.299772 -370.884657) (xy 424.29938 -370.893848) (xy 424.29938 -371.386354)
			(xy 424.299817 -371.395538) (xy 424.306312 -371.412723) (xy 424.31208 -371.419882) (xy 424.333958 -371.445536)
			(xy 424.372048 -371.501171) (xy 424.403199 -371.560969) (xy 424.426835 -371.623725) (xy 425.528941 -371.623725)
			(xy 425.528945 -371.556418) (xy 425.536992 -371.489593) (xy 425.552969 -371.424208) (xy 425.576645 -371.361202)
			(xy 425.607682 -371.301478) (xy 425.645634 -371.24589) (xy 425.667424 -371.220238) (xy 425.673232 -371.213101)
			(xy 425.679739 -371.195904) (xy 425.680124 -371.18671) (xy 425.680124 -371.028722) (xy 425.680582 -371.018554)
			(xy 425.688357 -370.999762) (xy 425.702732 -370.985377) (xy 425.721518 -370.977589) (xy 425.731686 -370.97716)
			(xy 426.447966 -370.97716) (xy 426.458138 -370.977592) (xy 426.476936 -370.98537) (xy 426.491323 -370.999754)
			(xy 426.499105 -371.01855) (xy 426.499528 -371.028722) (xy 426.499528 -371.18671) (xy 426.499927 -371.195898)
			(xy 426.506448 -371.213083) (xy 426.512228 -371.220238) (xy 426.533979 -371.24592) (xy 426.571931 -371.301502)
			(xy 426.602968 -371.361221) (xy 426.626645 -371.424221) (xy 426.642621 -371.4896) (xy 426.650669 -371.55642)
			(xy 426.650672 -371.623723) (xy 426.642631 -371.690543) (xy 426.626661 -371.755924) (xy 426.602991 -371.818927)
			(xy 426.571961 -371.878649) (xy 426.534014 -371.934234) (xy 426.512228 -371.959886) (xy 426.506404 -371.967011)
			(xy 426.499908 -371.984217) (xy 426.499528 -371.993414) (xy 426.499528 -372.486682) (xy 426.49994 -372.495869)
			(xy 426.506452 -372.513054) (xy 426.512228 -372.52021) (xy 426.53405 -372.545834) (xy 426.572 -372.601424)
			(xy 426.603034 -372.661151) (xy 426.626706 -372.724159) (xy 426.642678 -372.789545) (xy 426.65072 -372.856371)
			(xy 426.650717 -372.92368) (xy 426.642669 -372.990505) (xy 426.626691 -373.05589) (xy 426.603013 -373.118896)
			(xy 426.571974 -373.17862) (xy 426.534019 -373.234206) (xy 426.512228 -373.259858) (xy 426.506416 -373.266992)
			(xy 426.499912 -373.284191) (xy 426.499528 -373.293386) (xy 426.499528 -373.451374) (xy 426.499114 -373.461548)
			(xy 426.491331 -373.480349) (xy 426.476942 -373.494736) (xy 426.45814 -373.502515) (xy 426.447966 -373.502936)
			(xy 425.731686 -373.502936) (xy 425.72151 -373.502547) (xy 425.70271 -373.494752) (xy 425.688325 -373.480356)
			(xy 425.680545 -373.46155) (xy 425.680124 -373.451374) (xy 425.680124 -373.293386) (xy 425.679715 -373.284199)
			(xy 425.6732 -373.267015) (xy 425.667424 -373.259858) (xy 425.64567 -373.234178) (xy 425.607722 -373.178595)
			(xy 425.576688 -373.118875) (xy 425.553014 -373.055874) (xy 425.537039 -372.990496) (xy 425.528992 -372.923677)
			(xy 425.528989 -372.856375) (xy 425.53703 -372.789555) (xy 425.552999 -372.724174) (xy 425.576667 -372.661171)
			(xy 425.607695 -372.601449) (xy 425.645639 -372.545863) (xy 425.667424 -372.52021) (xy 425.673244 -372.513082)
			(xy 425.679744 -372.495878) (xy 425.680124 -372.486682) (xy 425.680124 -371.993414) (xy 425.679702 -371.984228)
			(xy 425.673196 -371.967044) (xy 425.667424 -371.959886) (xy 425.645599 -371.934264) (xy 425.607653 -371.878673)
			(xy 425.576622 -371.818945) (xy 425.552952 -371.755937) (xy 425.536982 -371.690551) (xy 425.528941 -371.623725)
			(xy 424.426835 -371.623725) (xy 424.426964 -371.624067) (xy 424.442999 -371.689558) (xy 424.451074 -371.756498)
			(xy 424.451072 -371.823923) (xy 424.442995 -371.890863) (xy 424.426957 -371.956353) (xy 424.403191 -372.01945)
			(xy 424.372037 -372.079247) (xy 424.333946 -372.134881) (xy 424.31208 -372.160546) (xy 424.306279 -372.167688)
			(xy 424.299768 -372.184881) (xy 424.29938 -372.194074) (xy 424.29938 -372.351554) (xy 424.298836 -372.361675)
			(xy 424.291127 -372.380392) (xy 424.276858 -372.394749) (xy 424.25819 -372.402573) (xy 424.248072 -372.403116)
			(xy 423.531792 -372.403116) (xy 423.521685 -372.402622) (xy 423.50301 -372.394884) (xy 423.488716 -372.38059)
			(xy 423.480978 -372.361915) (xy 423.480484 -372.351808) (xy 423.480484 -372.194074) (xy 423.48009 -372.184885)
			(xy 423.473565 -372.167701) (xy 423.467784 -372.160546) (xy 423.445934 -372.134869) (xy 423.407846 -372.079236)
			(xy 423.376696 -372.019441) (xy 423.352932 -371.956346) (xy 423.336896 -371.890858) (xy 423.328819 -371.823922)
			(xy 423.328818 -371.756499) (xy 423.336892 -371.689562) (xy 423.352925 -371.624074) (xy 423.376687 -371.560978)
			(xy 423.407835 -371.501182) (xy 423.445921 -371.445547) (xy 423.467784 -371.419882) (xy 423.473569 -371.412728)
			(xy 423.480091 -371.395544) (xy 423.480484 -371.386354) (xy 423.480484 -370.893848) (xy 423.480055 -370.884663)
			(xy 423.473555 -370.867478) (xy 423.467784 -370.86032) (xy 423.445909 -370.834664) (xy 423.407821 -370.779028)
			(xy 423.376672 -370.71923) (xy 423.352909 -370.656132) (xy 423.336875 -370.590642) (xy 423.328801 -370.523703)
			(xy 420.05073 -370.523703) (xy 420.042694 -370.590464) (xy 420.026724 -370.655845) (xy 420.003054 -370.718849)
			(xy 419.972023 -370.778573) (xy 419.934078 -370.834159) (xy 419.912292 -370.859812) (xy 419.906507 -370.866965)
			(xy 419.899986 -370.88415) (xy 419.899592 -370.89334) (xy 419.899592 -371.386862) (xy 419.900022 -371.396047)
			(xy 419.906522 -371.413231) (xy 419.912292 -371.42039) (xy 419.934093 -371.446031) (xy 419.972039 -371.50162)
			(xy 420.00307 -371.561345) (xy 420.026528 -371.623785) (xy 421.128621 -371.623785) (xy 421.128625 -371.556358)
			(xy 421.136705 -371.489416) (xy 421.152746 -371.423925) (xy 421.176516 -371.360826) (xy 421.207673 -371.301029)
			(xy 421.245769 -371.245395) (xy 421.267636 -371.21973) (xy 421.273449 -371.212597) (xy 421.279953 -371.195397)
			(xy 421.280336 -371.186202) (xy 421.280336 -371.028722) (xy 421.280844 -371.018597) (xy 421.288564 -370.999877)
			(xy 421.302844 -370.98552) (xy 421.321522 -370.9777) (xy 421.331644 -370.97716) (xy 422.047924 -370.97716)
			(xy 422.058029 -370.977664) (xy 422.076701 -370.985402) (xy 422.090993 -370.999693) (xy 422.098734 -371.018363)
			(xy 422.099232 -371.028468) (xy 422.099232 -371.186202) (xy 422.099656 -371.195387) (xy 422.106162 -371.212571)
			(xy 422.111932 -371.21973) (xy 422.133758 -371.245427) (xy 422.171845 -371.301057) (xy 422.202996 -371.36085)
			(xy 422.226761 -371.423942) (xy 422.242798 -371.489427) (xy 422.250876 -371.556361) (xy 422.25088 -371.623781)
			(xy 422.242808 -371.690717) (xy 422.226778 -371.756203) (xy 422.203019 -371.819298) (xy 422.171875 -371.879094)
			(xy 422.133793 -371.934728) (xy 422.111932 -371.960394) (xy 422.106147 -371.967547) (xy 422.099627 -371.984732)
			(xy 422.099232 -371.993922) (xy 422.099232 -372.486174) (xy 422.09967 -372.495358) (xy 422.106166 -372.512542)
			(xy 422.111932 -372.519702) (xy 422.133828 -372.54534) (xy 422.171914 -372.600979) (xy 422.203061 -372.66078)
			(xy 422.226822 -372.72388) (xy 422.242854 -372.789372) (xy 422.250927 -372.856313) (xy 422.250924 -372.923738)
			(xy 422.242845 -372.990678) (xy 422.226807 -373.056169) (xy 422.20304 -373.119267) (xy 422.171888 -373.179064)
			(xy 422.133797 -373.2347) (xy 422.111932 -373.260366) (xy 422.106117 -373.267498) (xy 422.099615 -373.284699)
			(xy 422.099232 -373.293894) (xy 422.099232 -373.451374) (xy 422.098751 -373.461503) (xy 422.091027 -373.480228)
			(xy 422.076738 -373.494587) (xy 422.05805 -373.502402) (xy 422.047924 -373.502936) (xy 421.331644 -373.502936)
			(xy 421.321529 -373.502449) (xy 421.302833 -373.494722) (xy 421.288519 -373.480427) (xy 421.280765 -373.461743)
			(xy 421.280336 -373.451628) (xy 421.280336 -373.293894) (xy 421.279921 -373.284708) (xy 421.27341 -373.267524)
			(xy 421.267636 -373.260366) (xy 421.245804 -373.234674) (xy 421.207712 -373.179044) (xy 421.176558 -373.119252)
			(xy 421.15279 -373.056158) (xy 421.136751 -372.990672) (xy 421.128672 -372.923736) (xy 421.128669 -372.856315)
			(xy 421.136742 -372.789378) (xy 421.152775 -372.72389) (xy 421.176537 -372.660795) (xy 421.207686 -372.601)
			(xy 421.245773 -372.545367) (xy 421.267636 -372.519702) (xy 421.273419 -372.512547) (xy 421.279941 -372.495364)
			(xy 421.280336 -372.486174) (xy 421.280336 -371.993922) (xy 421.279907 -371.984737) (xy 421.273406 -371.967553)
			(xy 421.267636 -371.960394) (xy 421.245733 -371.93476) (xy 421.207643 -371.879122) (xy 421.176492 -371.819322)
			(xy 421.152729 -371.756221) (xy 421.136695 -371.690727) (xy 421.128621 -371.623785) (xy 420.026528 -371.623785)
			(xy 420.026741 -371.624351) (xy 420.042712 -371.689734) (xy 420.050754 -371.756558) (xy 420.050753 -371.823863)
			(xy 420.042708 -371.890686) (xy 420.026734 -371.956069) (xy 420.003061 -372.019074) (xy 419.972028 -372.078798)
			(xy 419.93408 -372.134385) (xy 419.912292 -372.160038) (xy 419.906496 -372.167183) (xy 419.899981 -372.184374)
			(xy 419.899592 -372.193566) (xy 419.899592 -372.351554) (xy 419.899099 -372.361719) (xy 419.891335 -372.380507)
			(xy 419.876971 -372.394892) (xy 419.858194 -372.402684) (xy 419.84803 -372.403116) (xy 419.13175 -372.403116)
			(xy 419.121576 -372.402694) (xy 419.102773 -372.394917) (xy 419.088385 -372.38053) (xy 419.080607 -372.361728)
			(xy 419.080188 -372.351554) (xy 419.080188 -372.193566) (xy 419.079797 -372.184377) (xy 419.07327 -372.167192)
			(xy 419.067488 -372.160038) (xy 419.045713 -372.134375) (xy 419.00776 -372.078791) (xy 418.976724 -372.01907)
			(xy 418.953048 -371.956067) (xy 418.937072 -371.890685) (xy 418.929026 -371.823863) (xy 418.929025 -371.756558)
			(xy 418.937069 -371.689736) (xy 418.953042 -371.624354) (xy 418.976715 -371.561349) (xy 419.007749 -371.501627)
			(xy 419.0457 -371.446041) (xy 419.067488 -371.42039) (xy 419.07327 -371.413234) (xy 419.079794 -371.396052)
			(xy 419.080188 -371.386862) (xy 419.080188 -370.89334) (xy 419.079761 -370.884154) (xy 419.07326 -370.86697)
			(xy 419.067488 -370.859812) (xy 419.045687 -370.83417) (xy 419.007735 -370.778583) (xy 418.9767 -370.718859)
			(xy 418.953026 -370.655853) (xy 418.937052 -370.590469) (xy 418.929008 -370.523644) (xy 389.250706 -370.523644)
			(xy 389.242663 -370.590465) (xy 389.226691 -370.655847) (xy 389.203019 -370.718851) (xy 389.171987 -370.778574)
			(xy 389.134039 -370.83416) (xy 389.112252 -370.859812) (xy 389.106462 -370.866962) (xy 389.099945 -370.884149)
			(xy 389.099552 -370.89334) (xy 389.099552 -371.386862) (xy 389.099991 -371.396046) (xy 389.106486 -371.41323)
			(xy 389.112252 -371.42039) (xy 389.134054 -371.446031) (xy 389.172003 -371.501618) (xy 389.203036 -371.561344)
			(xy 389.226474 -371.623725) (xy 390.32912 -371.623725) (xy 390.329123 -371.556418) (xy 390.337171 -371.489593)
			(xy 390.353146 -371.42421) (xy 390.376822 -371.361204) (xy 390.407857 -371.301479) (xy 390.445807 -371.245891)
			(xy 390.467596 -371.220238) (xy 390.473401 -371.213099) (xy 390.479911 -371.195904) (xy 390.480296 -371.18671)
			(xy 390.480296 -371.028722) (xy 390.48085 -371.018571) (xy 390.48861 -370.99981) (xy 390.502956 -370.985446)
			(xy 390.521707 -370.977663) (xy 390.531858 -370.97716) (xy 391.248138 -370.97716) (xy 391.258301 -370.977603)
			(xy 391.277075 -370.985394) (xy 391.29144 -370.999775) (xy 391.299209 -371.018558) (xy 391.2997 -371.028722)
			(xy 391.2997 -371.18671) (xy 391.300106 -371.195898) (xy 391.306623 -371.213082) (xy 391.3124 -371.220238)
			(xy 391.334149 -371.245921) (xy 391.372097 -371.301504) (xy 391.403129 -371.361224) (xy 391.426803 -371.424224)
			(xy 391.442777 -371.489602) (xy 391.450824 -371.556421) (xy 391.450827 -371.623722) (xy 391.442787 -371.690541)
			(xy 391.42682 -371.755921) (xy 391.403153 -371.818924) (xy 391.372126 -371.878647) (xy 391.334184 -371.934233)
			(xy 391.3124 -371.959886) (xy 391.306584 -371.967018) (xy 391.300081 -371.984219) (xy 391.2997 -371.993414)
			(xy 391.2997 -372.486682) (xy 391.300119 -372.495868) (xy 391.306627 -372.513053) (xy 391.3124 -372.52021)
			(xy 391.33422 -372.545835) (xy 391.372165 -372.601426) (xy 391.403195 -372.661154) (xy 391.426864 -372.724162)
			(xy 391.442833 -372.789547) (xy 391.450874 -372.856372) (xy 391.450871 -372.923679) (xy 391.442824 -372.990503)
			(xy 391.426849 -373.055887) (xy 391.403174 -373.118893) (xy 391.372139 -373.178617) (xy 391.334189 -373.234205)
			(xy 391.3124 -373.259858) (xy 391.306596 -373.266998) (xy 391.300086 -373.284193) (xy 391.2997 -373.293386)
			(xy 391.2997 -373.451374) (xy 391.299146 -373.461525) (xy 391.291388 -373.480287) (xy 391.277041 -373.494652)
			(xy 391.258289 -373.502434) (xy 391.248138 -373.502936) (xy 390.531858 -373.502936) (xy 390.521694 -373.5025)
			(xy 390.502919 -373.494707) (xy 390.488555 -373.480324) (xy 390.480786 -373.461538) (xy 390.480296 -373.451374)
			(xy 390.480296 -373.293386) (xy 390.479893 -373.284198) (xy 390.473374 -373.267014) (xy 390.467596 -373.259858)
			(xy 390.445843 -373.234178) (xy 390.407896 -373.178594) (xy 390.376864 -373.118874) (xy 390.353191 -373.055874)
			(xy 390.337217 -372.990495) (xy 390.329171 -372.923676) (xy 390.329167 -372.856375) (xy 390.337208 -372.789555)
			(xy 390.353176 -372.724175) (xy 390.376843 -372.661173) (xy 390.40787 -372.60145) (xy 390.445812 -372.545863)
			(xy 390.467596 -372.52021) (xy 390.473413 -372.513079) (xy 390.479916 -372.495878) (xy 390.480296 -372.486682)
			(xy 390.480296 -371.993414) (xy 390.47988 -371.984227) (xy 390.47337 -371.967043) (xy 390.467596 -371.959886)
			(xy 390.445772 -371.934264) (xy 390.407827 -371.878672) (xy 390.376798 -371.818944) (xy 390.353129 -371.755936)
			(xy 390.33716 -371.69055) (xy 390.32912 -371.623725) (xy 389.226474 -371.623725) (xy 389.226709 -371.62435)
			(xy 389.242681 -371.689733) (xy 389.250724 -371.756557) (xy 389.250723 -371.823864) (xy 389.242677 -371.890687)
			(xy 389.226702 -371.956071) (xy 389.203028 -372.019076) (xy 389.171992 -372.0788) (xy 389.134041 -372.134386)
			(xy 389.112252 -372.160038) (xy 389.106451 -372.16718) (xy 389.09994 -372.184373) (xy 389.099552 -372.193566)
			(xy 389.099552 -372.351554) (xy 389.099098 -372.361724) (xy 389.091327 -372.380519) (xy 389.07695 -372.394906)
			(xy 389.05816 -372.402691) (xy 389.04799 -372.403116) (xy 388.33171 -372.403116) (xy 388.321533 -372.402727)
			(xy 388.30273 -372.394937) (xy 388.288343 -372.38054) (xy 388.280566 -372.361731) (xy 388.280148 -372.351554)
			(xy 388.280148 -372.193566) (xy 388.279743 -372.184378) (xy 388.273225 -372.167195) (xy 388.267448 -372.160038)
			(xy 388.245674 -372.134375) (xy 388.207724 -372.07879) (xy 388.17669 -372.019068) (xy 388.153016 -371.956065)
			(xy 388.137042 -371.890684) (xy 388.128996 -371.823863) (xy 388.128995 -371.756558) (xy 388.137038 -371.689737)
			(xy 388.15301 -371.624355) (xy 388.176681 -371.561351) (xy 388.207713 -371.501628) (xy 388.245661 -371.446042)
			(xy 388.267448 -371.42039) (xy 388.273237 -371.41324) (xy 388.279755 -371.396053) (xy 388.280148 -371.386862)
			(xy 388.280148 -370.89334) (xy 388.279708 -370.884156) (xy 388.273214 -370.866972) (xy 388.267448 -370.859812)
			(xy 388.245648 -370.83417) (xy 388.207699 -370.778582) (xy 388.176666 -370.718857) (xy 388.152993 -370.655851)
			(xy 388.137021 -370.590468) (xy 388.128977 -370.523644) (xy 384.850915 -370.523644) (xy 384.842872 -370.590465)
			(xy 384.826901 -370.655846) (xy 384.80323 -370.71885) (xy 384.772198 -370.778573) (xy 384.734251 -370.83416)
			(xy 384.712464 -370.859812) (xy 384.706675 -370.866963) (xy 384.700157 -370.884149) (xy 384.699764 -370.89334)
			(xy 384.699764 -371.386862) (xy 384.700201 -371.396046) (xy 384.706697 -371.41323) (xy 384.712464 -371.42039)
			(xy 384.734266 -371.446031) (xy 384.772214 -371.501619) (xy 384.803246 -371.561344) (xy 384.826706 -371.623785)
			(xy 385.9288 -371.623785) (xy 385.928804 -371.556358) (xy 385.936884 -371.489417) (xy 385.952923 -371.423926)
			(xy 385.976692 -371.360827) (xy 386.007848 -371.30103) (xy 386.045941 -371.245395) (xy 386.067808 -371.21973)
			(xy 386.073618 -371.212594) (xy 386.080124 -371.195396) (xy 386.080508 -371.186202) (xy 386.080508 -371.028722)
			(xy 386.081044 -371.018601) (xy 386.088758 -370.999886) (xy 386.103029 -370.98553) (xy 386.121698 -370.977704)
			(xy 386.131816 -370.97716) (xy 386.848096 -370.97716) (xy 386.858245 -370.977624) (xy 386.876989 -370.985411)
			(xy 386.891311 -370.999794) (xy 386.899019 -371.018571) (xy 386.899404 -371.028722) (xy 386.899404 -371.186202)
			(xy 386.899812 -371.195389) (xy 386.906327 -371.212574) (xy 386.912104 -371.21973) (xy 386.93393 -371.245426)
			(xy 386.97202 -371.301056) (xy 387.003172 -371.360848) (xy 387.026938 -371.423941) (xy 387.042976 -371.489426)
			(xy 387.051055 -371.556361) (xy 387.051059 -371.623782) (xy 387.042987 -371.690717) (xy 387.026955 -371.756204)
			(xy 387.003196 -371.8193) (xy 386.972049 -371.879095) (xy 386.933966 -371.934729) (xy 386.912104 -371.960394)
			(xy 386.906328 -371.967554) (xy 386.899801 -371.984733) (xy 386.899404 -371.993922) (xy 386.899404 -372.486174)
			(xy 386.899826 -372.49536) (xy 386.906331 -372.512545) (xy 386.912104 -372.519702) (xy 386.934001 -372.54534)
			(xy 386.972089 -372.600978) (xy 387.003238 -372.660778) (xy 387.027 -372.723879) (xy 387.043033 -372.789371)
			(xy 387.051106 -372.856312) (xy 387.051103 -372.923739) (xy 387.043024 -372.990679) (xy 387.026985 -373.05617)
			(xy 387.003217 -373.119268) (xy 386.972062 -373.179066) (xy 386.93397 -373.234701) (xy 386.912104 -373.260366)
			(xy 386.906297 -373.267504) (xy 386.899789 -373.2847) (xy 386.899404 -373.293894) (xy 386.899404 -373.451374)
			(xy 386.898854 -373.461494) (xy 386.891142 -373.480206) (xy 386.876876 -373.494562) (xy 386.858212 -373.50239)
			(xy 386.848096 -373.502936) (xy 386.131816 -373.502936) (xy 386.121667 -373.502466) (xy 386.102922 -373.494683)
			(xy 386.0886 -373.480301) (xy 386.080893 -373.461524) (xy 386.080508 -373.451374) (xy 386.080508 -373.293894)
			(xy 386.080099 -373.284707) (xy 386.073584 -373.267523) (xy 386.067808 -373.260366) (xy 386.045977 -373.234673)
			(xy 386.007887 -373.179043) (xy 385.976734 -373.119251) (xy 385.952968 -373.056157) (xy 385.93693 -372.990671)
			(xy 385.928851 -372.923736) (xy 385.928848 -372.856315) (xy 385.936921 -372.789379) (xy 385.952953 -372.723892)
			(xy 385.976713 -372.660796) (xy 386.007861 -372.601001) (xy 386.045946 -372.545367) (xy 386.067808 -372.519702)
			(xy 386.073587 -372.512544) (xy 386.080112 -372.495363) (xy 386.080508 -372.486174) (xy 386.080508 -371.993922)
			(xy 386.080085 -371.984736) (xy 386.07358 -371.967552) (xy 386.067808 -371.960394) (xy 386.045906 -371.93476)
			(xy 386.007818 -371.879121) (xy 385.976669 -371.819321) (xy 385.952906 -371.75622) (xy 385.936873 -371.690727)
			(xy 385.9288 -371.623785) (xy 384.826706 -371.623785) (xy 384.826918 -371.62435) (xy 384.84289 -371.689734)
			(xy 384.850933 -371.756557) (xy 384.850932 -371.823864) (xy 384.842886 -371.890687) (xy 384.826912 -371.95607)
			(xy 384.803238 -372.019075) (xy 384.772203 -372.078799) (xy 384.734253 -372.134386) (xy 384.712464 -372.160038)
			(xy 384.706664 -372.167181) (xy 384.700152 -372.184373) (xy 384.699764 -372.193566) (xy 384.699764 -372.351554)
			(xy 384.699299 -372.361722) (xy 384.691529 -372.380516) (xy 384.677156 -372.394902) (xy 384.65837 -372.402689)
			(xy 384.648202 -372.403116) (xy 383.931922 -372.403116) (xy 383.921746 -372.402717) (xy 383.902943 -372.394931)
			(xy 383.888556 -372.380537) (xy 383.880778 -372.36173) (xy 383.88036 -372.351554) (xy 383.88036 -372.193566)
			(xy 383.879953 -372.184379) (xy 383.873435 -372.167195) (xy 383.86766 -372.160038) (xy 383.845886 -372.134375)
			(xy 383.807935 -372.07879) (xy 383.7769 -372.019069) (xy 383.753225 -371.956065) (xy 383.737251 -371.890684)
			(xy 383.729205 -371.823863) (xy 383.729204 -371.756558) (xy 383.737247 -371.689736) (xy 383.753219 -371.624355)
			(xy 383.776891 -371.561351) (xy 383.807924 -371.501628) (xy 383.845873 -371.446042) (xy 383.86766 -371.42039)
			(xy 383.873451 -371.413241) (xy 383.879967 -371.396053) (xy 383.88036 -371.386862) (xy 383.88036 -370.89334)
			(xy 383.879917 -370.884157) (xy 383.873425 -370.866972) (xy 383.86766 -370.859812) (xy 383.84586 -370.83417)
			(xy 383.80791 -370.778582) (xy 383.776876 -370.718858) (xy 383.753203 -370.655852) (xy 383.737231 -370.590468)
			(xy 383.729187 -370.523644) (xy 380.451147 -370.523644) (xy 380.451147 -370.523703) (xy 380.443072 -370.590641)
			(xy 380.427037 -370.656129) (xy 380.403273 -370.719226) (xy 380.372122 -370.779022) (xy 380.334032 -370.834655)
			(xy 380.312168 -370.86032) (xy 380.306376 -370.867469) (xy 380.299859 -370.884657) (xy 380.299468 -370.893848)
			(xy 380.299468 -371.386354) (xy 380.299908 -371.395538) (xy 380.306402 -371.412722) (xy 380.312168 -371.419882)
			(xy 380.334047 -371.445535) (xy 380.372137 -371.501171) (xy 380.403289 -371.560968) (xy 380.426925 -371.623725)
			(xy 381.529032 -371.623725) (xy 381.529035 -371.556418) (xy 381.537083 -371.489593) (xy 381.553059 -371.424209)
			(xy 381.576735 -371.361203) (xy 381.607771 -371.301478) (xy 381.645723 -371.245891) (xy 381.667512 -371.220238)
			(xy 381.673319 -371.2131) (xy 381.679827 -371.195904) (xy 381.680212 -371.18671) (xy 381.680212 -371.028722)
			(xy 381.680751 -371.018569) (xy 381.688513 -370.999805) (xy 381.702865 -370.98544) (xy 381.721621 -370.97766)
			(xy 381.731774 -370.97716) (xy 382.448054 -370.97716) (xy 382.458225 -370.977602) (xy 382.477023 -370.985376)
			(xy 382.491411 -370.999757) (xy 382.499193 -371.018551) (xy 382.499616 -371.028722) (xy 382.499616 -371.18671)
			(xy 382.500018 -371.195898) (xy 382.506537 -371.213083) (xy 382.512316 -371.220238) (xy 382.534068 -371.24592)
			(xy 382.572021 -371.301501) (xy 382.603058 -371.36122) (xy 382.626735 -371.424221) (xy 382.642712 -371.4896)
			(xy 382.65076 -371.55642) (xy 382.650763 -371.623723) (xy 382.642722 -371.690544) (xy 382.626752 -371.755924)
			(xy 382.603081 -371.818927) (xy 382.57205 -371.87865) (xy 382.534103 -371.934234) (xy 382.512316 -371.959886)
			(xy 382.506502 -371.967019) (xy 382.499997 -371.984219) (xy 382.499616 -371.993414) (xy 382.499616 -372.486682)
			(xy 382.500031 -372.495869) (xy 382.506541 -372.513053) (xy 382.512316 -372.52021) (xy 382.534138 -372.545834)
			(xy 382.572089 -372.601424) (xy 382.603123 -372.661151) (xy 382.626796 -372.724159) (xy 382.642768 -372.789545)
			(xy 382.65081 -372.856371) (xy 382.650807 -372.92368) (xy 382.642759 -372.990506) (xy 382.626781 -373.05589)
			(xy 382.603103 -373.118896) (xy 382.572063 -373.17862) (xy 382.534107 -373.234206) (xy 382.512316 -373.259858)
			(xy 382.506514 -373.267) (xy 382.500002 -373.284193) (xy 382.499616 -373.293386) (xy 382.499616 -373.451374)
			(xy 382.499214 -373.46155) (xy 382.491429 -373.480352) (xy 382.477036 -373.49474) (xy 382.45823 -373.502517)
			(xy 382.448054 -373.502936) (xy 381.731774 -373.502936) (xy 381.721611 -373.502487) (xy 381.702837 -373.4947)
			(xy 381.688471 -373.48032) (xy 381.680702 -373.461537) (xy 381.680212 -373.451374) (xy 381.680212 -373.293386)
			(xy 381.679806 -373.284198) (xy 381.673289 -373.267014) (xy 381.667512 -373.259858) (xy 381.645758 -373.234178)
			(xy 381.60781 -373.178595) (xy 381.576777 -373.118875) (xy 381.553104 -373.055874) (xy 381.537129 -372.990496)
			(xy 381.529083 -372.923676) (xy 381.52908 -372.856375) (xy 381.53712 -372.789555) (xy 381.553088 -372.724175)
			(xy 381.576756 -372.661172) (xy 381.607784 -372.601449) (xy 381.645727 -372.545862) (xy 381.667512 -372.52021)
			(xy 381.673331 -372.51308) (xy 381.679832 -372.495878) (xy 381.680212 -372.486682) (xy 381.680212 -371.993414)
			(xy 381.679792 -371.984228) (xy 381.673285 -371.967044) (xy 381.667512 -371.959886) (xy 381.645688 -371.934264)
			(xy 381.607742 -371.878673) (xy 381.576712 -371.818945) (xy 381.553042 -371.755936) (xy 381.537073 -371.690551)
			(xy 381.529032 -371.623725) (xy 380.426925 -371.623725) (xy 380.427054 -371.624067) (xy 380.443089 -371.689558)
			(xy 380.451165 -371.756498) (xy 380.451163 -371.823923) (xy 380.443086 -371.890863) (xy 380.427048 -371.956353)
			(xy 380.403281 -372.019451) (xy 380.372126 -372.079247) (xy 380.334034 -372.134881) (xy 380.312168 -372.160546)
			(xy 380.306365 -372.167687) (xy 380.299855 -372.184881) (xy 380.299468 -372.194074) (xy 380.299468 -372.351554)
			(xy 380.298936 -372.361677) (xy 380.291225 -372.380395) (xy 380.276952 -372.394753) (xy 380.25828 -372.402575)
			(xy 380.24816 -372.403116) (xy 379.53188 -372.403116) (xy 379.521727 -372.402695) (xy 379.502977 -372.394896)
			(xy 379.488655 -372.3805) (xy 379.480953 -372.36171) (xy 379.480572 -372.351554) (xy 379.480572 -372.194074)
			(xy 379.480181 -372.184885) (xy 379.473655 -372.1677) (xy 379.467872 -372.160546) (xy 379.446023 -372.134869)
			(xy 379.407935 -372.079235) (xy 379.376786 -372.019441) (xy 379.353022 -371.956345) (xy 379.336986 -371.890858)
			(xy 379.32891 -371.823922) (xy 379.328909 -371.7565) (xy 379.336983 -371.689563) (xy 379.353016 -371.624075)
			(xy 379.376777 -371.560979) (xy 379.407925 -371.501183) (xy 379.44601 -371.445548) (xy 379.467872 -371.419882)
			(xy 379.473667 -371.412736) (xy 379.480181 -371.395546) (xy 379.480572 -371.386354) (xy 379.480572 -370.893848)
			(xy 379.480145 -370.884663) (xy 379.473644 -370.867478) (xy 379.467872 -370.86032) (xy 379.445997 -370.834664)
			(xy 379.407911 -370.779027) (xy 379.376762 -370.71923) (xy 379.353 -370.656132) (xy 379.336966 -370.590642)
			(xy 379.328892 -370.523703) (xy 376.050821 -370.523703) (xy 376.042785 -370.590464) (xy 376.026814 -370.655846)
			(xy 376.003143 -370.71885) (xy 375.972113 -370.778573) (xy 375.934166 -370.83416) (xy 375.91238 -370.859812)
			(xy 375.906594 -370.866964) (xy 375.900073 -370.884149) (xy 375.89968 -370.89334) (xy 375.89968 -371.386862)
			(xy 375.900113 -371.396047) (xy 375.906611 -371.413231) (xy 375.91238 -371.42039) (xy 375.934181 -371.446031)
			(xy 375.972128 -371.50162) (xy 376.00316 -371.561345) (xy 376.026618 -371.623785) (xy 377.128712 -371.623785)
			(xy 377.128716 -371.556358) (xy 377.136796 -371.489417) (xy 377.152836 -371.423925) (xy 377.176606 -371.360827)
			(xy 377.207762 -371.301029) (xy 377.245857 -371.245395) (xy 377.267724 -371.21973) (xy 377.273536 -371.212596)
			(xy 377.28004 -371.195397) (xy 377.280424 -371.186202) (xy 377.280424 -371.028722) (xy 377.280944 -371.018599)
			(xy 377.288662 -370.999881) (xy 377.302938 -370.985524) (xy 377.321612 -370.977702) (xy 377.331732 -370.97716)
			(xy 378.048012 -370.97716) (xy 378.058162 -370.977611) (xy 378.076907 -370.985403) (xy 378.091229 -370.99979)
			(xy 378.098935 -371.01857) (xy 378.09932 -371.028722) (xy 378.09932 -371.186202) (xy 378.099725 -371.19539)
			(xy 378.106242 -371.212574) (xy 378.11202 -371.21973) (xy 378.133846 -371.245426) (xy 378.171934 -371.301057)
			(xy 378.203086 -371.360849) (xy 378.226851 -371.423942) (xy 378.242889 -371.489427) (xy 378.250967 -371.556361)
			(xy 378.250971 -371.623782) (xy 378.242899 -371.690717) (xy 378.226868 -371.756204) (xy 378.203109 -371.819299)
			(xy 378.171964 -371.879094) (xy 378.133881 -371.934728) (xy 378.11202 -371.960394) (xy 378.106246 -371.967555)
			(xy 378.099717 -371.984733) (xy 378.09932 -371.993922) (xy 378.09932 -372.486174) (xy 378.099738 -372.49536)
			(xy 378.106246 -372.512545) (xy 378.11202 -372.519702) (xy 378.133917 -372.54534) (xy 378.172003 -372.600979)
			(xy 378.203151 -372.660779) (xy 378.226913 -372.723879) (xy 378.242945 -372.789372) (xy 378.251018 -372.856313)
			(xy 378.251015 -372.923739) (xy 378.242936 -372.990679) (xy 378.226897 -373.056169) (xy 378.20313 -373.119268)
			(xy 378.171977 -373.179065) (xy 378.133885 -373.2347) (xy 378.11202 -373.260366) (xy 378.106215 -373.267506)
			(xy 378.099705 -373.2847) (xy 378.09932 -373.293894) (xy 378.09932 -373.451374) (xy 378.098851 -373.461504)
			(xy 378.091125 -373.480232) (xy 378.076832 -373.494591) (xy 378.05814 -373.502404) (xy 378.048012 -373.502936)
			(xy 377.331732 -373.502936) (xy 377.321584 -373.502453) (xy 377.30284 -373.494675) (xy 377.288516 -373.480297)
			(xy 377.280809 -373.461523) (xy 377.280424 -373.451374) (xy 377.280424 -373.293894) (xy 377.280012 -373.284707)
			(xy 377.273499 -373.267523) (xy 377.267724 -373.260366) (xy 377.245893 -373.234674) (xy 377.207801 -373.179044)
			(xy 377.176648 -373.119251) (xy 377.152881 -373.056158) (xy 377.136842 -372.990672) (xy 377.128763 -372.923736)
			(xy 377.12876 -372.856315) (xy 377.136833 -372.789378) (xy 377.152865 -372.723891) (xy 377.176627 -372.660795)
			(xy 377.207775 -372.601) (xy 377.245861 -372.545367) (xy 377.267724 -372.519702) (xy 377.273505 -372.512546)
			(xy 377.280028 -372.495364) (xy 377.280424 -372.486174) (xy 377.280424 -371.993922) (xy 377.279998 -371.984737)
			(xy 377.273495 -371.967552) (xy 377.267724 -371.960394) (xy 377.245822 -371.93476) (xy 377.207733 -371.879122)
			(xy 377.176582 -371.819321) (xy 377.152819 -371.75622) (xy 377.136786 -371.690727) (xy 377.128712 -371.623785)
			(xy 376.026618 -371.623785) (xy 376.026831 -371.624351) (xy 376.042802 -371.689734) (xy 376.050845 -371.756558)
			(xy 376.050844 -371.823863) (xy 376.042799 -371.890687) (xy 376.026825 -371.956069) (xy 376.003151 -372.019074)
			(xy 375.972117 -372.078799) (xy 375.934168 -372.134386) (xy 375.91238 -372.160038) (xy 375.906582 -372.167182)
			(xy 375.900069 -372.184374) (xy 375.89968 -372.193566) (xy 375.89968 -372.351554) (xy 375.899199 -372.36172)
			(xy 375.891432 -372.380511) (xy 375.877064 -372.394896) (xy 375.858284 -372.402686) (xy 375.848118 -372.403116)
			(xy 375.131838 -372.403116) (xy 375.121663 -372.402704) (xy 375.102861 -372.394923) (xy 375.088473 -372.380533)
			(xy 375.080695 -372.361729) (xy 375.080276 -372.351554) (xy 375.080276 -372.193566) (xy 375.079887 -372.184376)
			(xy 375.073359 -372.167192) (xy 375.067576 -372.160038) (xy 375.045801 -372.134375) (xy 375.007849 -372.078791)
			(xy 374.976813 -372.019069) (xy 374.953138 -371.956066) (xy 374.937163 -371.890685) (xy 374.929117 -371.823863)
			(xy 374.929116 -371.756558) (xy 374.937159 -371.689736) (xy 374.953132 -371.624354) (xy 374.976805 -371.56135)
			(xy 375.007838 -371.501627) (xy 375.045788 -371.446042) (xy 375.067576 -371.42039) (xy 375.073357 -371.413233)
			(xy 375.079882 -371.396052) (xy 375.080276 -371.386862) (xy 375.080276 -370.89334) (xy 375.079852 -370.884154)
			(xy 375.073349 -370.866969) (xy 375.067576 -370.859812) (xy 375.045775 -370.83417) (xy 375.007825 -370.778583)
			(xy 374.97679 -370.718858) (xy 374.953116 -370.655852) (xy 374.937143 -370.590469) (xy 374.929099 -370.523644)
			(xy 345.250797 -370.523644) (xy 345.242754 -370.590465) (xy 345.226782 -370.655847) (xy 345.203109 -370.718851)
			(xy 345.172076 -370.778574) (xy 345.134128 -370.83416) (xy 345.11234 -370.859812) (xy 345.106548 -370.86696)
			(xy 345.100032 -370.884149) (xy 345.09964 -370.89334) (xy 345.09964 -371.386862) (xy 345.100082 -371.396046)
			(xy 345.106575 -371.41323) (xy 345.11234 -371.42039) (xy 345.134142 -371.446031) (xy 345.172092 -371.501618)
			(xy 345.203126 -371.561343) (xy 345.226564 -371.623726) (xy 346.329187 -371.623726) (xy 346.32919 -371.556417)
			(xy 346.337239 -371.489591) (xy 346.353217 -371.424206) (xy 346.376896 -371.3612) (xy 346.407936 -371.301476)
			(xy 346.445893 -371.24589) (xy 346.467684 -371.220238) (xy 346.473488 -371.213098) (xy 346.479999 -371.195904)
			(xy 346.480384 -371.18671) (xy 346.480384 -371.028722) (xy 346.480783 -371.018546) (xy 346.488569 -370.999743)
			(xy 346.502963 -370.985356) (xy 346.52177 -370.977578) (xy 346.531946 -370.97716) (xy 347.248226 -370.97716)
			(xy 347.258388 -370.977612) (xy 347.277162 -370.9854) (xy 347.291527 -370.999778) (xy 347.299297 -371.018559)
			(xy 347.299788 -371.028722) (xy 347.299788 -371.18671) (xy 347.300196 -371.195897) (xy 347.306711 -371.213082)
			(xy 347.312488 -371.220238) (xy 347.334237 -371.245921) (xy 347.372185 -371.301504) (xy 347.403219 -371.361224)
			(xy 347.426893 -371.424224) (xy 347.442867 -371.489602) (xy 347.450914 -371.556421) (xy 347.450918 -371.623722)
			(xy 347.442878 -371.690542) (xy 347.426909 -371.755921) (xy 347.403242 -371.818924) (xy 347.372215 -371.878647)
			(xy 347.334272 -371.934233) (xy 347.312488 -371.959886) (xy 347.306671 -371.967017) (xy 347.300169 -371.984218)
			(xy 347.299788 -371.993414) (xy 347.299788 -372.486682) (xy 347.30021 -372.495868) (xy 347.306716 -372.513052)
			(xy 347.312488 -372.52021) (xy 347.334308 -372.545835) (xy 347.372254 -372.601426) (xy 347.403285 -372.661154)
			(xy 347.426954 -372.724162) (xy 347.442924 -372.789547) (xy 347.450965 -372.856372) (xy 347.450962 -372.923679)
			(xy 347.442915 -372.990504) (xy 347.426939 -373.055887) (xy 347.403264 -373.118893) (xy 347.372228 -373.178618)
			(xy 347.334277 -373.234205) (xy 347.312488 -373.259858) (xy 347.306683 -373.266997) (xy 347.300174 -373.284192)
			(xy 347.299788 -373.293386) (xy 347.299788 -373.451374) (xy 347.299246 -373.461527) (xy 347.291485 -373.480291)
			(xy 347.277134 -373.494656) (xy 347.258378 -373.502436) (xy 347.248226 -373.502936) (xy 346.531946 -373.502936)
			(xy 346.521774 -373.502498) (xy 346.502975 -373.494723) (xy 346.488588 -373.480341) (xy 346.480806 -373.461546)
			(xy 346.480384 -373.451374) (xy 346.480384 -373.293386) (xy 346.479984 -373.284198) (xy 346.473464 -373.267013)
			(xy 346.467684 -373.259858) (xy 346.445928 -373.234179) (xy 346.407976 -373.178597) (xy 346.376938 -373.118878)
			(xy 346.353262 -373.055877) (xy 346.337285 -372.990498) (xy 346.329237 -372.923677) (xy 346.329234 -372.856374)
			(xy 346.337276 -372.789553) (xy 346.353247 -372.724172) (xy 346.376917 -372.661169) (xy 346.407949 -372.601447)
			(xy 346.445897 -372.545862) (xy 346.467684 -372.52021) (xy 346.473499 -372.513078) (xy 346.480003 -372.495877)
			(xy 346.480384 -372.486682) (xy 346.480384 -371.993414) (xy 346.479971 -371.984227) (xy 346.47346 -371.967042)
			(xy 346.467684 -371.959886) (xy 346.445858 -371.934265) (xy 346.407907 -371.878675) (xy 346.376873 -371.818948)
			(xy 346.3532 -371.755939) (xy 346.337229 -371.690553) (xy 346.329187 -371.623726) (xy 345.226564 -371.623726)
			(xy 345.226798 -371.624349) (xy 345.242771 -371.689733) (xy 345.250814 -371.756557) (xy 345.250813 -371.823864)
			(xy 345.242767 -371.890688) (xy 345.226792 -371.956071) (xy 345.203117 -372.019076) (xy 345.172081 -372.0788)
			(xy 345.134129 -372.134386) (xy 345.11234 -372.160038) (xy 345.106537 -372.167179) (xy 345.100028 -372.184373)
			(xy 345.09964 -372.193566) (xy 345.09964 -372.351554) (xy 345.099198 -372.361725) (xy 345.091424 -372.380523)
			(xy 345.077043 -372.394911) (xy 345.058249 -372.402693) (xy 345.048078 -372.403116) (xy 344.331798 -372.403116)
			(xy 344.321621 -372.402737) (xy 344.302817 -372.394942) (xy 344.288431 -372.380543) (xy 344.280654 -372.361732)
			(xy 344.280236 -372.351554) (xy 344.280236 -372.193566) (xy 344.279834 -372.184378) (xy 344.273314 -372.167194)
			(xy 344.267536 -372.160038) (xy 344.245762 -372.134374) (xy 344.207813 -372.078789) (xy 344.17678 -372.019067)
			(xy 344.153106 -371.956064) (xy 344.137132 -371.890684) (xy 344.129087 -371.823862) (xy 344.129086 -371.756559)
			(xy 344.137129 -371.689737) (xy 344.1531 -371.624356) (xy 344.176771 -371.561352) (xy 344.207803 -371.501629)
			(xy 344.245749 -371.446042) (xy 344.267536 -371.42039) (xy 344.273324 -371.413239) (xy 344.279843 -371.396053)
			(xy 344.280236 -371.386862) (xy 344.280236 -370.89334) (xy 344.279798 -370.884156) (xy 344.273303 -370.866972)
			(xy 344.267536 -370.859812) (xy 344.245736 -370.83417) (xy 344.207788 -370.778582) (xy 344.176756 -370.718857)
			(xy 344.153084 -370.655851) (xy 344.137112 -370.590468) (xy 344.129068 -370.523644) (xy 340.851006 -370.523644)
			(xy 340.842963 -370.590465) (xy 340.826991 -370.655847) (xy 340.803319 -370.718851) (xy 340.772287 -370.778574)
			(xy 340.734339 -370.83416) (xy 340.712552 -370.859812) (xy 340.706762 -370.866962) (xy 340.700245 -370.884149)
			(xy 340.699852 -370.89334) (xy 340.699852 -371.386862) (xy 340.700291 -371.396046) (xy 340.706786 -371.41323)
			(xy 340.712552 -371.42039) (xy 340.734354 -371.446031) (xy 340.772303 -371.501618) (xy 340.803336 -371.561344)
			(xy 340.826797 -371.623785) (xy 341.928891 -371.623785) (xy 341.928895 -371.556358) (xy 341.936974 -371.489417)
			(xy 341.953014 -371.423926) (xy 341.976782 -371.360828) (xy 342.007937 -371.301031) (xy 342.04603 -371.245395)
			(xy 342.067896 -371.21973) (xy 342.073704 -371.212593) (xy 342.080212 -371.195396) (xy 342.080596 -371.186202)
			(xy 342.080596 -371.028722) (xy 342.081143 -371.018602) (xy 342.088856 -370.99989) (xy 342.103123 -370.985534)
			(xy 342.121787 -370.977706) (xy 342.131904 -370.97716) (xy 342.848184 -370.97716) (xy 342.858332 -370.977634)
			(xy 342.877076 -370.985417) (xy 342.891399 -370.999797) (xy 342.899106 -371.018572) (xy 342.899492 -371.028722)
			(xy 342.899492 -371.186202) (xy 342.899903 -371.195389) (xy 342.906416 -371.212573) (xy 342.912192 -371.21973)
			(xy 342.934019 -371.245426) (xy 342.972109 -371.301056) (xy 343.003262 -371.360848) (xy 343.027029 -371.423941)
			(xy 343.043067 -371.489426) (xy 343.051146 -371.556361) (xy 343.05115 -371.623782) (xy 343.043077 -371.690718)
			(xy 343.027046 -371.756205) (xy 343.003285 -371.8193) (xy 342.972139 -371.879095) (xy 342.934054 -371.934729)
			(xy 342.912192 -371.960394) (xy 342.906415 -371.967553) (xy 342.899889 -371.984733) (xy 342.899492 -371.993922)
			(xy 342.899492 -372.486174) (xy 342.899917 -372.49536) (xy 342.90642 -372.512544) (xy 342.912192 -372.519702)
			(xy 342.93409 -372.54534) (xy 342.972178 -372.600978) (xy 343.003328 -372.660778) (xy 343.02709 -372.723878)
			(xy 343.043124 -372.789371) (xy 343.051197 -372.856312) (xy 343.051194 -372.923739) (xy 343.043114 -372.99068)
			(xy 343.027075 -373.056171) (xy 343.003307 -373.119269) (xy 342.972152 -373.179066) (xy 342.934058 -373.234701)
			(xy 342.912192 -373.260366) (xy 342.906384 -373.267503) (xy 342.899876 -373.2847) (xy 342.899492 -373.293894)
			(xy 342.899492 -373.451374) (xy 342.898953 -373.461495) (xy 342.89124 -373.48021) (xy 342.87697 -373.494566)
			(xy 342.858302 -373.502392) (xy 342.848184 -373.502936) (xy 342.131904 -373.502936) (xy 342.121755 -373.502476)
			(xy 342.103009 -373.494688) (xy 342.088687 -373.480304) (xy 342.080981 -373.461525) (xy 342.080596 -373.451374)
			(xy 342.080596 -373.293894) (xy 342.080189 -373.284706) (xy 342.073673 -373.267522) (xy 342.067896 -373.260366)
			(xy 342.046066 -373.234673) (xy 342.007976 -373.179042) (xy 341.976824 -373.11925) (xy 341.953058 -373.056157)
			(xy 341.937021 -372.990671) (xy 341.928942 -372.923736) (xy 341.928939 -372.856315) (xy 341.937011 -372.789379)
			(xy 341.953043 -372.723892) (xy 341.976803 -372.660797) (xy 342.00795 -372.601001) (xy 342.046034 -372.545367)
			(xy 342.067896 -372.519702) (xy 342.073674 -372.512543) (xy 342.0802 -372.495363) (xy 342.080596 -372.486174)
			(xy 342.080596 -371.993922) (xy 342.080176 -371.984736) (xy 342.073669 -371.967551) (xy 342.067896 -371.960394)
			(xy 342.045995 -371.934759) (xy 342.007908 -371.87912) (xy 341.976759 -371.81932) (xy 341.952997 -371.756219)
			(xy 341.936964 -371.690726) (xy 341.928891 -371.623785) (xy 340.826797 -371.623785) (xy 340.827009 -371.62435)
			(xy 340.842981 -371.689733) (xy 340.851024 -371.756557) (xy 340.851023 -371.823864) (xy 340.842977 -371.890687)
			(xy 340.827002 -371.956071) (xy 340.803328 -372.019076) (xy 340.772292 -372.0788) (xy 340.734341 -372.134386)
			(xy 340.712552 -372.160038) (xy 340.706751 -372.16718) (xy 340.70024 -372.184373) (xy 340.699852 -372.193566)
			(xy 340.699852 -372.351554) (xy 340.699398 -372.361724) (xy 340.691627 -372.380519) (xy 340.67725 -372.394906)
			(xy 340.65846 -372.402691) (xy 340.64829 -372.403116) (xy 339.93201 -372.403116) (xy 339.921833 -372.402727)
			(xy 339.90303 -372.394937) (xy 339.888643 -372.38054) (xy 339.880866 -372.361731) (xy 339.880448 -372.351554)
			(xy 339.880448 -372.193566) (xy 339.880043 -372.184378) (xy 339.873525 -372.167195) (xy 339.867748 -372.160038)
			(xy 339.845974 -372.134375) (xy 339.808024 -372.07879) (xy 339.77699 -372.019068) (xy 339.753316 -371.956065)
			(xy 339.737342 -371.890684) (xy 339.729296 -371.823863) (xy 339.729295 -371.756558) (xy 339.737338 -371.689737)
			(xy 339.75331 -371.624355) (xy 339.776981 -371.561351) (xy 339.808013 -371.501628) (xy 339.845961 -371.446042)
			(xy 339.867748 -371.42039) (xy 339.873537 -371.41324) (xy 339.880055 -371.396053) (xy 339.880448 -371.386862)
			(xy 339.880448 -370.89334) (xy 339.880008 -370.884156) (xy 339.873514 -370.866972) (xy 339.867748 -370.859812)
			(xy 339.845948 -370.83417) (xy 339.807999 -370.778582) (xy 339.776966 -370.718857) (xy 339.753293 -370.655851)
			(xy 339.737321 -370.590468) (xy 339.729277 -370.523644) (xy 336.451238 -370.523644) (xy 336.451238 -370.523703)
			(xy 336.443163 -370.590641) (xy 336.427128 -370.65613) (xy 336.403363 -370.719227) (xy 336.372211 -370.779022)
			(xy 336.334121 -370.834656) (xy 336.312256 -370.86032) (xy 336.306463 -370.867467) (xy 336.299947 -370.884656)
			(xy 336.299556 -370.893848) (xy 336.299556 -371.386354) (xy 336.299998 -371.395538) (xy 336.306491 -371.412722)
			(xy 336.312256 -371.419882) (xy 336.334135 -371.445535) (xy 336.372226 -371.50117) (xy 336.403379 -371.560968)
			(xy 336.427016 -371.623725) (xy 337.529123 -371.623725) (xy 337.529126 -371.556418) (xy 337.537174 -371.489593)
			(xy 337.55315 -371.424209) (xy 337.576825 -371.361204) (xy 337.60786 -371.301479) (xy 337.645811 -371.245891)
			(xy 337.6676 -371.220238) (xy 337.673405 -371.213099) (xy 337.679915 -371.195904) (xy 337.6803 -371.18671)
			(xy 337.6803 -371.028722) (xy 337.68085 -371.01857) (xy 337.68861 -370.999809) (xy 337.702958 -370.985444)
			(xy 337.721711 -370.977662) (xy 337.731862 -370.97716) (xy 338.448142 -370.97716) (xy 338.458305 -370.9776)
			(xy 338.477079 -370.985392) (xy 338.491444 -370.999774) (xy 338.499213 -371.018558) (xy 338.499704 -371.028722)
			(xy 338.499704 -371.18671) (xy 338.500109 -371.195898) (xy 338.506626 -371.213082) (xy 338.512404 -371.220238)
			(xy 338.534153 -371.245921) (xy 338.5721 -371.301504) (xy 338.603133 -371.361224) (xy 338.626806 -371.424224)
			(xy 338.64278 -371.489602) (xy 338.650827 -371.556421) (xy 338.65083 -371.623722) (xy 338.64279 -371.690541)
			(xy 338.626823 -371.755921) (xy 338.603156 -371.818924) (xy 338.57213 -371.878646) (xy 338.534188 -371.934233)
			(xy 338.512404 -371.959886) (xy 338.506589 -371.967018) (xy 338.500085 -371.984219) (xy 338.499704 -371.993414)
			(xy 338.499704 -372.486682) (xy 338.500122 -372.495868) (xy 338.50663 -372.513053) (xy 338.512404 -372.52021)
			(xy 338.534224 -372.545835) (xy 338.572169 -372.601427) (xy 338.603198 -372.661154) (xy 338.626867 -372.724162)
			(xy 338.642836 -372.789547) (xy 338.650877 -372.856372) (xy 338.650874 -372.923679) (xy 338.642827 -372.990503)
			(xy 338.626852 -373.055887) (xy 338.603177 -373.118892) (xy 338.572142 -373.178617) (xy 338.534192 -373.234205)
			(xy 338.512404 -373.259858) (xy 338.506601 -373.266999) (xy 338.50009 -373.284193) (xy 338.499704 -373.293386)
			(xy 338.499704 -373.451374) (xy 338.499147 -373.461525) (xy 338.491388 -373.480286) (xy 338.477043 -373.49465)
			(xy 338.458292 -373.502433) (xy 338.448142 -373.502936) (xy 337.731862 -373.502936) (xy 337.721699 -373.502497)
			(xy 337.702924 -373.494705) (xy 337.688559 -373.480323) (xy 337.68079 -373.461538) (xy 337.6803 -373.451374)
			(xy 337.6803 -373.293386) (xy 337.679896 -373.284198) (xy 337.673378 -373.267014) (xy 337.6676 -373.259858)
			(xy 337.645847 -373.234178) (xy 337.6079 -373.178595) (xy 337.576867 -373.118874) (xy 337.553194 -373.055874)
			(xy 337.53722 -372.990495) (xy 337.529174 -372.923676) (xy 337.52917 -372.856375) (xy 337.537211 -372.789555)
			(xy 337.553179 -372.724175) (xy 337.576846 -372.661172) (xy 337.607873 -372.601449) (xy 337.645816 -372.545863)
			(xy 337.6676 -372.52021) (xy 337.673417 -372.513079) (xy 337.67992 -372.495878) (xy 337.6803 -372.486682)
			(xy 337.6803 -371.993414) (xy 337.679883 -371.984228) (xy 337.673374 -371.967043) (xy 337.6676 -371.959886)
			(xy 337.645776 -371.934264) (xy 337.607831 -371.878672) (xy 337.576802 -371.818944) (xy 337.553133 -371.755936)
			(xy 337.537163 -371.69055) (xy 337.529123 -371.623725) (xy 336.427016 -371.623725) (xy 336.427144 -371.624066)
			(xy 336.44318 -371.689557) (xy 336.451256 -371.756498) (xy 336.451254 -371.823923) (xy 336.443176 -371.890863)
			(xy 336.427138 -371.956354) (xy 336.40337 -372.019451) (xy 336.372216 -372.079248) (xy 336.334122 -372.134881)
			(xy 336.312256 -372.160546) (xy 336.306452 -372.167686) (xy 336.299943 -372.184881) (xy 336.299556 -372.194074)
			(xy 336.299556 -372.351554) (xy 336.299036 -372.361678) (xy 336.291322 -372.380399) (xy 336.277046 -372.394757)
			(xy 336.258369 -372.402577) (xy 336.248248 -372.403116) (xy 335.531968 -372.403116) (xy 335.521814 -372.402705)
			(xy 335.503064 -372.394902) (xy 335.488742 -372.380502) (xy 335.481041 -372.36171) (xy 335.48066 -372.351554)
			(xy 335.48066 -372.194074) (xy 335.480249 -372.184887) (xy 335.473734 -372.167704) (xy 335.46796 -372.160546)
			(xy 335.446111 -372.134869) (xy 335.408025 -372.079235) (xy 335.376876 -372.01944) (xy 335.353112 -371.956345)
			(xy 335.337077 -371.890858) (xy 335.329001 -371.823921) (xy 335.329 -371.7565) (xy 335.337073 -371.689563)
			(xy 335.353106 -371.624075) (xy 335.376867 -371.560979) (xy 335.408014 -371.501183) (xy 335.446098 -371.445548)
			(xy 335.46796 -371.419882) (xy 335.473754 -371.412735) (xy 335.480269 -371.395546) (xy 335.48066 -371.386354)
			(xy 335.48066 -370.893848) (xy 335.480214 -370.884665) (xy 335.473724 -370.867481) (xy 335.46796 -370.86032)
			(xy 335.446086 -370.834664) (xy 335.408 -370.779027) (xy 335.376852 -370.719229) (xy 335.35309 -370.656131)
			(xy 335.337057 -370.590642) (xy 335.328983 -370.523703) (xy 332.050912 -370.523703) (xy 332.042876 -370.590465)
			(xy 332.026905 -370.655846) (xy 332.003233 -370.71885) (xy 331.972202 -370.778573) (xy 331.934255 -370.83416)
			(xy 331.912468 -370.859812) (xy 331.90668 -370.866963) (xy 331.900161 -370.884149) (xy 331.899768 -370.89334)
			(xy 331.899768 -371.386862) (xy 331.900204 -371.396046) (xy 331.906701 -371.41323) (xy 331.912468 -371.42039)
			(xy 331.934269 -371.446031) (xy 331.972217 -371.501619) (xy 332.00325 -371.561344) (xy 332.026709 -371.623785)
			(xy 333.128803 -371.623785) (xy 333.128807 -371.556358) (xy 333.136887 -371.489417) (xy 333.152927 -371.423926)
			(xy 333.176696 -371.360827) (xy 333.207851 -371.30103) (xy 333.245945 -371.245395) (xy 333.267812 -371.21973)
			(xy 333.273622 -371.212594) (xy 333.280128 -371.195397) (xy 333.280512 -371.186202) (xy 333.280512 -371.028722)
			(xy 333.281044 -371.0186) (xy 333.288759 -370.999885) (xy 333.303031 -370.985529) (xy 333.321701 -370.977704)
			(xy 333.33182 -370.97716) (xy 334.0481 -370.97716) (xy 334.058249 -370.977621) (xy 334.076994 -370.985409)
			(xy 334.091316 -370.999793) (xy 334.099023 -371.018571) (xy 334.099408 -371.028722) (xy 334.099408 -371.186202)
			(xy 334.099815 -371.195389) (xy 334.106331 -371.212574) (xy 334.112108 -371.21973) (xy 334.133934 -371.245426)
			(xy 334.172024 -371.301056) (xy 334.203176 -371.360848) (xy 334.226942 -371.423941) (xy 334.242979 -371.489426)
			(xy 334.251058 -371.556361) (xy 334.251062 -371.623782) (xy 334.24299 -371.690717) (xy 334.226958 -371.756204)
			(xy 334.203199 -371.819299) (xy 334.172053 -371.879095) (xy 334.133969 -371.934729) (xy 334.112108 -371.960394)
			(xy 334.106332 -371.967554) (xy 334.099805 -371.984733) (xy 334.099408 -371.993922) (xy 334.099408 -372.486174)
			(xy 334.099829 -372.49536) (xy 334.106335 -372.512545) (xy 334.112108 -372.519702) (xy 334.134005 -372.54534)
			(xy 334.172092 -372.600978) (xy 334.203241 -372.660779) (xy 334.227003 -372.723879) (xy 334.243036 -372.789371)
			(xy 334.251109 -372.856312) (xy 334.251106 -372.923739) (xy 334.243027 -372.990679) (xy 334.226988 -373.05617)
			(xy 334.20322 -373.119268) (xy 334.172066 -373.179065) (xy 334.133974 -373.234701) (xy 334.112108 -373.260366)
			(xy 334.106302 -373.267504) (xy 334.099793 -373.2847) (xy 334.099408 -373.293894) (xy 334.099408 -373.451374)
			(xy 334.098854 -373.461493) (xy 334.091143 -373.480205) (xy 334.076878 -373.49456) (xy 334.058216 -373.502389)
			(xy 334.0481 -373.502936) (xy 333.33182 -373.502936) (xy 333.321672 -373.502463) (xy 333.302927 -373.494681)
			(xy 333.288604 -373.4803) (xy 333.280897 -373.461524) (xy 333.280512 -373.451374) (xy 333.280512 -373.293894)
			(xy 333.280102 -373.284707) (xy 333.273588 -373.267523) (xy 333.267812 -373.260366) (xy 333.245981 -373.234673)
			(xy 333.20789 -373.179043) (xy 333.176738 -373.119251) (xy 333.152971 -373.056157) (xy 333.136933 -372.990672)
			(xy 333.128854 -372.923736) (xy 333.128851 -372.856315) (xy 333.136924 -372.789379) (xy 333.152956 -372.723891)
			(xy 333.176717 -372.660796) (xy 333.207864 -372.601001) (xy 333.24595 -372.545367) (xy 333.267812 -372.519702)
			(xy 333.273592 -372.512545) (xy 333.280116 -372.495363) (xy 333.280512 -372.486174) (xy 333.280512 -371.993922)
			(xy 333.280088 -371.984736) (xy 333.273584 -371.967552) (xy 333.267812 -371.960394) (xy 333.24591 -371.93476)
			(xy 333.207822 -371.879121) (xy 333.176672 -371.819321) (xy 333.15291 -371.75622) (xy 333.136876 -371.690727)
			(xy 333.128803 -371.623785) (xy 332.026709 -371.623785) (xy 332.026921 -371.62435) (xy 332.042893 -371.689734)
			(xy 332.050936 -371.756558) (xy 332.050935 -371.823864) (xy 332.042889 -371.890687) (xy 332.026915 -371.95607)
			(xy 332.003241 -372.019075) (xy 331.972207 -372.078799) (xy 331.934256 -372.134386) (xy 331.912468 -372.160038)
			(xy 331.906669 -372.167181) (xy 331.900156 -372.184373) (xy 331.899768 -372.193566) (xy 331.899768 -372.351554)
			(xy 331.899299 -372.361722) (xy 331.89153 -372.380514) (xy 331.877158 -372.394901) (xy 331.858373 -372.402688)
			(xy 331.848206 -372.403116) (xy 331.131926 -372.403116) (xy 331.12175 -372.402714) (xy 331.102948 -372.394929)
			(xy 331.08856 -372.380536) (xy 331.080783 -372.36173) (xy 331.080364 -372.351554) (xy 331.080364 -372.193566)
			(xy 331.079956 -372.184379) (xy 331.073439 -372.167195) (xy 331.067664 -372.160038) (xy 331.045889 -372.134375)
			(xy 331.007939 -372.078791) (xy 330.976903 -372.019069) (xy 330.953229 -371.956066) (xy 330.937254 -371.890684)
			(xy 330.929208 -371.823863) (xy 330.929207 -371.756558) (xy 330.93725 -371.689736) (xy 330.953222 -371.624355)
			(xy 330.976895 -371.561351) (xy 331.007928 -371.501628) (xy 331.045876 -371.446042) (xy 331.067664 -371.42039)
			(xy 331.073455 -371.413241) (xy 331.079971 -371.396053) (xy 331.080364 -371.386862) (xy 331.080364 -370.89334)
			(xy 331.07992 -370.884157) (xy 331.073428 -370.866973) (xy 331.067664 -370.859812) (xy 331.045864 -370.83417)
			(xy 331.007914 -370.778582) (xy 330.97688 -370.718858) (xy 330.953206 -370.655852) (xy 330.937234 -370.590468)
			(xy 330.92919 -370.523644) (xy 301.250887 -370.523644) (xy 301.250887 -370.523702) (xy 301.242812 -370.590639)
			(xy 301.226779 -370.656127) (xy 301.203017 -370.719224) (xy 301.171869 -370.77902) (xy 301.133783 -370.834654)
			(xy 301.11192 -370.86032) (xy 301.106135 -370.867473) (xy 301.099613 -370.884658) (xy 301.09922 -370.893848)
			(xy 301.09922 -371.386354) (xy 301.099648 -371.395539) (xy 301.106149 -371.412724) (xy 301.11192 -371.419882)
			(xy 301.133797 -371.445536) (xy 301.171884 -371.501173) (xy 301.203033 -371.560971) (xy 301.226688 -371.623785)
			(xy 302.328773 -371.623785) (xy 302.328777 -371.556358) (xy 302.336856 -371.489418) (xy 302.352895 -371.423927)
			(xy 302.376662 -371.360829) (xy 302.407815 -371.301031) (xy 302.445907 -371.245396) (xy 302.467772 -371.21973)
			(xy 302.47359 -371.2126) (xy 302.48009 -371.195398) (xy 302.480472 -371.186202) (xy 302.480472 -371.028722)
			(xy 302.480945 -371.018593) (xy 302.488672 -370.999866) (xy 302.502963 -370.985508) (xy 302.521653 -370.977693)
			(xy 302.53178 -370.97716) (xy 303.24806 -370.97716) (xy 303.258207 -370.977654) (xy 303.27695 -370.985429)
			(xy 303.291274 -370.999803) (xy 303.298982 -371.018574) (xy 303.299368 -371.028722) (xy 303.299368 -371.186202)
			(xy 303.299784 -371.195388) (xy 303.306294 -371.212572) (xy 303.312068 -371.21973) (xy 303.333896 -371.245425)
			(xy 303.371988 -371.301055) (xy 303.403142 -371.360847) (xy 303.42691 -371.42394) (xy 303.442949 -371.489425)
			(xy 303.451028 -371.556361) (xy 303.451031 -371.623782) (xy 303.442959 -371.690718) (xy 303.426926 -371.756206)
			(xy 303.403165 -371.819301) (xy 303.372017 -371.879096) (xy 303.333931 -371.934729) (xy 303.312068 -371.960394)
			(xy 303.306287 -371.96755) (xy 303.299764 -371.984732) (xy 303.299368 -371.993922) (xy 303.299368 -372.486174)
			(xy 303.299798 -372.495359) (xy 303.306299 -372.512543) (xy 303.312068 -372.519702) (xy 303.333966 -372.545339)
			(xy 303.372056 -372.600977) (xy 303.403207 -372.660777) (xy 303.426971 -372.723877) (xy 303.443005 -372.78937)
			(xy 303.451079 -372.856312) (xy 303.451076 -372.923739) (xy 303.442996 -372.99068) (xy 303.426956 -373.056172)
			(xy 303.403186 -373.11927) (xy 303.37203 -373.179067) (xy 303.333935 -373.234701) (xy 303.312068 -373.260366)
			(xy 303.306257 -373.267501) (xy 303.299752 -373.284699) (xy 303.299368 -373.293894) (xy 303.299368 -373.451374)
			(xy 303.298853 -373.461498) (xy 303.291135 -373.480217) (xy 303.276857 -373.494574) (xy 303.258181 -373.502396)
			(xy 303.24806 -373.502936) (xy 302.53178 -373.502936) (xy 302.521629 -373.502496) (xy 302.502883 -373.4947)
			(xy 302.488562 -373.48031) (xy 302.480856 -373.461527) (xy 302.480472 -373.451374) (xy 302.480472 -373.293894)
			(xy 302.480071 -373.284706) (xy 302.473552 -373.267521) (xy 302.467772 -373.260366) (xy 302.445942 -373.234673)
			(xy 302.407855 -373.179042) (xy 302.376704 -373.119249) (xy 302.352939 -373.056156) (xy 302.336902 -372.99067)
			(xy 302.328824 -372.923736) (xy 302.328821 -372.856315) (xy 302.336893 -372.78938) (xy 302.352924 -372.723893)
			(xy 302.376683 -372.660798) (xy 302.407828 -372.601002) (xy 302.445911 -372.545368) (xy 302.467772 -372.519702)
			(xy 302.473559 -372.51255) (xy 302.480077 -372.495364) (xy 302.480472 -372.486174) (xy 302.480472 -371.993922)
			(xy 302.480058 -371.984735) (xy 302.473548 -371.96755) (xy 302.467772 -371.960394) (xy 302.445872 -371.934759)
			(xy 302.407786 -371.87912) (xy 302.376638 -371.819319) (xy 302.352878 -371.756218) (xy 302.336846 -371.690726)
			(xy 302.328773 -371.623785) (xy 301.226688 -371.623785) (xy 301.226795 -371.624069) (xy 301.242829 -371.689559)
			(xy 301.250904 -371.756498) (xy 301.250903 -371.823923) (xy 301.242826 -371.890862) (xy 301.226789 -371.956351)
			(xy 301.203024 -372.019449) (xy 301.171873 -372.079245) (xy 301.133784 -372.13488) (xy 301.11192 -372.160546)
			(xy 301.106124 -372.167692) (xy 301.099608 -372.184882) (xy 301.09922 -372.194074) (xy 301.09922 -372.351554)
			(xy 301.098734 -372.361683) (xy 301.091014 -372.38041) (xy 301.076727 -372.39477) (xy 301.058038 -372.402583)
			(xy 301.047912 -372.403116) (xy 300.331632 -372.403116) (xy 300.321482 -372.402653) (xy 300.302733 -372.394871)
			(xy 300.288409 -372.380487) (xy 300.280705 -372.361706) (xy 300.280324 -372.351554) (xy 300.280324 -372.194074)
			(xy 300.279921 -372.184886) (xy 300.273402 -372.167702) (xy 300.267624 -372.160546) (xy 300.245773 -372.13487)
			(xy 300.207682 -372.079237) (xy 300.17653 -372.019443) (xy 300.152764 -371.956347) (xy 300.136726 -371.890859)
			(xy 300.128649 -371.823922) (xy 300.128648 -371.756499) (xy 300.136723 -371.689561) (xy 300.152757 -371.624073)
			(xy 300.176521 -371.560976) (xy 300.207671 -371.501181) (xy 300.24576 -371.445547) (xy 300.267624 -371.419882)
			(xy 300.273413 -371.412732) (xy 300.279932 -371.395545) (xy 300.280324 -371.386354) (xy 300.280324 -370.893848)
			(xy 300.279885 -370.884664) (xy 300.273391 -370.86748) (xy 300.267624 -370.86032) (xy 300.245747 -370.834665)
			(xy 300.207657 -370.779029) (xy 300.176506 -370.719232) (xy 300.152741 -370.656134) (xy 300.136706 -370.590643)
			(xy 300.128631 -370.523704) (xy 296.851096 -370.523704) (xy 296.843021 -370.590639) (xy 296.826988 -370.656127)
			(xy 296.803227 -370.719223) (xy 296.772079 -370.779019) (xy 296.733994 -370.834654) (xy 296.712132 -370.86032)
			(xy 296.706336 -370.867465) (xy 296.699823 -370.884656) (xy 296.699432 -370.893848) (xy 296.699432 -371.386354)
			(xy 296.699879 -371.395537) (xy 296.706369 -371.412721) (xy 296.712132 -371.419882) (xy 296.734009 -371.445536)
			(xy 296.772095 -371.501173) (xy 296.803243 -371.560971) (xy 296.826876 -371.623726) (xy 297.92898 -371.623726)
			(xy 297.928984 -371.556417) (xy 297.937032 -371.489591) (xy 297.95301 -371.424206) (xy 297.976689 -371.3612)
			(xy 298.007729 -371.301476) (xy 298.045685 -371.245889) (xy 298.067476 -371.220238) (xy 298.073279 -371.213097)
			(xy 298.07979 -371.195903) (xy 298.080176 -371.18671) (xy 298.080176 -371.028722) (xy 298.080583 -371.018547)
			(xy 298.088368 -370.999746) (xy 298.102759 -370.985359) (xy 298.121563 -370.97758) (xy 298.131738 -370.97716)
			(xy 298.848018 -370.97716) (xy 298.858193 -370.97755) (xy 298.876993 -370.985345) (xy 298.891378 -370.999741)
			(xy 298.899158 -371.018546) (xy 298.89958 -371.028722) (xy 298.89958 -371.18671) (xy 298.89999 -371.195897)
			(xy 298.906504 -371.213081) (xy 298.91228 -371.220238) (xy 298.93403 -371.245921) (xy 298.971978 -371.301504)
			(xy 299.003012 -371.361223) (xy 299.026686 -371.424224) (xy 299.042661 -371.489602) (xy 299.050708 -371.556421)
			(xy 299.050711 -371.623722) (xy 299.042671 -371.690542) (xy 299.026703 -371.755922) (xy 299.003035 -371.818925)
			(xy 298.972008 -371.878647) (xy 298.934065 -371.934233) (xy 298.91228 -371.959886) (xy 298.906462 -371.967016)
			(xy 298.899961 -371.984218) (xy 298.89958 -371.993414) (xy 298.89958 -372.486682) (xy 298.900003 -372.495868)
			(xy 298.906508 -372.513052) (xy 298.91228 -372.52021) (xy 298.934101 -372.545835) (xy 298.972047 -372.601426)
			(xy 299.003078 -372.661153) (xy 299.026748 -372.724161) (xy 299.042718 -372.789547) (xy 299.050759 -372.856372)
			(xy 299.050756 -372.923679) (xy 299.042709 -372.990504) (xy 299.026733 -373.055888) (xy 299.003057 -373.118894)
			(xy 298.972021 -373.178618) (xy 298.934069 -373.234206) (xy 298.91228 -373.259858) (xy 298.906474 -373.266996)
			(xy 298.899966 -373.284192) (xy 298.89958 -373.293386) (xy 298.89958 -373.451374) (xy 298.899115 -373.461542)
			(xy 298.891342 -373.480332) (xy 298.876969 -373.494717) (xy 298.858185 -373.502506) (xy 298.848018 -373.502936)
			(xy 298.131738 -373.502936) (xy 298.121566 -373.502504) (xy 298.102767 -373.494727) (xy 298.08838 -373.480343)
			(xy 298.080598 -373.461546) (xy 298.080176 -373.451374) (xy 298.080176 -373.293386) (xy 298.079778 -373.284197)
			(xy 298.073256 -373.267013) (xy 298.067476 -373.259858) (xy 298.045721 -373.234179) (xy 298.007768 -373.178597)
			(xy 297.976732 -373.118878) (xy 297.953055 -373.055877) (xy 297.937079 -372.990497) (xy 297.929031 -372.923677)
			(xy 297.929028 -372.856374) (xy 297.93707 -372.789553) (xy 297.95304 -372.724172) (xy 297.976711 -372.661169)
			(xy 298.007742 -372.601447) (xy 298.045689 -372.545862) (xy 298.067476 -372.52021) (xy 298.073291 -372.513077)
			(xy 298.079795 -372.495877) (xy 298.080176 -372.486682) (xy 298.080176 -371.993414) (xy 298.079765 -371.984227)
			(xy 298.073252 -371.967042) (xy 298.067476 -371.959886) (xy 298.04565 -371.934265) (xy 298.007699 -371.878675)
			(xy 297.976666 -371.818948) (xy 297.952993 -371.755939) (xy 297.937022 -371.690552) (xy 297.92898 -371.623726)
			(xy 296.826876 -371.623726) (xy 296.827005 -371.624069) (xy 296.843039 -371.689559) (xy 296.851113 -371.756498)
			(xy 296.851112 -371.823923) (xy 296.843035 -371.890861) (xy 296.826999 -371.956351) (xy 296.803235 -372.019448)
			(xy 296.772084 -372.079245) (xy 296.733996 -372.13488) (xy 296.712132 -372.160546) (xy 296.706325 -372.167684)
			(xy 296.699819 -372.18488) (xy 296.699432 -372.194074) (xy 296.699432 -372.351554) (xy 296.698935 -372.361681)
			(xy 296.691217 -372.380407) (xy 296.676933 -372.394765) (xy 296.658249 -372.402581) (xy 296.648124 -372.403116)
			(xy 295.931844 -372.403116) (xy 295.921695 -372.402643) (xy 295.902946 -372.394865) (xy 295.888622 -372.380484)
			(xy 295.880918 -372.361705) (xy 295.880536 -372.351554) (xy 295.880536 -372.194074) (xy 295.88013 -372.184887)
			(xy 295.873613 -372.167703) (xy 295.867836 -372.160546) (xy 295.845985 -372.13487) (xy 295.807893 -372.079238)
			(xy 295.77674 -372.019444) (xy 295.752973 -371.956348) (xy 295.736936 -371.89086) (xy 295.728858 -371.823922)
			(xy 295.728857 -371.756499) (xy 295.736932 -371.689561) (xy 295.752967 -371.624072) (xy 295.776731 -371.560976)
			(xy 295.807882 -371.50118) (xy 295.845972 -371.445547) (xy 295.867836 -371.419882) (xy 295.873627 -371.412733)
			(xy 295.880144 -371.395545) (xy 295.880536 -371.386354) (xy 295.880536 -370.893848) (xy 295.880095 -370.884664)
			(xy 295.873602 -370.86748) (xy 295.867836 -370.86032) (xy 295.845959 -370.834665) (xy 295.807868 -370.77903)
			(xy 295.776716 -370.719233) (xy 295.752951 -370.656134) (xy 295.736915 -370.590644) (xy 295.72884 -370.523704)
			(xy 292.450793 -370.523704) (xy 292.442757 -370.590465) (xy 292.426785 -370.655847) (xy 292.403113 -370.718851)
			(xy 292.37208 -370.778574) (xy 292.334131 -370.83416) (xy 292.312344 -370.859812) (xy 292.306553 -370.866961)
			(xy 292.300036 -370.884149) (xy 292.299644 -370.89334) (xy 292.299644 -371.386862) (xy 292.300085 -371.396046)
			(xy 292.306578 -371.41323) (xy 292.312344 -371.42039) (xy 292.334146 -371.44603) (xy 292.372096 -371.501618)
			(xy 292.403129 -371.561343) (xy 292.42659 -371.623785) (xy 293.528685 -371.623785) (xy 293.528689 -371.556358)
			(xy 293.536768 -371.489418) (xy 293.552807 -371.423927) (xy 293.576575 -371.360828) (xy 293.60773 -371.301031)
			(xy 293.645822 -371.245395) (xy 293.667688 -371.21973) (xy 293.673495 -371.212592) (xy 293.680004 -371.195396)
			(xy 293.680388 -371.186202) (xy 293.680388 -371.028722) (xy 293.680943 -371.018603) (xy 293.688654 -370.999892)
			(xy 293.702919 -370.985537) (xy 293.72158 -370.977708) (xy 293.731696 -370.97716) (xy 294.447976 -370.97716)
			(xy 294.458078 -370.977704) (xy 294.476748 -370.985426) (xy 294.491043 -370.999705) (xy 294.498785 -371.018366)
			(xy 294.499284 -371.028468) (xy 294.499284 -371.186202) (xy 294.499697 -371.195389) (xy 294.506209 -371.212573)
			(xy 294.511984 -371.21973) (xy 294.533811 -371.245426) (xy 294.571902 -371.301056) (xy 294.603055 -371.360847)
			(xy 294.626822 -371.42394) (xy 294.642861 -371.489426) (xy 294.65094 -371.556361) (xy 294.650944 -371.623782)
			(xy 294.642871 -371.690718) (xy 294.626839 -371.756205) (xy 294.603079 -371.8193) (xy 294.571932 -371.879095)
			(xy 294.533846 -371.934729) (xy 294.511984 -371.960394) (xy 294.506206 -371.967552) (xy 294.499681 -371.984733)
			(xy 294.499284 -371.993922) (xy 294.499284 -372.486174) (xy 294.49971 -372.495359) (xy 294.506213 -372.512544)
			(xy 294.511984 -372.519702) (xy 294.533882 -372.545339) (xy 294.571971 -372.600978) (xy 294.603121 -372.660777)
			(xy 294.626884 -372.723878) (xy 294.642917 -372.789371) (xy 294.650991 -372.856312) (xy 294.650988 -372.923739)
			(xy 294.642908 -372.99068) (xy 294.626869 -373.056171) (xy 294.6031 -373.119269) (xy 294.571944 -373.179066)
			(xy 294.533851 -373.234701) (xy 294.511984 -373.260366) (xy 294.506175 -373.267502) (xy 294.499668 -373.2847)
			(xy 294.499284 -373.293894) (xy 294.499284 -373.451374) (xy 294.498753 -373.461496) (xy 294.491038 -373.480212)
			(xy 294.476766 -373.494569) (xy 294.458095 -373.502393) (xy 294.447976 -373.502936) (xy 293.731696 -373.502936)
			(xy 293.721591 -373.502419) (xy 293.70292 -373.494687) (xy 293.688627 -373.4804) (xy 293.680886 -373.461732)
			(xy 293.680388 -373.451628) (xy 293.680388 -373.293894) (xy 293.679983 -373.284706) (xy 293.673466 -373.267522)
			(xy 293.667688 -373.260366) (xy 293.645858 -373.234673) (xy 293.607769 -373.179042) (xy 293.576617 -373.11925)
			(xy 293.552852 -373.056156) (xy 293.536814 -372.990671) (xy 293.528736 -372.923736) (xy 293.528733 -372.856315)
			(xy 293.536805 -372.789379) (xy 293.552837 -372.723892) (xy 293.576597 -372.660797) (xy 293.607743 -372.601002)
			(xy 293.645826 -372.545367) (xy 293.667688 -372.519702) (xy 293.673465 -372.512543) (xy 293.679992 -372.495363)
			(xy 293.680388 -372.486174) (xy 293.680388 -371.993922) (xy 293.67997 -371.984736) (xy 293.673462 -371.967551)
			(xy 293.667688 -371.960394) (xy 293.645787 -371.934759) (xy 293.6077 -371.87912) (xy 293.576552 -371.81932)
			(xy 293.55279 -371.756219) (xy 293.536758 -371.690726) (xy 293.528685 -371.623785) (xy 292.42659 -371.623785)
			(xy 292.426802 -371.624349) (xy 292.442775 -371.689733) (xy 292.450818 -371.756557) (xy 292.450817 -371.823864)
			(xy 292.442771 -371.890688) (xy 292.426796 -371.956071) (xy 292.403121 -372.019076) (xy 292.372085 -372.0788)
			(xy 292.334133 -372.134386) (xy 292.312344 -372.160038) (xy 292.306542 -372.167179) (xy 292.300032 -372.184373)
			(xy 292.299644 -372.193566) (xy 292.299644 -372.351554) (xy 292.299198 -372.361725) (xy 292.291425 -372.380522)
			(xy 292.277046 -372.394909) (xy 292.258253 -372.402693) (xy 292.248082 -372.403116) (xy 291.531802 -372.403116)
			(xy 291.521625 -372.402733) (xy 291.502821 -372.394941) (xy 291.488435 -372.380542) (xy 291.480658 -372.361732)
			(xy 291.48024 -372.351554) (xy 291.48024 -372.193566) (xy 291.479837 -372.184378) (xy 291.473317 -372.167194)
			(xy 291.46754 -372.160038) (xy 291.445766 -372.134374) (xy 291.407817 -372.07879) (xy 291.376783 -372.019068)
			(xy 291.353109 -371.956065) (xy 291.337135 -371.890684) (xy 291.32909 -371.823862) (xy 291.329089 -371.756559)
			(xy 291.337132 -371.689737) (xy 291.353103 -371.624356) (xy 291.376774 -371.561352) (xy 291.407806 -371.501628)
			(xy 291.445753 -371.446042) (xy 291.46754 -371.42039) (xy 291.473328 -371.413239) (xy 291.479847 -371.396053)
			(xy 291.48024 -371.386862) (xy 291.48024 -370.89334) (xy 291.479801 -370.884156) (xy 291.473306 -370.866972)
			(xy 291.46754 -370.859812) (xy 291.44574 -370.83417) (xy 291.407792 -370.778582) (xy 291.376759 -370.718857)
			(xy 291.353087 -370.655851) (xy 291.337115 -370.590468) (xy 291.329071 -370.523644) (xy 288.051032 -370.523644)
			(xy 288.051032 -370.523703) (xy 288.042957 -370.590641) (xy 288.026921 -370.65613) (xy 288.003156 -370.719227)
			(xy 287.972004 -370.779022) (xy 287.933913 -370.834656) (xy 287.912048 -370.86032) (xy 287.906254 -370.867467)
			(xy 287.899739 -370.884656) (xy 287.899348 -370.893848) (xy 287.899348 -371.386354) (xy 287.899792 -371.395537)
			(xy 287.906284 -371.412721) (xy 287.912048 -371.419882) (xy 287.933928 -371.445535) (xy 287.972019 -371.50117)
			(xy 288.003172 -371.560967) (xy 288.02681 -371.623726) (xy 289.128893 -371.623726) (xy 289.128896 -371.556417)
			(xy 289.136945 -371.489591) (xy 289.152924 -371.424206) (xy 289.176603 -371.3612) (xy 289.207644 -371.301475)
			(xy 289.2456 -371.245889) (xy 289.267392 -371.220238) (xy 289.273196 -371.213098) (xy 289.279707 -371.195904)
			(xy 289.280092 -371.18671) (xy 289.280092 -371.028722) (xy 289.28065 -371.018571) (xy 289.288409 -370.999811)
			(xy 289.302754 -370.985447) (xy 289.321504 -370.977663) (xy 289.331654 -370.97716) (xy 290.047934 -370.97716)
			(xy 290.058097 -370.977606) (xy 290.076871 -370.985396) (xy 290.091236 -370.999776) (xy 290.099005 -371.018559)
			(xy 290.099496 -371.028722) (xy 290.099496 -371.18671) (xy 290.099902 -371.195898) (xy 290.106419 -371.213082)
			(xy 290.112196 -371.220238) (xy 290.133945 -371.245921) (xy 290.171893 -371.301504) (xy 290.202926 -371.361224)
			(xy 290.226599 -371.424224) (xy 290.242574 -371.489602) (xy 290.250621 -371.556421) (xy 290.250624 -371.623722)
			(xy 290.242584 -371.690542) (xy 290.226616 -371.755921) (xy 290.202949 -371.818924) (xy 290.171922 -371.878647)
			(xy 290.13398 -371.934233) (xy 290.112196 -371.959886) (xy 290.10638 -371.967017) (xy 290.099877 -371.984218)
			(xy 290.099496 -371.993414) (xy 290.099496 -372.486682) (xy 290.099916 -372.495868) (xy 290.106423 -372.513053)
			(xy 290.112196 -372.52021) (xy 290.134016 -372.545835) (xy 290.171962 -372.601426) (xy 290.202991 -372.661154)
			(xy 290.226661 -372.724162) (xy 290.24263 -372.789547) (xy 290.250671 -372.856372) (xy 290.250668 -372.923679)
			(xy 290.242621 -372.990503) (xy 290.226646 -373.055887) (xy 290.202971 -373.118893) (xy 290.171935 -373.178618)
			(xy 290.133985 -373.234205) (xy 290.112196 -373.259858) (xy 290.106392 -373.266998) (xy 290.099882 -373.284192)
			(xy 290.099496 -373.293386) (xy 290.099496 -373.451374) (xy 290.098946 -373.461526) (xy 290.091187 -373.480288)
			(xy 290.076838 -373.494653) (xy 290.058085 -373.502435) (xy 290.047934 -373.502936) (xy 289.331654 -373.502936)
			(xy 289.32149 -373.502504) (xy 289.302715 -373.494709) (xy 289.28835 -373.480325) (xy 289.280582 -373.461539)
			(xy 289.280092 -373.451374) (xy 289.280092 -373.293386) (xy 289.27969 -373.284198) (xy 289.273171 -373.267014)
			(xy 289.267392 -373.259858) (xy 289.245636 -373.234179) (xy 289.207683 -373.178598) (xy 289.176645 -373.118878)
			(xy 289.152968 -373.055877) (xy 289.136991 -372.990498) (xy 289.128943 -372.923677) (xy 289.12894 -372.856374)
			(xy 289.136982 -372.789553) (xy 289.152953 -372.724172) (xy 289.176624 -372.661168) (xy 289.207656 -372.601446)
			(xy 289.245605 -372.545861) (xy 289.267392 -372.52021) (xy 289.273208 -372.513079) (xy 289.279711 -372.495878)
			(xy 289.280092 -372.486682) (xy 289.280092 -371.993414) (xy 289.279677 -371.984227) (xy 289.273167 -371.967043)
			(xy 289.267392 -371.959886) (xy 289.245565 -371.934265) (xy 289.207614 -371.878676) (xy 289.17658 -371.818948)
			(xy 289.152907 -371.755939) (xy 289.136935 -371.690553) (xy 289.128893 -371.623726) (xy 288.02681 -371.623726)
			(xy 288.026938 -371.624066) (xy 288.042974 -371.689557) (xy 288.05105 -371.756498) (xy 288.051048 -371.823923)
			(xy 288.04297 -371.890864) (xy 288.026932 -371.956354) (xy 288.003164 -372.019452) (xy 287.972008 -372.079248)
			(xy 287.933915 -372.134882) (xy 287.912048 -372.160546) (xy 287.906243 -372.167685) (xy 287.899735 -372.18488)
			(xy 287.899348 -372.194074) (xy 287.899348 -372.351554) (xy 287.898835 -372.361679) (xy 287.89112 -372.380402)
			(xy 287.876842 -372.39476) (xy 287.858162 -372.402579) (xy 287.84804 -372.403116) (xy 287.13176 -372.403116)
			(xy 287.121651 -372.402648) (xy 287.102975 -372.3949) (xy 287.088682 -372.380598) (xy 287.080946 -372.361918)
			(xy 287.080452 -372.351808) (xy 287.080452 -372.194074) (xy 287.080043 -372.184887) (xy 287.073527 -372.167703)
			(xy 287.067752 -372.160546) (xy 287.0459 -372.13487) (xy 287.007807 -372.079238) (xy 286.976653 -372.019444)
			(xy 286.952886 -371.956349) (xy 286.936848 -371.89086) (xy 286.92877 -371.823922) (xy 286.928769 -371.756499)
			(xy 286.936844 -371.68956) (xy 286.95288 -371.624072) (xy 286.976645 -371.560975) (xy 287.007797 -371.50118)
			(xy 287.045887 -371.445546) (xy 287.067752 -371.419882) (xy 287.073545 -371.412735) (xy 287.08006 -371.395546)
			(xy 287.080452 -371.386354) (xy 287.080452 -370.893848) (xy 287.080007 -370.884665) (xy 287.073516 -370.867481)
			(xy 287.067752 -370.86032) (xy 287.045874 -370.834665) (xy 287.007783 -370.779031) (xy 286.97663 -370.719233)
			(xy 286.952864 -370.656135) (xy 286.936828 -370.590644) (xy 286.928752 -370.523704) (xy 266.12088 -370.523704)
			(xy 266.12088 -374.423882) (xy 286.928731 -374.423882) (xy 286.928735 -374.356454) (xy 286.936815 -374.289512)
			(xy 286.952857 -374.22402) (xy 286.976628 -374.160921) (xy 287.007787 -374.101124) (xy 287.045884 -374.04549)
			(xy 287.067752 -374.019826) (xy 287.073569 -374.012695) (xy 287.08007 -373.995494) (xy 287.080452 -373.986298)
			(xy 287.080452 -373.828818) (xy 287.080942 -373.818691) (xy 287.088666 -373.799968) (xy 287.102951 -373.785611)
			(xy 287.121636 -373.777793) (xy 287.13176 -373.777256) (xy 287.84804 -373.777256) (xy 287.858146 -373.777751)
			(xy 287.876817 -373.785494) (xy 287.891108 -373.799787) (xy 287.898849 -373.818458) (xy 287.899348 -373.828564)
			(xy 287.899348 -373.986298) (xy 287.899771 -373.995484) (xy 287.906277 -374.012667) (xy 287.912048 -374.019826)
			(xy 287.933873 -374.045524) (xy 287.971966 -374.101153) (xy 288.003121 -374.160944) (xy 288.02689 -374.224037)
			(xy 288.04293 -374.289522) (xy 288.05101 -374.356458) (xy 288.051014 -374.423823) (xy 291.32905 -374.423823)
			(xy 291.329054 -374.356514) (xy 291.337102 -374.289689) (xy 291.35308 -374.224304) (xy 291.376757 -374.161298)
			(xy 291.407796 -374.101573) (xy 291.44575 -374.045986) (xy 291.46754 -374.020334) (xy 291.473352 -374.0132)
			(xy 291.479857 -373.996001) (xy 291.48024 -373.986806) (xy 291.48024 -373.828818) (xy 291.480678 -373.818647)
			(xy 291.488458 -373.799853) (xy 291.502839 -373.785467) (xy 291.521631 -373.777682) (xy 291.531802 -373.777256)
			(xy 292.248082 -373.777256) (xy 292.258255 -373.777679) (xy 292.277053 -373.785461) (xy 292.291439 -373.799847)
			(xy 292.299221 -373.818645) (xy 292.299644 -373.828818) (xy 292.299644 -373.986806) (xy 292.300064 -373.995992)
			(xy 292.306572 -374.013176) (xy 292.312344 -374.020334) (xy 292.334091 -374.04602) (xy 292.372042 -374.101601)
			(xy 292.403078 -374.16132) (xy 292.426754 -374.22432) (xy 292.44273 -374.289698) (xy 292.450778 -374.356517)
			(xy 292.450782 -374.423819) (xy 292.450774 -374.423882) (xy 295.728819 -374.423882) (xy 295.728822 -374.356455)
			(xy 295.736903 -374.289513) (xy 295.752944 -374.224021) (xy 295.776715 -374.160922) (xy 295.807872 -374.101125)
			(xy 295.845968 -374.045491) (xy 295.867836 -374.019826) (xy 295.873651 -374.012694) (xy 295.880154 -373.995493)
			(xy 295.880536 -373.986298) (xy 295.880536 -373.828818) (xy 295.881041 -373.818693) (xy 295.888762 -373.799973)
			(xy 295.903043 -373.785616) (xy 295.921722 -373.777796) (xy 295.931844 -373.777256) (xy 296.648124 -373.777256)
			(xy 296.658274 -373.777701) (xy 296.677019 -373.785496) (xy 296.69134 -373.799885) (xy 296.699046 -373.818666)
			(xy 296.699432 -373.828818) (xy 296.699432 -373.986298) (xy 296.699858 -373.995483) (xy 296.706362 -374.012667)
			(xy 296.712132 -374.019826) (xy 296.733954 -374.045526) (xy 296.772041 -374.101156) (xy 296.803192 -374.160948)
			(xy 296.826957 -374.22404) (xy 296.842995 -374.289525) (xy 296.851073 -374.356459) (xy 296.851077 -374.423878)
			(xy 296.851077 -374.423882) (xy 300.12861 -374.423882) (xy 300.128613 -374.356455) (xy 300.136694 -374.289513)
			(xy 300.152734 -374.224021) (xy 300.176504 -374.160923) (xy 300.207661 -374.101126) (xy 300.245757 -374.045491)
			(xy 300.267624 -374.019826) (xy 300.273437 -374.012693) (xy 300.279941 -373.995493) (xy 300.280324 -373.986298)
			(xy 300.280324 -373.828818) (xy 300.280841 -373.818694) (xy 300.28856 -373.799977) (xy 300.302837 -373.78562)
			(xy 300.321511 -373.777798) (xy 300.331632 -373.777256) (xy 301.047912 -373.777256) (xy 301.058061 -373.777711)
			(xy 301.076806 -373.785502) (xy 301.091127 -373.799888) (xy 301.098834 -373.818667) (xy 301.09922 -373.828818)
			(xy 301.09922 -373.986298) (xy 301.099627 -373.995486) (xy 301.106142 -374.01267) (xy 301.11192 -374.019826)
			(xy 301.133742 -374.045526) (xy 301.171831 -374.101156) (xy 301.202982 -374.160947) (xy 301.226748 -374.22404)
			(xy 301.242785 -374.289524) (xy 301.250864 -374.356458) (xy 301.250868 -374.423823) (xy 330.929168 -374.423823)
			(xy 330.929172 -374.356514) (xy 330.937221 -374.289688) (xy 330.953199 -374.224303) (xy 330.976878 -374.161297)
			(xy 331.007917 -374.101572) (xy 331.045873 -374.045986) (xy 331.067664 -374.020334) (xy 331.073479 -374.013202)
			(xy 331.079981 -373.996001) (xy 331.080364 -373.986806) (xy 331.080364 -373.828818) (xy 331.080779 -373.818644)
			(xy 331.088563 -373.799845) (xy 331.102952 -373.785458) (xy 331.121752 -373.777677) (xy 331.131926 -373.777256)
			(xy 331.848206 -373.777256) (xy 331.85838 -373.777659) (xy 331.877178 -373.78545) (xy 331.891564 -373.799842)
			(xy 331.899345 -373.818644) (xy 331.899768 -373.828818) (xy 331.899768 -373.986806) (xy 331.900182 -373.995993)
			(xy 331.906694 -374.013177) (xy 331.912468 -374.020334) (xy 331.934214 -374.04602) (xy 331.972164 -374.101602)
			(xy 332.003198 -374.161321) (xy 332.026873 -374.224321) (xy 332.042849 -374.289699) (xy 332.050896 -374.356518)
			(xy 332.0509 -374.423819) (xy 332.050892 -374.423882) (xy 335.328961 -374.423882) (xy 335.328965 -374.356455)
			(xy 335.337045 -374.289515) (xy 335.353083 -374.224024) (xy 335.37685 -374.160926) (xy 335.408004 -374.101128)
			(xy 335.446095 -374.045492) (xy 335.46796 -374.019826) (xy 335.473778 -374.012696) (xy 335.480278 -373.995494)
			(xy 335.48066 -373.986298) (xy 335.48066 -373.828818) (xy 335.481142 -373.81869) (xy 335.488867 -373.799965)
			(xy 335.503156 -373.785608) (xy 335.521842 -373.777791) (xy 335.531968 -373.777256) (xy 336.248248 -373.777256)
			(xy 336.2584 -373.777682) (xy 336.277145 -373.785485) (xy 336.291465 -373.799879) (xy 336.299171 -373.818664)
			(xy 336.299556 -373.828818) (xy 336.299556 -373.986298) (xy 336.299977 -373.995484) (xy 336.306484 -374.012668)
			(xy 336.312256 -374.019826) (xy 336.33408 -374.045525) (xy 336.372173 -374.101153) (xy 336.403328 -374.160944)
			(xy 336.427097 -374.224037) (xy 336.443136 -374.289523) (xy 336.451216 -374.356458) (xy 336.45122 -374.423823)
			(xy 339.729256 -374.423823) (xy 339.72926 -374.356514) (xy 339.737309 -374.289689) (xy 339.753286 -374.224304)
			(xy 339.776964 -374.161298) (xy 339.808003 -374.101573) (xy 339.845957 -374.045986) (xy 339.867748 -374.020334)
			(xy 339.873561 -374.013201) (xy 339.880065 -373.996001) (xy 339.880448 -373.986806) (xy 339.880448 -373.828818)
			(xy 339.880879 -373.818646) (xy 339.88866 -373.79985) (xy 339.903043 -373.785464) (xy 339.921838 -373.77768)
			(xy 339.93201 -373.777256) (xy 340.64829 -373.777256) (xy 340.658463 -373.777672) (xy 340.677261 -373.785457)
			(xy 340.691647 -373.799846) (xy 340.699429 -373.818645) (xy 340.699852 -373.828818) (xy 340.699852 -373.986806)
			(xy 340.70027 -373.995992) (xy 340.706779 -374.013176) (xy 340.712552 -374.020334) (xy 340.734299 -374.04602)
			(xy 340.772249 -374.101601) (xy 340.803285 -374.16132) (xy 340.82696 -374.22432) (xy 340.842936 -374.289699)
			(xy 340.850984 -374.356517) (xy 340.850988 -374.423819) (xy 340.850988 -374.423823) (xy 344.129047 -374.423823)
			(xy 344.129051 -374.356514) (xy 344.137099 -374.289689) (xy 344.153077 -374.224304) (xy 344.176754 -374.161298)
			(xy 344.207792 -374.101573) (xy 344.245746 -374.045986) (xy 344.267536 -374.020334) (xy 344.273348 -374.0132)
			(xy 344.279852 -373.996001) (xy 344.280236 -373.986806) (xy 344.280236 -373.828818) (xy 344.280678 -373.818648)
			(xy 344.288457 -373.799854) (xy 344.302837 -373.785468) (xy 344.321628 -373.777682) (xy 344.331798 -373.777256)
			(xy 345.048078 -373.777256) (xy 345.05825 -373.777683) (xy 345.077048 -373.785464) (xy 345.091434 -373.799849)
			(xy 345.099217 -373.818646) (xy 345.09964 -373.828818) (xy 345.09964 -373.986806) (xy 345.100061 -373.995992)
			(xy 345.106569 -374.013175) (xy 345.11234 -374.020334) (xy 345.134087 -374.04602) (xy 345.172038 -374.101601)
			(xy 345.203075 -374.16132) (xy 345.226751 -374.22432) (xy 345.242727 -374.289698) (xy 345.250775 -374.356517)
			(xy 345.250779 -374.423819) (xy 345.250779 -374.423823) (xy 374.929078 -374.423823) (xy 374.929081 -374.356514)
			(xy 374.93713 -374.289688) (xy 374.953109 -374.224303) (xy 374.976788 -374.161296) (xy 375.007828 -374.101572)
			(xy 375.045784 -374.045985) (xy 375.067576 -374.020334) (xy 375.07338 -374.013194) (xy 375.079891 -373.996)
			(xy 375.080276 -373.986806) (xy 375.080276 -373.828818) (xy 375.080679 -373.818643) (xy 375.088465 -373.799841)
			(xy 375.102858 -373.785454) (xy 375.121663 -373.777675) (xy 375.131838 -373.777256) (xy 375.848118 -373.777256)
			(xy 375.858279 -373.777719) (xy 375.877052 -373.785503) (xy 375.891418 -373.799878) (xy 375.899188 -373.818656)
			(xy 375.89968 -373.828818) (xy 375.89968 -373.986806) (xy 375.900092 -373.995993) (xy 375.906605 -374.013177)
			(xy 375.91238 -374.020334) (xy 375.934126 -374.046021) (xy 375.972074 -374.101603) (xy 376.003108 -374.161322)
			(xy 376.026783 -374.224321) (xy 376.042758 -374.289699) (xy 376.050805 -374.356518) (xy 376.050809 -374.423819)
			(xy 376.050801 -374.423882) (xy 379.32887 -374.423882) (xy 379.328874 -374.356455) (xy 379.336954 -374.289515)
			(xy 379.352993 -374.224024) (xy 379.376761 -374.160925) (xy 379.407915 -374.101127) (xy 379.446007 -374.045492)
			(xy 379.467872 -374.019826) (xy 379.473691 -374.012697) (xy 379.48019 -373.995494) (xy 379.480572 -373.986298)
			(xy 379.480572 -373.828818) (xy 379.481042 -373.818688) (xy 379.48877 -373.799962) (xy 379.503062 -373.785604)
			(xy 379.521753 -373.777789) (xy 379.53188 -373.777256) (xy 380.24816 -373.777256) (xy 380.258306 -373.777754)
			(xy 380.277049 -373.785528) (xy 380.291372 -373.799901) (xy 380.299081 -373.818671) (xy 380.299468 -373.828818)
			(xy 380.299468 -373.986298) (xy 380.299886 -373.995484) (xy 380.306395 -374.012668) (xy 380.312168 -374.019826)
			(xy 380.333992 -374.045525) (xy 380.372084 -374.101154) (xy 380.403238 -374.160945) (xy 380.427006 -374.224038)
			(xy 380.443046 -374.289523) (xy 380.451125 -374.356458) (xy 380.451129 -374.423823) (xy 383.729165 -374.423823)
			(xy 383.729169 -374.356514) (xy 383.737218 -374.289688) (xy 383.753196 -374.224303) (xy 383.776874 -374.161297)
			(xy 383.807914 -374.101572) (xy 383.845869 -374.045986) (xy 383.86766 -374.020334) (xy 383.873474 -374.013202)
			(xy 383.879977 -373.996001) (xy 383.88036 -373.986806) (xy 383.88036 -373.828818) (xy 383.880779 -373.818645)
			(xy 383.888562 -373.799846) (xy 383.90295 -373.78546) (xy 383.921749 -373.777678) (xy 383.931922 -373.777256)
			(xy 384.648202 -373.777256) (xy 384.658376 -373.777663) (xy 384.677174 -373.785452) (xy 384.69156 -373.799843)
			(xy 384.699341 -373.818644) (xy 384.699764 -373.828818) (xy 384.699764 -373.986806) (xy 384.700179 -373.995992)
			(xy 384.70669 -374.013176) (xy 384.712464 -374.020334) (xy 384.73421 -374.04602) (xy 384.77216 -374.101602)
			(xy 384.803195 -374.161321) (xy 384.82687 -374.224321) (xy 384.842846 -374.289699) (xy 384.850893 -374.356518)
			(xy 384.850897 -374.423819) (xy 384.850897 -374.423823) (xy 388.128956 -374.423823) (xy 388.12896 -374.356514)
			(xy 388.137009 -374.289689) (xy 388.152986 -374.224304) (xy 388.176664 -374.161298) (xy 388.207703 -374.101573)
			(xy 388.245657 -374.045986) (xy 388.267448 -374.020334) (xy 388.273261 -374.013201) (xy 388.279765 -373.996001)
			(xy 388.280148 -373.986806) (xy 388.280148 -373.828818) (xy 388.280579 -373.818646) (xy 388.28836 -373.79985)
			(xy 388.302743 -373.785464) (xy 388.321538 -373.77768) (xy 388.33171 -373.777256) (xy 389.04799 -373.777256)
			(xy 389.058163 -373.777672) (xy 389.076961 -373.785457) (xy 389.091347 -373.799846) (xy 389.099129 -373.818645)
			(xy 389.099552 -373.828818) (xy 389.099552 -373.986806) (xy 389.09997 -373.995992) (xy 389.106479 -374.013176)
			(xy 389.112252 -374.020334) (xy 389.133999 -374.04602) (xy 389.171949 -374.101601) (xy 389.202985 -374.16132)
			(xy 389.22666 -374.22432) (xy 389.242636 -374.289699) (xy 389.250684 -374.356517) (xy 389.250688 -374.423819)
			(xy 389.250688 -374.423823) (xy 418.928987 -374.423823) (xy 418.928991 -374.356514) (xy 418.93704 -374.289688)
			(xy 418.953019 -374.224302) (xy 418.976698 -374.161296) (xy 419.007739 -374.101572) (xy 419.045696 -374.045986)
			(xy 419.067488 -374.020334) (xy 419.073294 -374.013195) (xy 419.079803 -373.996) (xy 419.080188 -373.986806)
			(xy 419.080188 -373.828818) (xy 419.08058 -373.818641) (xy 419.088368 -373.799837) (xy 419.102764 -373.78545)
			(xy 419.121573 -373.777673) (xy 419.13175 -373.777256) (xy 419.84803 -373.777256) (xy 419.858192 -373.777709)
			(xy 419.876965 -373.785497) (xy 419.89133 -373.799875) (xy 419.8991 -373.818656) (xy 419.899592 -373.828818)
			(xy 419.899592 -373.986806) (xy 419.900001 -373.995993) (xy 419.906516 -374.013177) (xy 419.912292 -374.020334)
			(xy 419.934038 -374.04602) (xy 419.971986 -374.101603) (xy 420.003019 -374.161322) (xy 420.026693 -374.224322)
			(xy 420.042668 -374.2897) (xy 420.050715 -374.356518) (xy 420.050719 -374.423819) (xy 420.050711 -374.423882)
			(xy 423.328779 -374.423882) (xy 423.328783 -374.356455) (xy 423.336863 -374.289514) (xy 423.352903 -374.224023)
			(xy 423.376671 -374.160925) (xy 423.407825 -374.101127) (xy 423.445918 -374.045492) (xy 423.467784 -374.019826)
			(xy 423.473593 -374.012689) (xy 423.480101 -373.995492) (xy 423.480484 -373.986298) (xy 423.480484 -373.828818)
			(xy 423.480942 -373.818687) (xy 423.488672 -373.799958) (xy 423.502968 -373.785599) (xy 423.521663 -373.777787)
			(xy 423.531792 -373.777256) (xy 424.248072 -373.777256) (xy 424.258174 -373.777807) (xy 424.276843 -373.785527)
			(xy 424.291137 -373.799803) (xy 424.298881 -373.818463) (xy 424.29938 -373.828564) (xy 424.29938 -373.986298)
			(xy 424.299795 -373.995485) (xy 424.306306 -374.012669) (xy 424.31208 -374.019826) (xy 424.333903 -374.045525)
			(xy 424.371995 -374.101154) (xy 424.403148 -374.160946) (xy 424.426916 -374.224038) (xy 424.442955 -374.289523)
			(xy 424.451034 -374.356458) (xy 424.451038 -374.423823) (xy 427.729074 -374.423823) (xy 427.729078 -374.356514)
			(xy 427.737127 -374.289688) (xy 427.753106 -374.224303) (xy 427.776784 -374.161296) (xy 427.807824 -374.101572)
			(xy 427.84578 -374.045986) (xy 427.867572 -374.020334) (xy 427.873388 -374.013203) (xy 427.879889 -373.996001)
			(xy 427.880272 -373.986806) (xy 427.880272 -373.828818) (xy 427.880679 -373.818643) (xy 427.888465 -373.799842)
			(xy 427.902856 -373.785456) (xy 427.921659 -373.777676) (xy 427.931834 -373.777256) (xy 428.648114 -373.777256)
			(xy 428.658289 -373.777653) (xy 428.677087 -373.785446) (xy 428.691472 -373.79984) (xy 428.699253 -373.818643)
			(xy 428.699676 -373.828818) (xy 428.699676 -373.986806) (xy 428.700088 -373.995993) (xy 428.706601 -374.013177)
			(xy 428.712376 -374.020334) (xy 428.734122 -374.04602) (xy 428.772071 -374.101602) (xy 428.803105 -374.161321)
			(xy 428.82678 -374.224321) (xy 428.842755 -374.289699) (xy 428.850802 -374.356518) (xy 428.850806 -374.423819)
			(xy 428.850806 -374.423823) (xy 432.128865 -374.423823) (xy 432.128869 -374.356514) (xy 432.136918 -374.289688)
			(xy 432.152896 -374.224303) (xy 432.176574 -374.161297) (xy 432.207614 -374.101572) (xy 432.245569 -374.045986)
			(xy 432.26736 -374.020334) (xy 432.273174 -374.013202) (xy 432.279677 -373.996001) (xy 432.28006 -373.986806)
			(xy 432.28006 -373.828818) (xy 432.280479 -373.818645) (xy 432.288262 -373.799846) (xy 432.30265 -373.78546)
			(xy 432.321449 -373.777678) (xy 432.331622 -373.777256) (xy 433.047902 -373.777256) (xy 433.058076 -373.777663)
			(xy 433.076874 -373.785452) (xy 433.09126 -373.799843) (xy 433.099041 -373.818644) (xy 433.099464 -373.828818)
			(xy 433.099464 -373.986806) (xy 433.099879 -373.995992) (xy 433.10639 -374.013176) (xy 433.112164 -374.020334)
			(xy 433.13391 -374.04602) (xy 433.17186 -374.101602) (xy 433.202895 -374.161321) (xy 433.22657 -374.224321)
			(xy 433.242546 -374.289699) (xy 433.250593 -374.356518) (xy 433.250597 -374.423819) (xy 433.242557 -374.490639)
			(xy 433.226589 -374.556019) (xy 433.202921 -374.619021) (xy 433.171892 -374.678744) (xy 433.133949 -374.73433)
			(xy 433.112164 -374.759982) (xy 433.106346 -374.767112) (xy 433.099845 -374.784314) (xy 433.099464 -374.79351)
			(xy 433.099464 -375.286778) (xy 433.099893 -375.295963) (xy 433.106394 -375.313147) (xy 433.112164 -375.320306)
			(xy 433.133981 -375.345934) (xy 433.171929 -375.401524) (xy 433.202961 -375.461251) (xy 433.226632 -375.524259)
			(xy 433.242603 -375.589644) (xy 433.250644 -375.656469) (xy 433.250642 -375.723776) (xy 433.242594 -375.790601)
			(xy 433.226618 -375.855985) (xy 433.202942 -375.91899) (xy 433.171906 -375.978715) (xy 433.133954 -376.034302)
			(xy 433.112164 -376.059954) (xy 433.106357 -376.067092) (xy 433.09985 -376.084288) (xy 433.099464 -376.093482)
			(xy 433.099464 -376.25147) (xy 433.099011 -376.261639) (xy 433.091237 -376.280433) (xy 433.07686 -376.294819)
			(xy 433.058071 -376.302605) (xy 433.047902 -376.303032) (xy 432.331622 -376.303032) (xy 432.321448 -376.302617)
			(xy 432.302648 -376.294834) (xy 432.288262 -376.280445) (xy 432.280481 -376.261644) (xy 432.28006 -376.25147)
			(xy 432.28006 -376.093482) (xy 432.279645 -376.084296) (xy 432.273133 -376.067112) (xy 432.26736 -376.059954)
			(xy 432.245601 -376.034278) (xy 432.20765 -375.978695) (xy 432.176614 -375.918975) (xy 432.152939 -375.855974)
			(xy 432.136963 -375.790594) (xy 432.128917 -375.723774) (xy 432.128914 -375.656471) (xy 432.136955 -375.58965)
			(xy 432.152926 -375.524269) (xy 432.176596 -375.461266) (xy 432.207627 -375.401543) (xy 432.245574 -375.345958)
			(xy 432.26736 -375.320306) (xy 432.273144 -375.313152) (xy 432.279664 -375.295968) (xy 432.28006 -375.286778)
			(xy 432.28006 -374.79351) (xy 432.279632 -374.784325) (xy 432.273129 -374.767141) (xy 432.26736 -374.759982)
			(xy 432.24553 -374.734364) (xy 432.207581 -374.678773) (xy 432.176549 -374.619045) (xy 432.152877 -374.556036)
			(xy 432.136907 -374.49065) (xy 432.128865 -374.423823) (xy 428.850806 -374.423823) (xy 428.842766 -374.490639)
			(xy 428.826798 -374.556018) (xy 428.803131 -374.619021) (xy 428.772103 -374.678743) (xy 428.73416 -374.734329)
			(xy 428.712376 -374.759982) (xy 428.706559 -374.767113) (xy 428.700057 -374.784314) (xy 428.699676 -374.79351)
			(xy 428.699676 -375.286778) (xy 428.700102 -375.295963) (xy 428.706605 -375.313148) (xy 428.712376 -375.320306)
			(xy 428.734193 -375.345934) (xy 428.77214 -375.401524) (xy 428.803171 -375.461251) (xy 428.826841 -375.524259)
			(xy 428.842812 -375.589644) (xy 428.850853 -375.656469) (xy 428.850851 -375.723776) (xy 428.842804 -375.790601)
			(xy 428.826828 -375.855984) (xy 428.803152 -375.91899) (xy 428.772117 -375.978714) (xy 428.734165 -376.034302)
			(xy 428.712376 -376.059954) (xy 428.706571 -376.067093) (xy 428.700062 -376.084288) (xy 428.699676 -376.093482)
			(xy 428.699676 -376.25147) (xy 428.699212 -376.261638) (xy 428.691439 -376.280429) (xy 428.677066 -376.294815)
			(xy 428.658282 -376.302603) (xy 428.648114 -376.303032) (xy 427.931834 -376.303032) (xy 427.921661 -376.302607)
			(xy 427.902861 -376.294828) (xy 427.888474 -376.280442) (xy 427.880693 -376.261643) (xy 427.880272 -376.25147)
			(xy 427.880272 -376.093482) (xy 427.879877 -376.084293) (xy 427.873353 -376.067109) (xy 427.867572 -376.059954)
			(xy 427.845813 -376.034278) (xy 427.807861 -375.978696) (xy 427.776825 -375.918976) (xy 427.753149 -375.855974)
			(xy 427.737173 -375.790595) (xy 427.729126 -375.723774) (xy 427.729123 -375.656471) (xy 427.737165 -375.58965)
			(xy 427.753135 -375.524269) (xy 427.776806 -375.461266) (xy 427.807838 -375.401543) (xy 427.845785 -375.345958)
			(xy 427.867572 -375.320306) (xy 427.873357 -375.313153) (xy 427.879877 -375.295968) (xy 427.880272 -375.286778)
			(xy 427.880272 -374.79351) (xy 427.879863 -374.784323) (xy 427.873349 -374.767138) (xy 427.867572 -374.759982)
			(xy 427.845742 -374.734364) (xy 427.807792 -374.678774) (xy 427.776759 -374.619046) (xy 427.753087 -374.556037)
			(xy 427.737116 -374.49065) (xy 427.729074 -374.423823) (xy 424.451038 -374.423823) (xy 424.451038 -374.423879)
			(xy 424.442966 -374.490815) (xy 424.426934 -374.556302) (xy 424.403174 -374.619397) (xy 424.372027 -374.679192)
			(xy 424.333942 -374.734825) (xy 424.31208 -374.76049) (xy 424.30626 -374.767619) (xy 424.29976 -374.784822)
			(xy 424.29938 -374.794018) (xy 424.29938 -375.28627) (xy 424.299809 -375.295455) (xy 424.30631 -375.312639)
			(xy 424.31208 -375.319798) (xy 424.333974 -375.345439) (xy 424.372063 -375.401076) (xy 424.403214 -375.460876)
			(xy 424.426977 -375.523976) (xy 424.443011 -375.589468) (xy 424.451085 -375.656409) (xy 424.451082 -375.723836)
			(xy 424.443003 -375.790776) (xy 424.426964 -375.856267) (xy 424.403195 -375.919366) (xy 424.37204 -375.979163)
			(xy 424.333946 -376.034797) (xy 424.31208 -376.060462) (xy 424.306272 -376.067599) (xy 424.299765 -376.084796)
			(xy 424.29938 -376.09399) (xy 424.29938 -376.25147) (xy 424.29885 -376.261592) (xy 424.291135 -376.280309)
			(xy 424.276863 -376.294666) (xy 424.258191 -376.30249) (xy 424.248072 -376.303032) (xy 423.531792 -376.303032)
			(xy 423.521687 -376.302522) (xy 423.503015 -376.294788) (xy 423.488721 -376.280499) (xy 423.480981 -376.261829)
			(xy 423.480484 -376.251724) (xy 423.480484 -376.09399) (xy 423.480082 -376.084802) (xy 423.473563 -376.067617)
			(xy 423.467784 -376.060462) (xy 423.44595 -376.034772) (xy 423.407862 -375.979141) (xy 423.37671 -375.919348)
			(xy 423.352945 -375.856254) (xy 423.336908 -375.790768) (xy 423.32883 -375.723833) (xy 423.328827 -375.656412)
			(xy 423.3369 -375.589476) (xy 423.352932 -375.523989) (xy 423.376692 -375.460893) (xy 423.407838 -375.401098)
			(xy 423.445922 -375.345463) (xy 423.467784 -375.319798) (xy 423.473562 -375.31264) (xy 423.480088 -375.295459)
			(xy 423.480484 -375.28627) (xy 423.480484 -374.794018) (xy 423.480069 -374.784831) (xy 423.473559 -374.767647)
			(xy 423.467784 -374.76049) (xy 423.445879 -374.734859) (xy 423.407793 -374.679219) (xy 423.376645 -374.619418)
			(xy 423.352884 -374.556317) (xy 423.336852 -374.490824) (xy 423.328779 -374.423882) (xy 420.050711 -374.423882)
			(xy 420.042679 -374.490638) (xy 420.026712 -374.556018) (xy 420.003045 -374.61902) (xy 419.972018 -374.678743)
			(xy 419.934076 -374.73433) (xy 419.912292 -374.759982) (xy 419.906477 -374.767114) (xy 419.899974 -374.784315)
			(xy 419.899592 -374.79351) (xy 419.899592 -375.286778) (xy 419.900015 -375.295964) (xy 419.90652 -375.313148)
			(xy 419.912292 -375.320306) (xy 419.934108 -375.345934) (xy 419.972054 -375.401525) (xy 420.003084 -375.461252)
			(xy 420.026754 -375.52426) (xy 420.042724 -375.589644) (xy 420.050765 -375.656469) (xy 420.050763 -375.723776)
			(xy 420.042716 -375.7906) (xy 420.026741 -375.855984) (xy 420.003066 -375.918989) (xy 419.972031 -375.978714)
			(xy 419.934081 -376.034301) (xy 419.912292 -376.059954) (xy 419.906489 -376.067095) (xy 419.899978 -376.084289)
			(xy 419.899592 -376.093482) (xy 419.899592 -376.25147) (xy 419.899043 -376.261622) (xy 419.891284 -376.280385)
			(xy 419.876935 -376.29475) (xy 419.858182 -376.302531) (xy 419.84803 -376.303032) (xy 419.13175 -376.303032)
			(xy 419.121578 -376.302595) (xy 419.102779 -376.29482) (xy 419.088391 -376.280438) (xy 419.080609 -376.261642)
			(xy 419.080188 -376.25147) (xy 419.080188 -376.093482) (xy 419.079789 -376.084294) (xy 419.073268 -376.067109)
			(xy 419.067488 -376.059954) (xy 419.045728 -376.034278) (xy 419.007775 -375.978696) (xy 418.976738 -375.918976)
			(xy 418.953061 -375.855975) (xy 418.937085 -375.790595) (xy 418.929038 -375.723774) (xy 418.929035 -375.656471)
			(xy 418.937077 -375.589649) (xy 418.953048 -375.524268) (xy 418.97672 -375.461265) (xy 419.007752 -375.401542)
			(xy 419.045701 -375.345957) (xy 419.067488 -375.320306) (xy 419.073263 -375.313145) (xy 419.079791 -375.295967)
			(xy 419.080188 -375.286778) (xy 419.080188 -374.79351) (xy 419.079776 -374.784323) (xy 419.073264 -374.767138)
			(xy 419.067488 -374.759982) (xy 419.045658 -374.734364) (xy 419.007707 -374.678774) (xy 418.976673 -374.619046)
			(xy 418.953 -374.556037) (xy 418.937029 -374.49065) (xy 418.928987 -374.423823) (xy 389.250688 -374.423823)
			(xy 389.242648 -374.490639) (xy 389.226679 -374.556019) (xy 389.203011 -374.619022) (xy 389.171982 -374.678744)
			(xy 389.134037 -374.73433) (xy 389.112252 -374.759982) (xy 389.106432 -374.76711) (xy 389.099933 -374.784314)
			(xy 389.099552 -374.79351) (xy 389.099552 -375.286778) (xy 389.099983 -375.295963) (xy 389.106483 -375.313147)
			(xy 389.112252 -375.320306) (xy 389.13407 -375.345934) (xy 389.172018 -375.401523) (xy 389.203051 -375.46125)
			(xy 389.226722 -375.524258) (xy 389.242693 -375.589643) (xy 389.250735 -375.656469) (xy 389.250732 -375.723776)
			(xy 389.242685 -375.790601) (xy 389.226709 -375.855985) (xy 389.203032 -375.918991) (xy 389.171995 -375.978715)
			(xy 389.134042 -376.034302) (xy 389.112252 -376.059954) (xy 389.106444 -376.067091) (xy 389.099937 -376.084288)
			(xy 389.099552 -376.093482) (xy 389.099552 -376.25147) (xy 389.099111 -376.261641) (xy 389.091334 -376.280437)
			(xy 389.076954 -376.294823) (xy 389.058161 -376.302607) (xy 389.04799 -376.303032) (xy 388.33171 -376.303032)
			(xy 388.321535 -376.302627) (xy 388.302735 -376.29484) (xy 388.288349 -376.280448) (xy 388.280569 -376.261645)
			(xy 388.280148 -376.25147) (xy 388.280148 -376.093482) (xy 388.279736 -376.084295) (xy 388.273222 -376.067111)
			(xy 388.267448 -376.059954) (xy 388.24569 -376.034278) (xy 388.207739 -375.978695) (xy 388.176704 -375.918975)
			(xy 388.153029 -375.855973) (xy 388.137054 -375.790594) (xy 388.129007 -375.723774) (xy 388.129005 -375.656471)
			(xy 388.137046 -375.58965) (xy 388.153016 -375.52427) (xy 388.176686 -375.461267) (xy 388.207716 -375.401544)
			(xy 388.245662 -375.345958) (xy 388.267448 -375.320306) (xy 388.273231 -375.313151) (xy 388.279752 -375.295968)
			(xy 388.280148 -375.286778) (xy 388.280148 -374.79351) (xy 388.279722 -374.784325) (xy 388.273218 -374.767141)
			(xy 388.267448 -374.759982) (xy 388.245619 -374.734364) (xy 388.20767 -374.678773) (xy 388.176638 -374.619045)
			(xy 388.152968 -374.556036) (xy 388.136997 -374.490649) (xy 388.128956 -374.423823) (xy 384.850897 -374.423823)
			(xy 384.842857 -374.490639) (xy 384.826889 -374.556019) (xy 384.803221 -374.619021) (xy 384.772192 -374.678744)
			(xy 384.734249 -374.73433) (xy 384.712464 -374.759982) (xy 384.706646 -374.767112) (xy 384.700145 -374.784314)
			(xy 384.699764 -374.79351) (xy 384.699764 -375.286778) (xy 384.700193 -375.295963) (xy 384.706694 -375.313147)
			(xy 384.712464 -375.320306) (xy 384.734281 -375.345934) (xy 384.772229 -375.401524) (xy 384.803261 -375.461251)
			(xy 384.826932 -375.524259) (xy 384.842903 -375.589644) (xy 384.850944 -375.656469) (xy 384.850942 -375.723776)
			(xy 384.842894 -375.790601) (xy 384.826918 -375.855985) (xy 384.803242 -375.91899) (xy 384.772206 -375.978715)
			(xy 384.734254 -376.034302) (xy 384.712464 -376.059954) (xy 384.706657 -376.067092) (xy 384.70015 -376.084288)
			(xy 384.699764 -376.093482) (xy 384.699764 -376.25147) (xy 384.699311 -376.261639) (xy 384.691537 -376.280433)
			(xy 384.67716 -376.294819) (xy 384.658371 -376.302605) (xy 384.648202 -376.303032) (xy 383.931922 -376.303032)
			(xy 383.921748 -376.302617) (xy 383.902948 -376.294834) (xy 383.888562 -376.280445) (xy 383.880781 -376.261644)
			(xy 383.88036 -376.25147) (xy 383.88036 -376.093482) (xy 383.879945 -376.084296) (xy 383.873433 -376.067112)
			(xy 383.86766 -376.059954) (xy 383.845901 -376.034278) (xy 383.80795 -375.978695) (xy 383.776914 -375.918975)
			(xy 383.753239 -375.855974) (xy 383.737263 -375.790594) (xy 383.729217 -375.723774) (xy 383.729214 -375.656471)
			(xy 383.737255 -375.58965) (xy 383.753226 -375.524269) (xy 383.776896 -375.461266) (xy 383.807927 -375.401543)
			(xy 383.845874 -375.345958) (xy 383.86766 -375.320306) (xy 383.873444 -375.313152) (xy 383.879964 -375.295968)
			(xy 383.88036 -375.286778) (xy 383.88036 -374.79351) (xy 383.879932 -374.784325) (xy 383.873429 -374.767141)
			(xy 383.86766 -374.759982) (xy 383.84583 -374.734364) (xy 383.807881 -374.678773) (xy 383.776849 -374.619045)
			(xy 383.753177 -374.556036) (xy 383.737207 -374.49065) (xy 383.729165 -374.423823) (xy 380.451129 -374.423823)
			(xy 380.451129 -374.423879) (xy 380.443057 -374.490815) (xy 380.427025 -374.556302) (xy 380.403264 -374.619397)
			(xy 380.372116 -374.679192) (xy 380.334031 -374.734825) (xy 380.312168 -374.76049) (xy 380.306347 -374.767617)
			(xy 380.299847 -374.784822) (xy 380.299468 -374.794018) (xy 380.299468 -375.28627) (xy 380.2999 -375.295455)
			(xy 380.306399 -375.312639) (xy 380.312168 -375.319798) (xy 380.334063 -375.345438) (xy 380.372152 -375.401076)
			(xy 380.403304 -375.460875) (xy 380.427068 -375.523975) (xy 380.443102 -375.589468) (xy 380.451176 -375.656409)
			(xy 380.451173 -375.723836) (xy 380.443094 -375.790777) (xy 380.427054 -375.856268) (xy 380.403285 -375.919366)
			(xy 380.372129 -375.979163) (xy 380.334035 -376.034797) (xy 380.312168 -376.060462) (xy 380.306358 -376.067598)
			(xy 380.299852 -376.084796) (xy 380.299468 -376.09399) (xy 380.299468 -376.25147) (xy 380.298949 -376.261594)
			(xy 380.291233 -376.280313) (xy 380.276956 -376.29467) (xy 380.258281 -376.302492) (xy 380.24816 -376.303032)
			(xy 379.53188 -376.303032) (xy 379.521729 -376.302596) (xy 379.502982 -376.294799) (xy 379.48866 -376.280408)
			(xy 379.480955 -376.261623) (xy 379.480572 -376.25147) (xy 379.480572 -376.09399) (xy 379.480173 -376.084802)
			(xy 379.473652 -376.067617) (xy 379.467872 -376.060462) (xy 379.446038 -376.034772) (xy 379.407951 -375.97914)
			(xy 379.3768 -375.919347) (xy 379.353036 -375.856254) (xy 379.336999 -375.790768) (xy 379.328921 -375.723833)
			(xy 379.328918 -375.656412) (xy 379.336991 -375.589476) (xy 379.353022 -375.523989) (xy 379.376782 -375.460894)
			(xy 379.407928 -375.401098) (xy 379.446011 -375.345464) (xy 379.467872 -375.319798) (xy 379.473661 -375.312648)
			(xy 379.480178 -375.295461) (xy 379.480572 -375.28627) (xy 379.480572 -374.794018) (xy 379.48016 -374.784831)
			(xy 379.473648 -374.767646) (xy 379.467872 -374.76049) (xy 379.445968 -374.734858) (xy 379.407882 -374.679218)
			(xy 379.376735 -374.619417) (xy 379.352974 -374.556316) (xy 379.336943 -374.490823) (xy 379.32887 -374.423882)
			(xy 376.050801 -374.423882) (xy 376.042769 -374.490638) (xy 376.026801 -374.556018) (xy 376.003134 -374.619021)
			(xy 375.972107 -374.678743) (xy 375.934164 -374.734329) (xy 375.91238 -374.759982) (xy 375.906564 -374.767113)
			(xy 375.900062 -374.784315) (xy 375.89968 -374.79351) (xy 375.89968 -375.286778) (xy 375.900105 -375.295963)
			(xy 375.906609 -375.313148) (xy 375.91238 -375.320306) (xy 375.934197 -375.345934) (xy 375.972143 -375.401524)
			(xy 376.003174 -375.461252) (xy 376.026845 -375.524259) (xy 376.042815 -375.589644) (xy 376.050856 -375.656469)
			(xy 376.050854 -375.723776) (xy 376.042807 -375.7906) (xy 376.026831 -375.855984) (xy 376.003156 -375.91899)
			(xy 375.97212 -375.978714) (xy 375.934169 -376.034302) (xy 375.91238 -376.059954) (xy 375.906576 -376.067094)
			(xy 375.900066 -376.084288) (xy 375.89968 -376.093482) (xy 375.89968 -376.25147) (xy 375.899212 -376.261637)
			(xy 375.89144 -376.280428) (xy 375.877068 -376.294813) (xy 375.858285 -376.302602) (xy 375.848118 -376.303032)
			(xy 375.131838 -376.303032) (xy 375.121665 -376.302604) (xy 375.102866 -376.294826) (xy 375.088478 -376.280441)
			(xy 375.080697 -376.261643) (xy 375.080276 -376.25147) (xy 375.080276 -376.093482) (xy 375.07988 -376.084293)
			(xy 375.073357 -376.067109) (xy 375.067576 -376.059954) (xy 375.045817 -376.034278) (xy 375.007865 -375.978696)
			(xy 374.976828 -375.918976) (xy 374.953152 -375.855974) (xy 374.937176 -375.790595) (xy 374.929129 -375.723774)
			(xy 374.929126 -375.656471) (xy 374.937168 -375.58965) (xy 374.953138 -375.524269) (xy 374.97681 -375.461265)
			(xy 375.007841 -375.401543) (xy 375.045789 -375.345958) (xy 375.067576 -375.320306) (xy 375.07335 -375.313144)
			(xy 375.079879 -375.295967) (xy 375.080276 -375.286778) (xy 375.080276 -374.79351) (xy 375.079866 -374.784323)
			(xy 375.073353 -374.767138) (xy 375.067576 -374.759982) (xy 375.045746 -374.734365) (xy 375.007796 -374.678774)
			(xy 374.976762 -374.619046) (xy 374.95309 -374.556037) (xy 374.937119 -374.49065) (xy 374.929078 -374.423823)
			(xy 345.250779 -374.423823) (xy 345.242739 -374.49064) (xy 345.226769 -374.55602) (xy 345.2031 -374.619022)
			(xy 345.172071 -374.678745) (xy 345.134126 -374.73433) (xy 345.11234 -374.759982) (xy 345.106519 -374.767109)
			(xy 345.10002 -374.784314) (xy 345.09964 -374.79351) (xy 345.09964 -375.286778) (xy 345.100074 -375.295962)
			(xy 345.106573 -375.313146) (xy 345.11234 -375.320306) (xy 345.134158 -375.345933) (xy 345.172107 -375.401523)
			(xy 345.203141 -375.46125) (xy 345.226813 -375.524258) (xy 345.242784 -375.589643) (xy 345.250826 -375.656469)
			(xy 345.250823 -375.723776) (xy 345.242776 -375.790602) (xy 345.226799 -375.855986) (xy 345.203122 -375.918992)
			(xy 345.172084 -375.978716) (xy 345.13413 -376.034302) (xy 345.11234 -376.059954) (xy 345.106531 -376.06709)
			(xy 345.100025 -376.084288) (xy 345.09964 -376.093482) (xy 345.09964 -376.25147) (xy 345.099211 -376.261642)
			(xy 345.091432 -376.280441) (xy 345.077047 -376.294827) (xy 345.05825 -376.302609) (xy 345.048078 -376.303032)
			(xy 344.331798 -376.303032) (xy 344.321623 -376.302637) (xy 344.302822 -376.294846) (xy 344.288436 -376.280451)
			(xy 344.280657 -376.261646) (xy 344.280236 -376.25147) (xy 344.280236 -376.093482) (xy 344.279826 -376.084295)
			(xy 344.273311 -376.067111) (xy 344.267536 -376.059954) (xy 344.245778 -376.034277) (xy 344.207829 -375.978694)
			(xy 344.176794 -375.918974) (xy 344.15312 -375.855973) (xy 344.137145 -375.790594) (xy 344.129098 -375.723774)
			(xy 344.129096 -375.656471) (xy 344.137137 -375.589651) (xy 344.153106 -375.52427) (xy 344.176776 -375.461267)
			(xy 344.207805 -375.401544) (xy 344.24575 -375.345958) (xy 344.267536 -375.320306) (xy 344.273317 -375.31315)
			(xy 344.27984 -375.295968) (xy 344.280236 -375.286778) (xy 344.280236 -374.79351) (xy 344.279813 -374.784324)
			(xy 344.273308 -374.76714) (xy 344.267536 -374.759982) (xy 344.245707 -374.734364) (xy 344.20776 -374.678772)
			(xy 344.176728 -374.619044) (xy 344.153058 -374.556035) (xy 344.137088 -374.490649) (xy 344.129047 -374.423823)
			(xy 340.850988 -374.423823) (xy 340.842948 -374.490639) (xy 340.826979 -374.556019) (xy 340.803311 -374.619022)
			(xy 340.772282 -374.678744) (xy 340.734337 -374.73433) (xy 340.712552 -374.759982) (xy 340.706732 -374.76711)
			(xy 340.700233 -374.784314) (xy 340.699852 -374.79351) (xy 340.699852 -375.286778) (xy 340.700283 -375.295963)
			(xy 340.706783 -375.313147) (xy 340.712552 -375.320306) (xy 340.73437 -375.345934) (xy 340.772318 -375.401523)
			(xy 340.803351 -375.46125) (xy 340.827022 -375.524258) (xy 340.842993 -375.589643) (xy 340.851035 -375.656469)
			(xy 340.851032 -375.723776) (xy 340.842985 -375.790601) (xy 340.827009 -375.855985) (xy 340.803332 -375.918991)
			(xy 340.772295 -375.978715) (xy 340.734342 -376.034302) (xy 340.712552 -376.059954) (xy 340.706744 -376.067091)
			(xy 340.700237 -376.084288) (xy 340.699852 -376.093482) (xy 340.699852 -376.25147) (xy 340.699411 -376.261641)
			(xy 340.691634 -376.280437) (xy 340.677254 -376.294823) (xy 340.658461 -376.302607) (xy 340.64829 -376.303032)
			(xy 339.93201 -376.303032) (xy 339.921835 -376.302627) (xy 339.903035 -376.29484) (xy 339.888649 -376.280448)
			(xy 339.880869 -376.261645) (xy 339.880448 -376.25147) (xy 339.880448 -376.093482) (xy 339.880036 -376.084295)
			(xy 339.873522 -376.067111) (xy 339.867748 -376.059954) (xy 339.84599 -376.034278) (xy 339.808039 -375.978695)
			(xy 339.777004 -375.918975) (xy 339.753329 -375.855973) (xy 339.737354 -375.790594) (xy 339.729307 -375.723774)
			(xy 339.729305 -375.656471) (xy 339.737346 -375.58965) (xy 339.753316 -375.52427) (xy 339.776986 -375.461267)
			(xy 339.808016 -375.401544) (xy 339.845962 -375.345958) (xy 339.867748 -375.320306) (xy 339.873531 -375.313151)
			(xy 339.880052 -375.295968) (xy 339.880448 -375.286778) (xy 339.880448 -374.79351) (xy 339.880022 -374.784325)
			(xy 339.873518 -374.767141) (xy 339.867748 -374.759982) (xy 339.845919 -374.734364) (xy 339.80797 -374.678773)
			(xy 339.776938 -374.619045) (xy 339.753268 -374.556036) (xy 339.737297 -374.490649) (xy 339.729256 -374.423823)
			(xy 336.45122 -374.423823) (xy 336.45122 -374.423879) (xy 336.443148 -374.490815) (xy 336.427115 -374.556303)
			(xy 336.403354 -374.619398) (xy 336.372206 -374.679193) (xy 336.334119 -374.734826) (xy 336.312256 -374.76049)
			(xy 336.306433 -374.767616) (xy 336.299935 -374.784821) (xy 336.299556 -374.794018) (xy 336.299556 -375.28627)
			(xy 336.29999 -375.295454) (xy 336.306488 -375.312639) (xy 336.312256 -375.319798) (xy 336.334151 -375.345438)
			(xy 336.372242 -375.401075) (xy 336.403394 -375.460875) (xy 336.427158 -375.523975) (xy 336.443193 -375.589467)
			(xy 336.451267 -375.656409) (xy 336.451264 -375.723836) (xy 336.443185 -375.790777) (xy 336.427145 -375.856268)
			(xy 336.403375 -375.919367) (xy 336.372218 -375.979163) (xy 336.334123 -376.034797) (xy 336.312256 -376.060462)
			(xy 336.306445 -376.067597) (xy 336.29994 -376.084795) (xy 336.299556 -376.09399) (xy 336.299556 -376.25147)
			(xy 336.299049 -376.261595) (xy 336.29133 -376.280317) (xy 336.27705 -376.294674) (xy 336.258371 -376.302494)
			(xy 336.248248 -376.303032) (xy 335.531968 -376.303032) (xy 335.521816 -376.302605) (xy 335.503069 -376.294805)
			(xy 335.488748 -376.280411) (xy 335.481043 -376.261624) (xy 335.48066 -376.25147) (xy 335.48066 -376.09399)
			(xy 335.480241 -376.084804) (xy 335.473732 -376.06762) (xy 335.46796 -376.060462) (xy 335.446127 -376.034772)
			(xy 335.40804 -375.97914) (xy 335.37689 -375.919347) (xy 335.353126 -375.856253) (xy 335.33709 -375.790768)
			(xy 335.329012 -375.723833) (xy 335.329009 -375.656412) (xy 335.337082 -375.589477) (xy 335.353113 -375.52399)
			(xy 335.376872 -375.460894) (xy 335.408017 -375.401099) (xy 335.446099 -375.345464) (xy 335.46796 -375.319798)
			(xy 335.473747 -375.312647) (xy 335.480266 -375.295461) (xy 335.48066 -375.28627) (xy 335.48066 -374.794018)
			(xy 335.480228 -374.784833) (xy 335.473728 -374.76765) (xy 335.46796 -374.76049) (xy 335.446056 -374.734858)
			(xy 335.407971 -374.679218) (xy 335.376825 -374.619417) (xy 335.353065 -374.556316) (xy 335.337033 -374.490823)
			(xy 335.328961 -374.423882) (xy 332.050892 -374.423882) (xy 332.04286 -374.490639) (xy 332.026892 -374.556019)
			(xy 332.003224 -374.619021) (xy 331.972196 -374.678744) (xy 331.934253 -374.73433) (xy 331.912468 -374.759982)
			(xy 331.90665 -374.767112) (xy 331.900149 -374.784314) (xy 331.899768 -374.79351) (xy 331.899768 -375.286778)
			(xy 331.900196 -375.295963) (xy 331.906698 -375.313147) (xy 331.912468 -375.320306) (xy 331.934285 -375.345934)
			(xy 331.972233 -375.401524) (xy 332.003264 -375.461251) (xy 332.026935 -375.524259) (xy 332.042906 -375.589644)
			(xy 332.050947 -375.656469) (xy 332.050945 -375.723776) (xy 332.042898 -375.790601) (xy 332.026922 -375.855985)
			(xy 332.003246 -375.91899) (xy 331.972209 -375.978715) (xy 331.934257 -376.034302) (xy 331.912468 -376.059954)
			(xy 331.906662 -376.067092) (xy 331.900154 -376.084288) (xy 331.899768 -376.093482) (xy 331.899768 -376.25147)
			(xy 331.899312 -376.261639) (xy 331.891538 -376.280432) (xy 331.877162 -376.294817) (xy 331.858375 -376.302604)
			(xy 331.848206 -376.303032) (xy 331.131926 -376.303032) (xy 331.121752 -376.302614) (xy 331.102953 -376.294832)
			(xy 331.088566 -376.280444) (xy 331.080785 -376.261644) (xy 331.080364 -376.25147) (xy 331.080364 -376.093482)
			(xy 331.079948 -376.084296) (xy 331.073437 -376.067112) (xy 331.067664 -376.059954) (xy 331.045905 -376.034278)
			(xy 331.007954 -375.978695) (xy 330.976918 -375.918975) (xy 330.953242 -375.855974) (xy 330.937266 -375.790594)
			(xy 330.92922 -375.723774) (xy 330.929217 -375.656471) (xy 330.937258 -375.58965) (xy 330.953229 -375.524269)
			(xy 330.976899 -375.461266) (xy 331.007931 -375.401543) (xy 331.045877 -375.345958) (xy 331.067664 -375.320306)
			(xy 331.073448 -375.313152) (xy 331.079969 -375.295968) (xy 331.080364 -375.286778) (xy 331.080364 -374.79351)
			(xy 331.079935 -374.784325) (xy 331.073433 -374.767141) (xy 331.067664 -374.759982) (xy 331.045834 -374.734364)
			(xy 331.007885 -374.678773) (xy 330.976852 -374.619045) (xy 330.95318 -374.556036) (xy 330.93721 -374.49065)
			(xy 330.929168 -374.423823) (xy 301.250868 -374.423823) (xy 301.250868 -374.423878) (xy 301.242797 -374.490814)
			(xy 301.226766 -374.5563) (xy 301.203008 -374.619395) (xy 301.171863 -374.67919) (xy 301.133781 -374.734824)
			(xy 301.11192 -374.76049) (xy 301.106105 -374.767622) (xy 301.099601 -374.784823) (xy 301.09922 -374.794018)
			(xy 301.09922 -375.28627) (xy 301.09964 -375.295456) (xy 301.106146 -375.312641) (xy 301.11192 -375.319798)
			(xy 301.133813 -375.345439) (xy 301.171899 -375.401078) (xy 301.203048 -375.460877) (xy 301.226809 -375.523977)
			(xy 301.242842 -375.589469) (xy 301.250915 -375.65641) (xy 301.250912 -375.723835) (xy 301.242834 -375.790775)
			(xy 301.226796 -375.856266) (xy 301.203029 -375.919364) (xy 301.171876 -375.979161) (xy 301.133785 -376.034796)
			(xy 301.11192 -376.060462) (xy 301.106117 -376.067603) (xy 301.099605 -376.084797) (xy 301.09922 -376.09399)
			(xy 301.09922 -376.25147) (xy 301.098748 -376.2616) (xy 301.091023 -376.280328) (xy 301.076731 -376.294687)
			(xy 301.058039 -376.3025) (xy 301.047912 -376.303032) (xy 300.331632 -376.303032) (xy 300.321484 -376.302553)
			(xy 300.302738 -376.294774) (xy 300.288415 -376.280395) (xy 300.280708 -376.26162) (xy 300.280324 -376.25147)
			(xy 300.280324 -376.09399) (xy 300.279913 -376.084803) (xy 300.2734 -376.067619) (xy 300.267624 -376.060462)
			(xy 300.245789 -376.034773) (xy 300.207697 -375.979142) (xy 300.176544 -375.91935) (xy 300.152777 -375.856256)
			(xy 300.136739 -375.790769) (xy 300.12866 -375.723833) (xy 300.128658 -375.656412) (xy 300.136731 -375.589475)
			(xy 300.152764 -375.523987) (xy 300.176526 -375.460892) (xy 300.207674 -375.401096) (xy 300.245761 -375.345463)
			(xy 300.267624 -375.319798) (xy 300.273407 -375.312643) (xy 300.279929 -375.29546) (xy 300.280324 -375.28627)
			(xy 300.280324 -374.794018) (xy 300.2799 -374.784832) (xy 300.273395 -374.767648) (xy 300.267624 -374.76049)
			(xy 300.245718 -374.734859) (xy 300.207629 -374.67922) (xy 300.176479 -374.61942) (xy 300.152716 -374.556318)
			(xy 300.136683 -374.490825) (xy 300.12861 -374.423882) (xy 296.851077 -374.423882) (xy 296.843006 -374.490813)
			(xy 296.826976 -374.556299) (xy 296.803218 -374.619394) (xy 296.772074 -374.67919) (xy 296.733992 -374.734824)
			(xy 296.712132 -374.76049) (xy 296.706306 -374.767614) (xy 296.699811 -374.784821) (xy 296.699432 -374.794018)
			(xy 296.699432 -375.28627) (xy 296.699872 -375.295454) (xy 296.706366 -375.312638) (xy 296.712132 -375.319798)
			(xy 296.734024 -375.345439) (xy 296.77211 -375.401078) (xy 296.803258 -375.460878) (xy 296.827019 -375.523978)
			(xy 296.843051 -375.589469) (xy 296.851124 -375.65641) (xy 296.851121 -375.723835) (xy 296.843043 -375.790775)
			(xy 296.827005 -375.856265) (xy 296.803239 -375.919363) (xy 296.772087 -375.979161) (xy 296.733997 -376.034796)
			(xy 296.712132 -376.060462) (xy 296.706318 -376.067595) (xy 296.699816 -376.084795) (xy 296.699432 -376.09399)
			(xy 296.699432 -376.25147) (xy 296.698948 -376.261598) (xy 296.691225 -376.280324) (xy 296.676937 -376.294683)
			(xy 296.65825 -376.302498) (xy 296.648124 -376.303032) (xy 295.931844 -376.303032) (xy 295.921697 -376.302543)
			(xy 295.902951 -376.294768) (xy 295.888628 -376.280392) (xy 295.880921 -376.261619) (xy 295.880536 -376.25147)
			(xy 295.880536 -376.09399) (xy 295.880123 -376.084803) (xy 295.87361 -376.067619) (xy 295.867836 -376.060462)
			(xy 295.846 -376.034773) (xy 295.807908 -375.979143) (xy 295.776754 -375.91935) (xy 295.752987 -375.856256)
			(xy 295.736948 -375.79077) (xy 295.728869 -375.723834) (xy 295.728867 -375.656412) (xy 295.73694 -375.589475)
			(xy 295.752973 -375.523987) (xy 295.776736 -375.460891) (xy 295.807885 -375.401096) (xy 295.845973 -375.345463)
			(xy 295.867836 -375.319798) (xy 295.873621 -375.312644) (xy 295.880142 -375.29546) (xy 295.880536 -375.28627)
			(xy 295.880536 -374.794018) (xy 295.880109 -374.784833) (xy 295.873606 -374.767649) (xy 295.867836 -374.76049)
			(xy 295.84593 -374.734859) (xy 295.80784 -374.679221) (xy 295.776689 -374.61942) (xy 295.752925 -374.556319)
			(xy 295.736892 -374.490825) (xy 295.728819 -374.423882) (xy 292.450774 -374.423882) (xy 292.442742 -374.490639)
			(xy 292.426773 -374.55602) (xy 292.403104 -374.619022) (xy 292.372075 -374.678745) (xy 292.33413 -374.73433)
			(xy 292.312344 -374.759982) (xy 292.306523 -374.76711) (xy 292.300025 -374.784314) (xy 292.299644 -374.79351)
			(xy 292.299644 -375.286778) (xy 292.300077 -375.295962) (xy 292.306576 -375.313146) (xy 292.312344 -375.320306)
			(xy 292.334162 -375.345934) (xy 292.372111 -375.401523) (xy 292.403144 -375.46125) (xy 292.426816 -375.524258)
			(xy 292.442787 -375.589643) (xy 292.450829 -375.656469) (xy 292.450826 -375.723776) (xy 292.442779 -375.790601)
			(xy 292.426802 -375.855985) (xy 292.403125 -375.918991) (xy 292.372088 -375.978716) (xy 292.334134 -376.034302)
			(xy 292.312344 -376.059954) (xy 292.306535 -376.06709) (xy 292.300029 -376.084288) (xy 292.299644 -376.093482)
			(xy 292.299644 -376.25147) (xy 292.299211 -376.261642) (xy 292.291433 -376.280439) (xy 292.277049 -376.294826)
			(xy 292.258254 -376.302609) (xy 292.248082 -376.303032) (xy 291.531802 -376.303032) (xy 291.521627 -376.302634)
			(xy 291.502826 -376.294844) (xy 291.48844 -376.28045) (xy 291.480661 -376.261645) (xy 291.48024 -376.25147)
			(xy 291.48024 -376.093482) (xy 291.47983 -376.084295) (xy 291.473315 -376.067111) (xy 291.46754 -376.059954)
			(xy 291.445782 -376.034277) (xy 291.407832 -375.978695) (xy 291.376798 -375.918974) (xy 291.353123 -375.855973)
			(xy 291.337148 -375.790594) (xy 291.329101 -375.723774) (xy 291.329099 -375.656471) (xy 291.33714 -375.589651)
			(xy 291.35311 -375.52427) (xy 291.376779 -375.461267) (xy 291.407809 -375.401544) (xy 291.445754 -375.345958)
			(xy 291.46754 -375.320306) (xy 291.473322 -375.31315) (xy 291.479844 -375.295968) (xy 291.48024 -375.286778)
			(xy 291.48024 -374.79351) (xy 291.479816 -374.784324) (xy 291.473311 -374.76714) (xy 291.46754 -374.759982)
			(xy 291.445711 -374.734364) (xy 291.407763 -374.678773) (xy 291.376732 -374.619044) (xy 291.353061 -374.556035)
			(xy 291.337091 -374.490649) (xy 291.32905 -374.423823) (xy 288.051014 -374.423823) (xy 288.051014 -374.423879)
			(xy 288.042941 -374.490816) (xy 288.026909 -374.556303) (xy 288.003147 -374.619398) (xy 287.971998 -374.679193)
			(xy 287.933911 -374.734826) (xy 287.912048 -374.76049) (xy 287.906224 -374.767616) (xy 287.899727 -374.784821)
			(xy 287.899348 -374.794018) (xy 287.899348 -375.28627) (xy 287.899784 -375.295454) (xy 287.906281 -375.312638)
			(xy 287.912048 -375.319798) (xy 287.933943 -375.345438) (xy 287.972035 -375.401075) (xy 288.003187 -375.460874)
			(xy 288.026952 -375.523974) (xy 288.042987 -375.589467) (xy 288.051061 -375.656409) (xy 288.051058 -375.723836)
			(xy 288.042978 -375.790777) (xy 288.026938 -375.856269) (xy 288.003168 -375.919367) (xy 287.972011 -375.979164)
			(xy 287.933916 -376.034798) (xy 287.912048 -376.060462) (xy 287.906236 -376.067596) (xy 287.899732 -376.084795)
			(xy 287.899348 -376.09399) (xy 287.899348 -376.25147) (xy 287.898849 -376.261596) (xy 287.891129 -376.280319)
			(xy 287.876846 -376.294677) (xy 287.858164 -376.302495) (xy 287.84804 -376.303032) (xy 287.13176 -376.303032)
			(xy 287.121653 -376.302548) (xy 287.10298 -376.294804) (xy 287.088687 -376.280507) (xy 287.080948 -376.261831)
			(xy 287.080452 -376.251724) (xy 287.080452 -376.09399) (xy 287.080035 -376.084804) (xy 287.073525 -376.06762)
			(xy 287.067752 -376.060462) (xy 287.045916 -376.034773) (xy 287.007823 -375.979143) (xy 286.976668 -375.919351)
			(xy 286.9529 -375.856257) (xy 286.93686 -375.79077) (xy 286.928781 -375.723834) (xy 286.928779 -375.656411)
			(xy 286.936852 -375.589474) (xy 286.952886 -375.523986) (xy 286.976649 -375.46089) (xy 287.007799 -375.401095)
			(xy 287.045888 -375.345462) (xy 287.067752 -375.319798) (xy 287.073538 -375.312646) (xy 287.080058 -375.29546)
			(xy 287.080452 -375.28627) (xy 287.080452 -374.794018) (xy 287.080022 -374.784833) (xy 287.073521 -374.767649)
			(xy 287.067752 -374.76049) (xy 287.045845 -374.73486) (xy 287.007754 -374.679221) (xy 286.976602 -374.619421)
			(xy 286.952838 -374.556319) (xy 286.936804 -374.490825) (xy 286.928731 -374.423882) (xy 266.12088 -374.423882)
			(xy 266.12088 -377.534932) (xy 266.120477 -377.545004) (xy 266.112741 -377.563602) (xy 266.105894 -377.571)
			(xy 265.757406 -377.919234) (xy 265.750002 -377.926069) (xy 265.731406 -377.933791) (xy 265.721338 -377.93422)
			(xy 243.05133 -377.93422) (xy 243.04126 -377.9338) (xy 243.022661 -377.926078) (xy 243.015262 -377.919234)
			(xy 242.506246 -377.410472) (xy 242.499408 -377.40307) (xy 242.491685 -377.384473) (xy 242.49126 -377.374404)
			(xy 234.964478 -377.374404) (xy 236.356885 -378.766811) (xy 269.68983 -378.766811) (xy 269.68983 -378.633249)
			(xy 269.697894 -378.499931) (xy 269.713994 -378.367343) (xy 269.738069 -378.235969) (xy 269.770032 -378.106288)
			(xy 269.809767 -377.978774) (xy 269.857129 -377.853891) (xy 269.911944 -377.732096) (xy 269.974014 -377.613833)
			(xy 270.04311 -377.499534) (xy 270.118982 -377.389614) (xy 270.201352 -377.284477) (xy 270.28992 -377.184504)
			(xy 270.384362 -377.090062) (xy 270.484335 -377.001494) (xy 270.589472 -376.919124) (xy 270.699392 -376.843252)
			(xy 270.813691 -376.774156) (xy 270.931954 -376.712086) (xy 271.053749 -376.657271) (xy 271.178632 -376.609909)
			(xy 271.306146 -376.570174) (xy 271.435827 -376.538211) (xy 271.567201 -376.514136) (xy 271.699789 -376.498036)
			(xy 271.833107 -376.489972) (xy 271.966669 -376.489972) (xy 272.099987 -376.498036) (xy 272.232575 -376.514136)
			(xy 272.363949 -376.538211) (xy 272.49363 -376.570174) (xy 272.621144 -376.609909) (xy 272.746027 -376.657271)
			(xy 272.867822 -376.712086) (xy 272.986085 -376.774156) (xy 273.068299 -376.823856) (xy 289.128922 -376.823856)
			(xy 289.128922 -376.75655) (xy 289.136967 -376.689727) (xy 289.152941 -376.624344) (xy 289.176615 -376.56134)
			(xy 289.207651 -376.501617) (xy 289.245603 -376.446031) (xy 289.267392 -376.42038) (xy 289.273179 -376.413228)
			(xy 289.2797 -376.396043) (xy 289.280092 -376.386852) (xy 289.280092 -375.893584) (xy 289.279691 -375.884396)
			(xy 289.273171 -375.867212) (xy 289.267392 -375.860056) (xy 289.245634 -375.834379) (xy 289.207681 -375.778797)
			(xy 289.176643 -375.719078) (xy 289.152966 -375.656076) (xy 289.13699 -375.590696) (xy 289.128942 -375.523876)
			(xy 289.128939 -375.456572) (xy 289.136981 -375.389751) (xy 289.152952 -375.32437) (xy 289.176624 -375.261367)
			(xy 289.207656 -375.201644) (xy 289.245605 -375.146059) (xy 289.267392 -375.120408) (xy 289.273167 -375.113247)
			(xy 289.279695 -375.096069) (xy 289.280092 -375.08688) (xy 289.280092 -374.928638) (xy 289.280664 -374.918488)
			(xy 289.288417 -374.899729) (xy 289.302758 -374.885364) (xy 289.321505 -374.87758) (xy 289.331654 -374.877076)
			(xy 290.047934 -374.877076) (xy 290.058113 -374.877437) (xy 290.076915 -374.88524) (xy 290.0913 -374.899645)
			(xy 290.099077 -374.918459) (xy 290.099496 -374.928638) (xy 290.099496 -375.08688) (xy 290.099917 -375.096066)
			(xy 290.106423 -375.11325) (xy 290.112196 -375.120408) (xy 290.134014 -375.146035) (xy 290.17196 -375.201626)
			(xy 290.20299 -375.261353) (xy 290.226659 -375.324361) (xy 290.242629 -375.389746) (xy 290.25067 -375.456571)
			(xy 290.250667 -375.523878) (xy 290.24262 -375.590702) (xy 290.226645 -375.656085) (xy 290.20297 -375.719091)
			(xy 290.171935 -375.778816) (xy 290.133985 -375.834403) (xy 290.112196 -375.860056) (xy 290.106393 -375.867196)
			(xy 290.099882 -375.884391) (xy 290.099496 -375.893584) (xy 290.099496 -376.386852) (xy 290.09993 -376.396037)
			(xy 290.106427 -376.413221) (xy 290.112196 -376.42038) (xy 290.133987 -376.446029) (xy 290.171933 -376.501617)
			(xy 290.202964 -376.561341) (xy 290.226635 -376.624346) (xy 290.242607 -376.689728) (xy 290.25065 -376.756551)
			(xy 290.25065 -376.823855) (xy 290.250643 -376.823915) (xy 293.528715 -376.823915) (xy 293.528715 -376.756491)
			(xy 293.53679 -376.689554) (xy 293.552824 -376.624065) (xy 293.576588 -376.560968) (xy 293.607737 -376.501172)
			(xy 293.645825 -376.445537) (xy 293.667688 -376.419872) (xy 293.673478 -376.412722) (xy 293.679997 -376.395535)
			(xy 293.680388 -376.386344) (xy 293.680388 -375.894092) (xy 293.679984 -375.884904) (xy 293.673466 -375.86772)
			(xy 293.667688 -375.860564) (xy 293.645856 -375.834873) (xy 293.607767 -375.779242) (xy 293.576616 -375.719449)
			(xy 293.55285 -375.656355) (xy 293.536813 -375.59087) (xy 293.528735 -375.523934) (xy 293.528732 -375.456514)
			(xy 293.536804 -375.389578) (xy 293.552836 -375.324091) (xy 293.576596 -375.260995) (xy 293.607742 -375.2012)
			(xy 293.645826 -375.145565) (xy 293.667688 -375.1199) (xy 293.673466 -375.112741) (xy 293.679992 -375.095561)
			(xy 293.680388 -375.086372) (xy 293.680388 -374.928638) (xy 293.680956 -374.91852) (xy 293.688662 -374.89981)
			(xy 293.702923 -374.885454) (xy 293.721582 -374.877624) (xy 293.731696 -374.877076) (xy 294.447976 -374.877076)
			(xy 294.458094 -374.877535) (xy 294.476793 -374.885271) (xy 294.491107 -374.899574) (xy 294.498857 -374.918266)
			(xy 294.499284 -374.928384) (xy 294.499284 -375.086372) (xy 294.499711 -375.095557) (xy 294.506214 -375.112742)
			(xy 294.511984 -375.1199) (xy 294.53388 -375.145539) (xy 294.571969 -375.201177) (xy 294.603119 -375.260977)
			(xy 294.626882 -375.324077) (xy 294.642916 -375.389569) (xy 294.650989 -375.456511) (xy 294.650986 -375.523937)
			(xy 294.642907 -375.590878) (xy 294.626868 -375.656369) (xy 294.603099 -375.719467) (xy 294.571944 -375.779264)
			(xy 294.53385 -375.834899) (xy 294.511984 -375.860564) (xy 294.506176 -375.867701) (xy 294.499669 -375.884898)
			(xy 294.499284 -375.894092) (xy 294.499284 -376.386344) (xy 294.499677 -376.395533) (xy 294.506203 -376.412717)
			(xy 294.511984 -376.419872) (xy 294.533852 -376.445534) (xy 294.571942 -376.501168) (xy 294.603094 -376.560965)
			(xy 294.626858 -376.624062) (xy 294.642894 -376.689552) (xy 294.65097 -376.756491) (xy 294.650969 -376.823856)
			(xy 297.92901 -376.823856) (xy 297.92901 -376.75655) (xy 297.937054 -376.689727) (xy 297.953028 -376.624345)
			(xy 297.976702 -376.56134) (xy 298.007737 -376.501617) (xy 298.045687 -376.446032) (xy 298.067476 -376.42038)
			(xy 298.073261 -376.413226) (xy 298.079783 -376.396042) (xy 298.080176 -376.386852) (xy 298.080176 -375.893584)
			(xy 298.079779 -375.884395) (xy 298.073257 -375.867211) (xy 298.067476 -375.860056) (xy 298.045719 -375.834378)
			(xy 298.007766 -375.778797) (xy 297.97673 -375.719077) (xy 297.953054 -375.656076) (xy 297.937077 -375.590696)
			(xy 297.92903 -375.523876) (xy 297.929027 -375.456572) (xy 297.937069 -375.389751) (xy 297.953039 -375.324371)
			(xy 297.97671 -375.261367) (xy 298.007742 -375.201645) (xy 298.045689 -375.14606) (xy 298.067476 -375.120408)
			(xy 298.073249 -375.113246) (xy 298.079778 -375.096068) (xy 298.080176 -375.08688) (xy 298.080176 -374.928638)
			(xy 298.080596 -374.918464) (xy 298.088376 -374.899663) (xy 298.102763 -374.885276) (xy 298.121564 -374.877496)
			(xy 298.131738 -374.877076) (xy 298.848018 -374.877076) (xy 298.858195 -374.87745) (xy 298.876998 -374.885248)
			(xy 298.891383 -374.899649) (xy 298.899161 -374.91846) (xy 298.89958 -374.928638) (xy 298.89958 -375.08688)
			(xy 298.900004 -375.096066) (xy 298.906509 -375.11325) (xy 298.91228 -375.120408) (xy 298.934099 -375.146035)
			(xy 298.972045 -375.201625) (xy 299.003076 -375.261352) (xy 299.026746 -375.32436) (xy 299.042716 -375.389745)
			(xy 299.050758 -375.45657) (xy 299.050755 -375.523878) (xy 299.042708 -375.590702) (xy 299.026732 -375.656086)
			(xy 299.003056 -375.719092) (xy 298.972021 -375.778816) (xy 298.934069 -375.834404) (xy 298.91228 -375.860056)
			(xy 298.906475 -375.867195) (xy 298.899966 -375.88439) (xy 298.89958 -375.893584) (xy 298.89958 -376.386852)
			(xy 298.900018 -376.396036) (xy 298.906513 -376.413221) (xy 298.91228 -376.42038) (xy 298.934071 -376.446029)
			(xy 298.972019 -376.501616) (xy 299.003051 -376.561341) (xy 299.026722 -376.624345) (xy 299.042695 -376.689728)
			(xy 299.050731 -376.756492) (xy 302.328802 -376.756492) (xy 302.336877 -376.689554) (xy 302.352912 -376.624066)
			(xy 302.376674 -376.560969) (xy 302.407823 -376.501173) (xy 302.445909 -376.445538) (xy 302.467772 -376.419872)
			(xy 302.473572 -376.412729) (xy 302.480082 -376.395537) (xy 302.480472 -376.386344) (xy 302.480472 -375.894092)
			(xy 302.480072 -375.884904) (xy 302.473552 -375.867719) (xy 302.467772 -375.860564) (xy 302.44594 -375.834872)
			(xy 302.407853 -375.779241) (xy 302.376702 -375.719448) (xy 302.352937 -375.656355) (xy 302.336901 -375.590869)
			(xy 302.328823 -375.523934) (xy 302.32882 -375.456514) (xy 302.336892 -375.389578) (xy 302.352923 -375.324091)
			(xy 302.376682 -375.260996) (xy 302.407828 -375.2012) (xy 302.445911 -375.145566) (xy 302.467772 -375.1199)
			(xy 302.47356 -375.112749) (xy 302.480078 -375.095563) (xy 302.480472 -375.086372) (xy 302.480472 -374.928638)
			(xy 302.480959 -374.91851) (xy 302.48868 -374.899784) (xy 302.502967 -374.885425) (xy 302.521654 -374.87761)
			(xy 302.53178 -374.877076) (xy 303.24806 -374.877076) (xy 303.258209 -374.877554) (xy 303.276955 -374.885332)
			(xy 303.291279 -374.899711) (xy 303.298985 -374.918488) (xy 303.299368 -374.928638) (xy 303.299368 -375.086372)
			(xy 303.299799 -375.095557) (xy 303.306299 -375.112741) (xy 303.312068 -375.1199) (xy 303.333965 -375.145539)
			(xy 303.372054 -375.201176) (xy 303.403205 -375.260976) (xy 303.426969 -375.324076) (xy 303.443004 -375.389569)
			(xy 303.451077 -375.456511) (xy 303.451074 -375.523937) (xy 303.442995 -375.590878) (xy 303.426955 -375.65637)
			(xy 303.403186 -375.719468) (xy 303.37203 -375.779265) (xy 303.333935 -375.834899) (xy 303.312068 -375.860564)
			(xy 303.306258 -375.867699) (xy 303.299752 -375.884898) (xy 303.299368 -375.894092) (xy 303.299368 -376.386344)
			(xy 303.299764 -376.395533) (xy 303.306288 -376.412716) (xy 303.312068 -376.419872) (xy 303.333937 -376.445533)
			(xy 303.372028 -376.501168) (xy 303.40318 -376.560964) (xy 303.426945 -376.624062) (xy 303.442982 -376.689551)
			(xy 303.451058 -376.756491) (xy 303.451057 -376.823915) (xy 333.128833 -376.823915) (xy 333.128833 -376.756491)
			(xy 333.136908 -376.689553) (xy 333.152944 -376.624064) (xy 333.176708 -376.560967) (xy 333.207859 -376.501171)
			(xy 333.245948 -376.445537) (xy 333.267812 -376.419872) (xy 333.273604 -376.412724) (xy 333.280121 -376.395536)
			(xy 333.280512 -376.386344) (xy 333.280512 -375.894092) (xy 333.280103 -375.884905) (xy 333.273588 -375.86772)
			(xy 333.267812 -375.860564) (xy 333.245979 -375.834873) (xy 333.207889 -375.779242) (xy 333.176736 -375.71945)
			(xy 333.152969 -375.656356) (xy 333.136931 -375.59087) (xy 333.128853 -375.523935) (xy 333.12885 -375.456513)
			(xy 333.136923 -375.389577) (xy 333.152955 -375.32409) (xy 333.176716 -375.260994) (xy 333.207864 -375.201199)
			(xy 333.24595 -375.145565) (xy 333.267812 -375.1199) (xy 333.273592 -375.112743) (xy 333.280116 -375.095562)
			(xy 333.280512 -375.086372) (xy 333.280512 -374.928638) (xy 333.281057 -374.918517) (xy 333.288767 -374.899802)
			(xy 333.303035 -374.885446) (xy 333.321702 -374.87762) (xy 333.33182 -374.877076) (xy 334.0481 -374.877076)
			(xy 334.058251 -374.877521) (xy 334.076999 -374.885312) (xy 334.091321 -374.899701) (xy 334.099025 -374.918485)
			(xy 334.099408 -374.928638) (xy 334.099408 -375.086372) (xy 334.09983 -375.095558) (xy 334.106335 -375.112743)
			(xy 334.112108 -375.1199) (xy 334.134003 -375.145539) (xy 334.17209 -375.201178) (xy 334.203239 -375.260978)
			(xy 334.227001 -375.324078) (xy 334.243034 -375.38957) (xy 334.251107 -375.456511) (xy 334.251105 -375.523937)
			(xy 334.243026 -375.590877) (xy 334.226987 -375.656368) (xy 334.20322 -375.719466) (xy 334.172066 -375.779263)
			(xy 334.133974 -375.834899) (xy 334.112108 -375.860564) (xy 334.106303 -375.867703) (xy 334.099793 -375.884898)
			(xy 334.099408 -375.894092) (xy 334.099408 -376.386344) (xy 334.099795 -376.395534) (xy 334.106324 -376.412718)
			(xy 334.112108 -376.419872) (xy 334.133976 -376.445534) (xy 334.172064 -376.501169) (xy 334.203214 -376.560966)
			(xy 334.226977 -376.624063) (xy 334.243012 -376.689553) (xy 334.251088 -376.756491) (xy 334.251087 -376.823855)
			(xy 337.529152 -376.823855) (xy 337.529152 -376.756551) (xy 337.537195 -376.689729) (xy 337.553167 -376.624348)
			(xy 337.576837 -376.561344) (xy 337.607868 -376.50162) (xy 337.645814 -376.446033) (xy 337.6676 -376.42038)
			(xy 337.673388 -376.413228) (xy 337.679908 -376.396043) (xy 337.6803 -376.386852) (xy 337.6803 -375.893584)
			(xy 337.679897 -375.884396) (xy 337.673378 -375.867212) (xy 337.6676 -375.860056) (xy 337.645845 -375.834377)
			(xy 337.607898 -375.778794) (xy 337.576865 -375.719074) (xy 337.553192 -375.656073) (xy 337.537218 -375.590694)
			(xy 337.529172 -375.523875) (xy 337.529169 -375.456573) (xy 337.53721 -375.389753) (xy 337.553178 -375.324373)
			(xy 337.576846 -375.26137) (xy 337.607873 -375.201647) (xy 337.645815 -375.146061) (xy 337.6676 -375.120408)
			(xy 337.673376 -375.113248) (xy 337.679903 -375.096069) (xy 337.6803 -375.08688) (xy 337.6803 -374.928638)
			(xy 337.680864 -374.918487) (xy 337.688619 -374.899726) (xy 337.702963 -374.885361) (xy 337.721712 -374.877579)
			(xy 337.731862 -374.877076) (xy 338.448142 -374.877076) (xy 338.458307 -374.8775) (xy 338.477085 -374.885295)
			(xy 338.49145 -374.899683) (xy 338.499216 -374.918472) (xy 338.499704 -374.928638) (xy 338.499704 -375.08688)
			(xy 338.500123 -375.096066) (xy 338.50663 -375.113251) (xy 338.512404 -375.120408) (xy 338.534222 -375.146035)
			(xy 338.572167 -375.201626) (xy 338.603196 -375.261353) (xy 338.626865 -375.324361) (xy 338.642835 -375.389746)
			(xy 338.650876 -375.456571) (xy 338.650873 -375.523877) (xy 338.642826 -375.590701) (xy 338.626851 -375.656085)
			(xy 338.603177 -375.719091) (xy 338.572142 -375.778815) (xy 338.534192 -375.834403) (xy 338.512404 -375.860056)
			(xy 338.506602 -375.867197) (xy 338.50009 -375.884391) (xy 338.499704 -375.893584) (xy 338.499704 -376.386852)
			(xy 338.500136 -376.396037) (xy 338.506634 -376.413222) (xy 338.512404 -376.42038) (xy 338.534194 -376.44603)
			(xy 338.57214 -376.501617) (xy 338.603171 -376.561342) (xy 338.626842 -376.624346) (xy 338.642813 -376.689729)
			(xy 338.650856 -376.756551) (xy 338.650856 -376.823855) (xy 338.650849 -376.823915) (xy 341.928921 -376.823915)
			(xy 341.928921 -376.756491) (xy 341.936996 -376.689553) (xy 341.953031 -376.624065) (xy 341.976794 -376.560968)
			(xy 342.007944 -376.501172) (xy 342.046032 -376.445537) (xy 342.067896 -376.419872) (xy 342.073686 -376.412722)
			(xy 342.080205 -376.395535) (xy 342.080596 -376.386344) (xy 342.080596 -375.894092) (xy 342.08019 -375.884904)
			(xy 342.073674 -375.86772) (xy 342.067896 -375.860564) (xy 342.046064 -375.834873) (xy 342.007974 -375.779242)
			(xy 341.976822 -375.719449) (xy 341.953057 -375.656356) (xy 341.937019 -375.59087) (xy 341.928941 -375.523935)
			(xy 341.928938 -375.456513) (xy 341.93701 -375.389577) (xy 341.953042 -375.32409) (xy 341.976803 -375.260995)
			(xy 342.007949 -375.201199) (xy 342.046034 -375.145565) (xy 342.067896 -375.1199) (xy 342.073675 -375.112742)
			(xy 342.0802 -375.095561) (xy 342.080596 -375.086372) (xy 342.080596 -374.928638) (xy 342.081157 -374.918519)
			(xy 342.088864 -374.899807) (xy 342.103127 -374.885451) (xy 342.121789 -374.877623) (xy 342.131904 -374.877076)
			(xy 342.848184 -374.877076) (xy 342.858334 -374.877534) (xy 342.877082 -374.88532) (xy 342.891405 -374.899705)
			(xy 342.899109 -374.918486) (xy 342.899492 -374.928638) (xy 342.899492 -375.086372) (xy 342.899917 -375.095558)
			(xy 342.906421 -375.112742) (xy 342.912192 -375.1199) (xy 342.934088 -375.145539) (xy 342.972176 -375.201177)
			(xy 343.003326 -375.260977) (xy 343.027088 -375.324077) (xy 343.043122 -375.38957) (xy 343.051195 -375.456511)
			(xy 343.051193 -375.523937) (xy 343.043113 -375.590878) (xy 343.027074 -375.656369) (xy 343.003306 -375.719467)
			(xy 342.972151 -375.779264) (xy 342.934058 -375.834899) (xy 342.912192 -375.860564) (xy 342.906385 -375.867702)
			(xy 342.899877 -375.884898) (xy 342.899492 -375.894092) (xy 342.899492 -376.386344) (xy 342.899883 -376.395533)
			(xy 342.90641 -376.412717) (xy 342.912192 -376.419872) (xy 342.93406 -376.445534) (xy 342.972149 -376.501169)
			(xy 343.0033 -376.560965) (xy 343.027065 -376.624063) (xy 343.0431 -376.689552) (xy 343.051176 -376.756491)
			(xy 343.051175 -376.823856) (xy 346.329216 -376.823856) (xy 346.329216 -376.75655) (xy 346.33726 -376.689727)
			(xy 346.353234 -376.624345) (xy 346.376909 -376.56134) (xy 346.407944 -376.501617) (xy 346.445895 -376.446032)
			(xy 346.467684 -376.42038) (xy 346.47347 -376.413227) (xy 346.479991 -376.396043) (xy 346.480384 -376.386852)
			(xy 346.480384 -375.893584) (xy 346.479985 -375.884396) (xy 346.473464 -375.867211) (xy 346.467684 -375.860056)
			(xy 346.445926 -375.834379) (xy 346.407974 -375.778797) (xy 346.376937 -375.719077) (xy 346.35326 -375.656076)
			(xy 346.337283 -375.590696) (xy 346.329236 -375.523876) (xy 346.329233 -375.456572) (xy 346.337275 -375.389751)
			(xy 346.353246 -375.32437) (xy 346.376917 -375.261367) (xy 346.407949 -375.201645) (xy 346.445897 -375.14606)
			(xy 346.467684 -375.120408) (xy 346.473458 -375.113247) (xy 346.479987 -375.096069) (xy 346.480384 -375.08688)
			(xy 346.480384 -374.928638) (xy 346.480796 -374.918463) (xy 346.488577 -374.899661) (xy 346.502967 -374.885273)
			(xy 346.521771 -374.877495) (xy 346.531946 -374.877076) (xy 347.248226 -374.877076) (xy 347.258404 -374.877443)
			(xy 347.277207 -374.885244) (xy 347.291592 -374.899647) (xy 347.299369 -374.918459) (xy 347.299788 -374.928638)
			(xy 347.299788 -375.08688) (xy 347.300211 -375.096066) (xy 347.306716 -375.11325) (xy 347.312488 -375.120408)
			(xy 347.334306 -375.146035) (xy 347.372252 -375.201625) (xy 347.403283 -375.261353) (xy 347.426953 -375.324361)
			(xy 347.442923 -375.389746) (xy 347.450964 -375.456571) (xy 347.450961 -375.523878) (xy 347.442914 -375.590702)
			(xy 347.426938 -375.656086) (xy 347.403263 -375.719091) (xy 347.372228 -375.778816) (xy 347.334277 -375.834403)
			(xy 347.312488 -375.860056) (xy 347.306684 -375.867196) (xy 347.300174 -375.88439) (xy 347.299788 -375.893584)
			(xy 347.299788 -376.386852) (xy 347.300224 -376.396036) (xy 347.30672 -376.413221) (xy 347.312488 -376.42038)
			(xy 347.334279 -376.446029) (xy 347.372226 -376.501617) (xy 347.403257 -376.561341) (xy 347.426929 -376.624346)
			(xy 347.442901 -376.689728) (xy 347.450944 -376.756551) (xy 347.450944 -376.823855) (xy 347.450937 -376.823915)
			(xy 377.128742 -376.823915) (xy 377.128742 -376.756491) (xy 377.136817 -376.689553) (xy 377.152853 -376.624064)
			(xy 377.176618 -376.560967) (xy 377.20777 -376.501171) (xy 377.245859 -376.445537) (xy 377.267724 -376.419872)
			(xy 377.273518 -376.412725) (xy 377.280033 -376.395536) (xy 377.280424 -376.386344) (xy 377.280424 -375.894092)
			(xy 377.280012 -375.884905) (xy 377.273499 -375.867721) (xy 377.267724 -375.860564) (xy 377.245891 -375.834873)
			(xy 377.207799 -375.779243) (xy 377.176646 -375.71945) (xy 377.152879 -375.656357) (xy 377.136841 -375.590871)
			(xy 377.128762 -375.523935) (xy 377.128759 -375.456513) (xy 377.136832 -375.389577) (xy 377.152865 -375.324089)
			(xy 377.176626 -375.260993) (xy 377.207775 -375.201198) (xy 377.245861 -375.145565) (xy 377.267724 -375.1199)
			(xy 377.273506 -375.112744) (xy 377.280029 -375.095562) (xy 377.280424 -375.086372) (xy 377.280424 -374.928638)
			(xy 377.280957 -374.918516) (xy 377.28867 -374.899799) (xy 377.302942 -374.885442) (xy 377.321613 -374.877618)
			(xy 377.331732 -374.877076) (xy 378.048012 -374.877076) (xy 378.058164 -374.877511) (xy 378.076912 -374.885306)
			(xy 378.091234 -374.899698) (xy 378.098938 -374.918484) (xy 378.09932 -374.928638) (xy 378.09932 -375.086372)
			(xy 378.099739 -375.095558) (xy 378.106246 -375.112743) (xy 378.11202 -375.1199) (xy 378.133915 -375.14554)
			(xy 378.172001 -375.201178) (xy 378.203149 -375.260978) (xy 378.226911 -375.324078) (xy 378.242943 -375.38957)
			(xy 378.251016 -375.456511) (xy 378.251014 -375.523937) (xy 378.242935 -375.590877) (xy 378.226897 -375.656368)
			(xy 378.20313 -375.719466) (xy 378.171976 -375.779263) (xy 378.133885 -375.834898) (xy 378.11202 -375.860564)
			(xy 378.106216 -375.867704) (xy 378.099705 -375.884898) (xy 378.09932 -375.894092) (xy 378.09932 -376.386344)
			(xy 378.099704 -376.395534) (xy 378.106235 -376.412718) (xy 378.11202 -376.419872) (xy 378.133887 -376.445534)
			(xy 378.171974 -376.50117) (xy 378.203124 -376.560967) (xy 378.226887 -376.624064) (xy 378.242922 -376.689553)
			(xy 378.250997 -376.756491) (xy 378.250997 -376.756551) (xy 381.529061 -376.756551) (xy 381.537105 -376.689729)
			(xy 381.553076 -376.624347) (xy 381.576747 -376.561343) (xy 381.607779 -376.501619) (xy 381.645725 -376.446032)
			(xy 381.667512 -376.42038) (xy 381.673301 -376.413229) (xy 381.67982 -376.396043) (xy 381.680212 -376.386852)
			(xy 381.680212 -375.893584) (xy 381.679807 -375.884396) (xy 381.67329 -375.867212) (xy 381.667512 -375.860056)
			(xy 381.645756 -375.834378) (xy 381.607808 -375.778794) (xy 381.576775 -375.719074) (xy 381.553102 -375.656073)
			(xy 381.537127 -375.590694) (xy 381.529081 -375.523875) (xy 381.529078 -375.456573) (xy 381.537119 -375.389753)
			(xy 381.553088 -375.324373) (xy 381.576756 -375.26137) (xy 381.607784 -375.201647) (xy 381.645727 -375.14606)
			(xy 381.667512 -375.120408) (xy 381.673289 -375.113249) (xy 381.679815 -375.096069) (xy 381.680212 -375.08688)
			(xy 381.680212 -374.928638) (xy 381.680694 -374.918472) (xy 381.688462 -374.899683) (xy 381.702829 -374.885298)
			(xy 381.721609 -374.877507) (xy 381.731774 -374.877076) (xy 382.448054 -374.877076) (xy 382.458227 -374.877502)
			(xy 382.477028 -374.885279) (xy 382.491416 -374.899665) (xy 382.499196 -374.918465) (xy 382.499616 -374.928638)
			(xy 382.499616 -375.08688) (xy 382.500032 -375.096067) (xy 382.506541 -375.113251) (xy 382.512316 -375.120408)
			(xy 382.534136 -375.146034) (xy 382.572087 -375.201623) (xy 382.603122 -375.26135) (xy 382.626795 -375.324358)
			(xy 382.642767 -375.389744) (xy 382.650809 -375.45657) (xy 382.650806 -375.523878) (xy 382.642758 -375.590704)
			(xy 382.62678 -375.656088) (xy 382.603102 -375.719094) (xy 382.572063 -375.778818) (xy 382.534107 -375.834404)
			(xy 382.512316 -375.860056) (xy 382.506515 -375.867198) (xy 382.500002 -375.884391) (xy 382.499616 -375.893584)
			(xy 382.499616 -376.386852) (xy 382.500045 -376.396037) (xy 382.506545 -376.413222) (xy 382.512316 -376.42038)
			(xy 382.534109 -376.446028) (xy 382.572061 -376.501614) (xy 382.603096 -376.561338) (xy 382.626771 -376.624343)
			(xy 382.642745 -376.689726) (xy 382.650789 -376.75655) (xy 382.650789 -376.823856) (xy 382.650782 -376.823915)
			(xy 385.92883 -376.823915) (xy 385.92883 -376.756491) (xy 385.936905 -376.689553) (xy 385.95294 -376.624064)
			(xy 385.976705 -376.560967) (xy 386.007855 -376.501171) (xy 386.045944 -376.445537) (xy 386.067808 -376.419872)
			(xy 386.0736 -376.412724) (xy 386.080117 -376.395535) (xy 386.080508 -376.386344) (xy 386.080508 -375.894092)
			(xy 386.0801 -375.884905) (xy 386.073584 -375.867721) (xy 386.067808 -375.860564) (xy 386.045975 -375.834873)
			(xy 386.007885 -375.779242) (xy 385.976732 -375.71945) (xy 385.952966 -375.656356) (xy 385.936928 -375.59087)
			(xy 385.92885 -375.523935) (xy 385.928847 -375.456513) (xy 385.93692 -375.389577) (xy 385.952952 -375.32409)
			(xy 385.976713 -375.260994) (xy 386.00786 -375.201199) (xy 386.045946 -375.145565) (xy 386.067808 -375.1199)
			(xy 386.073588 -375.112743) (xy 386.080112 -375.095562) (xy 386.080508 -375.086372) (xy 386.080508 -374.928638)
			(xy 386.081057 -374.918518) (xy 386.088766 -374.899804) (xy 386.103033 -374.885447) (xy 386.121699 -374.877621)
			(xy 386.131816 -374.877076) (xy 386.848096 -374.877076) (xy 386.858247 -374.877524) (xy 386.876995 -374.885314)
			(xy 386.891317 -374.899702) (xy 386.899021 -374.918485) (xy 386.899404 -374.928638) (xy 386.899404 -375.086372)
			(xy 386.899827 -375.095558) (xy 386.906332 -375.112742) (xy 386.912104 -375.1199) (xy 386.933999 -375.145539)
			(xy 386.972087 -375.201178) (xy 387.003236 -375.260978) (xy 387.026998 -375.324078) (xy 387.043031 -375.38957)
			(xy 387.051104 -375.456511) (xy 387.051102 -375.523937) (xy 387.043023 -375.590877) (xy 387.026984 -375.656368)
			(xy 387.003216 -375.719466) (xy 386.972062 -375.779264) (xy 386.93397 -375.834899) (xy 386.912104 -375.860564)
			(xy 386.906298 -375.867703) (xy 386.899789 -375.884898) (xy 386.899404 -375.894092) (xy 386.899404 -376.386344)
			(xy 386.899792 -376.395534) (xy 386.906321 -376.412718) (xy 386.912104 -376.419872) (xy 386.933972 -376.445534)
			(xy 386.97206 -376.501169) (xy 387.00321 -376.560966) (xy 387.026974 -376.624063) (xy 387.043009 -376.689552)
			(xy 387.051085 -376.756491) (xy 387.051084 -376.823855) (xy 390.329149 -376.823855) (xy 390.329149 -376.756551)
			(xy 390.337192 -376.689729) (xy 390.353163 -376.624348) (xy 390.376834 -376.561344) (xy 390.407864 -376.50162)
			(xy 390.44581 -376.446033) (xy 390.467596 -376.42038) (xy 390.473383 -376.413228) (xy 390.479904 -376.396043)
			(xy 390.480296 -376.386852) (xy 390.480296 -375.893584) (xy 390.479894 -375.884396) (xy 390.473375 -375.867212)
			(xy 390.467596 -375.860056) (xy 390.445841 -375.834377) (xy 390.407894 -375.778794) (xy 390.376862 -375.719073)
			(xy 390.353189 -375.656072) (xy 390.337215 -375.590694) (xy 390.329169 -375.523875) (xy 390.329166 -375.456573)
			(xy 390.337207 -375.389754) (xy 390.353175 -375.324374) (xy 390.376842 -375.261371) (xy 390.407869 -375.201648)
			(xy 390.445812 -375.146061) (xy 390.467596 -375.120408) (xy 390.473371 -375.113248) (xy 390.479899 -375.096069)
			(xy 390.480296 -375.08688) (xy 390.480296 -374.928638) (xy 390.480864 -374.918488) (xy 390.488618 -374.899728)
			(xy 390.502961 -374.885363) (xy 390.521709 -374.877579) (xy 390.531858 -374.877076) (xy 391.248138 -374.877076)
			(xy 391.258303 -374.877503) (xy 391.27708 -374.885297) (xy 391.291445 -374.899684) (xy 391.299212 -374.918472)
			(xy 391.2997 -374.928638) (xy 391.2997 -375.08688) (xy 391.30012 -375.096066) (xy 391.306627 -375.113251)
			(xy 391.3124 -375.120408) (xy 391.334218 -375.146035) (xy 391.372163 -375.201626) (xy 391.403193 -375.261353)
			(xy 391.426862 -375.324361) (xy 391.442832 -375.389746) (xy 391.450873 -375.456571) (xy 391.45087 -375.523877)
			(xy 391.442823 -375.590702) (xy 391.426848 -375.656085) (xy 391.403173 -375.719091) (xy 391.372139 -375.778816)
			(xy 391.334188 -375.834403) (xy 391.3124 -375.860056) (xy 391.306597 -375.867197) (xy 391.300086 -375.884391)
			(xy 391.2997 -375.893584) (xy 391.2997 -376.386852) (xy 391.300133 -376.396037) (xy 391.306631 -376.413221)
			(xy 391.3124 -376.42038) (xy 391.33419 -376.446029) (xy 391.372137 -376.501617) (xy 391.403168 -376.561342)
			(xy 391.426838 -376.624346) (xy 391.44281 -376.689728) (xy 391.450853 -376.756551) (xy 391.450853 -376.823855)
			(xy 391.450846 -376.823915) (xy 421.128651 -376.823915) (xy 421.128651 -376.756491) (xy 421.136727 -376.689552)
			(xy 421.152763 -376.624063) (xy 421.176528 -376.560966) (xy 421.20768 -376.50117) (xy 421.245771 -376.445537)
			(xy 421.267636 -376.419872) (xy 421.273432 -376.412726) (xy 421.279946 -376.395536) (xy 421.280336 -376.386344)
			(xy 421.280336 -375.894092) (xy 421.279922 -375.884905) (xy 421.27341 -375.867721) (xy 421.267636 -375.860564)
			(xy 421.245802 -375.834873) (xy 421.20771 -375.779243) (xy 421.176556 -375.719451) (xy 421.152788 -375.656357)
			(xy 421.13675 -375.590871) (xy 421.128671 -375.523935) (xy 421.128668 -375.456513) (xy 421.136741 -375.389576)
			(xy 421.152774 -375.324089) (xy 421.176536 -375.260993) (xy 421.207685 -375.201198) (xy 421.245773 -375.145565)
			(xy 421.267636 -375.1199) (xy 421.27342 -375.112746) (xy 421.279941 -375.095562) (xy 421.280336 -375.086372)
			(xy 421.280336 -374.928638) (xy 421.280858 -374.918514) (xy 421.288572 -374.899795) (xy 421.302848 -374.885437)
			(xy 421.321523 -374.877616) (xy 421.331644 -374.877076) (xy 422.047924 -374.877076) (xy 422.058031 -374.877565)
			(xy 422.076706 -374.885306) (xy 422.090999 -374.899601) (xy 422.098737 -374.918277) (xy 422.099232 -374.928384)
			(xy 422.099232 -375.086372) (xy 422.099671 -375.095556) (xy 422.106166 -375.11274) (xy 422.111932 -375.1199)
			(xy 422.133826 -375.14554) (xy 422.171912 -375.201179) (xy 422.203059 -375.260979) (xy 422.22682 -375.324079)
			(xy 422.242853 -375.389571) (xy 422.250926 -375.456511) (xy 422.250923 -375.523937) (xy 422.242844 -375.590877)
			(xy 422.226806 -375.656367) (xy 422.20304 -375.719465) (xy 422.171887 -375.779263) (xy 422.133797 -375.834898)
			(xy 422.111932 -375.860564) (xy 422.106117 -375.867696) (xy 422.099615 -375.884897) (xy 422.099232 -375.894092)
			(xy 422.099232 -376.386344) (xy 422.099636 -376.395532) (xy 422.106156 -376.412715) (xy 422.111932 -376.419872)
			(xy 422.133799 -376.445535) (xy 422.171885 -376.50117) (xy 422.203034 -376.560967) (xy 422.226797 -376.624064)
			(xy 422.242831 -376.689553) (xy 422.250906 -376.756491) (xy 422.250906 -376.756551) (xy 425.52897 -376.756551)
			(xy 425.537014 -376.689729) (xy 425.552986 -376.624347) (xy 425.576658 -376.561343) (xy 425.607689 -376.501619)
			(xy 425.645637 -376.446032) (xy 425.667424 -376.42038) (xy 425.673214 -376.413231) (xy 425.679732 -376.396043)
			(xy 425.680124 -376.386852) (xy 425.680124 -375.893584) (xy 425.679716 -375.884397) (xy 425.6732 -375.867213)
			(xy 425.667424 -375.860056) (xy 425.645668 -375.834378) (xy 425.60772 -375.778795) (xy 425.576686 -375.719074)
			(xy 425.553012 -375.656073) (xy 425.537037 -375.590695) (xy 425.528991 -375.523875) (xy 425.528988 -375.456573)
			(xy 425.537029 -375.389753) (xy 425.552998 -375.324373) (xy 425.576666 -375.26137) (xy 425.607695 -375.201647)
			(xy 425.645639 -375.146061) (xy 425.667424 -375.120408) (xy 425.673202 -375.11325) (xy 425.679727 -375.096069)
			(xy 425.680124 -375.08688) (xy 425.680124 -374.928638) (xy 425.680595 -374.918471) (xy 425.688365 -374.899679)
			(xy 425.702736 -374.885294) (xy 425.721519 -374.877505) (xy 425.731686 -374.877076) (xy 426.447966 -374.877076)
			(xy 426.45814 -374.877493) (xy 426.476941 -374.885274) (xy 426.491329 -374.899662) (xy 426.499108 -374.918464)
			(xy 426.499528 -374.928638) (xy 426.499528 -375.08688) (xy 426.499941 -375.096067) (xy 426.506452 -375.113252)
			(xy 426.512228 -375.120408) (xy 426.534048 -375.146034) (xy 426.571998 -375.201623) (xy 426.603032 -375.26135)
			(xy 426.626705 -375.324358) (xy 426.642676 -375.389744) (xy 426.650718 -375.45657) (xy 426.650716 -375.523878)
			(xy 426.642668 -375.590704) (xy 426.62669 -375.656088) (xy 426.603013 -375.719094) (xy 426.571974 -375.778818)
			(xy 426.534019 -375.834404) (xy 426.512228 -375.860056) (xy 426.506416 -375.86719) (xy 426.499913 -375.884389)
			(xy 426.499528 -375.893584) (xy 426.499528 -376.386852) (xy 426.499955 -376.396037) (xy 426.506456 -376.413222)
			(xy 426.512228 -376.42038) (xy 426.534021 -376.446029) (xy 426.571971 -376.501615) (xy 426.603006 -376.561338)
			(xy 426.62668 -376.624344) (xy 426.642654 -376.689727) (xy 426.650698 -376.75655) (xy 426.650698 -376.823856)
			(xy 426.650691 -376.823915) (xy 429.928739 -376.823915) (xy 429.928739 -376.756491) (xy 429.936814 -376.689553)
			(xy 429.95285 -376.624064) (xy 429.976615 -376.560967) (xy 430.007766 -376.501171) (xy 430.045856 -376.445537)
			(xy 430.06772 -376.419872) (xy 430.073513 -376.412725) (xy 430.080029 -376.395536) (xy 430.08042 -376.386344)
			(xy 430.08042 -375.894092) (xy 430.080009 -375.884905) (xy 430.073496 -375.867721) (xy 430.06772 -375.860564)
			(xy 430.045887 -375.834873) (xy 430.007796 -375.779243) (xy 429.976643 -375.71945) (xy 429.952876 -375.656357)
			(xy 429.936837 -375.590871) (xy 429.928759 -375.523935) (xy 429.928756 -375.456513) (xy 429.936829 -375.389577)
			(xy 429.952861 -375.324089) (xy 429.976623 -375.260994) (xy 430.007771 -375.201199) (xy 430.045857 -375.145565)
			(xy 430.06772 -375.1199) (xy 430.073501 -375.112744) (xy 430.080024 -375.095562) (xy 430.08042 -375.086372)
			(xy 430.08042 -374.928638) (xy 430.080957 -374.918516) (xy 430.088669 -374.8998) (xy 430.10294 -374.885443)
			(xy 430.121609 -374.877619) (xy 430.131728 -374.877076) (xy 430.848008 -374.877076) (xy 430.85816 -374.877515)
			(xy 430.876907 -374.885308) (xy 430.89123 -374.899699) (xy 430.898933 -374.918484) (xy 430.899316 -374.928638)
			(xy 430.899316 -375.086372) (xy 430.899736 -375.095558) (xy 430.906242 -375.112743) (xy 430.912016 -375.1199)
			(xy 430.933911 -375.14554) (xy 430.971998 -375.201178) (xy 431.003146 -375.260978) (xy 431.026908 -375.324078)
			(xy 431.04294 -375.38957) (xy 431.051013 -375.456511) (xy 431.051011 -375.523937) (xy 431.042932 -375.590877)
			(xy 431.026893 -375.656368) (xy 431.003126 -375.719466) (xy 430.971973 -375.779263) (xy 430.933881 -375.834898)
			(xy 430.912016 -375.860564) (xy 430.906212 -375.867704) (xy 430.899701 -375.884898) (xy 430.899316 -375.894092)
			(xy 430.899316 -376.386344) (xy 430.899701 -376.395534) (xy 430.906232 -376.412718) (xy 430.912016 -376.419872)
			(xy 430.933883 -376.445534) (xy 430.971971 -376.50117) (xy 431.003121 -376.560966) (xy 431.026884 -376.624064)
			(xy 431.042918 -376.689553) (xy 431.050994 -376.756491) (xy 431.050994 -376.756551) (xy 434.329058 -376.756551)
			(xy 434.337101 -376.689729) (xy 434.353073 -376.624348) (xy 434.376744 -376.561343) (xy 434.407775 -376.50162)
			(xy 434.445721 -376.446033) (xy 434.467508 -376.42038) (xy 434.473296 -376.413229) (xy 434.479816 -376.396043)
			(xy 434.480208 -376.386852) (xy 434.480208 -375.893584) (xy 434.479804 -375.884396) (xy 434.473286 -375.867212)
			(xy 434.467508 -375.860056) (xy 434.445753 -375.834378) (xy 434.407805 -375.778794) (xy 434.376772 -375.719074)
			(xy 434.353099 -375.656073) (xy 434.337124 -375.590694) (xy 434.329078 -375.523875) (xy 434.329075 -375.456573)
			(xy 434.337116 -375.389753) (xy 434.353084 -375.324373) (xy 434.376752 -375.26137) (xy 434.40778 -375.201647)
			(xy 434.445723 -375.146061) (xy 434.467508 -375.120408) (xy 434.473285 -375.113249) (xy 434.479811 -375.096069)
			(xy 434.480208 -375.08688) (xy 434.480208 -374.928638) (xy 434.480694 -374.918473) (xy 434.488461 -374.899684)
			(xy 434.502827 -374.885299) (xy 434.521605 -374.877508) (xy 434.53177 -374.877076) (xy 435.24805 -374.877076)
			(xy 435.258223 -374.877506) (xy 435.277024 -374.885281) (xy 435.291412 -374.899666) (xy 435.299192 -374.918465)
			(xy 435.299612 -374.928638) (xy 435.299612 -375.08688) (xy 435.300029 -375.096067) (xy 435.306538 -375.113251)
			(xy 435.312312 -375.120408) (xy 435.334133 -375.146034) (xy 435.372084 -375.201623) (xy 435.403118 -375.26135)
			(xy 435.426791 -375.324358) (xy 435.442764 -375.389744) (xy 435.450806 -375.45657) (xy 435.450803 -375.523878)
			(xy 435.442755 -375.590704) (xy 435.426777 -375.656088) (xy 435.403099 -375.719094) (xy 435.372059 -375.778819)
			(xy 435.334103 -375.834404) (xy 435.312312 -375.860056) (xy 435.306511 -375.867198) (xy 435.299998 -375.884391)
			(xy 435.299612 -375.893584) (xy 435.299612 -376.386852) (xy 435.300042 -376.396037) (xy 435.306542 -376.413222)
			(xy 435.312312 -376.42038) (xy 435.334105 -376.446028) (xy 435.372057 -376.501614) (xy 435.403093 -376.561338)
			(xy 435.426768 -376.624343) (xy 435.442742 -376.689726) (xy 435.450786 -376.75655) (xy 435.450786 -376.823856)
			(xy 435.442741 -376.89068) (xy 435.426766 -376.956063) (xy 435.40309 -377.019068) (xy 435.372054 -377.078791)
			(xy 435.334101 -377.134376) (xy 435.312312 -377.160028) (xy 435.306522 -377.167178) (xy 435.300003 -377.184365)
			(xy 435.299612 -377.193556) (xy 435.299612 -377.35129) (xy 435.299227 -377.361467) (xy 435.291436 -377.380271)
			(xy 435.277038 -377.394658) (xy 435.258228 -377.402435) (xy 435.24805 -377.402852) (xy 434.53177 -377.402852)
			(xy 434.521609 -377.402391) (xy 434.502837 -377.394605) (xy 434.488473 -377.380229) (xy 434.480701 -377.361451)
			(xy 434.480208 -377.35129) (xy 434.480208 -377.193556) (xy 434.479817 -377.184367) (xy 434.47329 -377.167183)
			(xy 434.467508 -377.160028) (xy 434.445725 -377.134372) (xy 434.407778 -377.078786) (xy 434.376746 -377.019062)
			(xy 434.353075 -376.956058) (xy 434.337103 -376.890677) (xy 434.329059 -376.823855) (xy 434.329058 -376.756551)
			(xy 431.050994 -376.756551) (xy 431.050993 -376.823915) (xy 431.042917 -376.890853) (xy 431.026882 -376.956342)
			(xy 431.003118 -377.019439) (xy 430.971968 -377.079236) (xy 430.93388 -377.13487) (xy 430.912016 -377.160536)
			(xy 430.906223 -377.167684) (xy 430.899706 -377.184872) (xy 430.899316 -377.194064) (xy 430.899316 -377.35129)
			(xy 430.898864 -377.361421) (xy 430.891131 -377.380151) (xy 430.876834 -377.394509) (xy 430.858137 -377.402321)
			(xy 430.848008 -377.402852) (xy 430.131728 -377.402852) (xy 430.121582 -377.402357) (xy 430.10284 -377.39458)
			(xy 430.088518 -377.380207) (xy 430.080808 -377.361437) (xy 430.08042 -377.35129) (xy 430.08042 -377.194064)
			(xy 430.080023 -377.184876) (xy 430.0735 -377.167692) (xy 430.06772 -377.160536) (xy 430.045859 -377.134868)
			(xy 430.007769 -377.079234) (xy 429.976617 -377.019439) (xy 429.952852 -376.956342) (xy 429.936815 -376.890853)
			(xy 429.928739 -376.823915) (xy 426.650691 -376.823915) (xy 426.642653 -376.890679) (xy 426.626679 -376.956062)
			(xy 426.603004 -377.019067) (xy 426.571968 -377.07879) (xy 426.534017 -377.134376) (xy 426.512228 -377.160028)
			(xy 426.506428 -377.167171) (xy 426.499918 -377.184363) (xy 426.499528 -377.193556) (xy 426.499528 -377.35129)
			(xy 426.499127 -377.361465) (xy 426.491339 -377.380266) (xy 426.476946 -377.394653) (xy 426.458141 -377.402432)
			(xy 426.447966 -377.402852) (xy 425.731686 -377.402852) (xy 425.721526 -377.402378) (xy 425.702755 -377.394597)
			(xy 425.68839 -377.380225) (xy 425.680618 -377.36145) (xy 425.680124 -377.35129) (xy 425.680124 -377.193556)
			(xy 425.67973 -377.184367) (xy 425.673204 -377.167183) (xy 425.667424 -377.160028) (xy 425.645641 -377.134372)
			(xy 425.607693 -377.078786) (xy 425.57666 -377.019063) (xy 425.552988 -376.956059) (xy 425.537015 -376.890677)
			(xy 425.528971 -376.823855) (xy 425.52897 -376.756551) (xy 422.250906 -376.756551) (xy 422.250905 -376.823915)
			(xy 422.24283 -376.890853) (xy 422.226795 -376.956342) (xy 422.203032 -377.019438) (xy 422.171882 -377.079235)
			(xy 422.133795 -377.13487) (xy 422.111932 -377.160536) (xy 422.106129 -377.167677) (xy 422.09962 -377.184871)
			(xy 422.099232 -377.194064) (xy 422.099232 -377.35129) (xy 422.098764 -377.36142) (xy 422.091035 -377.380146)
			(xy 422.076742 -377.394503) (xy 422.058051 -377.402318) (xy 422.047924 -377.402852) (xy 421.331644 -377.402852)
			(xy 421.321544 -377.40228) (xy 421.302877 -377.394567) (xy 421.288583 -377.380297) (xy 421.280837 -377.361643)
			(xy 421.280336 -377.351544) (xy 421.280336 -377.194064) (xy 421.279935 -377.184876) (xy 421.273414 -377.167692)
			(xy 421.267636 -377.160536) (xy 421.245775 -377.134868) (xy 421.207684 -377.079235) (xy 421.176531 -377.019439)
			(xy 421.152765 -376.956343) (xy 421.136728 -376.890854) (xy 421.128651 -376.823915) (xy 391.450846 -376.823915)
			(xy 391.442809 -376.890678) (xy 391.426837 -376.956059) (xy 391.403165 -377.019064) (xy 391.372134 -377.078788)
			(xy 391.334187 -377.134375) (xy 391.3124 -377.160028) (xy 391.306609 -377.167177) (xy 391.300091 -377.184365)
			(xy 391.2997 -377.193556) (xy 391.2997 -377.35129) (xy 391.299159 -377.361442) (xy 391.291395 -377.380204)
			(xy 391.277044 -377.394568) (xy 391.25829 -377.40235) (xy 391.248138 -377.402852) (xy 390.531858 -377.402852)
			(xy 390.521696 -377.402401) (xy 390.502924 -377.394611) (xy 390.48856 -377.380232) (xy 390.480789 -377.361452)
			(xy 390.480296 -377.35129) (xy 390.480296 -377.193556) (xy 390.479908 -377.184366) (xy 390.473379 -377.167182)
			(xy 390.467596 -377.160028) (xy 390.445814 -377.134372) (xy 390.407867 -377.078785) (xy 390.376836 -377.019062)
			(xy 390.353165 -376.956058) (xy 390.337193 -376.890676) (xy 390.329149 -376.823855) (xy 387.051084 -376.823855)
			(xy 387.051084 -376.823915) (xy 387.043008 -376.890853) (xy 387.026972 -376.956343) (xy 387.003208 -377.01944)
			(xy 386.972057 -377.079236) (xy 386.933968 -377.134871) (xy 386.912104 -377.160536) (xy 386.90631 -377.167683)
			(xy 386.899794 -377.184872) (xy 386.899404 -377.194064) (xy 386.899404 -377.35129) (xy 386.898867 -377.361411)
			(xy 386.89115 -377.380123) (xy 386.87688 -377.394478) (xy 386.858214 -377.402306) (xy 386.848096 -377.402852)
			(xy 386.131816 -377.402852) (xy 386.121669 -377.402366) (xy 386.102927 -377.394586) (xy 386.088605 -377.380209)
			(xy 386.080896 -377.361438) (xy 386.080508 -377.35129) (xy 386.080508 -377.194064) (xy 386.080114 -377.184875)
			(xy 386.073589 -377.167691) (xy 386.067808 -377.160536) (xy 386.045948 -377.134868) (xy 386.007858 -377.079234)
			(xy 385.976707 -377.019438) (xy 385.952942 -376.956342) (xy 385.936906 -376.890853) (xy 385.92883 -376.823915)
			(xy 382.650782 -376.823915) (xy 382.642744 -376.89068) (xy 382.626769 -376.956063) (xy 382.603094 -377.019068)
			(xy 382.572058 -377.078791) (xy 382.534105 -377.134376) (xy 382.512316 -377.160028) (xy 382.506527 -377.167179)
			(xy 382.500007 -377.184365) (xy 382.499616 -377.193556) (xy 382.499616 -377.35129) (xy 382.499227 -377.361467)
			(xy 382.491437 -377.38027) (xy 382.47704 -377.394657) (xy 382.458231 -377.402434) (xy 382.448054 -377.402852)
			(xy 381.731774 -377.402852) (xy 381.721613 -377.402388) (xy 381.702842 -377.394603) (xy 381.688477 -377.380228)
			(xy 381.680705 -377.361451) (xy 381.680212 -377.35129) (xy 381.680212 -377.193556) (xy 381.67982 -377.184367)
			(xy 381.673294 -377.167183) (xy 381.667512 -377.160028) (xy 381.645729 -377.134372) (xy 381.607782 -377.078786)
			(xy 381.57675 -377.019062) (xy 381.553078 -376.956058) (xy 381.537106 -376.890677) (xy 381.529062 -376.823855)
			(xy 381.529061 -376.756551) (xy 378.250997 -376.756551) (xy 378.250996 -376.823915) (xy 378.24292 -376.890853)
			(xy 378.226885 -376.956342) (xy 378.203121 -377.019439) (xy 378.171971 -377.079235) (xy 378.133884 -377.13487)
			(xy 378.11202 -377.160536) (xy 378.106228 -377.167685) (xy 378.09971 -377.184872) (xy 378.09932 -377.194064)
			(xy 378.09932 -377.35129) (xy 378.098864 -377.361421) (xy 378.091132 -377.38015) (xy 378.076836 -377.394508)
			(xy 378.058141 -377.40232) (xy 378.048012 -377.402852) (xy 377.331732 -377.402852) (xy 377.321586 -377.402353)
			(xy 377.302845 -377.394578) (xy 377.288522 -377.380206) (xy 377.280812 -377.361437) (xy 377.280424 -377.35129)
			(xy 377.280424 -377.194064) (xy 377.280026 -377.184876) (xy 377.273503 -377.167692) (xy 377.267724 -377.160536)
			(xy 377.245863 -377.134868) (xy 377.207773 -377.079234) (xy 377.17662 -377.019439) (xy 377.152855 -376.956342)
			(xy 377.136819 -376.890853) (xy 377.128742 -376.823915) (xy 347.450937 -376.823915) (xy 347.4429 -376.890678)
			(xy 347.426927 -376.95606) (xy 347.403255 -377.019065) (xy 347.372223 -377.078788) (xy 347.334275 -377.134376)
			(xy 347.312488 -377.160028) (xy 347.306696 -377.167176) (xy 347.300179 -377.184364) (xy 347.299788 -377.193556)
			(xy 347.299788 -377.35129) (xy 347.299259 -377.361444) (xy 347.291493 -377.380208) (xy 347.277138 -377.394573)
			(xy 347.25838 -377.402352) (xy 347.248226 -377.402852) (xy 346.531946 -377.402852) (xy 346.521776 -377.402398)
			(xy 346.502981 -377.394627) (xy 346.488594 -377.38025) (xy 346.480809 -377.36146) (xy 346.480384 -377.35129)
			(xy 346.480384 -377.193556) (xy 346.479999 -377.184366) (xy 346.473468 -377.167182) (xy 346.467684 -377.160028)
			(xy 346.445899 -377.134373) (xy 346.407947 -377.078788) (xy 346.376911 -377.019065) (xy 346.353236 -376.956061)
			(xy 346.337262 -376.890679) (xy 346.329216 -376.823856) (xy 343.051175 -376.823856) (xy 343.051175 -376.823915)
			(xy 343.043099 -376.890854) (xy 343.027063 -376.956343) (xy 343.003298 -377.01944) (xy 342.972146 -377.079236)
			(xy 342.934056 -377.134871) (xy 342.912192 -377.160536) (xy 342.906397 -377.167682) (xy 342.899882 -377.184872)
			(xy 342.899492 -377.194064) (xy 342.899492 -377.35129) (xy 342.898966 -377.361412) (xy 342.891248 -377.380127)
			(xy 342.876974 -377.394483) (xy 342.858303 -377.402308) (xy 342.848184 -377.402852) (xy 342.131904 -377.402852)
			(xy 342.121757 -377.402376) (xy 342.103014 -377.394592) (xy 342.088693 -377.380212) (xy 342.080984 -377.361439)
			(xy 342.080596 -377.35129) (xy 342.080596 -377.194064) (xy 342.080204 -377.184875) (xy 342.073678 -377.167691)
			(xy 342.067896 -377.160536) (xy 342.046036 -377.134867) (xy 342.007948 -377.079233) (xy 341.976797 -377.019438)
			(xy 341.953033 -376.956341) (xy 341.936997 -376.890852) (xy 341.928921 -376.823915) (xy 338.650849 -376.823915)
			(xy 338.642812 -376.890677) (xy 338.62684 -376.956059) (xy 338.603168 -377.019064) (xy 338.572137 -377.078788)
			(xy 338.534191 -377.134375) (xy 338.512404 -377.160028) (xy 338.506614 -377.167178) (xy 338.500095 -377.184365)
			(xy 338.499704 -377.193556) (xy 338.499704 -377.35129) (xy 338.49916 -377.361442) (xy 338.491396 -377.380203)
			(xy 338.477047 -377.394567) (xy 338.458293 -377.402349) (xy 338.448142 -377.402852) (xy 337.731862 -377.402852)
			(xy 337.721701 -377.402397) (xy 337.702929 -377.394609) (xy 337.688564 -377.380231) (xy 337.680793 -377.361452)
			(xy 337.6803 -377.35129) (xy 337.6803 -377.193556) (xy 337.679911 -377.184367) (xy 337.673383 -377.167182)
			(xy 337.6676 -377.160028) (xy 337.645817 -377.134372) (xy 337.607871 -377.078785) (xy 337.57684 -377.019062)
			(xy 337.553168 -376.956058) (xy 337.537196 -376.890677) (xy 337.529152 -376.823855) (xy 334.251087 -376.823855)
			(xy 334.251087 -376.823915) (xy 334.243011 -376.890853) (xy 334.226976 -376.956342) (xy 334.203211 -377.019439)
			(xy 334.172061 -377.079236) (xy 334.133972 -377.134871) (xy 334.112108 -377.160536) (xy 334.106315 -377.167684)
			(xy 334.099798 -377.184872) (xy 334.099408 -377.194064) (xy 334.099408 -377.35129) (xy 334.098867 -377.36141)
			(xy 334.091151 -377.380122) (xy 334.076882 -377.394477) (xy 334.058217 -377.402305) (xy 334.0481 -377.402852)
			(xy 333.33182 -377.402852) (xy 333.321674 -377.402363) (xy 333.302932 -377.394584) (xy 333.288609 -377.380209)
			(xy 333.2809 -377.361438) (xy 333.280512 -377.35129) (xy 333.280512 -377.194064) (xy 333.280117 -377.184875)
			(xy 333.273592 -377.167691) (xy 333.267812 -377.160536) (xy 333.245952 -377.134868) (xy 333.207862 -377.079234)
			(xy 333.17671 -377.019438) (xy 333.152945 -376.956342) (xy 333.136909 -376.890853) (xy 333.128833 -376.823915)
			(xy 303.451057 -376.823915) (xy 303.44298 -376.890854) (xy 303.426944 -376.956344) (xy 303.403178 -377.019441)
			(xy 303.372025 -377.079237) (xy 303.333933 -377.134871) (xy 303.312068 -377.160536) (xy 303.30627 -377.16768)
			(xy 303.299757 -377.184871) (xy 303.299368 -377.194064) (xy 303.299368 -377.35129) (xy 303.298865 -377.361415)
			(xy 303.291142 -377.380135) (xy 303.276861 -377.394491) (xy 303.258182 -377.402312) (xy 303.24806 -377.402852)
			(xy 302.53178 -377.402852) (xy 302.521631 -377.402396) (xy 302.502888 -377.394604) (xy 302.488567 -377.380218)
			(xy 302.480859 -377.361441) (xy 302.480472 -377.35129) (xy 302.480472 -377.194064) (xy 302.480085 -377.184874)
			(xy 302.473556 -377.16769) (xy 302.467772 -377.160536) (xy 302.445913 -377.134867) (xy 302.407826 -377.079232)
			(xy 302.376677 -377.019436) (xy 302.352913 -376.95634) (xy 302.336879 -376.890852) (xy 302.328803 -376.823914)
			(xy 302.328802 -376.756492) (xy 299.050731 -376.756492) (xy 299.050738 -376.756551) (xy 299.050738 -376.823856)
			(xy 299.042693 -376.890678) (xy 299.026721 -376.95606) (xy 299.003048 -377.019065) (xy 298.972016 -377.078789)
			(xy 298.934067 -377.134376) (xy 298.91228 -377.160028) (xy 298.906487 -377.167175) (xy 298.899971 -377.184364)
			(xy 298.89958 -377.193556) (xy 298.89958 -377.35129) (xy 298.899059 -377.361445) (xy 298.891291 -377.38021)
			(xy 298.876934 -377.394575) (xy 298.858173 -377.402353) (xy 298.848018 -377.402852) (xy 298.131738 -377.402852)
			(xy 298.121568 -377.402405) (xy 298.102772 -377.39463) (xy 298.088385 -377.380252) (xy 298.080601 -377.36146)
			(xy 298.080176 -377.35129) (xy 298.080176 -377.193556) (xy 298.079792 -377.184366) (xy 298.073261 -377.167182)
			(xy 298.067476 -377.160028) (xy 298.045691 -377.134373) (xy 298.00774 -377.078788) (xy 297.976704 -377.019065)
			(xy 297.95303 -376.956061) (xy 297.937055 -376.890679) (xy 297.92901 -376.823856) (xy 294.650969 -376.823856)
			(xy 294.650969 -376.823915) (xy 294.642893 -376.890854) (xy 294.626856 -376.956343) (xy 294.603091 -377.019441)
			(xy 294.571939 -377.079237) (xy 294.533849 -377.134871) (xy 294.511984 -377.160536) (xy 294.506188 -377.167681)
			(xy 294.499673 -377.184872) (xy 294.499284 -377.194064) (xy 294.499284 -377.35129) (xy 294.498766 -377.361413)
			(xy 294.491046 -377.38013) (xy 294.47677 -377.394485) (xy 294.458096 -377.402309) (xy 294.447976 -377.402852)
			(xy 293.731696 -377.402852) (xy 293.721593 -377.402319) (xy 293.702925 -377.39459) (xy 293.688632 -377.380308)
			(xy 293.680889 -377.361646) (xy 293.680388 -377.351544) (xy 293.680388 -377.194064) (xy 293.679998 -377.184875)
			(xy 293.673471 -377.16769) (xy 293.667688 -377.160536) (xy 293.645828 -377.134867) (xy 293.60774 -377.079233)
			(xy 293.57659 -377.019437) (xy 293.552826 -376.956341) (xy 293.536791 -376.890852) (xy 293.528715 -376.823915)
			(xy 290.250643 -376.823915) (xy 290.242606 -376.890678) (xy 290.226633 -376.95606) (xy 290.202962 -377.019064)
			(xy 290.17193 -377.078788) (xy 290.133983 -377.134375) (xy 290.112196 -377.160028) (xy 290.106405 -377.167177)
			(xy 290.099887 -377.184365) (xy 290.099496 -377.193556) (xy 290.099496 -377.35129) (xy 290.098959 -377.361443)
			(xy 290.091194 -377.380205) (xy 290.076842 -377.39457) (xy 290.058087 -377.402351) (xy 290.047934 -377.402852)
			(xy 289.331654 -377.402852) (xy 289.321492 -377.402404) (xy 289.30272 -377.394613) (xy 289.288356 -377.380233)
			(xy 289.280585 -377.361452) (xy 289.280092 -377.35129) (xy 289.280092 -377.193556) (xy 289.279705 -377.184366)
			(xy 289.273176 -377.167182) (xy 289.267392 -377.160028) (xy 289.245607 -377.134373) (xy 289.207654 -377.078788)
			(xy 289.176618 -377.019066) (xy 289.152942 -376.956061) (xy 289.136968 -376.890679) (xy 289.128922 -376.823856)
			(xy 273.068299 -376.823856) (xy 273.100384 -376.843252) (xy 273.210304 -376.919124) (xy 273.315441 -377.001494)
			(xy 273.415414 -377.090062) (xy 273.509856 -377.184504) (xy 273.598424 -377.284477) (xy 273.680794 -377.389614)
			(xy 273.756666 -377.499534) (xy 273.825762 -377.613833) (xy 273.887832 -377.732096) (xy 273.942647 -377.853891)
			(xy 273.990009 -377.978774) (xy 274.029744 -378.106288) (xy 274.061707 -378.235969) (xy 274.077801 -378.323794)
			(xy 286.928742 -378.323794) (xy 286.928744 -378.256367) (xy 286.936824 -378.189426) (xy 286.952863 -378.123935)
			(xy 286.976633 -378.060837) (xy 287.007789 -378.00104) (xy 287.045885 -377.945406) (xy 287.067752 -377.919742)
			(xy 287.073562 -377.912607) (xy 287.080067 -377.895408) (xy 287.080452 -377.886214) (xy 287.080452 -377.728734)
			(xy 287.080955 -377.718608) (xy 287.088674 -377.699885) (xy 287.102955 -377.685528) (xy 287.121637 -377.677709)
			(xy 287.13176 -377.677172) (xy 287.84804 -377.677172) (xy 287.858148 -377.677652) (xy 287.876822 -377.685397)
			(xy 287.891114 -377.699695) (xy 287.898852 -377.718372) (xy 287.899348 -377.72848) (xy 287.899348 -377.886214)
			(xy 287.899763 -377.8954) (xy 287.906275 -377.912584) (xy 287.912048 -377.919742) (xy 287.933888 -377.945427)
			(xy 287.971981 -378.001058) (xy 288.003136 -378.060851) (xy 288.026904 -378.123945) (xy 288.042943 -378.189432)
			(xy 288.051021 -378.256369) (xy 288.051024 -378.323734) (xy 291.329062 -378.323734) (xy 291.329064 -378.256427)
			(xy 291.337111 -378.189602) (xy 291.353086 -378.124219) (xy 291.376762 -378.061213) (xy 291.407799 -378.001489)
			(xy 291.445751 -377.945902) (xy 291.46754 -377.92025) (xy 291.473345 -377.913111) (xy 291.479854 -377.895916)
			(xy 291.48024 -377.886722) (xy 291.48024 -377.728734) (xy 291.480692 -377.718564) (xy 291.488466 -377.69977)
			(xy 291.502843 -377.685384) (xy 291.521633 -377.677598) (xy 291.531802 -377.677172) (xy 292.248082 -377.677172)
			(xy 292.258257 -377.677579) (xy 292.277058 -377.685365) (xy 292.291444 -377.699756) (xy 292.299224 -377.718559)
			(xy 292.299644 -377.728734) (xy 292.299644 -377.886722) (xy 292.300056 -377.895909) (xy 292.30657 -377.913092)
			(xy 292.312344 -377.92025) (xy 292.334107 -377.945923) (xy 292.372057 -378.001506) (xy 292.403093 -378.061227)
			(xy 292.426768 -378.124228) (xy 292.442743 -378.189608) (xy 292.450789 -378.256429) (xy 292.450792 -378.323732)
			(xy 292.450785 -378.323794) (xy 295.72883 -378.323794) (xy 295.728832 -378.256367) (xy 295.736911 -378.189427)
			(xy 295.752951 -378.123936) (xy 295.776719 -378.060837) (xy 295.807875 -378.001041) (xy 295.845969 -377.945407)
			(xy 295.867836 -377.919742) (xy 295.873644 -377.912605) (xy 295.880151 -377.895408) (xy 295.880536 -377.886214)
			(xy 295.880536 -377.728734) (xy 295.881055 -377.71861) (xy 295.88877 -377.69989) (xy 295.903047 -377.685533)
			(xy 295.921723 -377.677712) (xy 295.931844 -377.677172) (xy 296.648124 -377.677172) (xy 296.658276 -377.677601)
			(xy 296.677024 -377.6854) (xy 296.691345 -377.699793) (xy 296.699049 -377.71858) (xy 296.699432 -377.728734)
			(xy 296.699432 -377.886214) (xy 296.699851 -377.8954) (xy 296.70636 -377.912584) (xy 296.712132 -377.919742)
			(xy 296.733969 -377.945429) (xy 296.772057 -378.001061) (xy 296.803207 -378.060855) (xy 296.826971 -378.123949)
			(xy 296.843007 -378.189435) (xy 296.851085 -378.25637) (xy 296.851087 -378.323791) (xy 296.851087 -378.323794)
			(xy 300.128621 -378.323794) (xy 300.128623 -378.256367) (xy 300.136702 -378.189427) (xy 300.152741 -378.123936)
			(xy 300.176509 -378.060838) (xy 300.207664 -378.001041) (xy 300.245758 -377.945407) (xy 300.267624 -377.919742)
			(xy 300.27343 -377.912604) (xy 300.279938 -377.895408) (xy 300.280324 -377.886214) (xy 300.280324 -377.728734)
			(xy 300.280854 -377.718611) (xy 300.288568 -377.699894) (xy 300.302841 -377.685537) (xy 300.321512 -377.677714)
			(xy 300.331632 -377.677172) (xy 301.047912 -377.677172) (xy 301.058063 -377.677611) (xy 301.076811 -377.685405)
			(xy 301.091133 -377.699796) (xy 301.098837 -377.718581) (xy 301.09922 -377.728734) (xy 301.09922 -377.886214)
			(xy 301.099619 -377.895402) (xy 301.10614 -377.912587) (xy 301.11192 -377.919742) (xy 301.133758 -377.945429)
			(xy 301.171846 -378.001061) (xy 301.202997 -378.060854) (xy 301.226761 -378.123948) (xy 301.242798 -378.189434)
			(xy 301.250876 -378.25637) (xy 301.250878 -378.323734) (xy 330.92918 -378.323734) (xy 330.929182 -378.256427)
			(xy 330.937229 -378.189602) (xy 330.953206 -378.124218) (xy 330.976882 -378.061212) (xy 331.00792 -378.001488)
			(xy 331.045874 -377.945902) (xy 331.067664 -377.92025) (xy 331.073472 -377.913113) (xy 331.079978 -377.895916)
			(xy 331.080364 -377.886722) (xy 331.080364 -377.728734) (xy 331.080792 -377.718561) (xy 331.088571 -377.699763)
			(xy 331.102956 -377.685376) (xy 331.121753 -377.677594) (xy 331.131926 -377.677172) (xy 331.848206 -377.677172)
			(xy 331.858382 -377.67756) (xy 331.877184 -377.685353) (xy 331.891569 -377.69975) (xy 331.899348 -377.718557)
			(xy 331.899768 -377.728734) (xy 331.899768 -377.886722) (xy 331.900175 -377.895909) (xy 331.906692 -377.913093)
			(xy 331.912468 -377.92025) (xy 331.93423 -377.945923) (xy 331.972179 -378.001507) (xy 332.003213 -378.061228)
			(xy 332.026887 -378.124229) (xy 332.042861 -378.189609) (xy 332.050907 -378.256429) (xy 332.05091 -378.323732)
			(xy 332.050903 -378.323793) (xy 335.328973 -378.323793) (xy 335.328975 -378.256368) (xy 335.337053 -378.189429)
			(xy 335.35309 -378.123939) (xy 335.376855 -378.060841) (xy 335.408007 -378.001044) (xy 335.446096 -377.945408)
			(xy 335.46796 -377.919742) (xy 335.473771 -377.912607) (xy 335.480275 -377.895409) (xy 335.48066 -377.886214)
			(xy 335.48066 -377.728734) (xy 335.481155 -377.718607) (xy 335.488875 -377.699883) (xy 335.50316 -377.685525)
			(xy 335.521844 -377.677708) (xy 335.531968 -377.677172) (xy 336.248248 -377.677172) (xy 336.258402 -377.677582)
			(xy 336.27715 -377.685388) (xy 336.29147 -377.699787) (xy 336.299173 -377.718578) (xy 336.299556 -377.728734)
			(xy 336.299556 -377.886214) (xy 336.299969 -377.895401) (xy 336.306482 -377.912585) (xy 336.312256 -377.919742)
			(xy 336.334096 -377.945428) (xy 336.372188 -378.001058) (xy 336.403343 -378.060851) (xy 336.42711 -378.123945)
			(xy 336.443149 -378.189433) (xy 336.451227 -378.256369) (xy 336.45123 -378.323734) (xy 339.729268 -378.323734)
			(xy 339.72927 -378.256427) (xy 339.737317 -378.189602) (xy 339.753293 -378.124218) (xy 339.776969 -378.061213)
			(xy 339.808006 -378.001489) (xy 339.845958 -377.945902) (xy 339.867748 -377.92025) (xy 339.873554 -377.913112)
			(xy 339.880062 -377.895916) (xy 339.880448 -377.886722) (xy 339.880448 -377.728734) (xy 339.880892 -377.718563)
			(xy 339.888668 -377.699768) (xy 339.903047 -377.685381) (xy 339.92184 -377.677597) (xy 339.93201 -377.677172)
			(xy 340.64829 -377.677172) (xy 340.658465 -377.677573) (xy 340.677266 -377.685361) (xy 340.691653 -377.699754)
			(xy 340.699432 -377.718559) (xy 340.699852 -377.728734) (xy 340.699852 -377.886722) (xy 340.700262 -377.895909)
			(xy 340.706777 -377.913093) (xy 340.712552 -377.92025) (xy 340.734314 -377.945923) (xy 340.772264 -378.001506)
			(xy 340.803299 -378.061227) (xy 340.826974 -378.124229) (xy 340.842949 -378.189608) (xy 340.850995 -378.256429)
			(xy 340.850998 -378.323732) (xy 340.850998 -378.323734) (xy 344.129059 -378.323734) (xy 344.129061 -378.256427)
			(xy 344.137108 -378.189603) (xy 344.153083 -378.124219) (xy 344.176759 -378.061213) (xy 344.207795 -378.001489)
			(xy 344.245747 -377.945902) (xy 344.267536 -377.92025) (xy 344.273341 -377.913111) (xy 344.27985 -377.895916)
			(xy 344.280236 -377.886722) (xy 344.280236 -377.728734) (xy 344.280692 -377.718565) (xy 344.288465 -377.699771)
			(xy 344.302841 -377.685385) (xy 344.321629 -377.677599) (xy 344.331798 -377.677172) (xy 345.048078 -377.677172)
			(xy 345.058252 -377.677583) (xy 345.077053 -377.685367) (xy 345.09144 -377.699757) (xy 345.099219 -377.71856)
			(xy 345.09964 -377.728734) (xy 345.09964 -377.886722) (xy 345.100053 -377.895909) (xy 345.106566 -377.913092)
			(xy 345.11234 -377.92025) (xy 345.134103 -377.945923) (xy 345.172054 -378.001506) (xy 345.203089 -378.061226)
			(xy 345.226764 -378.124228) (xy 345.24274 -378.189608) (xy 345.250786 -378.256429) (xy 345.250789 -378.323732)
			(xy 345.250789 -378.323734) (xy 374.929089 -378.323734) (xy 374.929092 -378.256427) (xy 374.937139 -378.189602)
			(xy 374.953116 -378.124218) (xy 374.976793 -378.061212) (xy 375.007831 -378.001488) (xy 375.045786 -377.945902)
			(xy 375.067576 -377.92025) (xy 375.073374 -377.913105) (xy 375.079888 -377.895915) (xy 375.080276 -377.886722)
			(xy 375.080276 -377.728734) (xy 375.080693 -377.71856) (xy 375.088474 -377.699759) (xy 375.102862 -377.685371)
			(xy 375.121664 -377.677592) (xy 375.131838 -377.677172) (xy 375.848118 -377.677172) (xy 375.858295 -377.67755)
			(xy 375.877097 -377.685347) (xy 375.891482 -377.699747) (xy 375.89926 -377.718557) (xy 375.89968 -377.728734)
			(xy 375.89968 -377.886722) (xy 375.900084 -377.89591) (xy 375.906602 -377.913094) (xy 375.91238 -377.92025)
			(xy 375.934142 -377.945923) (xy 375.97209 -378.001507) (xy 376.003123 -378.061228) (xy 376.026797 -378.12423)
			(xy 376.042771 -378.189609) (xy 376.050817 -378.256429) (xy 376.050819 -378.323732) (xy 376.050812 -378.323793)
			(xy 379.328882 -378.323793) (xy 379.328884 -378.256368) (xy 379.336962 -378.189428) (xy 379.352999 -378.123938)
			(xy 379.376765 -378.06084) (xy 379.407917 -378.001043) (xy 379.446007 -377.945408) (xy 379.467872 -377.919742)
			(xy 379.473684 -377.912608) (xy 379.480188 -377.895409) (xy 379.480572 -377.886214) (xy 379.480572 -377.728734)
			(xy 379.481056 -377.718606) (xy 379.488778 -377.699879) (xy 379.503066 -377.685521) (xy 379.521754 -377.677706)
			(xy 379.53188 -377.677172) (xy 380.24816 -377.677172) (xy 380.258308 -377.677654) (xy 380.277054 -377.685431)
			(xy 380.291378 -377.699809) (xy 380.299084 -377.718584) (xy 380.299468 -377.728734) (xy 380.299468 -377.886214)
			(xy 380.299878 -377.895401) (xy 380.306393 -377.912585) (xy 380.312168 -377.919742) (xy 380.334008 -377.945428)
			(xy 380.372099 -378.001059) (xy 380.403253 -378.060852) (xy 380.42702 -378.123946) (xy 380.443058 -378.189433)
			(xy 380.451137 -378.256369) (xy 380.451139 -378.323734) (xy 383.729177 -378.323734) (xy 383.729179 -378.256427)
			(xy 383.737226 -378.189602) (xy 383.753202 -378.124218) (xy 383.776879 -378.061212) (xy 383.807917 -378.001488)
			(xy 383.84587 -377.945902) (xy 383.86766 -377.92025) (xy 383.873468 -377.913113) (xy 383.879974 -377.895916)
			(xy 383.88036 -377.886722) (xy 383.88036 -377.728734) (xy 383.880792 -377.718562) (xy 383.88857 -377.699764)
			(xy 383.902954 -377.685377) (xy 383.92175 -377.677595) (xy 383.931922 -377.677172) (xy 384.648202 -377.677172)
			(xy 384.658378 -377.677563) (xy 384.677179 -377.685355) (xy 384.691565 -377.699751) (xy 384.699344 -377.718558)
			(xy 384.699764 -377.728734) (xy 384.699764 -377.886722) (xy 384.700172 -377.895909) (xy 384.706688 -377.913093)
			(xy 384.712464 -377.92025) (xy 384.734226 -377.945923) (xy 384.772175 -378.001507) (xy 384.803209 -378.061228)
			(xy 384.826884 -378.124229) (xy 384.842858 -378.189609) (xy 384.850904 -378.256429) (xy 384.850907 -378.323732)
			(xy 384.850907 -378.323734) (xy 388.128968 -378.323734) (xy 388.12897 -378.256427) (xy 388.137017 -378.189602)
			(xy 388.152993 -378.124218) (xy 388.176669 -378.061213) (xy 388.207706 -378.001489) (xy 388.245658 -377.945902)
			(xy 388.267448 -377.92025) (xy 388.273254 -377.913112) (xy 388.279762 -377.895916) (xy 388.280148 -377.886722)
			(xy 388.280148 -377.728734) (xy 388.280592 -377.718563) (xy 388.288368 -377.699768) (xy 388.302747 -377.685381)
			(xy 388.32154 -377.677597) (xy 388.33171 -377.677172) (xy 389.04799 -377.677172) (xy 389.058165 -377.677573)
			(xy 389.076966 -377.685361) (xy 389.091353 -377.699754) (xy 389.099132 -377.718559) (xy 389.099552 -377.728734)
			(xy 389.099552 -377.886722) (xy 389.099962 -377.895909) (xy 389.106477 -377.913093) (xy 389.112252 -377.92025)
			(xy 389.134014 -377.945923) (xy 389.171964 -378.001506) (xy 389.202999 -378.061227) (xy 389.226674 -378.124229)
			(xy 389.242649 -378.189608) (xy 389.250695 -378.256429) (xy 389.250698 -378.323732) (xy 389.250698 -378.323734)
			(xy 418.928998 -378.323734) (xy 418.929001 -378.256426) (xy 418.937048 -378.189601) (xy 418.953025 -378.124217)
			(xy 418.976703 -378.061211) (xy 419.007742 -378.001487) (xy 419.045697 -377.945902) (xy 419.067488 -377.92025)
			(xy 419.073287 -377.913106) (xy 419.079801 -377.895915) (xy 419.080188 -377.886722) (xy 419.080188 -377.728734)
			(xy 419.080593 -377.718558) (xy 419.088376 -377.699755) (xy 419.102768 -377.685367) (xy 419.121574 -377.67759)
			(xy 419.13175 -377.677172) (xy 419.84803 -377.677172) (xy 419.858208 -377.67754) (xy 419.87701 -377.685341)
			(xy 419.891395 -377.699744) (xy 419.899173 -377.718556) (xy 419.899592 -377.728734) (xy 419.899592 -377.886722)
			(xy 419.899993 -377.89591) (xy 419.906513 -377.913094) (xy 419.912292 -377.92025) (xy 419.934053 -377.945924)
			(xy 419.972001 -378.001508) (xy 420.003034 -378.061229) (xy 420.026706 -378.12423) (xy 420.04268 -378.189609)
			(xy 420.050726 -378.256429) (xy 420.050728 -378.323732) (xy 420.050721 -378.323793) (xy 423.328791 -378.323793)
			(xy 423.328793 -378.256368) (xy 423.336871 -378.189428) (xy 423.352909 -378.123938) (xy 423.376675 -378.06084)
			(xy 423.407828 -378.001043) (xy 423.445919 -377.945408) (xy 423.467784 -377.919742) (xy 423.473586 -377.9126)
			(xy 423.480098 -377.895407) (xy 423.480484 -377.886214) (xy 423.480484 -377.728734) (xy 423.480956 -377.718604)
			(xy 423.488681 -377.699875) (xy 423.502972 -377.685516) (xy 423.521664 -377.677704) (xy 423.531792 -377.677172)
			(xy 424.248072 -377.677172) (xy 424.258189 -377.677638) (xy 424.276887 -377.685372) (xy 424.291201 -377.699673)
			(xy 424.298953 -377.718363) (xy 424.29938 -377.72848) (xy 424.29938 -377.886214) (xy 424.299788 -377.895401)
			(xy 424.306303 -377.912585) (xy 424.31208 -377.919742) (xy 424.333919 -377.945428) (xy 424.37201 -378.001059)
			(xy 424.403163 -378.060852) (xy 424.426929 -378.123946) (xy 424.442967 -378.189433) (xy 424.451046 -378.256369)
			(xy 424.451048 -378.323734) (xy 427.729086 -378.323734) (xy 427.729089 -378.256427) (xy 427.737136 -378.189602)
			(xy 427.753113 -378.124218) (xy 427.77679 -378.061212) (xy 427.807828 -378.001488) (xy 427.845782 -377.945902)
			(xy 427.867572 -377.92025) (xy 427.873381 -377.913114) (xy 427.879886 -377.895916) (xy 427.880272 -377.886722)
			(xy 427.880272 -377.728734) (xy 427.880693 -377.71856) (xy 427.888473 -377.69976) (xy 427.90286 -377.685373)
			(xy 427.92166 -377.677593) (xy 427.931834 -377.677172) (xy 428.648114 -377.677172) (xy 428.658291 -377.677553)
			(xy 428.677092 -377.685349) (xy 428.691478 -377.699748) (xy 428.699256 -377.718557) (xy 428.699676 -377.728734)
			(xy 428.699676 -377.886722) (xy 428.700081 -377.89591) (xy 428.706599 -377.913094) (xy 428.712376 -377.92025)
			(xy 428.734137 -377.945924) (xy 428.772086 -378.001507) (xy 428.80312 -378.061228) (xy 428.826793 -378.12423)
			(xy 428.842767 -378.189609) (xy 428.850813 -378.256429) (xy 428.850816 -378.323732) (xy 428.850816 -378.323734)
			(xy 432.128877 -378.323734) (xy 432.128879 -378.256427) (xy 432.136926 -378.189602) (xy 432.152902 -378.124218)
			(xy 432.176579 -378.061212) (xy 432.207617 -378.001488) (xy 432.24557 -377.945902) (xy 432.26736 -377.92025)
			(xy 432.273168 -377.913113) (xy 432.279674 -377.895916) (xy 432.28006 -377.886722) (xy 432.28006 -377.728734)
			(xy 432.280492 -377.718562) (xy 432.28827 -377.699764) (xy 432.302654 -377.685377) (xy 432.32145 -377.677595)
			(xy 432.331622 -377.677172) (xy 433.047902 -377.677172) (xy 433.058078 -377.677563) (xy 433.076879 -377.685355)
			(xy 433.091265 -377.699751) (xy 433.099044 -377.718558) (xy 433.099464 -377.728734) (xy 433.099464 -377.886722)
			(xy 433.099872 -377.895909) (xy 433.106388 -377.913093) (xy 433.112164 -377.92025) (xy 433.133926 -377.945923)
			(xy 433.171875 -378.001507) (xy 433.202909 -378.061228) (xy 433.226584 -378.124229) (xy 433.242558 -378.189609)
			(xy 433.250604 -378.256429) (xy 433.250607 -378.323732) (xy 433.242565 -378.390553) (xy 433.226595 -378.455933)
			(xy 433.202925 -378.518937) (xy 433.171895 -378.57866) (xy 433.13395 -378.634246) (xy 433.112164 -378.659898)
			(xy 433.106381 -378.667053) (xy 433.099859 -378.684236) (xy 433.099464 -378.693426) (xy 433.099464 -379.186694)
			(xy 433.099885 -379.19588) (xy 433.106392 -379.213064) (xy 433.112164 -379.220222) (xy 433.133997 -379.245837)
			(xy 433.171944 -379.301429) (xy 433.202975 -379.361158) (xy 433.226645 -379.424167) (xy 433.242615 -379.489554)
			(xy 433.250655 -379.55638) (xy 433.250651 -379.623689) (xy 433.242603 -379.690515) (xy 433.226625 -379.755899)
			(xy 433.202947 -379.818906) (xy 433.171909 -379.878631) (xy 433.133955 -379.934218) (xy 433.112164 -379.95987)
			(xy 433.106351 -379.967003) (xy 433.099847 -379.984203) (xy 433.099464 -379.993398) (xy 433.099464 -380.151386)
			(xy 433.099025 -380.161556) (xy 433.091245 -380.180351) (xy 433.076864 -380.194736) (xy 433.058072 -380.202522)
			(xy 433.047902 -380.202948) (xy 432.331622 -380.202948) (xy 432.32145 -380.202518) (xy 432.302653 -380.194737)
			(xy 432.288267 -380.180353) (xy 432.280484 -380.161558) (xy 432.28006 -380.151386) (xy 432.28006 -379.993398)
			(xy 432.279637 -379.984212) (xy 432.273131 -379.967029) (xy 432.26736 -379.95987) (xy 432.245617 -379.934181)
			(xy 432.207665 -379.8786) (xy 432.176629 -379.818882) (xy 432.152953 -379.755882) (xy 432.136976 -379.690504)
			(xy 432.128928 -379.623685) (xy 432.128924 -379.556384) (xy 432.136964 -379.489564) (xy 432.152932 -379.424184)
			(xy 432.176601 -379.361181) (xy 432.20763 -379.301459) (xy 432.245575 -379.245874) (xy 432.26736 -379.220222)
			(xy 432.27318 -379.213093) (xy 432.279679 -379.19589) (xy 432.28006 -379.186694) (xy 432.28006 -378.693426)
			(xy 432.279624 -378.684242) (xy 432.273127 -378.667058) (xy 432.26736 -378.659898) (xy 432.245546 -378.634267)
			(xy 432.207596 -378.578678) (xy 432.176563 -378.518952) (xy 432.152891 -378.455945) (xy 432.136919 -378.39056)
			(xy 432.128877 -378.323734) (xy 428.850816 -378.323734) (xy 428.842774 -378.390552) (xy 428.826805 -378.455933)
			(xy 428.803136 -378.518936) (xy 428.772106 -378.578659) (xy 428.734161 -378.634245) (xy 428.712376 -378.659898)
			(xy 428.706595 -378.667054) (xy 428.700072 -378.684236) (xy 428.699676 -378.693426) (xy 428.699676 -379.186694)
			(xy 428.700094 -379.19588) (xy 428.706603 -379.213064) (xy 428.712376 -379.220222) (xy 428.734209 -379.245837)
			(xy 428.772155 -379.301429) (xy 428.803185 -379.361158) (xy 428.826855 -379.424167) (xy 428.842824 -379.489554)
			(xy 428.850865 -379.55638) (xy 428.85086 -379.623689) (xy 428.842812 -379.690514) (xy 428.826835 -379.755899)
			(xy 428.803157 -379.818905) (xy 428.772119 -379.87863) (xy 428.734166 -379.934218) (xy 428.712376 -379.95987)
			(xy 428.706564 -379.967004) (xy 428.70006 -379.984203) (xy 428.699676 -379.993398) (xy 428.699676 -380.151386)
			(xy 428.699156 -380.161541) (xy 428.691388 -380.180307) (xy 428.677031 -380.194673) (xy 428.658269 -380.20245)
			(xy 428.648114 -380.202948) (xy 427.931834 -380.202948) (xy 427.921663 -380.202508) (xy 427.902866 -380.194731)
			(xy 427.88848 -380.180351) (xy 427.880696 -380.161557) (xy 427.880272 -380.151386) (xy 427.880272 -379.993398)
			(xy 427.879869 -379.98421) (xy 427.873351 -379.967025) (xy 427.867572 -379.95987) (xy 427.845829 -379.934181)
			(xy 427.807876 -379.878601) (xy 427.776839 -379.818882) (xy 427.753162 -379.755883) (xy 427.737185 -379.690505)
			(xy 427.729137 -379.623686) (xy 427.729133 -379.556384) (xy 427.737173 -379.489564) (xy 427.753142 -379.424183)
			(xy 427.776811 -379.361181) (xy 427.807841 -379.301459) (xy 427.845786 -379.245874) (xy 427.867572 -379.220222)
			(xy 427.873393 -379.213094) (xy 427.879891 -379.19589) (xy 427.880272 -379.186694) (xy 427.880272 -378.693426)
			(xy 427.879856 -378.684239) (xy 427.873347 -378.667055) (xy 427.867572 -378.659898) (xy 427.845758 -378.634267)
			(xy 427.807808 -378.578678) (xy 427.776774 -378.518952) (xy 427.753101 -378.455945) (xy 427.737129 -378.39056)
			(xy 427.729086 -378.323734) (xy 424.451048 -378.323734) (xy 424.451048 -378.323791) (xy 424.442974 -378.390728)
			(xy 424.426941 -378.456216) (xy 424.403179 -378.519312) (xy 424.37203 -378.579107) (xy 424.333943 -378.634741)
			(xy 424.31208 -378.660406) (xy 424.306296 -378.66756) (xy 424.299775 -378.684744) (xy 424.29938 -378.693934)
			(xy 424.29938 -379.186186) (xy 424.299802 -379.195372) (xy 424.306308 -379.212556) (xy 424.31208 -379.219714)
			(xy 424.33399 -379.245342) (xy 424.372079 -379.300981) (xy 424.403228 -379.360782) (xy 424.426991 -379.423884)
			(xy 424.443024 -379.489378) (xy 424.451096 -379.556321) (xy 424.451092 -379.623748) (xy 424.443011 -379.69069)
			(xy 424.42697 -379.756182) (xy 424.4032 -379.819281) (xy 424.372043 -379.879078) (xy 424.333947 -379.934713)
			(xy 424.31208 -379.960378) (xy 424.306266 -379.96751) (xy 424.299762 -379.984711) (xy 424.29938 -379.993906)
			(xy 424.29938 -380.151386) (xy 424.298863 -380.161509) (xy 424.291143 -380.180226) (xy 424.276866 -380.194583)
			(xy 424.258193 -380.202406) (xy 424.248072 -380.202948) (xy 423.531792 -380.202948) (xy 423.521689 -380.202422)
			(xy 423.50302 -380.194691) (xy 423.488727 -380.180407) (xy 423.480984 -380.161743) (xy 423.480484 -380.15164)
			(xy 423.480484 -379.993906) (xy 423.480075 -379.984719) (xy 423.473561 -379.967534) (xy 423.467784 -379.960378)
			(xy 423.445966 -379.934675) (xy 423.407877 -379.879046) (xy 423.376725 -379.819255) (xy 423.352959 -379.756163)
			(xy 423.336921 -379.690678) (xy 423.328841 -379.623744) (xy 423.328837 -379.556325) (xy 423.336908 -379.48939)
			(xy 423.352938 -379.423904) (xy 423.376697 -379.360809) (xy 423.407841 -379.301014) (xy 423.445923 -379.245379)
			(xy 423.467784 -379.219714) (xy 423.473598 -379.212581) (xy 423.480103 -379.195381) (xy 423.480484 -379.186186)
			(xy 423.480484 -378.693934) (xy 423.480061 -378.684748) (xy 423.473557 -378.667563) (xy 423.467784 -378.660406)
			(xy 423.445895 -378.634762) (xy 423.407808 -378.579124) (xy 423.376659 -378.519324) (xy 423.352897 -378.456225)
			(xy 423.336864 -378.390733) (xy 423.328791 -378.323793) (xy 420.050721 -378.323793) (xy 420.042687 -378.390552)
			(xy 420.026718 -378.455932) (xy 420.003049 -378.518936) (xy 419.972021 -378.578659) (xy 419.934077 -378.634245)
			(xy 419.912292 -378.659898) (xy 419.906513 -378.667056) (xy 419.899988 -378.684237) (xy 419.899592 -378.693426)
			(xy 419.899592 -379.186694) (xy 419.900007 -379.195881) (xy 419.906518 -379.213065) (xy 419.912292 -379.220222)
			(xy 419.934124 -379.245837) (xy 419.972069 -379.30143) (xy 420.003099 -379.361159) (xy 420.026768 -379.424168)
			(xy 420.042737 -379.489554) (xy 420.050777 -379.556381) (xy 420.050772 -379.623689) (xy 420.042724 -379.690514)
			(xy 420.026747 -379.755898) (xy 420.003071 -379.818905) (xy 419.972034 -379.87863) (xy 419.934082 -379.934217)
			(xy 419.912292 -379.95987) (xy 419.906482 -379.967006) (xy 419.899976 -379.984204) (xy 419.899592 -379.993398)
			(xy 419.899592 -380.151386) (xy 419.899056 -380.161539) (xy 419.891292 -380.180302) (xy 419.876939 -380.194667)
			(xy 419.858183 -380.202447) (xy 419.84803 -380.202948) (xy 419.13175 -380.202948) (xy 419.12158 -380.202495)
			(xy 419.102784 -380.194724) (xy 419.088396 -380.180347) (xy 419.080612 -380.161556) (xy 419.080188 -380.151386)
			(xy 419.080188 -379.993398) (xy 419.079781 -379.98421) (xy 419.073266 -379.967026) (xy 419.067488 -379.95987)
			(xy 419.045744 -379.934181) (xy 419.007791 -379.878601) (xy 418.976753 -379.818883) (xy 418.953075 -379.755883)
			(xy 418.937097 -379.690505) (xy 418.929049 -379.623686) (xy 418.929045 -379.556383) (xy 418.937085 -379.489563)
			(xy 418.953055 -379.424183) (xy 418.976724 -379.36118) (xy 419.007755 -379.301458) (xy 419.045702 -379.245873)
			(xy 419.067488 -379.220222) (xy 419.073299 -379.213087) (xy 419.079805 -379.195889) (xy 419.080188 -379.186694)
			(xy 419.080188 -378.693426) (xy 419.079768 -378.68424) (xy 419.073262 -378.667055) (xy 419.067488 -378.659898)
			(xy 419.045673 -378.634268) (xy 419.007722 -378.578679) (xy 418.976687 -378.518953) (xy 418.953014 -378.455946)
			(xy 418.937041 -378.39056) (xy 418.928998 -378.323734) (xy 389.250698 -378.323734) (xy 389.242656 -378.390553)
			(xy 389.226686 -378.455934) (xy 389.203015 -378.518937) (xy 389.171985 -378.57866) (xy 389.134038 -378.634246)
			(xy 389.112252 -378.659898) (xy 389.106468 -378.667052) (xy 389.099947 -378.684236) (xy 389.099552 -378.693426)
			(xy 389.099552 -379.186694) (xy 389.099976 -379.19588) (xy 389.106481 -379.213063) (xy 389.112252 -379.220222)
			(xy 389.134085 -379.245837) (xy 389.172033 -379.301428) (xy 389.203065 -379.361157) (xy 389.226736 -379.424166)
			(xy 389.242706 -379.489553) (xy 389.250746 -379.55638) (xy 389.250742 -379.623689) (xy 389.242693 -379.690515)
			(xy 389.226715 -379.7559) (xy 389.203037 -379.818906) (xy 389.171998 -379.878631) (xy 389.134043 -379.934218)
			(xy 389.112252 -379.95987) (xy 389.106437 -379.967002) (xy 389.099935 -379.984203) (xy 389.099552 -379.993398)
			(xy 389.099552 -380.151386) (xy 389.099125 -380.161558) (xy 389.091342 -380.180354) (xy 389.076958 -380.19474)
			(xy 389.058162 -380.202524) (xy 389.04799 -380.202948) (xy 388.33171 -380.202948) (xy 388.321537 -380.202528)
			(xy 388.30274 -380.194743) (xy 388.288354 -380.180357) (xy 388.280571 -380.161559) (xy 388.280148 -380.151386)
			(xy 388.280148 -379.993398) (xy 388.279728 -379.984212) (xy 388.27322 -379.967028) (xy 388.267448 -379.95987)
			(xy 388.245705 -379.934181) (xy 388.207755 -379.8786) (xy 388.176719 -379.818881) (xy 388.153043 -379.755882)
			(xy 388.137067 -379.690504) (xy 388.129019 -379.623685) (xy 388.129015 -379.556384) (xy 388.137054 -379.489564)
			(xy 388.153023 -379.424184) (xy 388.176691 -379.361182) (xy 388.207719 -379.30146) (xy 388.245663 -379.245874)
			(xy 388.267448 -379.220222) (xy 388.273266 -379.213092) (xy 388.279767 -379.19589) (xy 388.280148 -379.186694)
			(xy 388.280148 -378.693426) (xy 388.279715 -378.684241) (xy 388.273216 -378.667057) (xy 388.267448 -378.659898)
			(xy 388.245634 -378.634267) (xy 388.207686 -378.578678) (xy 388.176653 -378.518951) (xy 388.152981 -378.455944)
			(xy 388.13701 -378.390559) (xy 388.128968 -378.323734) (xy 384.850907 -378.323734) (xy 384.842865 -378.390553)
			(xy 384.826895 -378.455933) (xy 384.803225 -378.518937) (xy 384.772195 -378.57866) (xy 384.73425 -378.634246)
			(xy 384.712464 -378.659898) (xy 384.706681 -378.667053) (xy 384.700159 -378.684236) (xy 384.699764 -378.693426)
			(xy 384.699764 -379.186694) (xy 384.700185 -379.19588) (xy 384.706692 -379.213064) (xy 384.712464 -379.220222)
			(xy 384.734297 -379.245837) (xy 384.772244 -379.301429) (xy 384.803275 -379.361158) (xy 384.826945 -379.424167)
			(xy 384.842915 -379.489554) (xy 384.850955 -379.55638) (xy 384.850951 -379.623689) (xy 384.842903 -379.690515)
			(xy 384.826925 -379.755899) (xy 384.803247 -379.818906) (xy 384.772209 -379.878631) (xy 384.734255 -379.934218)
			(xy 384.712464 -379.95987) (xy 384.706651 -379.967003) (xy 384.700147 -379.984203) (xy 384.699764 -379.993398)
			(xy 384.699764 -380.151386) (xy 384.699325 -380.161556) (xy 384.691545 -380.180351) (xy 384.677164 -380.194736)
			(xy 384.658372 -380.202522) (xy 384.648202 -380.202948) (xy 383.931922 -380.202948) (xy 383.92175 -380.202518)
			(xy 383.902953 -380.194737) (xy 383.888567 -380.180353) (xy 383.880784 -380.161558) (xy 383.88036 -380.151386)
			(xy 383.88036 -379.993398) (xy 383.879937 -379.984212) (xy 383.873431 -379.967029) (xy 383.86766 -379.95987)
			(xy 383.845917 -379.934181) (xy 383.807965 -379.8786) (xy 383.776929 -379.818882) (xy 383.753253 -379.755882)
			(xy 383.737276 -379.690504) (xy 383.729228 -379.623685) (xy 383.729224 -379.556384) (xy 383.737264 -379.489564)
			(xy 383.753232 -379.424184) (xy 383.776901 -379.361181) (xy 383.80793 -379.301459) (xy 383.845875 -379.245874)
			(xy 383.86766 -379.220222) (xy 383.87348 -379.213093) (xy 383.879979 -379.19589) (xy 383.88036 -379.186694)
			(xy 383.88036 -378.693426) (xy 383.879924 -378.684242) (xy 383.873427 -378.667058) (xy 383.86766 -378.659898)
			(xy 383.845846 -378.634267) (xy 383.807896 -378.578678) (xy 383.776863 -378.518952) (xy 383.753191 -378.455945)
			(xy 383.737219 -378.39056) (xy 383.729177 -378.323734) (xy 380.451139 -378.323734) (xy 380.451139 -378.323792)
			(xy 380.443065 -378.390729) (xy 380.427031 -378.456217) (xy 380.403269 -378.519313) (xy 380.372119 -378.579108)
			(xy 380.334032 -378.634741) (xy 380.312168 -378.660406) (xy 380.306382 -378.667559) (xy 380.299862 -378.684744)
			(xy 380.299468 -378.693934) (xy 380.299468 -379.186186) (xy 380.299892 -379.195372) (xy 380.306397 -379.212556)
			(xy 380.312168 -379.219714) (xy 380.334078 -379.245341) (xy 380.372168 -379.300981) (xy 380.403318 -379.360782)
			(xy 380.427081 -379.423884) (xy 380.443114 -379.489378) (xy 380.451187 -379.556321) (xy 380.451183 -379.623749)
			(xy 380.443102 -379.69069) (xy 380.427061 -379.756182) (xy 380.40329 -379.819281) (xy 380.372132 -379.879079)
			(xy 380.334036 -379.934713) (xy 380.312168 -379.960378) (xy 380.306352 -379.967509) (xy 380.29985 -379.984711)
			(xy 380.299468 -379.993906) (xy 380.299468 -380.151386) (xy 380.298962 -380.161511) (xy 380.291241 -380.18023)
			(xy 380.27696 -380.194587) (xy 380.258282 -380.202408) (xy 380.24816 -380.202948) (xy 379.53188 -380.202948)
			(xy 379.521731 -380.202496) (xy 379.502987 -380.194703) (xy 379.488666 -380.180316) (xy 379.480958 -380.161537)
			(xy 379.480572 -380.151386) (xy 379.480572 -379.993906) (xy 379.480165 -379.984718) (xy 379.47365 -379.967534)
			(xy 379.467872 -379.960378) (xy 379.446054 -379.934675) (xy 379.407966 -379.879045) (xy 379.376815 -379.819254)
			(xy 379.353049 -379.756162) (xy 379.337011 -379.690678) (xy 379.328932 -379.623744) (xy 379.328928 -379.556325)
			(xy 379.336999 -379.48939) (xy 379.353029 -379.423904) (xy 379.376787 -379.360809) (xy 379.40793 -379.301014)
			(xy 379.446012 -379.24538) (xy 379.467872 -379.219714) (xy 379.473696 -379.212589) (xy 379.480192 -379.195383)
			(xy 379.480572 -379.186186) (xy 379.480572 -378.693934) (xy 379.480152 -378.684748) (xy 379.473646 -378.667563)
			(xy 379.467872 -378.660406) (xy 379.445983 -378.634761) (xy 379.407897 -378.579123) (xy 379.376749 -378.519324)
			(xy 379.352988 -378.456224) (xy 379.336955 -378.390733) (xy 379.328882 -378.323793) (xy 376.050812 -378.323793)
			(xy 376.042778 -378.390552) (xy 376.026808 -378.455933) (xy 376.003139 -378.518936) (xy 375.97211 -378.578659)
			(xy 375.934166 -378.634246) (xy 375.91238 -378.659898) (xy 375.906599 -378.667054) (xy 375.900076 -378.684236)
			(xy 375.89968 -378.693426) (xy 375.89968 -379.186694) (xy 375.900098 -379.19588) (xy 375.906607 -379.213064)
			(xy 375.91238 -379.220222) (xy 375.934212 -379.245837) (xy 375.972159 -379.301429) (xy 376.003189 -379.361158)
			(xy 376.026858 -379.424168) (xy 376.042827 -379.489554) (xy 376.050868 -379.55638) (xy 376.050863 -379.623689)
			(xy 376.042815 -379.690514) (xy 376.026838 -379.755899) (xy 376.003161 -379.818905) (xy 375.972123 -379.87863)
			(xy 375.93417 -379.934218) (xy 375.91238 -379.95987) (xy 375.906569 -379.967005) (xy 375.900064 -379.984203)
			(xy 375.89968 -379.993398) (xy 375.89968 -380.151386) (xy 375.899156 -380.161541) (xy 375.891389 -380.180306)
			(xy 375.877033 -380.194671) (xy 375.858272 -380.202449) (xy 375.848118 -380.202948) (xy 375.131838 -380.202948)
			(xy 375.121667 -380.202505) (xy 375.102871 -380.19473) (xy 375.088484 -380.18035) (xy 375.0807 -380.161557)
			(xy 375.080276 -380.151386) (xy 375.080276 -379.993398) (xy 375.079872 -379.98421) (xy 375.073355 -379.967025)
			(xy 375.067576 -379.95987) (xy 375.045832 -379.934181) (xy 375.00788 -379.878601) (xy 374.976842 -379.818883)
			(xy 374.953165 -379.755883) (xy 374.937188 -379.690505) (xy 374.92914 -379.623686) (xy 374.929136 -379.556384)
			(xy 374.937176 -379.489563) (xy 374.953145 -379.424183) (xy 374.976814 -379.361181) (xy 375.007844 -379.301459)
			(xy 375.04579 -379.245874) (xy 375.067576 -379.220222) (xy 375.073385 -379.213086) (xy 375.079893 -379.195889)
			(xy 375.080276 -379.186694) (xy 375.080276 -378.693426) (xy 375.079859 -378.684239) (xy 375.073351 -378.667055)
			(xy 375.067576 -378.659898) (xy 375.045762 -378.634267) (xy 375.007811 -378.578679) (xy 374.976777 -378.518952)
			(xy 374.953104 -378.455945) (xy 374.937132 -378.39056) (xy 374.929089 -378.323734) (xy 345.250789 -378.323734)
			(xy 345.242747 -378.390553) (xy 345.226776 -378.455934) (xy 345.203105 -378.518938) (xy 345.172074 -378.57866)
			(xy 345.134127 -378.634246) (xy 345.11234 -378.659898) (xy 345.106554 -378.667051) (xy 345.100035 -378.684236)
			(xy 345.09964 -378.693426) (xy 345.09964 -379.186694) (xy 345.100066 -379.195879) (xy 345.10657 -379.213063)
			(xy 345.11234 -379.220222) (xy 345.134174 -379.245837) (xy 345.172123 -379.301428) (xy 345.203155 -379.361156)
			(xy 345.226826 -379.424166) (xy 345.242797 -379.489553) (xy 345.250837 -379.55638) (xy 345.250833 -379.623689)
			(xy 345.242784 -379.690515) (xy 345.226806 -379.7559) (xy 345.203127 -379.818907) (xy 345.172087 -379.878632)
			(xy 345.134131 -379.934218) (xy 345.11234 -379.95987) (xy 345.106524 -379.967001) (xy 345.100023 -379.984203)
			(xy 345.09964 -379.993398) (xy 345.09964 -380.151386) (xy 345.099224 -380.161559) (xy 345.09144 -380.180358)
			(xy 345.077051 -380.194744) (xy 345.058252 -380.202526) (xy 345.048078 -380.202948) (xy 344.331798 -380.202948)
			(xy 344.321625 -380.202537) (xy 344.302827 -380.194749) (xy 344.288442 -380.180359) (xy 344.280659 -380.16156)
			(xy 344.280236 -380.151386) (xy 344.280236 -379.993398) (xy 344.279819 -379.984212) (xy 344.273309 -379.967028)
			(xy 344.267536 -379.95987) (xy 344.245794 -379.93418) (xy 344.207844 -379.878599) (xy 344.176809 -379.818881)
			(xy 344.153133 -379.755881) (xy 344.137157 -379.690504) (xy 344.12911 -379.623685) (xy 344.129106 -379.556384)
			(xy 344.137145 -379.489565) (xy 344.153113 -379.424185) (xy 344.17678 -379.361182) (xy 344.207808 -379.30146)
			(xy 344.245751 -379.245874) (xy 344.267536 -379.220222) (xy 344.273353 -379.213091) (xy 344.279855 -379.19589)
			(xy 344.280236 -379.186694) (xy 344.280236 -378.693426) (xy 344.279805 -378.684241) (xy 344.273305 -378.667057)
			(xy 344.267536 -378.659898) (xy 344.245723 -378.634267) (xy 344.207775 -378.578677) (xy 344.176743 -378.518951)
			(xy 344.153072 -378.455944) (xy 344.137101 -378.390559) (xy 344.129059 -378.323734) (xy 340.850998 -378.323734)
			(xy 340.842956 -378.390553) (xy 340.826986 -378.455934) (xy 340.803315 -378.518937) (xy 340.772285 -378.57866)
			(xy 340.734338 -378.634246) (xy 340.712552 -378.659898) (xy 340.706768 -378.667052) (xy 340.700247 -378.684236)
			(xy 340.699852 -378.693426) (xy 340.699852 -379.186694) (xy 340.700276 -379.19588) (xy 340.706781 -379.213063)
			(xy 340.712552 -379.220222) (xy 340.734385 -379.245837) (xy 340.772333 -379.301428) (xy 340.803365 -379.361157)
			(xy 340.827036 -379.424166) (xy 340.843006 -379.489553) (xy 340.851046 -379.55638) (xy 340.851042 -379.623689)
			(xy 340.842993 -379.690515) (xy 340.827015 -379.7559) (xy 340.803337 -379.818906) (xy 340.772298 -379.878631)
			(xy 340.734343 -379.934218) (xy 340.712552 -379.95987) (xy 340.706737 -379.967002) (xy 340.700235 -379.984203)
			(xy 340.699852 -379.993398) (xy 340.699852 -380.151386) (xy 340.699425 -380.161558) (xy 340.691642 -380.180354)
			(xy 340.677258 -380.19474) (xy 340.658462 -380.202524) (xy 340.64829 -380.202948) (xy 339.93201 -380.202948)
			(xy 339.921837 -380.202528) (xy 339.90304 -380.194743) (xy 339.888654 -380.180357) (xy 339.880871 -380.161559)
			(xy 339.880448 -380.151386) (xy 339.880448 -379.993398) (xy 339.880028 -379.984212) (xy 339.87352 -379.967028)
			(xy 339.867748 -379.95987) (xy 339.846005 -379.934181) (xy 339.808055 -379.8786) (xy 339.777019 -379.818881)
			(xy 339.753343 -379.755882) (xy 339.737367 -379.690504) (xy 339.729319 -379.623685) (xy 339.729315 -379.556384)
			(xy 339.737354 -379.489564) (xy 339.753323 -379.424184) (xy 339.776991 -379.361182) (xy 339.808019 -379.30146)
			(xy 339.845963 -379.245874) (xy 339.867748 -379.220222) (xy 339.873566 -379.213092) (xy 339.880067 -379.19589)
			(xy 339.880448 -379.186694) (xy 339.880448 -378.693426) (xy 339.880015 -378.684241) (xy 339.873516 -378.667057)
			(xy 339.867748 -378.659898) (xy 339.845934 -378.634267) (xy 339.807986 -378.578678) (xy 339.776953 -378.518951)
			(xy 339.753281 -378.455944) (xy 339.73731 -378.390559) (xy 339.729268 -378.323734) (xy 336.45123 -378.323734)
			(xy 336.45123 -378.323792) (xy 336.443156 -378.390729) (xy 336.427122 -378.456217) (xy 336.403359 -378.519313)
			(xy 336.372208 -378.579108) (xy 336.33412 -378.634742) (xy 336.312256 -378.660406) (xy 336.306469 -378.667558)
			(xy 336.29995 -378.684743) (xy 336.299556 -378.693934) (xy 336.299556 -379.186186) (xy 336.299983 -379.195371)
			(xy 336.306486 -379.212555) (xy 336.312256 -379.219714) (xy 336.334167 -379.245341) (xy 336.372257 -379.30098)
			(xy 336.403408 -379.360781) (xy 336.427172 -379.423883) (xy 336.443205 -379.489377) (xy 336.451278 -379.55632)
			(xy 336.451274 -379.623749) (xy 336.443193 -379.690691) (xy 336.427151 -379.756183) (xy 336.40338 -379.819282)
			(xy 336.372221 -379.879079) (xy 336.334124 -379.934713) (xy 336.312256 -379.960378) (xy 336.306438 -379.967508)
			(xy 336.299937 -379.98471) (xy 336.299556 -379.993906) (xy 336.299556 -380.151386) (xy 336.299062 -380.161512)
			(xy 336.291338 -380.180234) (xy 336.277054 -380.194591) (xy 336.258372 -380.20241) (xy 336.248248 -380.202948)
			(xy 335.531968 -380.202948) (xy 335.521818 -380.202506) (xy 335.503074 -380.194708) (xy 335.488753 -380.180319)
			(xy 335.481046 -380.161538) (xy 335.48066 -380.151386) (xy 335.48066 -379.993906) (xy 335.480234 -379.984721)
			(xy 335.47373 -379.967537) (xy 335.46796 -379.960378) (xy 335.446143 -379.934675) (xy 335.408055 -379.879045)
			(xy 335.376905 -379.819253) (xy 335.35314 -379.756162) (xy 335.337102 -379.690678) (xy 335.329023 -379.623744)
			(xy 335.329019 -379.556325) (xy 335.33709 -379.48939) (xy 335.353119 -379.423904) (xy 335.376876 -379.36081)
			(xy 335.40802 -379.301015) (xy 335.4461 -379.24538) (xy 335.46796 -379.219714) (xy 335.473783 -379.212588)
			(xy 335.48028 -379.195382) (xy 335.48066 -379.186186) (xy 335.48066 -378.693934) (xy 335.48022 -378.68475)
			(xy 335.473726 -378.667566) (xy 335.46796 -378.660406) (xy 335.446072 -378.634761) (xy 335.407987 -378.579123)
			(xy 335.376839 -378.519323) (xy 335.353078 -378.456224) (xy 335.337046 -378.390733) (xy 335.328973 -378.323793)
			(xy 332.050903 -378.323793) (xy 332.042868 -378.390553) (xy 332.026898 -378.455933) (xy 332.003229 -378.518937)
			(xy 331.972199 -378.578659) (xy 331.934254 -378.634246) (xy 331.912468 -378.659898) (xy 331.906686 -378.667053)
			(xy 331.900163 -378.684236) (xy 331.899768 -378.693426) (xy 331.899768 -379.186694) (xy 331.900188 -379.19588)
			(xy 331.906696 -379.213064) (xy 331.912468 -379.220222) (xy 331.934301 -379.245837) (xy 331.972248 -379.301429)
			(xy 332.003279 -379.361158) (xy 332.026949 -379.424167) (xy 332.042918 -379.489554) (xy 332.050958 -379.55638)
			(xy 332.050954 -379.623689) (xy 332.042906 -379.690514) (xy 332.026928 -379.755899) (xy 332.00325 -379.818906)
			(xy 331.972212 -379.878631) (xy 331.934258 -379.934218) (xy 331.912468 -379.95987) (xy 331.906655 -379.967003)
			(xy 331.900151 -379.984203) (xy 331.899768 -379.993398) (xy 331.899768 -380.151386) (xy 331.899325 -380.161556)
			(xy 331.891546 -380.180349) (xy 331.877166 -380.194734) (xy 331.858376 -380.202521) (xy 331.848206 -380.202948)
			(xy 331.131926 -380.202948) (xy 331.121754 -380.202514) (xy 331.102958 -380.194735) (xy 331.088571 -380.180352)
			(xy 331.080788 -380.161558) (xy 331.080364 -380.151386) (xy 331.080364 -379.993398) (xy 331.07994 -379.984213)
			(xy 331.073434 -379.967029) (xy 331.067664 -379.95987) (xy 331.045921 -379.934181) (xy 331.007969 -379.8786)
			(xy 330.976932 -379.818882) (xy 330.953256 -379.755882) (xy 330.937279 -379.690504) (xy 330.929231 -379.623686)
			(xy 330.929227 -379.556384) (xy 330.937267 -379.489564) (xy 330.953235 -379.424184) (xy 330.976904 -379.361181)
			(xy 331.007933 -379.301459) (xy 331.045878 -379.245874) (xy 331.067664 -379.220222) (xy 331.073484 -379.213094)
			(xy 331.079983 -379.19589) (xy 331.080364 -379.186694) (xy 331.080364 -378.693426) (xy 331.079927 -378.684242)
			(xy 331.07343 -378.667058) (xy 331.067664 -378.659898) (xy 331.04585 -378.634267) (xy 331.0079 -378.578678)
			(xy 330.976866 -378.518952) (xy 330.953194 -378.455945) (xy 330.937222 -378.39056) (xy 330.92918 -378.323734)
			(xy 301.250878 -378.323734) (xy 301.250878 -378.323791) (xy 301.242805 -378.390727) (xy 301.226773 -378.456215)
			(xy 301.203013 -378.51931) (xy 301.171866 -378.579106) (xy 301.133782 -378.63474) (xy 301.11192 -378.660406)
			(xy 301.106141 -378.667564) (xy 301.099615 -378.684745) (xy 301.09922 -378.693934) (xy 301.09922 -379.186186)
			(xy 301.099632 -379.195373) (xy 301.106144 -379.212558) (xy 301.11192 -379.219714) (xy 301.133828 -379.245342)
			(xy 301.171914 -379.300983) (xy 301.203062 -379.360784) (xy 301.226823 -379.423886) (xy 301.242854 -379.489379)
			(xy 301.250926 -379.556321) (xy 301.250922 -379.623748) (xy 301.242842 -379.690689) (xy 301.226802 -379.75618)
			(xy 301.203034 -379.819279) (xy 301.171879 -379.879077) (xy 301.133786 -379.934712) (xy 301.11192 -379.960378)
			(xy 301.10611 -379.967514) (xy 301.099603 -379.984711) (xy 301.09922 -379.993906) (xy 301.09922 -380.151386)
			(xy 301.098761 -380.161517) (xy 301.09103 -380.180245) (xy 301.076735 -380.194603) (xy 301.058041 -380.202416)
			(xy 301.047912 -380.202948) (xy 300.331632 -380.202948) (xy 300.321486 -380.202453) (xy 300.302743 -380.194677)
			(xy 300.28842 -380.180304) (xy 300.280711 -380.161534) (xy 300.280324 -380.151386) (xy 300.280324 -379.993906)
			(xy 300.279906 -379.98472) (xy 300.273397 -379.967536) (xy 300.267624 -379.960378) (xy 300.245804 -379.934676)
			(xy 300.207713 -379.879047) (xy 300.176559 -379.819256) (xy 300.152791 -379.756164) (xy 300.136751 -379.690679)
			(xy 300.128672 -379.623745) (xy 300.128667 -379.556324) (xy 300.136739 -379.489389) (xy 300.15277 -379.423902)
			(xy 300.17653 -379.360807) (xy 300.207677 -379.301012) (xy 300.245762 -379.245379) (xy 300.267624 -379.219714)
			(xy 300.273442 -379.212584) (xy 300.279943 -379.195382) (xy 300.280324 -379.186186) (xy 300.280324 -378.693934)
			(xy 300.279892 -378.684749) (xy 300.273393 -378.667565) (xy 300.267624 -378.660406) (xy 300.245734 -378.634762)
			(xy 300.207644 -378.579125) (xy 300.176493 -378.519326) (xy 300.152729 -378.456227) (xy 300.136695 -378.390735)
			(xy 300.128621 -378.323794) (xy 296.851087 -378.323794) (xy 296.843014 -378.390727) (xy 296.826983 -378.456214)
			(xy 296.803223 -378.51931) (xy 296.772077 -378.579105) (xy 296.733993 -378.63474) (xy 296.712132 -378.660406)
			(xy 296.706342 -378.667556) (xy 296.699825 -378.684743) (xy 296.699432 -378.693934) (xy 296.699432 -379.186186)
			(xy 296.699864 -379.195371) (xy 296.706364 -379.212554) (xy 296.712132 -379.219714) (xy 296.73404 -379.245342)
			(xy 296.772125 -379.300983) (xy 296.803272 -379.360785) (xy 296.827032 -379.423886) (xy 296.843064 -379.489379)
			(xy 296.851135 -379.556321) (xy 296.851131 -379.623748) (xy 296.843051 -379.690689) (xy 296.827012 -379.75618)
			(xy 296.803244 -379.819279) (xy 296.77209 -379.879076) (xy 296.733998 -379.934712) (xy 296.712132 -379.960378)
			(xy 296.706312 -379.967506) (xy 296.699813 -379.98471) (xy 296.699432 -379.993906) (xy 296.699432 -380.151386)
			(xy 296.698961 -380.161515) (xy 296.691233 -380.180241) (xy 296.676941 -380.194599) (xy 296.658251 -380.202414)
			(xy 296.648124 -380.202948) (xy 295.931844 -380.202948) (xy 295.921699 -380.202443) (xy 295.902957 -380.194671)
			(xy 295.888633 -380.1803) (xy 295.880924 -380.161533) (xy 295.880536 -380.151386) (xy 295.880536 -379.993906)
			(xy 295.880115 -379.98472) (xy 295.873608 -379.967536) (xy 295.867836 -379.960378) (xy 295.846016 -379.934676)
			(xy 295.807924 -379.879048) (xy 295.776769 -379.819257) (xy 295.753 -379.756165) (xy 295.736961 -379.69068)
			(xy 295.728881 -379.623745) (xy 295.728876 -379.556324) (xy 295.736948 -379.489388) (xy 295.75298 -379.423901)
			(xy 295.776741 -379.360806) (xy 295.807888 -379.301012) (xy 295.845974 -379.245379) (xy 295.867836 -379.219714)
			(xy 295.873656 -379.212586) (xy 295.880156 -379.195382) (xy 295.880536 -379.186186) (xy 295.880536 -378.693934)
			(xy 295.880101 -378.68475) (xy 295.873604 -378.667565) (xy 295.867836 -378.660406) (xy 295.845945 -378.634762)
			(xy 295.807855 -378.579126) (xy 295.776703 -378.519327) (xy 295.752939 -378.456227) (xy 295.736904 -378.390735)
			(xy 295.72883 -378.323794) (xy 292.450785 -378.323794) (xy 292.44275 -378.390553) (xy 292.426779 -378.455934)
			(xy 292.403109 -378.518938) (xy 292.372077 -378.57866) (xy 292.334131 -378.634246) (xy 292.312344 -378.659898)
			(xy 292.306559 -378.667051) (xy 292.300039 -378.684236) (xy 292.299644 -378.693426) (xy 292.299644 -379.186694)
			(xy 292.30007 -379.195879) (xy 292.306574 -379.213063) (xy 292.312344 -379.220222) (xy 292.334178 -379.245837)
			(xy 292.372126 -379.301428) (xy 292.403158 -379.361157) (xy 292.426829 -379.424166) (xy 292.4428 -379.489553)
			(xy 292.45084 -379.55638) (xy 292.450836 -379.623689) (xy 292.442787 -379.690515) (xy 292.426809 -379.7559)
			(xy 292.40313 -379.818907) (xy 292.372091 -379.878631) (xy 292.334135 -379.934218) (xy 292.312344 -379.95987)
			(xy 292.306528 -379.967001) (xy 292.300027 -379.984203) (xy 292.299644 -379.993398) (xy 292.299644 -380.151386)
			(xy 292.299224 -380.161559) (xy 292.291441 -380.180357) (xy 292.277054 -380.194743) (xy 292.258255 -380.202525)
			(xy 292.248082 -380.202948) (xy 291.531802 -380.202948) (xy 291.521629 -380.202534) (xy 291.502831 -380.194747)
			(xy 291.488446 -380.180358) (xy 291.480663 -380.161559) (xy 291.48024 -380.151386) (xy 291.48024 -379.993398)
			(xy 291.479822 -379.984212) (xy 291.473313 -379.967028) (xy 291.46754 -379.95987) (xy 291.445798 -379.934181)
			(xy 291.407847 -379.878599) (xy 291.376812 -379.818881) (xy 291.353137 -379.755881) (xy 291.337161 -379.690504)
			(xy 291.329113 -379.623685) (xy 291.329109 -379.556384) (xy 291.337148 -379.489564) (xy 291.353116 -379.424185)
			(xy 291.376784 -379.361182) (xy 291.407812 -379.30146) (xy 291.445755 -379.245874) (xy 291.46754 -379.220222)
			(xy 291.473357 -379.213092) (xy 291.479859 -379.19589) (xy 291.48024 -379.186694) (xy 291.48024 -378.693426)
			(xy 291.479809 -378.684241) (xy 291.473309 -378.667057) (xy 291.46754 -378.659898) (xy 291.445727 -378.634267)
			(xy 291.407778 -378.578678) (xy 291.376746 -378.518951) (xy 291.353075 -378.455944) (xy 291.337104 -378.390559)
			(xy 291.329062 -378.323734) (xy 288.051024 -378.323734) (xy 288.051024 -378.323792) (xy 288.04295 -378.390729)
			(xy 288.026915 -378.456218) (xy 288.003152 -378.519314) (xy 287.972001 -378.579109) (xy 287.933912 -378.634742)
			(xy 287.912048 -378.660406) (xy 287.90626 -378.667557) (xy 287.899742 -378.684743) (xy 287.899348 -378.693934)
			(xy 287.899348 -379.186186) (xy 287.899776 -379.195371) (xy 287.906279 -379.212555) (xy 287.912048 -379.219714)
			(xy 287.933959 -379.245341) (xy 287.97205 -379.30098) (xy 288.003201 -379.360781) (xy 288.026965 -379.423883)
			(xy 288.042999 -379.489377) (xy 288.051072 -379.55632) (xy 288.051068 -379.623749) (xy 288.042987 -379.690691)
			(xy 288.026945 -379.756183) (xy 288.003173 -379.819282) (xy 287.972014 -379.879079) (xy 287.933917 -379.934714)
			(xy 287.912048 -379.960378) (xy 287.906229 -379.967507) (xy 287.899729 -379.98471) (xy 287.899348 -379.993906)
			(xy 287.899348 -380.151386) (xy 287.898862 -380.161513) (xy 287.891136 -380.180236) (xy 287.87685 -380.194594)
			(xy 287.858165 -380.202411) (xy 287.84804 -380.202948) (xy 287.13176 -380.202948) (xy 287.121655 -380.202449)
			(xy 287.102985 -380.194707) (xy 287.088693 -380.180415) (xy 287.080951 -380.161745) (xy 287.080452 -380.15164)
			(xy 287.080452 -379.993906) (xy 287.080027 -379.984721) (xy 287.073523 -379.967537) (xy 287.067752 -379.960378)
			(xy 287.045931 -379.934676) (xy 287.007838 -379.879048) (xy 286.976682 -379.819258) (xy 286.952913 -379.756165)
			(xy 286.936873 -379.69068) (xy 286.928793 -379.623745) (xy 286.928788 -379.556324) (xy 286.936861 -379.489388)
			(xy 286.952893 -379.423901) (xy 286.976654 -379.360806) (xy 287.007802 -379.301011) (xy 287.045889 -379.245378)
			(xy 287.067752 -379.219714) (xy 287.073574 -379.212587) (xy 287.080072 -379.195382) (xy 287.080452 -379.186186)
			(xy 287.080452 -378.693934) (xy 287.080014 -378.68475) (xy 287.073519 -378.667566) (xy 287.067752 -378.660406)
			(xy 287.045861 -378.634763) (xy 287.007769 -378.579126) (xy 286.976617 -378.519328) (xy 286.952852 -378.456228)
			(xy 286.936817 -378.390735) (xy 286.928742 -378.323794) (xy 274.077801 -378.323794) (xy 274.085782 -378.367343)
			(xy 274.101882 -378.499931) (xy 274.109946 -378.633249) (xy 274.11045 -378.70003) (xy 274.109946 -378.766811)
			(xy 274.101882 -378.900129) (xy 274.085782 -379.032717) (xy 274.061707 -379.164091) (xy 274.029744 -379.293772)
			(xy 273.990009 -379.421286) (xy 273.942647 -379.546169) (xy 273.887832 -379.667964) (xy 273.825762 -379.786227)
			(xy 273.756666 -379.900526) (xy 273.680794 -380.010446) (xy 273.598424 -380.115583) (xy 273.509856 -380.215556)
			(xy 273.415414 -380.309998) (xy 273.315441 -380.398566) (xy 273.210304 -380.480936) (xy 273.100384 -380.556808)
			(xy 272.986085 -380.625904) (xy 272.92786 -380.656463) (xy 289.128932 -380.656463) (xy 289.136975 -380.589641)
			(xy 289.152947 -380.524259) (xy 289.17662 -380.461255) (xy 289.207654 -380.401532) (xy 289.245604 -380.345947)
			(xy 289.267392 -380.320296) (xy 289.273172 -380.313139) (xy 289.279697 -380.295958) (xy 289.280092 -380.286768)
			(xy 289.280092 -379.7935) (xy 289.279684 -379.784313) (xy 289.273169 -379.767128) (xy 289.267392 -379.759972)
			(xy 289.24565 -379.734282) (xy 289.207696 -379.678702) (xy 289.176658 -379.618984) (xy 289.15298 -379.555985)
			(xy 289.137002 -379.490606) (xy 289.128953 -379.423787) (xy 289.128949 -379.356485) (xy 289.136989 -379.289665)
			(xy 289.152959 -379.224284) (xy 289.176628 -379.161282) (xy 289.207659 -379.10156) (xy 289.245606 -379.045975)
			(xy 289.267392 -379.020324) (xy 289.273202 -379.013189) (xy 289.279709 -378.995991) (xy 289.280092 -378.986796)
			(xy 289.280092 -378.828554) (xy 289.280595 -378.818399) (xy 289.288376 -378.799638) (xy 289.302738 -378.785276)
			(xy 289.321499 -378.777495) (xy 289.331654 -378.776992) (xy 290.047934 -378.776992) (xy 290.058088 -378.777504)
			(xy 290.076849 -378.785281) (xy 290.091212 -378.799641) (xy 290.098993 -378.8184) (xy 290.099496 -378.828554)
			(xy 290.099496 -378.986796) (xy 290.099909 -378.995983) (xy 290.106421 -379.013167) (xy 290.112196 -379.020324)
			(xy 290.13403 -379.045938) (xy 290.171975 -379.101531) (xy 290.203004 -379.16126) (xy 290.226673 -379.224269)
			(xy 290.242641 -379.289656) (xy 290.250681 -379.356482) (xy 290.250677 -379.42379) (xy 290.242628 -379.490615)
			(xy 290.226651 -379.556) (xy 290.202975 -379.619006) (xy 290.171938 -379.678731) (xy 290.133986 -379.734319)
			(xy 290.112196 -379.759972) (xy 290.106386 -379.767108) (xy 290.099879 -379.784305) (xy 290.099496 -379.7935)
			(xy 290.099496 -380.286768) (xy 290.099922 -380.295953) (xy 290.106425 -380.313138) (xy 290.112196 -380.320296)
			(xy 290.134002 -380.345932) (xy 290.171948 -380.401522) (xy 290.202979 -380.461248) (xy 290.226649 -380.524255)
			(xy 290.242619 -380.589638) (xy 290.250654 -380.656404) (xy 293.528724 -380.656404) (xy 293.536798 -380.589467)
			(xy 293.552831 -380.52398) (xy 293.576592 -380.460884) (xy 293.60774 -380.401088) (xy 293.645826 -380.345453)
			(xy 293.667688 -380.319788) (xy 293.673471 -380.312633) (xy 293.679994 -380.29545) (xy 293.680388 -380.28626)
			(xy 293.680388 -379.794008) (xy 293.679977 -379.784821) (xy 293.673464 -379.767636) (xy 293.667688 -379.76048)
			(xy 293.645872 -379.734776) (xy 293.607782 -379.679146) (xy 293.57663 -379.619356) (xy 293.552864 -379.556264)
			(xy 293.536825 -379.49078) (xy 293.528746 -379.423846) (xy 293.528741 -379.356426) (xy 293.536812 -379.289491)
			(xy 293.552842 -379.224005) (xy 293.576601 -379.16091) (xy 293.607745 -379.101115) (xy 293.645827 -379.045481)
			(xy 293.667688 -379.019816) (xy 293.673501 -379.012683) (xy 293.680006 -378.995483) (xy 293.680388 -378.986288)
			(xy 293.680388 -378.828554) (xy 293.680887 -378.818431) (xy 293.688621 -378.799718) (xy 293.702902 -378.785366)
			(xy 293.721575 -378.777539) (xy 293.731696 -378.776992) (xy 294.447976 -378.776992) (xy 294.458096 -378.777435)
			(xy 294.476798 -378.785174) (xy 294.491112 -378.799482) (xy 294.49886 -378.81818) (xy 294.499284 -378.8283)
			(xy 294.499284 -378.986288) (xy 294.499704 -378.995474) (xy 294.506211 -379.012658) (xy 294.511984 -379.019816)
			(xy 294.533896 -379.045442) (xy 294.571984 -379.101082) (xy 294.603134 -379.160883) (xy 294.626896 -379.223985)
			(xy 294.642928 -379.289479) (xy 294.651001 -379.356422) (xy 294.650996 -379.42385) (xy 294.642915 -379.490792)
			(xy 294.626874 -379.556284) (xy 294.603104 -379.619383) (xy 294.571947 -379.67918) (xy 294.533851 -379.734815)
			(xy 294.511984 -379.76048) (xy 294.506169 -379.767612) (xy 294.499666 -379.784813) (xy 294.499284 -379.794008)
			(xy 294.499284 -380.28626) (xy 294.499717 -380.295445) (xy 294.506215 -380.312629) (xy 294.511984 -380.319788)
			(xy 294.533868 -380.345437) (xy 294.571957 -380.401073) (xy 294.603108 -380.460872) (xy 294.626872 -380.523971)
			(xy 294.642906 -380.589462) (xy 294.650981 -380.656402) (xy 294.650981 -380.656463) (xy 297.92902 -380.656463)
			(xy 297.937062 -380.589641) (xy 297.953034 -380.52426) (xy 297.976707 -380.461256) (xy 298.00774 -380.401533)
			(xy 298.045688 -380.345948) (xy 298.067476 -380.320296) (xy 298.073254 -380.313137) (xy 298.079781 -380.295957)
			(xy 298.080176 -380.286768) (xy 298.080176 -379.7935) (xy 298.079771 -379.784312) (xy 298.073254 -379.767128)
			(xy 298.067476 -379.759972) (xy 298.045734 -379.734282) (xy 298.007782 -379.678701) (xy 297.976744 -379.618984)
			(xy 297.953067 -379.555984) (xy 297.93709 -379.490606) (xy 297.929041 -379.423787) (xy 297.929037 -379.356485)
			(xy 297.937077 -379.289665) (xy 297.953046 -379.224285) (xy 297.976715 -379.161283) (xy 298.007745 -379.101561)
			(xy 298.04569 -379.045976) (xy 298.067476 -379.020324) (xy 298.073285 -379.013187) (xy 298.079793 -378.99599)
			(xy 298.080176 -378.986796) (xy 298.080176 -378.828554) (xy 298.080597 -378.818389) (xy 298.088393 -378.799611)
			(xy 298.102782 -378.785246) (xy 298.121572 -378.77748) (xy 298.131738 -378.776992) (xy 298.848018 -378.776992)
			(xy 298.858171 -378.777517) (xy 298.876932 -378.785289) (xy 298.891295 -378.799644) (xy 298.899077 -378.818401)
			(xy 298.89958 -378.828554) (xy 298.89958 -378.986796) (xy 298.899996 -378.995982) (xy 298.906506 -379.013167)
			(xy 298.91228 -379.020324) (xy 298.934114 -379.045938) (xy 298.972061 -379.10153) (xy 299.003091 -379.161259)
			(xy 299.02676 -379.224269) (xy 299.042729 -379.289655) (xy 299.050769 -379.356482) (xy 299.050765 -379.42379)
			(xy 299.042716 -379.490616) (xy 299.026739 -379.556) (xy 299.003061 -379.619007) (xy 298.972023 -379.678732)
			(xy 298.93407 -379.73432) (xy 298.91228 -379.759972) (xy 298.906468 -379.767106) (xy 298.899963 -379.784305)
			(xy 298.89958 -379.7935) (xy 298.89958 -380.286768) (xy 298.90001 -380.295953) (xy 298.90651 -380.313137)
			(xy 298.91228 -380.320296) (xy 298.934087 -380.345932) (xy 298.972034 -380.401521) (xy 299.003065 -380.461247)
			(xy 299.026736 -380.524254) (xy 299.042707 -380.589638) (xy 299.050742 -380.656404) (xy 302.328812 -380.656404)
			(xy 302.336886 -380.589468) (xy 302.352918 -380.52398) (xy 302.376679 -380.460884) (xy 302.407826 -380.401089)
			(xy 302.44591 -380.345454) (xy 302.467772 -380.319788) (xy 302.473565 -380.312641) (xy 302.48008 -380.295451)
			(xy 302.480472 -380.28626) (xy 302.480472 -379.794008) (xy 302.480064 -379.78482) (xy 302.47355 -379.767636)
			(xy 302.467772 -379.76048) (xy 302.445956 -379.734775) (xy 302.407868 -379.679146) (xy 302.376717 -379.619355)
			(xy 302.352951 -379.556263) (xy 302.336913 -379.490779) (xy 302.328834 -379.423846) (xy 302.328829 -379.356426)
			(xy 302.3369 -379.289492) (xy 302.35293 -379.224006) (xy 302.376687 -379.160911) (xy 302.407831 -379.101116)
			(xy 302.445912 -379.045482) (xy 302.467772 -379.019816) (xy 302.473595 -379.01269) (xy 302.480092 -378.995485)
			(xy 302.480472 -378.986288) (xy 302.480472 -378.828554) (xy 302.48089 -378.81842) (xy 302.488639 -378.799692)
			(xy 302.502946 -378.785336) (xy 302.521648 -378.777525) (xy 302.53178 -378.776992) (xy 303.24806 -378.776992)
			(xy 303.258211 -378.777454) (xy 303.27696 -378.785235) (xy 303.291285 -378.79962) (xy 303.298987 -378.818402)
			(xy 303.299368 -378.828554) (xy 303.299368 -378.986288) (xy 303.299791 -378.995474) (xy 303.306296 -379.012658)
			(xy 303.312068 -379.019816) (xy 303.33398 -379.045442) (xy 303.37207 -379.101081) (xy 303.40322 -379.160883)
			(xy 303.426983 -379.223985) (xy 303.443016 -379.289479) (xy 303.451089 -379.356422) (xy 303.451084 -379.42385)
			(xy 303.443003 -379.490792) (xy 303.426962 -379.556284) (xy 303.403191 -379.619383) (xy 303.372032 -379.679181)
			(xy 303.333936 -379.734815) (xy 303.312068 -379.76048) (xy 303.306251 -379.76761) (xy 303.299749 -379.784812)
			(xy 303.299368 -379.794008) (xy 303.299368 -380.28626) (xy 303.299805 -380.295444) (xy 303.306301 -380.312628)
			(xy 303.312068 -380.319788) (xy 303.333953 -380.345436) (xy 303.372043 -380.401073) (xy 303.403195 -380.460871)
			(xy 303.426959 -380.52397) (xy 303.442994 -380.589461) (xy 303.451069 -380.656402) (xy 303.451069 -380.656404)
			(xy 333.128842 -380.656404) (xy 333.136916 -380.589467) (xy 333.15295 -380.523979) (xy 333.176713 -380.460883)
			(xy 333.207862 -380.401087) (xy 333.245949 -380.345453) (xy 333.267812 -380.319788) (xy 333.273598 -380.312635)
			(xy 333.280118 -380.29545) (xy 333.280512 -380.28626) (xy 333.280512 -379.794008) (xy 333.280095 -379.784822)
			(xy 333.273586 -379.767637) (xy 333.267812 -379.76048) (xy 333.245995 -379.734776) (xy 333.207904 -379.679147)
			(xy 333.17675 -379.619357) (xy 333.152983 -379.556265) (xy 333.136944 -379.49078) (xy 333.128864 -379.423846)
			(xy 333.12886 -379.356426) (xy 333.136931 -379.289491) (xy 333.152962 -379.224004) (xy 333.176721 -379.160909)
			(xy 333.207867 -379.101115) (xy 333.24595 -379.045481) (xy 333.267812 -379.019816) (xy 333.273628 -379.012685)
			(xy 333.280131 -378.995483) (xy 333.280512 -378.986288) (xy 333.280512 -378.828554) (xy 333.280988 -378.818428)
			(xy 333.288726 -378.799711) (xy 333.303015 -378.785357) (xy 333.321696 -378.777535) (xy 333.33182 -378.776992)
			(xy 334.0481 -378.776992) (xy 334.058253 -378.777422) (xy 334.077004 -378.785216) (xy 334.091327 -378.79961)
			(xy 334.099028 -378.818399) (xy 334.099408 -378.828554) (xy 334.099408 -378.986288) (xy 334.099822 -378.995475)
			(xy 334.106333 -379.012659) (xy 334.112108 -379.019816) (xy 334.134019 -379.045442) (xy 334.172106 -379.101083)
			(xy 334.203254 -379.160884) (xy 334.227015 -379.223986) (xy 334.243047 -379.28948) (xy 334.251119 -379.356422)
			(xy 334.251114 -379.42385) (xy 334.243034 -379.490791) (xy 334.226994 -379.556283) (xy 334.203224 -379.619382)
			(xy 334.172068 -379.679179) (xy 334.133975 -379.734815) (xy 334.112108 -379.76048) (xy 334.106296 -379.767614)
			(xy 334.09979 -379.784813) (xy 334.099408 -379.794008) (xy 334.099408 -380.28626) (xy 334.099836 -380.295445)
			(xy 334.106337 -380.31263) (xy 334.112108 -380.319788) (xy 334.133991 -380.345437) (xy 334.172079 -380.401074)
			(xy 334.203228 -380.460873) (xy 334.226991 -380.523972) (xy 334.243025 -380.589463) (xy 334.251099 -380.656402)
			(xy 334.251099 -380.656464) (xy 337.529162 -380.656464) (xy 337.537203 -380.589643) (xy 337.553173 -380.524262)
			(xy 337.576842 -380.461259) (xy 337.607871 -380.401536) (xy 337.645815 -380.345949) (xy 337.6676 -380.320296)
			(xy 337.673381 -380.31314) (xy 337.679905 -380.295958) (xy 337.6803 -380.286768) (xy 337.6803 -379.7935)
			(xy 337.67989 -379.784313) (xy 337.673376 -379.767129) (xy 337.6676 -379.759972) (xy 337.645861 -379.734281)
			(xy 337.607913 -379.678699) (xy 337.57688 -379.61898) (xy 337.553206 -379.555981) (xy 337.537231 -379.490604)
			(xy 337.529183 -379.423786) (xy 337.529179 -379.356486) (xy 337.537218 -379.289667) (xy 337.553185 -379.224288)
			(xy 337.57685 -379.161286) (xy 337.607876 -379.101563) (xy 337.645816 -379.045977) (xy 337.6676 -379.020324)
			(xy 337.673411 -379.013189) (xy 337.679917 -378.995991) (xy 337.6803 -378.986796) (xy 337.6803 -378.828554)
			(xy 337.680795 -378.818398) (xy 337.688577 -378.799635) (xy 337.702942 -378.785273) (xy 337.721706 -378.777493)
			(xy 337.731862 -378.776992) (xy 338.448142 -378.776992) (xy 338.458297 -378.777498) (xy 338.477058 -378.785278)
			(xy 338.49142 -378.799639) (xy 338.499201 -378.818399) (xy 338.499704 -378.828554) (xy 338.499704 -378.986796)
			(xy 338.500115 -378.995983) (xy 338.506628 -379.013167) (xy 338.512404 -379.020324) (xy 338.534237 -379.045938)
			(xy 338.572182 -379.101531) (xy 338.603211 -379.16126) (xy 338.626879 -379.22427) (xy 338.642847 -379.289656)
			(xy 338.650887 -379.356482) (xy 338.650883 -379.42379) (xy 338.642834 -379.490615) (xy 338.626858 -379.556)
			(xy 338.603181 -379.619006) (xy 338.572145 -379.678731) (xy 338.534193 -379.734319) (xy 338.512404 -379.759972)
			(xy 338.506595 -379.767108) (xy 338.500088 -379.784306) (xy 338.499704 -379.7935) (xy 338.499704 -380.286768)
			(xy 338.500129 -380.295954) (xy 338.506632 -380.313138) (xy 338.512404 -380.320296) (xy 338.53421 -380.345933)
			(xy 338.572155 -380.401522) (xy 338.603185 -380.461248) (xy 338.626855 -380.524255) (xy 338.642826 -380.589639)
			(xy 338.65086 -380.656404) (xy 341.92893 -380.656404) (xy 341.937004 -380.589467) (xy 341.953037 -380.523979)
			(xy 341.976799 -380.460883) (xy 342.007947 -380.401088) (xy 342.046033 -380.345453) (xy 342.067896 -380.319788)
			(xy 342.07368 -380.312634) (xy 342.080202 -380.29545) (xy 342.080596 -380.28626) (xy 342.080596 -379.794008)
			(xy 342.080183 -379.784821) (xy 342.073671 -379.767637) (xy 342.067896 -379.76048) (xy 342.046079 -379.734776)
			(xy 342.007989 -379.679147) (xy 341.976837 -379.619356) (xy 341.95307 -379.556264) (xy 341.937032 -379.49078)
			(xy 341.928952 -379.423846) (xy 341.928948 -379.356426) (xy 341.937019 -379.289491) (xy 341.953049 -379.224005)
			(xy 341.976807 -379.16091) (xy 342.007952 -379.101115) (xy 342.046035 -379.045481) (xy 342.067896 -379.019816)
			(xy 342.07371 -379.012683) (xy 342.080215 -378.995483) (xy 342.080596 -378.986288) (xy 342.080596 -378.828554)
			(xy 342.081088 -378.81843) (xy 342.088822 -378.799716) (xy 342.103106 -378.785363) (xy 342.121782 -378.777538)
			(xy 342.131904 -378.776992) (xy 342.848184 -378.776992) (xy 342.858336 -378.777434) (xy 342.877087 -378.785223)
			(xy 342.89141 -378.799614) (xy 342.899112 -378.8184) (xy 342.899492 -378.828554) (xy 342.899492 -378.986288)
			(xy 342.89991 -378.995474) (xy 342.906418 -379.012659) (xy 342.912192 -379.019816) (xy 342.934103 -379.045442)
			(xy 342.972191 -379.101082) (xy 343.00334 -379.160884) (xy 343.027102 -379.223986) (xy 343.043135 -379.28948)
			(xy 343.051207 -379.356422) (xy 343.051202 -379.42385) (xy 343.043122 -379.490792) (xy 343.027081 -379.556283)
			(xy 343.003311 -379.619382) (xy 342.972154 -379.67918) (xy 342.934059 -379.734815) (xy 342.912192 -379.76048)
			(xy 342.906378 -379.767613) (xy 342.899874 -379.784813) (xy 342.899492 -379.794008) (xy 342.899492 -380.28626)
			(xy 342.899923 -380.295445) (xy 342.906422 -380.312629) (xy 342.912192 -380.319788) (xy 342.934076 -380.345437)
			(xy 342.972165 -380.401074) (xy 343.003315 -380.460872) (xy 343.027078 -380.523971) (xy 343.043113 -380.589462)
			(xy 343.051187 -380.656402) (xy 343.051187 -380.656463) (xy 346.329226 -380.656463) (xy 346.337269 -380.589641)
			(xy 346.353241 -380.524259) (xy 346.376913 -380.461255) (xy 346.407947 -380.401533) (xy 346.445896 -380.345948)
			(xy 346.467684 -380.320296) (xy 346.473463 -380.313138) (xy 346.479989 -380.295957) (xy 346.480384 -380.286768)
			(xy 346.480384 -379.7935) (xy 346.479977 -379.784312) (xy 346.473462 -379.767128) (xy 346.467684 -379.759972)
			(xy 346.445942 -379.734282) (xy 346.407989 -379.678702) (xy 346.376951 -379.618984) (xy 346.353274 -379.555984)
			(xy 346.337296 -379.490606) (xy 346.329247 -379.423787) (xy 346.329243 -379.356485) (xy 346.337283 -379.289665)
			(xy 346.353252 -379.224285) (xy 346.376922 -379.161282) (xy 346.407952 -379.10156) (xy 346.445898 -379.045976)
			(xy 346.467684 -379.020324) (xy 346.473493 -379.013188) (xy 346.480001 -378.99599) (xy 346.480384 -378.986796)
			(xy 346.480384 -378.828554) (xy 346.480797 -378.818388) (xy 346.488595 -378.799609) (xy 346.502986 -378.785243)
			(xy 346.521779 -378.777479) (xy 346.531946 -378.776992) (xy 347.248226 -378.776992) (xy 347.25838 -378.777511)
			(xy 347.277141 -378.785285) (xy 347.291504 -378.799642) (xy 347.299285 -378.8184) (xy 347.299788 -378.828554)
			(xy 347.299788 -378.986796) (xy 347.300203 -378.995983) (xy 347.306714 -379.013167) (xy 347.312488 -379.020324)
			(xy 347.334322 -379.045938) (xy 347.372268 -379.10153) (xy 347.403297 -379.161259) (xy 347.426966 -379.224269)
			(xy 347.442935 -379.289656) (xy 347.450975 -379.356482) (xy 347.450971 -379.42379) (xy 347.442922 -379.490616)
			(xy 347.426945 -379.556) (xy 347.403268 -379.619007) (xy 347.372231 -379.678732) (xy 347.334278 -379.734319)
			(xy 347.312488 -379.759972) (xy 347.306677 -379.767107) (xy 347.300171 -379.784305) (xy 347.299788 -379.7935)
			(xy 347.299788 -380.286768) (xy 347.300216 -380.295953) (xy 347.306718 -380.313138) (xy 347.312488 -380.320296)
			(xy 347.334295 -380.345932) (xy 347.372241 -380.401522) (xy 347.403272 -380.461248) (xy 347.426942 -380.524254)
			(xy 347.442913 -380.589638) (xy 347.450948 -380.656404) (xy 377.128751 -380.656404) (xy 377.136826 -380.589466)
			(xy 377.15286 -380.523978) (xy 377.176623 -380.460882) (xy 377.207772 -380.401087) (xy 377.24586 -380.345453)
			(xy 377.267724 -380.319788) (xy 377.273511 -380.312636) (xy 377.280031 -380.295451) (xy 377.280424 -380.28626)
			(xy 377.280424 -379.794008) (xy 377.280005 -379.784822) (xy 377.273497 -379.767638) (xy 377.267724 -379.76048)
			(xy 377.245906 -379.734776) (xy 377.207815 -379.679148) (xy 377.17666 -379.619357) (xy 377.152893 -379.556265)
			(xy 377.136853 -379.490781) (xy 377.128773 -379.423846) (xy 377.128769 -379.356426) (xy 377.13684 -379.28949)
			(xy 377.152871 -379.224004) (xy 377.176631 -379.160909) (xy 377.207777 -379.101114) (xy 377.245862 -379.045481)
			(xy 377.267724 -379.019816) (xy 377.273542 -379.012686) (xy 377.280043 -378.995484) (xy 377.280424 -378.986288)
			(xy 377.280424 -378.828554) (xy 377.280888 -378.818426) (xy 377.288628 -378.799707) (xy 377.302921 -378.785353)
			(xy 377.321607 -378.777533) (xy 377.331732 -378.776992) (xy 378.048012 -378.776992) (xy 378.058166 -378.777411)
			(xy 378.076917 -378.785209) (xy 378.09124 -378.799607) (xy 378.098941 -378.818398) (xy 378.09932 -378.828554)
			(xy 378.09932 -378.986288) (xy 378.099731 -378.995475) (xy 378.106244 -379.01266) (xy 378.11202 -379.019816)
			(xy 378.13393 -379.045443) (xy 378.172016 -379.101083) (xy 378.203164 -379.160885) (xy 378.226924 -379.223987)
			(xy 378.242956 -379.28948) (xy 378.251028 -379.356423) (xy 378.251023 -379.42385) (xy 378.242943 -379.490791)
			(xy 378.226903 -379.556282) (xy 378.203134 -379.619381) (xy 378.171979 -379.679179) (xy 378.133886 -379.734814)
			(xy 378.11202 -379.76048) (xy 378.106209 -379.767615) (xy 378.099702 -379.784813) (xy 378.09932 -379.794008)
			(xy 378.09932 -380.28626) (xy 378.099745 -380.295446) (xy 378.106248 -380.312631) (xy 378.11202 -380.319788)
			(xy 378.133903 -380.345437) (xy 378.17199 -380.401075) (xy 378.203138 -380.460873) (xy 378.226901 -380.523972)
			(xy 378.242934 -380.589463) (xy 378.251008 -380.656403) (xy 378.251008 -380.656464) (xy 381.529071 -380.656464)
			(xy 381.537113 -380.589643) (xy 381.553083 -380.524262) (xy 381.576752 -380.461258) (xy 381.607782 -380.401535)
			(xy 381.645726 -380.345948) (xy 381.667512 -380.320296) (xy 381.673294 -380.313141) (xy 381.679817 -380.295958)
			(xy 381.680212 -380.286768) (xy 381.680212 -379.7935) (xy 381.679799 -379.784313) (xy 381.673287 -379.767129)
			(xy 381.667512 -379.759972) (xy 381.645773 -379.73428) (xy 381.607824 -379.678699) (xy 381.57679 -379.618981)
			(xy 381.553116 -379.555981) (xy 381.537141 -379.490604) (xy 381.529093 -379.423786) (xy 381.529089 -379.356486)
			(xy 381.537128 -379.289667) (xy 381.553095 -379.224288) (xy 381.576761 -379.161285) (xy 381.607787 -379.101563)
			(xy 381.645728 -379.045977) (xy 381.667512 -379.020324) (xy 381.673325 -379.01319) (xy 381.679829 -378.995991)
			(xy 381.680212 -378.986796) (xy 381.680212 -378.828554) (xy 381.680695 -378.818397) (xy 381.68848 -378.799631)
			(xy 381.702848 -378.785269) (xy 381.721616 -378.777491) (xy 381.731774 -378.776992) (xy 382.448054 -378.776992)
			(xy 382.458203 -378.77757) (xy 382.476962 -378.785321) (xy 382.491328 -378.79966) (xy 382.499112 -378.818406)
			(xy 382.499616 -378.828554) (xy 382.499616 -378.986796) (xy 382.500025 -378.995983) (xy 382.506539 -379.013168)
			(xy 382.512316 -379.020324) (xy 382.534153 -379.045936) (xy 382.572103 -379.101528) (xy 382.603137 -379.161256)
			(xy 382.626809 -379.224266) (xy 382.64278 -379.289654) (xy 382.650821 -379.356481) (xy 382.650816 -379.423791)
			(xy 382.642767 -379.490618) (xy 382.626787 -379.556003) (xy 382.603107 -379.61901) (xy 382.572066 -379.678734)
			(xy 382.534108 -379.734321) (xy 382.512316 -379.759972) (xy 382.506508 -379.767109) (xy 382.5 -379.784306)
			(xy 382.499616 -379.7935) (xy 382.499616 -380.286768) (xy 382.500038 -380.295954) (xy 382.506543 -380.313139)
			(xy 382.512316 -380.320296) (xy 382.534125 -380.345931) (xy 382.572076 -380.401519) (xy 382.603111 -380.461245)
			(xy 382.626784 -380.524251) (xy 382.642757 -380.589636) (xy 382.650793 -380.656404) (xy 385.928839 -380.656404)
			(xy 385.936913 -380.589467) (xy 385.952947 -380.523979) (xy 385.976709 -380.460883) (xy 386.007858 -380.401087)
			(xy 386.045945 -380.345453) (xy 386.067808 -380.319788) (xy 386.073593 -380.312635) (xy 386.080114 -380.29545)
			(xy 386.080508 -380.28626) (xy 386.080508 -379.794008) (xy 386.080092 -379.784821) (xy 386.073582 -379.767637)
			(xy 386.067808 -379.76048) (xy 386.045991 -379.734776) (xy 386.0079 -379.679147) (xy 385.976747 -379.619356)
			(xy 385.95298 -379.556265) (xy 385.936941 -379.49078) (xy 385.928861 -379.423846) (xy 385.928857 -379.356426)
			(xy 385.936928 -379.289491) (xy 385.952958 -379.224004) (xy 385.976718 -379.160909) (xy 386.007863 -379.101115)
			(xy 386.045947 -379.045481) (xy 386.067808 -379.019816) (xy 386.073624 -379.012684) (xy 386.080127 -378.995483)
			(xy 386.080508 -378.986288) (xy 386.080508 -378.828554) (xy 386.080988 -378.818428) (xy 386.088725 -378.799712)
			(xy 386.103012 -378.785359) (xy 386.121693 -378.777535) (xy 386.131816 -378.776992) (xy 386.848096 -378.776992)
			(xy 386.858249 -378.777425) (xy 386.877 -378.785218) (xy 386.891323 -378.799611) (xy 386.899024 -378.818399)
			(xy 386.899404 -378.828554) (xy 386.899404 -378.986288) (xy 386.899819 -378.995475) (xy 386.906329 -379.012659)
			(xy 386.912104 -379.019816) (xy 386.934015 -379.045442) (xy 386.972102 -379.101083) (xy 387.00325 -379.160884)
			(xy 387.027012 -379.223986) (xy 387.043044 -379.28948) (xy 387.051116 -379.356422) (xy 387.051111 -379.42385)
			(xy 387.043031 -379.490791) (xy 387.02699 -379.556283) (xy 387.003221 -379.619382) (xy 386.972065 -379.679179)
			(xy 386.933971 -379.734815) (xy 386.912104 -379.76048) (xy 386.906291 -379.767614) (xy 386.899786 -379.784813)
			(xy 386.899404 -379.794008) (xy 386.899404 -380.28626) (xy 386.899832 -380.295445) (xy 386.906333 -380.31263)
			(xy 386.912104 -380.319788) (xy 386.933987 -380.345437) (xy 386.972075 -380.401074) (xy 387.003225 -380.460872)
			(xy 387.026988 -380.523971) (xy 387.043022 -380.589462) (xy 387.051096 -380.656402) (xy 387.051096 -380.656464)
			(xy 390.329159 -380.656464) (xy 390.3372 -380.589643) (xy 390.35317 -380.524263) (xy 390.376839 -380.461259)
			(xy 390.407867 -380.401536) (xy 390.445811 -380.345949) (xy 390.467596 -380.320296) (xy 390.473376 -380.313139)
			(xy 390.479901 -380.295958) (xy 390.480296 -380.286768) (xy 390.480296 -379.7935) (xy 390.479887 -379.784313)
			(xy 390.473372 -379.767128) (xy 390.467596 -379.759972) (xy 390.445857 -379.73428) (xy 390.407909 -379.678699)
			(xy 390.376876 -379.61898) (xy 390.353203 -379.555981) (xy 390.337228 -379.490604) (xy 390.32918 -379.423786)
			(xy 390.329176 -379.356486) (xy 390.337215 -379.289667) (xy 390.353181 -379.224288) (xy 390.376847 -379.161286)
			(xy 390.407872 -379.101563) (xy 390.445812 -379.045977) (xy 390.467596 -379.020324) (xy 390.473407 -379.013189)
			(xy 390.479913 -378.995991) (xy 390.480296 -378.986796) (xy 390.480296 -378.828554) (xy 390.480795 -378.818398)
			(xy 390.488576 -378.799636) (xy 390.50294 -378.785274) (xy 390.521702 -378.777494) (xy 390.531858 -378.776992)
			(xy 391.248138 -378.776992) (xy 391.258293 -378.777501) (xy 391.277054 -378.785279) (xy 391.291416 -378.79964)
			(xy 391.299197 -378.8184) (xy 391.2997 -378.828554) (xy 391.2997 -378.986796) (xy 391.300112 -378.995983)
			(xy 391.306625 -379.013167) (xy 391.3124 -379.020324) (xy 391.334234 -379.045938) (xy 391.372178 -379.101531)
			(xy 391.403207 -379.16126) (xy 391.426876 -379.224269) (xy 391.442844 -379.289656) (xy 391.450884 -379.356482)
			(xy 391.45088 -379.42379) (xy 391.442831 -379.490615) (xy 391.426855 -379.556) (xy 391.403178 -379.619006)
			(xy 391.372141 -379.678731) (xy 391.334189 -379.734319) (xy 391.3124 -379.759972) (xy 391.30659 -379.767108)
			(xy 391.300083 -379.784306) (xy 391.2997 -379.7935) (xy 391.2997 -380.286768) (xy 391.300126 -380.295954)
			(xy 391.306629 -380.313138) (xy 391.3124 -380.320296) (xy 391.334206 -380.345933) (xy 391.372152 -380.401522)
			(xy 391.403182 -380.461248) (xy 391.426852 -380.524255) (xy 391.442822 -380.589638) (xy 391.450857 -380.656404)
			(xy 421.12866 -380.656404) (xy 421.136735 -380.589466) (xy 421.152769 -380.523978) (xy 421.176533 -380.460881)
			(xy 421.207683 -380.401086) (xy 421.245772 -380.345453) (xy 421.267636 -380.319788) (xy 421.273425 -380.312637)
			(xy 421.279943 -380.295451) (xy 421.280336 -380.28626) (xy 421.280336 -379.794008) (xy 421.279914 -379.784822)
			(xy 421.273408 -379.767638) (xy 421.267636 -379.76048) (xy 421.245818 -379.734776) (xy 421.207725 -379.679148)
			(xy 421.176571 -379.619358) (xy 421.152802 -379.556266) (xy 421.136762 -379.490781) (xy 421.128682 -379.423846)
			(xy 421.128678 -379.356426) (xy 421.136749 -379.28949) (xy 421.152781 -379.224003) (xy 421.176541 -379.160908)
			(xy 421.207688 -379.101114) (xy 421.245774 -379.045481) (xy 421.267636 -379.019816) (xy 421.273455 -379.012687)
			(xy 421.279956 -378.995484) (xy 421.280336 -378.986288) (xy 421.280336 -378.828554) (xy 421.280789 -378.818425)
			(xy 421.288531 -378.799703) (xy 421.302827 -378.785349) (xy 421.321517 -378.777531) (xy 421.331644 -378.776992)
			(xy 422.047924 -378.776992) (xy 422.058033 -378.777465) (xy 422.076711 -378.785209) (xy 422.091004 -378.79951)
			(xy 422.09874 -378.81819) (xy 422.099232 -378.8283) (xy 422.099232 -378.986288) (xy 422.099663 -378.995473)
			(xy 422.106164 -379.012656) (xy 422.111932 -379.019816) (xy 422.133842 -379.045443) (xy 422.171927 -379.101084)
			(xy 422.203074 -379.160885) (xy 422.226834 -379.223987) (xy 422.242865 -379.289481) (xy 422.250937 -379.356423)
			(xy 422.250932 -379.423849) (xy 422.242852 -379.49079) (xy 422.226813 -379.556282) (xy 422.203045 -379.61938)
			(xy 422.17189 -379.679178) (xy 422.133798 -379.734814) (xy 422.111932 -379.76048) (xy 422.106111 -379.767607)
			(xy 422.099613 -379.784812) (xy 422.099232 -379.794008) (xy 422.099232 -380.28626) (xy 422.099677 -380.295443)
			(xy 422.106168 -380.312627) (xy 422.111932 -380.319788) (xy 422.133814 -380.345438) (xy 422.171901 -380.401075)
			(xy 422.203049 -380.460874) (xy 422.22681 -380.523973) (xy 422.242843 -380.589463) (xy 422.250917 -380.656403)
			(xy 422.250917 -380.656463) (xy 425.52898 -380.656463) (xy 425.537022 -380.589642) (xy 425.552992 -380.524262)
			(xy 425.576662 -380.461258) (xy 425.607692 -380.401535) (xy 425.645638 -380.345948) (xy 425.667424 -380.320296)
			(xy 425.673208 -380.313142) (xy 425.679729 -380.295958) (xy 425.680124 -380.286768) (xy 425.680124 -379.7935)
			(xy 425.679709 -379.784313) (xy 425.673198 -379.767129) (xy 425.667424 -379.759972) (xy 425.645684 -379.734281)
			(xy 425.607735 -379.678699) (xy 425.5767 -379.618981) (xy 425.553026 -379.555982) (xy 425.53705 -379.490605)
			(xy 425.529002 -379.423787) (xy 425.528998 -379.356486) (xy 425.537037 -379.289667) (xy 425.553004 -379.224287)
			(xy 425.576671 -379.161285) (xy 425.607698 -379.101563) (xy 425.64564 -379.045977) (xy 425.667424 -379.020324)
			(xy 425.673238 -379.013191) (xy 425.679742 -378.995991) (xy 425.680124 -378.986796) (xy 425.680124 -378.828554)
			(xy 425.680595 -378.818395) (xy 425.688382 -378.799628) (xy 425.702754 -378.785264) (xy 425.721527 -378.777489)
			(xy 425.731686 -378.776992) (xy 426.447966 -378.776992) (xy 426.458116 -378.77756) (xy 426.476875 -378.785315)
			(xy 426.49124 -378.799657) (xy 426.499024 -378.818405) (xy 426.499528 -378.828554) (xy 426.499528 -378.986796)
			(xy 426.499934 -378.995984) (xy 426.50645 -379.013168) (xy 426.512228 -379.020324) (xy 426.534064 -379.045937)
			(xy 426.572014 -379.101528) (xy 426.603047 -379.161257) (xy 426.626718 -379.224267) (xy 426.642689 -379.289654)
			(xy 426.65073 -379.356481) (xy 426.650725 -379.423791) (xy 426.642676 -379.490617) (xy 426.626697 -379.556003)
			(xy 426.603017 -379.619009) (xy 426.571977 -379.678734) (xy 426.53402 -379.73432) (xy 426.512228 -379.759972)
			(xy 426.50641 -379.767101) (xy 426.49991 -379.784304) (xy 426.499528 -379.7935) (xy 426.499528 -380.286768)
			(xy 426.499947 -380.295954) (xy 426.506454 -380.313139) (xy 426.512228 -380.320296) (xy 426.534036 -380.345932)
			(xy 426.571987 -380.40152) (xy 426.603021 -380.461245) (xy 426.626694 -380.524252) (xy 426.642667 -380.589636)
			(xy 426.650703 -380.656404) (xy 429.928748 -380.656404) (xy 429.936823 -380.589467) (xy 429.952857 -380.523978)
			(xy 429.976619 -380.460882) (xy 430.007769 -380.401087) (xy 430.045857 -380.345453) (xy 430.06772 -380.319788)
			(xy 430.073506 -380.312636) (xy 430.080027 -380.295451) (xy 430.08042 -380.28626) (xy 430.08042 -379.794008)
			(xy 430.080001 -379.784822) (xy 430.073493 -379.767638) (xy 430.06772 -379.76048) (xy 430.045902 -379.734776)
			(xy 430.007811 -379.679148) (xy 429.976657 -379.619357) (xy 429.952889 -379.556265) (xy 429.93685 -379.490781)
			(xy 429.92877 -379.423846) (xy 429.928766 -379.356426) (xy 429.936837 -379.289491) (xy 429.952868 -379.224004)
			(xy 429.976628 -379.160909) (xy 430.007774 -379.101114) (xy 430.045858 -379.045481) (xy 430.06772 -379.019816)
			(xy 430.073537 -379.012685) (xy 430.080039 -378.995484) (xy 430.08042 -378.986288) (xy 430.08042 -378.828554)
			(xy 430.080888 -378.818427) (xy 430.088628 -378.799708) (xy 430.102919 -378.785354) (xy 430.121603 -378.777533)
			(xy 430.131728 -378.776992) (xy 430.848008 -378.776992) (xy 430.858162 -378.777415) (xy 430.876913 -378.785212)
			(xy 430.891235 -378.799608) (xy 430.898936 -378.818398) (xy 430.899316 -378.828554) (xy 430.899316 -378.986288)
			(xy 430.899728 -378.995475) (xy 430.90624 -379.01266) (xy 430.912016 -379.019816) (xy 430.933927 -379.045443)
			(xy 430.972013 -379.101083) (xy 431.003161 -379.160885) (xy 431.026921 -379.223987) (xy 431.042953 -379.28948)
			(xy 431.051025 -379.356422) (xy 431.05102 -379.42385) (xy 431.04294 -379.490791) (xy 431.0269 -379.556282)
			(xy 431.003131 -379.619381) (xy 430.971976 -379.679179) (xy 430.933882 -379.734814) (xy 430.912016 -379.76048)
			(xy 430.906205 -379.767615) (xy 430.899698 -379.784813) (xy 430.899316 -379.794008) (xy 430.899316 -380.28626)
			(xy 430.899742 -380.295446) (xy 430.906244 -380.31263) (xy 430.912016 -380.319788) (xy 430.933899 -380.345437)
			(xy 430.971986 -380.401074) (xy 431.003135 -380.460873) (xy 431.026897 -380.523972) (xy 431.042931 -380.589463)
			(xy 431.051005 -380.656403) (xy 431.051005 -380.656464) (xy 434.329068 -380.656464) (xy 434.33711 -380.589643)
			(xy 434.35308 -380.524262) (xy 434.376749 -380.461259) (xy 434.407778 -380.401535) (xy 434.445722 -380.345949)
			(xy 434.467508 -380.320296) (xy 434.47329 -380.31314) (xy 434.479813 -380.295958) (xy 434.480208 -380.286768)
			(xy 434.480208 -379.7935) (xy 434.479796 -379.784313) (xy 434.473283 -379.767129) (xy 434.467508 -379.759972)
			(xy 434.445769 -379.73428) (xy 434.407821 -379.678699) (xy 434.376787 -379.61898) (xy 434.353113 -379.555981)
			(xy 434.337137 -379.490604) (xy 434.32909 -379.423786) (xy 434.329086 -379.356486) (xy 434.337125 -379.289667)
			(xy 434.353091 -379.224288) (xy 434.376757 -379.161286) (xy 434.407783 -379.101563) (xy 434.445724 -379.045977)
			(xy 434.467508 -379.020324) (xy 434.47332 -379.01319) (xy 434.479825 -378.995991) (xy 434.480208 -378.986796)
			(xy 434.480208 -378.828554) (xy 434.480695 -378.818397) (xy 434.488479 -378.799633) (xy 434.502846 -378.78527)
			(xy 434.521613 -378.777492) (xy 434.53177 -378.776992) (xy 435.24805 -378.776992) (xy 435.258213 -378.777504)
			(xy 435.276998 -378.785264) (xy 435.291383 -378.799622) (xy 435.299177 -378.818392) (xy 435.299612 -378.828554)
			(xy 435.299612 -378.986796) (xy 435.300021 -378.995983) (xy 435.306535 -379.013168) (xy 435.312312 -379.020324)
			(xy 435.334148 -379.045937) (xy 435.372099 -379.101528) (xy 435.403133 -379.161256) (xy 435.426805 -379.224266)
			(xy 435.442776 -379.289654) (xy 435.450817 -379.356481) (xy 435.450813 -379.423791) (xy 435.442763 -379.490618)
			(xy 435.426784 -379.556003) (xy 435.403103 -379.61901) (xy 435.372062 -379.678734) (xy 435.334104 -379.73432)
			(xy 435.312312 -379.759972) (xy 435.306504 -379.767109) (xy 435.299996 -379.784306) (xy 435.299612 -379.7935)
			(xy 435.299612 -380.286768) (xy 435.300035 -380.295954) (xy 435.306539 -380.313139) (xy 435.312312 -380.320296)
			(xy 435.334121 -380.345931) (xy 435.372072 -380.401519) (xy 435.403107 -380.461244) (xy 435.426781 -380.524251)
			(xy 435.442754 -380.589636) (xy 435.450797 -380.656461) (xy 435.450796 -380.723769) (xy 435.442749 -380.790594)
			(xy 435.426772 -380.855977) (xy 435.403095 -380.918983) (xy 435.372057 -380.978707) (xy 435.334102 -381.034292)
			(xy 435.312312 -381.059944) (xy 435.306516 -381.067089) (xy 435.3 -381.08428) (xy 435.299612 -381.093472)
			(xy 435.299612 -381.251206) (xy 435.29924 -381.261384) (xy 435.291444 -381.280189) (xy 435.277041 -381.294575)
			(xy 435.258229 -381.302351) (xy 435.24805 -381.302768) (xy 434.53177 -381.302768) (xy 434.521611 -381.302291)
			(xy 434.502842 -381.294508) (xy 434.488478 -381.280138) (xy 434.480704 -381.261365) (xy 434.480208 -381.251206)
			(xy 434.480208 -381.093472) (xy 434.47981 -381.084284) (xy 434.473288 -381.067099) (xy 434.467508 -381.059944)
			(xy 434.445741 -381.034275) (xy 434.407793 -380.97869) (xy 434.376761 -380.918969) (xy 434.353088 -380.855967)
			(xy 434.337115 -380.790587) (xy 434.32907 -380.723766) (xy 434.329068 -380.656464) (xy 431.051005 -380.656464)
			(xy 431.051003 -380.723827) (xy 431.042926 -380.790767) (xy 431.026889 -380.856257) (xy 431.003123 -380.919354)
			(xy 430.971971 -380.979151) (xy 430.933881 -381.034786) (xy 430.912016 -381.060452) (xy 430.906217 -381.067595)
			(xy 430.899703 -381.084787) (xy 430.899316 -381.09398) (xy 430.899316 -381.251206) (xy 430.898877 -381.261338)
			(xy 430.891139 -381.280068) (xy 430.876838 -381.294426) (xy 430.858138 -381.302237) (xy 430.848008 -381.302768)
			(xy 430.131728 -381.302768) (xy 430.121572 -381.302355) (xy 430.102814 -381.294563) (xy 430.088488 -381.280163)
			(xy 430.080793 -381.261364) (xy 430.08042 -381.251206) (xy 430.08042 -381.09398) (xy 430.080015 -381.084792)
			(xy 430.073497 -381.067608) (xy 430.06772 -381.060452) (xy 430.045875 -381.034771) (xy 430.007784 -380.979139)
			(xy 429.976632 -380.919345) (xy 429.952865 -380.85625) (xy 429.936828 -380.790763) (xy 429.92875 -380.723826)
			(xy 429.928748 -380.656404) (xy 426.650703 -380.656404) (xy 426.65071 -380.656461) (xy 426.650708 -380.723769)
			(xy 426.642661 -380.790593) (xy 426.626685 -380.855977) (xy 426.603009 -380.918982) (xy 426.571971 -380.978706)
			(xy 426.534018 -381.034292) (xy 426.512228 -381.059944) (xy 426.506422 -381.067082) (xy 426.499915 -381.084278)
			(xy 426.499528 -381.093472) (xy 426.499528 -381.251206) (xy 426.49914 -381.261382) (xy 426.491347 -381.280184)
			(xy 426.47695 -381.294569) (xy 426.458143 -381.302348) (xy 426.447966 -381.302768) (xy 425.731686 -381.302768)
			(xy 425.721528 -381.302278) (xy 425.70276 -381.2945) (xy 425.688395 -381.280133) (xy 425.68062 -381.261364)
			(xy 425.680124 -381.251206) (xy 425.680124 -381.093472) (xy 425.679722 -381.084284) (xy 425.673202 -381.0671)
			(xy 425.667424 -381.059944) (xy 425.645656 -381.034276) (xy 425.607708 -380.978691) (xy 425.576675 -380.91897)
			(xy 425.553001 -380.855967) (xy 425.537027 -380.790587) (xy 425.528982 -380.723767) (xy 425.52898 -380.656463)
			(xy 422.250917 -380.656463) (xy 422.250915 -380.723827) (xy 422.242838 -380.790766) (xy 422.226801 -380.856256)
			(xy 422.203036 -380.919354) (xy 422.171885 -380.979151) (xy 422.133796 -381.034786) (xy 422.111932 -381.060452)
			(xy 422.106123 -381.067588) (xy 422.099618 -381.084786) (xy 422.099232 -381.09398) (xy 422.099232 -381.251206)
			(xy 422.098777 -381.261337) (xy 422.091042 -381.280063) (xy 422.076746 -381.29442) (xy 422.058052 -381.302234)
			(xy 422.047924 -381.302768) (xy 421.331644 -381.302768) (xy 421.32152 -381.302347) (xy 421.302812 -381.294608)
			(xy 421.288495 -381.280292) (xy 421.280754 -381.261584) (xy 421.280336 -381.25146) (xy 421.280336 -381.09398)
			(xy 421.279927 -381.084793) (xy 421.273412 -381.067609) (xy 421.267636 -381.060452) (xy 421.24579 -381.034771)
			(xy 421.207699 -380.97914) (xy 421.176545 -380.919346) (xy 421.152778 -380.856251) (xy 421.13674 -380.790764)
			(xy 421.128662 -380.723826) (xy 421.12866 -380.656404) (xy 391.450857 -380.656404) (xy 391.450864 -380.656462)
			(xy 391.450863 -380.723768) (xy 391.442817 -380.790591) (xy 391.426843 -380.855974) (xy 391.40317 -380.918979)
			(xy 391.372136 -380.978704) (xy 391.334188 -381.034291) (xy 391.3124 -381.059944) (xy 391.306602 -381.067088)
			(xy 391.300088 -381.08428) (xy 391.2997 -381.093472) (xy 391.2997 -381.251206) (xy 391.299172 -381.261359)
			(xy 391.291403 -381.280121) (xy 391.277048 -381.294485) (xy 391.258291 -381.302266) (xy 391.248138 -381.302768)
			(xy 390.531858 -381.302768) (xy 390.521698 -381.302301) (xy 390.502929 -381.294514) (xy 390.488566 -381.28014)
			(xy 390.480792 -381.261366) (xy 390.480296 -381.251206) (xy 390.480296 -381.093472) (xy 390.4799 -381.084283)
			(xy 390.473377 -381.067099) (xy 390.467596 -381.059944) (xy 390.445829 -381.034275) (xy 390.407883 -380.97869)
			(xy 390.376851 -380.918968) (xy 390.353179 -380.855966) (xy 390.337206 -380.790586) (xy 390.329161 -380.723766)
			(xy 390.329159 -380.656464) (xy 387.051096 -380.656464) (xy 387.051094 -380.723828) (xy 387.043016 -380.790767)
			(xy 387.026979 -380.856257) (xy 387.003213 -380.919355) (xy 386.97206 -380.979152) (xy 386.933969 -381.034787)
			(xy 386.912104 -381.060452) (xy 386.906303 -381.067594) (xy 386.899791 -381.084787) (xy 386.899404 -381.09398)
			(xy 386.899404 -381.251206) (xy 386.89888 -381.261328) (xy 386.891158 -381.280041) (xy 386.876884 -381.294395)
			(xy 386.858215 -381.302222) (xy 386.848096 -381.302768) (xy 386.131816 -381.302768) (xy 386.121659 -381.302365)
			(xy 386.102901 -381.294568) (xy 386.088576 -381.280166) (xy 386.080881 -381.261365) (xy 386.080508 -381.251206)
			(xy 386.080508 -381.09398) (xy 386.080106 -381.084792) (xy 386.073587 -381.067608) (xy 386.067808 -381.060452)
			(xy 386.045963 -381.034771) (xy 386.007874 -380.979139) (xy 385.976722 -380.919345) (xy 385.952956 -380.85625)
			(xy 385.936919 -380.790763) (xy 385.928841 -380.723826) (xy 385.928839 -380.656404) (xy 382.650793 -380.656404)
			(xy 382.6508 -380.656461) (xy 382.650799 -380.723769) (xy 382.642752 -380.790593) (xy 382.626775 -380.855977)
			(xy 382.603098 -380.918983) (xy 382.57206 -380.978707) (xy 382.534106 -381.034292) (xy 382.512316 -381.059944)
			(xy 382.50652 -381.06709) (xy 382.500005 -381.08428) (xy 382.499616 -381.093472) (xy 382.499616 -381.251206)
			(xy 382.49924 -381.261384) (xy 382.491444 -381.280187) (xy 382.477044 -381.294574) (xy 382.458232 -381.30235)
			(xy 382.448054 -381.302768) (xy 381.731774 -381.302768) (xy 381.721615 -381.302288) (xy 381.702847 -381.294506)
			(xy 381.688482 -381.280137) (xy 381.680708 -381.261365) (xy 381.680212 -381.251206) (xy 381.680212 -381.093472)
			(xy 381.679813 -381.084284) (xy 381.673291 -381.0671) (xy 381.667512 -381.059944) (xy 381.645745 -381.034275)
			(xy 381.607797 -380.978691) (xy 381.576764 -380.918969) (xy 381.553092 -380.855967) (xy 381.537118 -380.790587)
			(xy 381.529073 -380.723767) (xy 381.529071 -380.656464) (xy 378.251008 -380.656464) (xy 378.251006 -380.723827)
			(xy 378.242929 -380.790767) (xy 378.226892 -380.856257) (xy 378.203126 -380.919354) (xy 378.171974 -380.979151)
			(xy 378.133884 -381.034786) (xy 378.11202 -381.060452) (xy 378.106221 -381.067596) (xy 378.099707 -381.084787)
			(xy 378.09932 -381.09398) (xy 378.09932 -381.251206) (xy 378.098877 -381.261338) (xy 378.09114 -381.280067)
			(xy 378.07684 -381.294424) (xy 378.058142 -381.302236) (xy 378.048012 -381.302768) (xy 377.331732 -381.302768)
			(xy 377.321576 -381.302352) (xy 377.302818 -381.294561) (xy 377.288492 -381.280162) (xy 377.280797 -381.261364)
			(xy 377.280424 -381.251206) (xy 377.280424 -381.09398) (xy 377.280018 -381.084792) (xy 377.273501 -381.067608)
			(xy 377.267724 -381.060452) (xy 377.245879 -381.034771) (xy 377.207788 -380.979139) (xy 377.176635 -380.919345)
			(xy 377.152869 -380.856251) (xy 377.136831 -380.790763) (xy 377.128753 -380.723826) (xy 377.128751 -380.656404)
			(xy 347.450948 -380.656404) (xy 347.450955 -380.656462) (xy 347.450954 -380.723768) (xy 347.442908 -380.790592)
			(xy 347.426934 -380.855975) (xy 347.40326 -380.91898) (xy 347.372226 -380.978704) (xy 347.334276 -381.034291)
			(xy 347.312488 -381.059944) (xy 347.306689 -381.067087) (xy 347.300176 -381.084279) (xy 347.299788 -381.093472)
			(xy 347.299788 -381.251206) (xy 347.299272 -381.261361) (xy 347.2915 -381.280125) (xy 347.277142 -381.294489)
			(xy 347.258381 -381.302268) (xy 347.248226 -381.302768) (xy 346.531946 -381.302768) (xy 346.521778 -381.302299)
			(xy 346.502986 -381.29453) (xy 346.488599 -381.280158) (xy 346.480812 -381.261373) (xy 346.480384 -381.251206)
			(xy 346.480384 -381.093472) (xy 346.479991 -381.084283) (xy 346.473466 -381.067099) (xy 346.467684 -381.059944)
			(xy 346.445915 -381.034276) (xy 346.407962 -380.978693) (xy 346.376926 -380.918972) (xy 346.35325 -380.85597)
			(xy 346.337274 -380.790589) (xy 346.329228 -380.723767) (xy 346.329226 -380.656463) (xy 343.051187 -380.656463)
			(xy 343.051185 -380.723828) (xy 343.043107 -380.790767) (xy 343.027069 -380.856258) (xy 343.003303 -380.919356)
			(xy 342.972149 -380.979152) (xy 342.934057 -381.034787) (xy 342.912192 -381.060452) (xy 342.90639 -381.067593)
			(xy 342.899879 -381.084787) (xy 342.899492 -381.09398) (xy 342.899492 -381.251206) (xy 342.898979 -381.261329)
			(xy 342.891255 -381.280044) (xy 342.876978 -381.294399) (xy 342.858304 -381.302224) (xy 342.848184 -381.302768)
			(xy 342.131904 -381.302768) (xy 342.121746 -381.302374) (xy 342.102988 -381.294574) (xy 342.088663 -381.280168)
			(xy 342.080969 -381.261366) (xy 342.080596 -381.251206) (xy 342.080596 -381.09398) (xy 342.080196 -381.084792)
			(xy 342.073675 -381.067608) (xy 342.067896 -381.060452) (xy 342.046052 -381.03477) (xy 342.007963 -380.979138)
			(xy 341.976811 -380.919344) (xy 341.953046 -380.856249) (xy 341.93701 -380.790762) (xy 341.928932 -380.723826)
			(xy 341.92893 -380.656404) (xy 338.65086 -380.656404) (xy 338.650867 -380.656462) (xy 338.650866 -380.723768)
			(xy 338.64282 -380.790591) (xy 338.626846 -380.855974) (xy 338.603173 -380.918979) (xy 338.57214 -380.978704)
			(xy 338.534192 -381.034291) (xy 338.512404 -381.059944) (xy 338.506607 -381.067089) (xy 338.500092 -381.08428)
			(xy 338.499704 -381.093472) (xy 338.499704 -381.251206) (xy 338.499172 -381.261359) (xy 338.491404 -381.28012)
			(xy 338.47705 -381.294484) (xy 338.458295 -381.302265) (xy 338.448142 -381.302768) (xy 337.731862 -381.302768)
			(xy 337.721703 -381.302298) (xy 337.702934 -381.294512) (xy 337.68857 -381.280139) (xy 337.680796 -381.261366)
			(xy 337.6803 -381.251206) (xy 337.6803 -381.093472) (xy 337.679904 -381.084283) (xy 337.67338 -381.067099)
			(xy 337.6676 -381.059944) (xy 337.645833 -381.034275) (xy 337.607886 -380.97869) (xy 337.576854 -380.918969)
			(xy 337.553182 -380.855966) (xy 337.537209 -380.790587) (xy 337.529164 -380.723766) (xy 337.529162 -380.656464)
			(xy 334.251099 -380.656464) (xy 334.251097 -380.723828) (xy 334.243019 -380.790767) (xy 334.226982 -380.856257)
			(xy 334.203216 -380.919355) (xy 334.172063 -380.979152) (xy 334.133973 -381.034787) (xy 334.112108 -381.060452)
			(xy 334.106308 -381.067595) (xy 334.099795 -381.084787) (xy 334.099408 -381.09398) (xy 334.099408 -381.251206)
			(xy 334.09888 -381.261327) (xy 334.091159 -381.280039) (xy 334.076886 -381.294394) (xy 334.058218 -381.302221)
			(xy 334.0481 -381.302768) (xy 333.33182 -381.302768) (xy 333.321663 -381.302362) (xy 333.302905 -381.294567)
			(xy 333.28858 -381.280165) (xy 333.280885 -381.261365) (xy 333.280512 -381.251206) (xy 333.280512 -381.09398)
			(xy 333.280109 -381.084792) (xy 333.27359 -381.067608) (xy 333.267812 -381.060452) (xy 333.245967 -381.034771)
			(xy 333.207877 -380.979139) (xy 333.176725 -380.919345) (xy 333.152959 -380.85625) (xy 333.136922 -380.790763)
			(xy 333.128844 -380.723826) (xy 333.128842 -380.656404) (xy 303.451069 -380.656404) (xy 303.451067 -380.723828)
			(xy 303.442989 -380.790768) (xy 303.42695 -380.856259) (xy 303.403182 -380.919357) (xy 303.372027 -380.979153)
			(xy 303.333934 -381.034787) (xy 303.312068 -381.060452) (xy 303.306263 -381.067591) (xy 303.299754 -381.084786)
			(xy 303.299368 -381.09398) (xy 303.299368 -381.251206) (xy 303.298878 -381.261332) (xy 303.29115 -381.280052)
			(xy 303.276865 -381.294408) (xy 303.258184 -381.302228) (xy 303.24806 -381.302768) (xy 302.53178 -381.302768)
			(xy 302.521621 -381.302394) (xy 302.502861 -381.294586) (xy 302.488538 -381.280174) (xy 302.480844 -381.261368)
			(xy 302.480472 -381.251206) (xy 302.480472 -381.09398) (xy 302.480078 -381.084791) (xy 302.473554 -381.067607)
			(xy 302.467772 -381.060452) (xy 302.445929 -381.03477) (xy 302.407841 -380.979137) (xy 302.376691 -380.919343)
			(xy 302.352927 -380.856248) (xy 302.336891 -380.790762) (xy 302.328814 -380.723826) (xy 302.328812 -380.656404)
			(xy 299.050742 -380.656404) (xy 299.050749 -380.656462) (xy 299.050747 -380.723768) (xy 299.042702 -380.790592)
			(xy 299.026727 -380.855975) (xy 299.003053 -380.91898) (xy 298.972018 -380.978704) (xy 298.934068 -381.034292)
			(xy 298.91228 -381.059944) (xy 298.90648 -381.067087) (xy 298.899968 -381.084279) (xy 298.89958 -381.093472)
			(xy 298.89958 -381.251206) (xy 298.899072 -381.261362) (xy 298.891299 -381.280128) (xy 298.876938 -381.294492)
			(xy 298.858174 -381.302269) (xy 298.848018 -381.302768) (xy 298.131738 -381.302768) (xy 298.12157 -381.302305)
			(xy 298.102777 -381.294534) (xy 298.088391 -381.28016) (xy 298.080604 -381.261374) (xy 298.080176 -381.251206)
			(xy 298.080176 -381.093472) (xy 298.079785 -381.084283) (xy 298.073258 -381.067098) (xy 298.067476 -381.059944)
			(xy 298.045707 -381.034276) (xy 298.007755 -380.978693) (xy 297.976719 -380.918972) (xy 297.953043 -380.855969)
			(xy 297.937068 -380.790589) (xy 297.929022 -380.723767) (xy 297.92902 -380.656463) (xy 294.650981 -380.656463)
			(xy 294.650979 -380.723828) (xy 294.642901 -380.790768) (xy 294.626863 -380.856258) (xy 294.603096 -380.919356)
			(xy 294.571942 -380.979153) (xy 294.53385 -381.034787) (xy 294.511984 -381.060452) (xy 294.506181 -381.067593)
			(xy 294.499671 -381.084787) (xy 294.499284 -381.09398) (xy 294.499284 -381.251206) (xy 294.498779 -381.26133)
			(xy 294.491054 -381.280047) (xy 294.476773 -381.294402) (xy 294.458097 -381.302225) (xy 294.447976 -381.302768)
			(xy 293.731696 -381.302768) (xy 293.721569 -381.302386) (xy 293.70286 -381.294631) (xy 293.688544 -381.280303)
			(xy 293.680805 -381.261587) (xy 293.680388 -381.25146) (xy 293.680388 -381.09398) (xy 293.67999 -381.084791)
			(xy 293.673468 -381.067607) (xy 293.667688 -381.060452) (xy 293.645844 -381.03477) (xy 293.607756 -380.979138)
			(xy 293.576605 -380.919344) (xy 293.55284 -380.856249) (xy 293.536803 -380.790762) (xy 293.528726 -380.723826)
			(xy 293.528724 -380.656404) (xy 290.250654 -380.656404) (xy 290.250661 -380.656462) (xy 290.25066 -380.723768)
			(xy 290.242614 -380.790591) (xy 290.22664 -380.855974) (xy 290.202966 -380.918979) (xy 290.171933 -380.978704)
			(xy 290.133984 -381.034291) (xy 290.112196 -381.059944) (xy 290.106398 -381.067088) (xy 290.099884 -381.084279)
			(xy 290.099496 -381.093472) (xy 290.099496 -381.251206) (xy 290.098972 -381.26136) (xy 290.091202 -381.280123)
			(xy 290.076846 -381.294486) (xy 290.058088 -381.302267) (xy 290.047934 -381.302768) (xy 289.331654 -381.302768)
			(xy 289.321494 -381.302304) (xy 289.302725 -381.294516) (xy 289.288362 -381.280141) (xy 289.280588 -381.261366)
			(xy 289.280092 -381.251206) (xy 289.280092 -381.093472) (xy 289.279697 -381.084283) (xy 289.273173 -381.067099)
			(xy 289.267392 -381.059944) (xy 289.245622 -381.034276) (xy 289.207669 -380.978693) (xy 289.176632 -380.918972)
			(xy 289.152956 -380.85597) (xy 289.13698 -380.790589) (xy 289.128934 -380.723767) (xy 289.128932 -380.656463)
			(xy 272.92786 -380.656463) (xy 272.867822 -380.687974) (xy 272.746027 -380.742789) (xy 272.621144 -380.790151)
			(xy 272.49363 -380.829886) (xy 272.363949 -380.861849) (xy 272.232575 -380.885924) (xy 272.099987 -380.902024)
			(xy 271.966669 -380.910088) (xy 271.833107 -380.910088) (xy 271.699789 -380.902024) (xy 271.567201 -380.885924)
			(xy 271.435827 -380.861849) (xy 271.306146 -380.829886) (xy 271.178632 -380.790151) (xy 271.053749 -380.742789)
			(xy 270.931954 -380.687974) (xy 270.813691 -380.625904) (xy 270.699392 -380.556808) (xy 270.589472 -380.480936)
			(xy 270.484335 -380.398566) (xy 270.384362 -380.309998) (xy 270.28992 -380.215556) (xy 270.201352 -380.115583)
			(xy 270.118982 -380.010446) (xy 270.04311 -379.900526) (xy 269.974014 -379.786227) (xy 269.911944 -379.667964)
			(xy 269.857129 -379.546169) (xy 269.809767 -379.421286) (xy 269.770032 -379.293772) (xy 269.738069 -379.164091)
			(xy 269.713994 -379.032717) (xy 269.697894 -378.900129) (xy 269.68983 -378.766811) (xy 236.356885 -378.766811)
			(xy 237.084108 -379.494034) (xy 237.084616 -379.494542) (xy 237.093852 -379.502751) (xy 237.116722 -379.512039)
			(xy 237.129066 -379.512576) (xy 239.773968 -379.512576) (xy 239.786313 -379.512049) (xy 239.809185 -379.502755)
			(xy 239.818418 -379.494542) (xy 239.818926 -379.494034) (xy 240.443004 -378.869702) (xy 240.450409 -378.862868)
			(xy 240.469004 -378.855145) (xy 240.479072 -378.854716) (xy 262.036814 -378.854716) (xy 262.046885 -378.85513)
			(xy 262.065482 -378.862858) (xy 262.072882 -378.869702) (xy 262.259318 -379.056138) (xy 262.26617 -379.063529)
			(xy 262.273882 -379.082135) (xy 262.274304 -379.092206) (xy 262.274304 -382.223705) (xy 286.928753 -382.223705)
			(xy 286.928754 -382.15628) (xy 286.936832 -382.08934) (xy 286.95287 -382.02385) (xy 286.976638 -381.960752)
			(xy 287.007792 -381.900956) (xy 287.045886 -381.845322) (xy 287.067752 -381.819658) (xy 287.073555 -381.812518)
			(xy 287.080065 -381.795323) (xy 287.080452 -381.78613) (xy 287.080452 -381.628904) (xy 287.080987 -381.618801)
			(xy 287.088715 -381.600133) (xy 287.102996 -381.585839) (xy 287.121658 -381.578096) (xy 287.13176 -381.577596)
			(xy 287.84804 -381.577596) (xy 287.858151 -381.578052) (xy 287.876829 -381.585802) (xy 287.891122 -381.600108)
			(xy 287.898856 -381.618793) (xy 287.899348 -381.628904) (xy 287.899348 -381.78613) (xy 287.899755 -381.795317)
			(xy 287.906272 -381.812501) (xy 287.912048 -381.819658) (xy 287.933904 -381.84533) (xy 287.971996 -381.900963)
			(xy 288.00315 -381.960757) (xy 288.026917 -382.023853) (xy 288.042955 -382.089342) (xy 288.051033 -382.156281)
			(xy 288.051034 -382.223645) (xy 291.329073 -382.223645) (xy 291.329074 -382.15634) (xy 291.337119 -382.089516)
			(xy 291.353093 -382.024133) (xy 291.376767 -381.961128) (xy 291.407801 -381.901405) (xy 291.445751 -381.845818)
			(xy 291.46754 -381.820166) (xy 291.473339 -381.813022) (xy 291.479851 -381.795831) (xy 291.48024 -381.786638)
			(xy 291.48024 -381.628904) (xy 291.48062 -381.618777) (xy 291.488375 -381.600066) (xy 291.502703 -381.58575)
			(xy 291.52142 -381.578012) (xy 291.531548 -381.577596) (xy 292.248082 -381.577596) (xy 292.258202 -381.57814)
			(xy 292.276915 -381.585854) (xy 292.29127 -381.600122) (xy 292.299098 -381.618787) (xy 292.299644 -381.628904)
			(xy 292.299644 -381.786638) (xy 292.300049 -381.795826) (xy 292.306568 -381.813009) (xy 292.312344 -381.820166)
			(xy 292.334122 -381.845826) (xy 292.372072 -381.901411) (xy 292.403107 -381.961133) (xy 292.426781 -382.024137)
			(xy 292.442755 -382.089518) (xy 292.450801 -382.15634) (xy 292.450801 -382.223645) (xy 292.450794 -382.223705)
			(xy 295.728841 -382.223705) (xy 295.728842 -382.15628) (xy 295.73692 -382.08934) (xy 295.752957 -382.02385)
			(xy 295.776724 -381.960753) (xy 295.807878 -381.900957) (xy 295.84597 -381.845323) (xy 295.867836 -381.819658)
			(xy 295.873637 -381.812516) (xy 295.880148 -381.795323) (xy 295.880536 -381.78613) (xy 295.880536 -381.628904)
			(xy 295.88092 -381.618777) (xy 295.888674 -381.600067) (xy 295.903001 -381.585751) (xy 295.921717 -381.578012)
			(xy 295.931844 -381.577596) (xy 296.648124 -381.577596) (xy 296.658234 -381.578065) (xy 296.676912 -381.58581)
			(xy 296.691206 -381.600112) (xy 296.69894 -381.618794) (xy 296.699432 -381.628904) (xy 296.699432 -381.78613)
			(xy 296.699843 -381.795317) (xy 296.706358 -381.8125) (xy 296.712132 -381.819658) (xy 296.733985 -381.845332)
			(xy 296.772072 -381.900966) (xy 296.803221 -381.960761) (xy 296.826985 -382.023857) (xy 296.84302 -382.089345)
			(xy 296.851096 -382.156281) (xy 296.851097 -382.223704) (xy 296.851097 -382.223705) (xy 300.128632 -382.223705)
			(xy 300.128633 -382.15628) (xy 300.13671 -382.089341) (xy 300.152748 -382.023851) (xy 300.176514 -381.960753)
			(xy 300.207667 -381.900957) (xy 300.245759 -381.845323) (xy 300.267624 -381.819658) (xy 300.273424 -381.812515)
			(xy 300.279936 -381.795323) (xy 300.280324 -381.78613) (xy 300.280324 -381.628904) (xy 300.28072 -381.618779)
			(xy 300.288471 -381.600071) (xy 300.302794 -381.585755) (xy 300.321507 -381.578014) (xy 300.331632 -381.577596)
			(xy 301.047912 -381.577596) (xy 301.058021 -381.578075) (xy 301.076699 -381.585816) (xy 301.090993 -381.600115)
			(xy 301.098728 -381.618795) (xy 301.09922 -381.628904) (xy 301.09922 -381.78613) (xy 301.099611 -381.795319)
			(xy 301.106138 -381.812504) (xy 301.11192 -381.819658) (xy 301.133773 -381.845332) (xy 301.171861 -381.900965)
			(xy 301.203011 -381.960761) (xy 301.226775 -382.023856) (xy 301.242811 -382.089344) (xy 301.250887 -382.156281)
			(xy 301.250888 -382.223646) (xy 330.929191 -382.223646) (xy 330.929192 -382.156339) (xy 330.937238 -382.089516)
			(xy 330.953213 -382.024133) (xy 330.976888 -381.961128) (xy 331.007923 -381.901404) (xy 331.045875 -381.845818)
			(xy 331.067664 -381.820166) (xy 331.073465 -381.813025) (xy 331.079975 -381.795831) (xy 331.080364 -381.786638)
			(xy 331.080364 -381.628904) (xy 331.080824 -381.618755) (xy 331.088612 -381.600009) (xy 331.102996 -381.585687)
			(xy 331.121775 -381.577981) (xy 331.131926 -381.577596) (xy 331.848206 -381.577596) (xy 331.858328 -381.57812)
			(xy 331.877041 -381.585842) (xy 331.891395 -381.600116) (xy 331.899222 -381.618785) (xy 331.899768 -381.628904)
			(xy 331.899768 -381.786638) (xy 331.900167 -381.795826) (xy 331.906689 -381.81301) (xy 331.912468 -381.820166)
			(xy 331.934246 -381.845826) (xy 331.972195 -381.901412) (xy 332.003228 -381.961134) (xy 332.026901 -382.024138)
			(xy 332.042874 -382.089519) (xy 332.050919 -382.15634) (xy 332.05092 -382.223645) (xy 332.050913 -382.223704)
			(xy 335.328984 -382.223704) (xy 335.328985 -382.156281) (xy 335.337061 -382.089342) (xy 335.353096 -382.023853)
			(xy 335.37686 -381.960756) (xy 335.40801 -381.900959) (xy 335.446097 -381.845324) (xy 335.46796 -381.819658)
			(xy 335.473764 -381.812519) (xy 335.480273 -381.795323) (xy 335.48066 -381.78613) (xy 335.48066 -381.628904)
			(xy 335.481187 -381.6188) (xy 335.488916 -381.60013) (xy 335.5032 -381.585837) (xy 335.521865 -381.578095)
			(xy 335.531968 -381.577596) (xy 336.248248 -381.577596) (xy 336.258359 -381.578046) (xy 336.277038 -381.585799)
			(xy 336.291331 -381.600106) (xy 336.299064 -381.618792) (xy 336.299556 -381.628904) (xy 336.299556 -381.78613)
			(xy 336.299962 -381.795317) (xy 336.30648 -381.812501) (xy 336.312256 -381.819658) (xy 336.334112 -381.845331)
			(xy 336.372204 -381.900963) (xy 336.403357 -381.960758) (xy 336.427124 -382.023854) (xy 336.443161 -382.089342)
			(xy 336.451239 -382.156281) (xy 336.45124 -382.223645) (xy 339.729279 -382.223645) (xy 339.72928 -382.156339)
			(xy 339.737325 -382.089516) (xy 339.753299 -382.024133) (xy 339.776974 -381.961128) (xy 339.808009 -381.901404)
			(xy 339.845959 -381.845818) (xy 339.867748 -381.820166) (xy 339.873547 -381.813023) (xy 339.880059 -381.795831)
			(xy 339.880448 -381.786638) (xy 339.880448 -381.628904) (xy 339.880924 -381.618757) (xy 339.888708 -381.600014)
			(xy 339.903088 -381.585693) (xy 339.921861 -381.577984) (xy 339.93201 -381.577596) (xy 340.64829 -381.577596)
			(xy 340.658411 -381.578133) (xy 340.677123 -381.58585) (xy 340.691478 -381.60012) (xy 340.699306 -381.618786)
			(xy 340.699852 -381.628904) (xy 340.699852 -381.786638) (xy 340.700255 -381.795826) (xy 340.706775 -381.813009)
			(xy 340.712552 -381.820166) (xy 340.73433 -381.845826) (xy 340.77228 -381.901411) (xy 340.803314 -381.961134)
			(xy 340.826988 -382.024137) (xy 340.842962 -382.089518) (xy 340.851007 -382.15634) (xy 340.851007 -382.223645)
			(xy 344.12907 -382.223645) (xy 344.129071 -382.15634) (xy 344.137116 -382.089516) (xy 344.15309 -382.024134)
			(xy 344.176764 -381.961129) (xy 344.207798 -381.901405) (xy 344.245748 -381.845818) (xy 344.267536 -381.820166)
			(xy 344.273334 -381.813022) (xy 344.279847 -381.79583) (xy 344.280236 -381.786638) (xy 344.280236 -381.628904)
			(xy 344.280626 -381.618746) (xy 344.288427 -381.599986) (xy 344.302834 -381.585662) (xy 344.321637 -381.577968)
			(xy 344.331798 -381.577596) (xy 345.048078 -381.577596) (xy 345.058198 -381.578143) (xy 345.07691 -381.585856)
			(xy 345.091266 -381.600123) (xy 345.099094 -381.618787) (xy 345.09964 -381.628904) (xy 345.09964 -381.786638)
			(xy 345.100045 -381.795825) (xy 345.106564 -381.813009) (xy 345.11234 -381.820166) (xy 345.134118 -381.845826)
			(xy 345.172069 -381.901411) (xy 345.203104 -381.961133) (xy 345.226778 -382.024137) (xy 345.242752 -382.089518)
			(xy 345.250798 -382.15634) (xy 345.250798 -382.223645) (xy 345.250798 -382.223646) (xy 374.9291 -382.223646)
			(xy 374.929101 -382.156339) (xy 374.937147 -382.089515) (xy 374.953122 -382.024132) (xy 374.976798 -381.961127)
			(xy 375.007834 -381.901404) (xy 375.045787 -381.845818) (xy 375.067576 -381.820166) (xy 375.073367 -381.813016)
			(xy 375.079886 -381.795829) (xy 375.080276 -381.786638) (xy 375.080276 -381.628904) (xy 375.080724 -381.618753)
			(xy 375.088514 -381.600005) (xy 375.102902 -381.585683) (xy 375.121685 -381.577979) (xy 375.131838 -381.577596)
			(xy 375.848118 -381.577596) (xy 375.85824 -381.57811) (xy 375.876954 -381.585836) (xy 375.891308 -381.600113)
			(xy 375.899134 -381.618784) (xy 375.89968 -381.628904) (xy 375.89968 -381.786638) (xy 375.900076 -381.795827)
			(xy 375.9066 -381.813011) (xy 375.91238 -381.820166) (xy 375.934157 -381.845826) (xy 375.972105 -381.901412)
			(xy 376.003138 -381.961135) (xy 376.02681 -382.024138) (xy 376.042784 -382.089519) (xy 376.050828 -382.156341)
			(xy 376.050829 -382.223644) (xy 376.050822 -382.223704) (xy 379.328893 -382.223704) (xy 379.328894 -382.156281)
			(xy 379.33697 -382.089342) (xy 379.353006 -382.023853) (xy 379.37677 -381.960756) (xy 379.40792 -381.900959)
			(xy 379.446008 -381.845324) (xy 379.467872 -381.819658) (xy 379.473678 -381.81252) (xy 379.480185 -381.795324)
			(xy 379.480572 -381.78613) (xy 379.480572 -381.628904) (xy 379.481088 -381.618799) (xy 379.488819 -381.600126)
			(xy 379.503106 -381.585832) (xy 379.521775 -381.578092) (xy 379.53188 -381.577596) (xy 380.24816 -381.577596)
			(xy 380.258279 -381.578049) (xy 380.276981 -381.585783) (xy 380.291297 -381.600088) (xy 380.299044 -381.618785)
			(xy 380.299468 -381.628904) (xy 380.299468 -381.78613) (xy 380.299871 -381.795318) (xy 380.30639 -381.812502)
			(xy 380.312168 -381.819658) (xy 380.334023 -381.845331) (xy 380.372114 -381.900963) (xy 380.403267 -381.960758)
			(xy 380.427033 -382.023854) (xy 380.443071 -382.089343) (xy 380.451148 -382.156281) (xy 380.451149 -382.223646)
			(xy 383.729188 -382.223646) (xy 383.729189 -382.156339) (xy 383.737235 -382.089516) (xy 383.753209 -382.024133)
			(xy 383.776884 -381.961128) (xy 383.80792 -381.901404) (xy 383.845871 -381.845818) (xy 383.86766 -381.820166)
			(xy 383.873461 -381.813024) (xy 383.879971 -381.795831) (xy 383.88036 -381.786638) (xy 383.88036 -381.628904)
			(xy 383.880824 -381.618755) (xy 383.888611 -381.600011) (xy 383.902994 -381.585689) (xy 383.921771 -381.577981)
			(xy 383.931922 -381.577596) (xy 384.648202 -381.577596) (xy 384.658323 -381.578124) (xy 384.677036 -381.585844)
			(xy 384.691391 -381.600117) (xy 384.699218 -381.618786) (xy 384.699764 -381.628904) (xy 384.699764 -381.786638)
			(xy 384.700164 -381.795826) (xy 384.706686 -381.81301) (xy 384.712464 -381.820166) (xy 384.734242 -381.845826)
			(xy 384.772191 -381.901412) (xy 384.803224 -381.961134) (xy 384.826898 -382.024137) (xy 384.842871 -382.089519)
			(xy 384.850916 -382.15634) (xy 384.850917 -382.223645) (xy 388.128979 -382.223645) (xy 388.12898 -382.156339)
			(xy 388.137025 -382.089516) (xy 388.152999 -382.024133) (xy 388.176674 -381.961128) (xy 388.207709 -381.901404)
			(xy 388.245659 -381.845818) (xy 388.267448 -381.820166) (xy 388.273247 -381.813023) (xy 388.279759 -381.795831)
			(xy 388.280148 -381.786638) (xy 388.280148 -381.628904) (xy 388.280624 -381.618757) (xy 388.288408 -381.600014)
			(xy 388.302788 -381.585693) (xy 388.321561 -381.577984) (xy 388.33171 -381.577596) (xy 389.04799 -381.577596)
			(xy 389.058111 -381.578133) (xy 389.076823 -381.58585) (xy 389.091178 -381.60012) (xy 389.099006 -381.618786)
			(xy 389.099552 -381.628904) (xy 389.099552 -381.786638) (xy 389.099955 -381.795826) (xy 389.106475 -381.813009)
			(xy 389.112252 -381.820166) (xy 389.13403 -381.845826) (xy 389.17198 -381.901411) (xy 389.203014 -381.961134)
			(xy 389.226688 -382.024137) (xy 389.242662 -382.089518) (xy 389.250707 -382.15634) (xy 389.250707 -382.223645)
			(xy 389.250707 -382.223646) (xy 418.92901 -382.223646) (xy 418.92901 -382.156339) (xy 418.937056 -382.089515)
			(xy 418.953032 -382.024132) (xy 418.976708 -381.961127) (xy 419.007745 -381.901403) (xy 419.045698 -381.845818)
			(xy 419.067488 -381.820166) (xy 419.07328 -381.813018) (xy 419.079798 -381.79583) (xy 419.080188 -381.786638)
			(xy 419.080188 -381.628904) (xy 419.080688 -381.618797) (xy 419.088422 -381.600121) (xy 419.102714 -381.585827)
			(xy 419.121389 -381.57809) (xy 419.131496 -381.577596) (xy 419.84803 -381.577596) (xy 419.858153 -381.578101)
			(xy 419.876867 -381.58583) (xy 419.89122 -381.60011) (xy 419.899046 -381.618783) (xy 419.899592 -381.628904)
			(xy 419.899592 -381.786638) (xy 419.899986 -381.795827) (xy 419.906511 -381.813011) (xy 419.912292 -381.820166)
			(xy 419.934069 -381.845827) (xy 419.972016 -381.901413) (xy 420.003048 -381.961135) (xy 420.02672 -382.024139)
			(xy 420.042693 -382.089519) (xy 420.050737 -382.156341) (xy 420.050738 -382.223644) (xy 420.050731 -382.223705)
			(xy 423.328802 -382.223705) (xy 423.328803 -382.15628) (xy 423.33688 -382.089342) (xy 423.352916 -382.023852)
			(xy 423.37668 -381.960755) (xy 423.407831 -381.900959) (xy 423.44592 -381.845324) (xy 423.467784 -381.819658)
			(xy 423.473579 -381.812512) (xy 423.480095 -381.795322) (xy 423.480484 -381.78613) (xy 423.480484 -381.628904)
			(xy 423.480988 -381.618798) (xy 423.488721 -381.600122) (xy 423.503012 -381.585828) (xy 423.521686 -381.57809)
			(xy 423.531792 -381.577596) (xy 424.248072 -381.577596) (xy 424.258192 -381.578039) (xy 424.276895 -381.585777)
			(xy 424.29121 -381.600085) (xy 424.298957 -381.618784) (xy 424.29938 -381.628904) (xy 424.29938 -381.78613)
			(xy 424.29978 -381.795318) (xy 424.306301 -381.812502) (xy 424.31208 -381.819658) (xy 424.333935 -381.845331)
			(xy 424.372025 -381.900964) (xy 424.403177 -381.960759) (xy 424.426943 -382.023855) (xy 424.44298 -382.089343)
			(xy 424.451057 -382.156281) (xy 424.451058 -382.223646) (xy 427.729097 -382.223646) (xy 427.729098 -382.156339)
			(xy 427.737144 -382.089515) (xy 427.753119 -382.024132) (xy 427.776794 -381.961127) (xy 427.807831 -381.901404)
			(xy 427.845783 -381.845818) (xy 427.867572 -381.820166) (xy 427.873374 -381.813025) (xy 427.879883 -381.795831)
			(xy 427.880272 -381.786638) (xy 427.880272 -381.628904) (xy 427.880724 -381.618754) (xy 427.888513 -381.600007)
			(xy 427.9029 -381.585684) (xy 427.921682 -381.577979) (xy 427.931834 -381.577596) (xy 428.648114 -381.577596)
			(xy 428.658236 -381.578114) (xy 428.676949 -381.585838) (xy 428.691303 -381.600114) (xy 428.69913 -381.618785)
			(xy 428.699676 -381.628904) (xy 428.699676 -381.786638) (xy 428.700073 -381.795826) (xy 428.706596 -381.81301)
			(xy 428.712376 -381.820166) (xy 428.734154 -381.845826) (xy 428.772102 -381.901412) (xy 428.803135 -381.961135)
			(xy 428.826807 -382.024138) (xy 428.84278 -382.089519) (xy 428.850825 -382.15634) (xy 428.850826 -382.223644)
			(xy 428.850826 -382.223646) (xy 432.128888 -382.223646) (xy 432.128889 -382.156339) (xy 432.136935 -382.089516)
			(xy 432.152909 -382.024133) (xy 432.176584 -381.961128) (xy 432.20762 -381.901404) (xy 432.245571 -381.845818)
			(xy 432.26736 -381.820166) (xy 432.273161 -381.813024) (xy 432.279671 -381.795831) (xy 432.28006 -381.786638)
			(xy 432.28006 -381.628904) (xy 432.280524 -381.618755) (xy 432.288311 -381.600011) (xy 432.302694 -381.585689)
			(xy 432.321471 -381.577981) (xy 432.331622 -381.577596) (xy 433.047902 -381.577596) (xy 433.058023 -381.578124)
			(xy 433.076736 -381.585844) (xy 433.091091 -381.600117) (xy 433.098918 -381.618786) (xy 433.099464 -381.628904)
			(xy 433.099464 -381.786638) (xy 433.099864 -381.795826) (xy 433.106386 -381.81301) (xy 433.112164 -381.820166)
			(xy 433.133942 -381.845826) (xy 433.171891 -381.901412) (xy 433.202924 -381.961134) (xy 433.226598 -382.024137)
			(xy 433.242571 -382.089519) (xy 433.250616 -382.15634) (xy 433.250617 -382.223645) (xy 433.242574 -382.290466)
			(xy 433.226602 -382.355848) (xy 433.202931 -382.418852) (xy 433.171899 -382.478576) (xy 433.133951 -382.534162)
			(xy 433.112164 -382.559814) (xy 433.106374 -382.566964) (xy 433.099856 -382.584151) (xy 433.099464 -382.593342)
			(xy 433.099464 -383.086864) (xy 433.0999 -383.096048) (xy 433.106397 -383.113232) (xy 433.112164 -383.120392)
			(xy 433.133967 -383.146031) (xy 433.171916 -383.20162) (xy 433.202948 -383.261345) (xy 433.226386 -383.323727)
			(xy 434.32903 -383.323727) (xy 434.329034 -383.256419) (xy 434.337081 -383.189595) (xy 434.353057 -383.124211)
			(xy 434.376732 -383.061205) (xy 434.407768 -383.00148) (xy 434.445719 -382.945893) (xy 434.467508 -382.92024)
			(xy 434.473313 -382.913101) (xy 434.479823 -382.895906) (xy 434.480208 -382.886712) (xy 434.480208 -382.728724)
			(xy 434.480641 -382.71857) (xy 434.48843 -382.699817) (xy 434.502824 -382.685492) (xy 434.521614 -382.677793)
			(xy 434.53177 -382.677416) (xy 435.24805 -382.677416) (xy 435.258171 -382.677967) (xy 435.276886 -382.685674)
			(xy 435.291243 -382.69994) (xy 435.299068 -382.718607) (xy 435.299612 -382.728724) (xy 435.299612 -382.886712)
			(xy 435.300014 -382.8959) (xy 435.306533 -382.913084) (xy 435.312312 -382.92024) (xy 435.334066 -382.945921)
			(xy 435.372019 -383.001502) (xy 435.403056 -383.061221) (xy 435.426733 -383.124222) (xy 435.44271 -383.189601)
			(xy 435.450758 -383.256421) (xy 435.450761 -383.323724) (xy 435.44272 -383.390546) (xy 435.426749 -383.455926)
			(xy 435.403079 -383.518929) (xy 435.372047 -383.578652) (xy 435.334099 -383.634237) (xy 435.312312 -383.659888)
			(xy 435.306497 -383.66702) (xy 435.299993 -383.684221) (xy 435.299612 -383.693416) (xy 435.299612 -384.186684)
			(xy 435.300027 -384.195871) (xy 435.306537 -384.213055) (xy 435.312312 -384.220212) (xy 435.334137 -384.245834)
			(xy 435.372087 -384.301424) (xy 435.403122 -384.361151) (xy 435.426795 -384.42416) (xy 435.442767 -384.489546)
			(xy 435.450809 -384.556373) (xy 435.450805 -384.623681) (xy 435.442757 -384.690507) (xy 435.426779 -384.755892)
			(xy 435.4031 -384.818898) (xy 435.37206 -384.878623) (xy 435.334103 -384.934208) (xy 435.312312 -384.95986)
			(xy 435.306509 -384.967001) (xy 435.299998 -384.984195) (xy 435.299612 -384.993388) (xy 435.299612 -385.151376)
			(xy 435.299159 -385.161527) (xy 435.291374 -385.180277) (xy 435.276987 -385.194601) (xy 435.258203 -385.202303)
			(xy 435.24805 -385.202684) (xy 434.53177 -385.202684) (xy 434.521644 -385.202199) (xy 434.502927 -385.194466)
			(xy 434.488573 -385.180179) (xy 434.48075 -385.161499) (xy 434.480208 -385.151376) (xy 434.480208 -384.993388)
			(xy 434.479802 -384.9842) (xy 434.473285 -384.967016) (xy 434.467508 -384.95986) (xy 434.445757 -384.934178)
			(xy 434.407809 -384.878595) (xy 434.376776 -384.818876) (xy 434.353102 -384.755875) (xy 434.337128 -384.690497)
			(xy 434.329081 -384.623678) (xy 434.329078 -384.556376) (xy 434.337118 -384.489557) (xy 434.353086 -384.424177)
			(xy 434.376753 -384.361174) (xy 434.407781 -384.301451) (xy 434.445723 -384.245864) (xy 434.467508 -384.220212)
			(xy 434.473325 -384.213082) (xy 434.479827 -384.19588) (xy 434.480208 -384.186684) (xy 434.480208 -383.693416)
			(xy 434.479788 -383.68423) (xy 434.473281 -383.667046) (xy 434.467508 -383.659888) (xy 434.445686 -383.634265)
			(xy 434.40774 -383.578673) (xy 434.37671 -383.518945) (xy 434.353041 -383.455937) (xy 434.337071 -383.390552)
			(xy 434.32903 -383.323727) (xy 433.226386 -383.323727) (xy 433.22662 -383.324351) (xy 433.242592 -383.389735)
			(xy 433.250634 -383.456559) (xy 433.250633 -383.523865) (xy 433.242587 -383.590689) (xy 433.226613 -383.656072)
			(xy 433.202938 -383.719077) (xy 433.171903 -383.778801) (xy 433.133953 -383.834388) (xy 433.112164 -383.86004)
			(xy 433.106363 -383.867182) (xy 433.099852 -383.884375) (xy 433.099464 -383.893568) (xy 433.099464 -384.051556)
			(xy 433.099042 -384.061712) (xy 433.091254 -384.08047) (xy 433.076856 -384.094796) (xy 433.05806 -384.102491)
			(xy 433.047902 -384.102864) (xy 432.331622 -384.102864) (xy 432.321497 -384.102356) (xy 432.302777 -384.094636)
			(xy 432.28842 -384.080356) (xy 432.2806 -384.061678) (xy 432.28006 -384.051556) (xy 432.28006 -383.893568)
			(xy 432.279652 -383.884381) (xy 432.273135 -383.867197) (xy 432.26736 -383.86004) (xy 432.245587 -383.834375)
			(xy 432.207637 -383.778791) (xy 432.176602 -383.719069) (xy 432.152927 -383.656066) (xy 432.136952 -383.590686)
			(xy 432.128907 -383.523864) (xy 432.128905 -383.45656) (xy 432.136948 -383.389738) (xy 432.15292 -383.324357)
			(xy 432.176592 -383.261353) (xy 432.207624 -383.20163) (xy 432.245573 -383.146044) (xy 432.26736 -383.120392)
			(xy 432.27315 -383.113242) (xy 432.279667 -383.096055) (xy 432.28006 -383.086864) (xy 432.28006 -382.593342)
			(xy 432.279616 -382.584159) (xy 432.273125 -382.566975) (xy 432.26736 -382.559814) (xy 432.245562 -382.53417)
			(xy 432.207612 -382.478583) (xy 432.176578 -382.418858) (xy 432.152905 -382.355853) (xy 432.136932 -382.290469)
			(xy 432.128888 -382.223646) (xy 428.850826 -382.223646) (xy 428.842783 -382.290466) (xy 428.826812 -382.355848)
			(xy 428.803141 -382.418852) (xy 428.772109 -382.478575) (xy 428.734163 -382.534162) (xy 428.712376 -382.559814)
			(xy 428.706588 -382.566965) (xy 428.700069 -382.584151) (xy 428.699676 -382.593342) (xy 428.699676 -383.086864)
			(xy 428.700109 -383.096049) (xy 428.706607 -383.113233) (xy 428.712376 -383.120392) (xy 428.734179 -383.146031)
			(xy 428.772126 -383.20162) (xy 428.803158 -383.261345) (xy 428.826616 -383.323786) (xy 429.928711 -383.323786)
			(xy 429.928714 -383.25636) (xy 429.936794 -383.189418) (xy 429.952834 -383.123927) (xy 429.976603 -383.060829)
			(xy 430.007759 -383.001032) (xy 430.045853 -382.945397) (xy 430.06772 -382.919732) (xy 430.07353 -382.912597)
			(xy 430.080036 -382.895398) (xy 430.08042 -382.886204) (xy 430.08042 -382.728724) (xy 430.080836 -382.718601)
			(xy 430.08858 -382.699894) (xy 430.102897 -382.685578) (xy 430.121605 -382.677835) (xy 430.131728 -382.677416)
			(xy 430.848008 -382.677416) (xy 430.858133 -382.67781) (xy 430.87684 -382.685564) (xy 430.891154 -382.699887)
			(xy 430.898896 -382.718599) (xy 430.899316 -382.728724) (xy 430.899316 -382.886204) (xy 430.899721 -382.895392)
			(xy 430.906238 -382.912576) (xy 430.912016 -382.919732) (xy 430.933844 -382.945427) (xy 430.971933 -383.001057)
			(xy 431.003084 -383.06085) (xy 431.02685 -383.123943) (xy 431.042887 -383.189428) (xy 431.050966 -383.256363)
			(xy 431.050969 -383.323783) (xy 431.042897 -383.390719) (xy 431.026866 -383.456206) (xy 431.003106 -383.519301)
			(xy 430.971961 -383.579096) (xy 430.933877 -383.634731) (xy 430.912016 -383.660396) (xy 430.90624 -383.667556)
			(xy 430.899713 -383.684735) (xy 430.899316 -383.693924) (xy 430.899316 -384.186176) (xy 430.899734 -384.195362)
			(xy 430.906242 -384.212547) (xy 430.912016 -384.219704) (xy 430.933915 -384.24534) (xy 430.972001 -384.300979)
			(xy 431.00315 -384.36078) (xy 431.026911 -384.42388) (xy 431.042944 -384.489373) (xy 431.051016 -384.556314)
			(xy 431.051013 -384.62374) (xy 431.042934 -384.690681) (xy 431.026895 -384.756171) (xy 431.003128 -384.81927)
			(xy 430.971974 -384.879067) (xy 430.933882 -384.934702) (xy 430.912016 -384.960368) (xy 430.90621 -384.967507)
			(xy 430.8997 -384.984702) (xy 430.899316 -384.993896) (xy 430.899316 -385.151376) (xy 430.898865 -385.161495)
			(xy 430.891128 -385.180195) (xy 430.876822 -385.19451) (xy 430.858127 -385.202259) (xy 430.848008 -385.202684)
			(xy 430.131728 -385.202684) (xy 430.121605 -385.202261) (xy 430.102899 -385.194519) (xy 430.088583 -385.180204)
			(xy 430.08084 -385.161499) (xy 430.08042 -385.151376) (xy 430.08042 -384.993896) (xy 430.080008 -384.984709)
			(xy 430.073495 -384.967525) (xy 430.06772 -384.960368) (xy 430.045891 -384.934674) (xy 430.0078 -384.879044)
			(xy 429.976646 -384.819252) (xy 429.952879 -384.756159) (xy 429.936841 -384.690673) (xy 429.928761 -384.623738)
			(xy 429.928758 -384.556316) (xy 429.936831 -384.48938) (xy 429.952863 -384.423893) (xy 429.976624 -384.360797)
			(xy 430.007772 -384.301002) (xy 430.045857 -384.245369) (xy 430.06772 -384.219704) (xy 430.0735 -384.212547)
			(xy 430.080024 -384.195365) (xy 430.08042 -384.186176) (xy 430.08042 -383.693924) (xy 430.079994 -383.684739)
			(xy 430.073491 -383.667554) (xy 430.06772 -383.660396) (xy 430.04582 -383.63476) (xy 430.007731 -383.579122)
			(xy 429.976581 -383.519322) (xy 429.952818 -383.456221) (xy 429.936784 -383.390728) (xy 429.928711 -383.323786)
			(xy 428.826616 -383.323786) (xy 428.826829 -383.324352) (xy 428.842801 -383.389735) (xy 428.850843 -383.456559)
			(xy 428.850842 -383.523865) (xy 428.842797 -383.590688) (xy 428.826822 -383.656071) (xy 428.803148 -383.719077)
			(xy 428.772114 -383.778801) (xy 428.734164 -383.834388) (xy 428.712376 -383.86004) (xy 428.706577 -383.867183)
			(xy 428.700065 -383.884375) (xy 428.699676 -383.893568) (xy 428.699676 -384.051556) (xy 428.699242 -384.06171)
			(xy 428.691456 -384.080466) (xy 428.677063 -384.094792) (xy 428.65827 -384.102489) (xy 428.648114 -384.102864)
			(xy 427.931834 -384.102864) (xy 427.92171 -384.102345) (xy 427.90299 -384.09463) (xy 427.888633 -384.080353)
			(xy 427.880812 -384.061677) (xy 427.880272 -384.051556) (xy 427.880272 -383.893568) (xy 427.879883 -383.884378)
			(xy 427.873355 -383.867194) (xy 427.867572 -383.86004) (xy 427.845799 -383.834375) (xy 427.807848 -383.778791)
			(xy 427.776812 -383.71907) (xy 427.753137 -383.656067) (xy 427.737162 -383.590686) (xy 427.729116 -383.523864)
			(xy 427.729114 -383.45656) (xy 427.737157 -383.389738) (xy 427.75313 -383.324356) (xy 427.776802 -383.261352)
			(xy 427.807835 -383.201629) (xy 427.845784 -383.146044) (xy 427.867572 -383.120392) (xy 427.873363 -383.113243)
			(xy 427.879879 -383.096055) (xy 427.880272 -383.086864) (xy 427.880272 -382.593342) (xy 427.879848 -382.584156)
			(xy 427.873344 -382.566971) (xy 427.867572 -382.559814) (xy 427.845774 -382.53417) (xy 427.807823 -382.478583)
			(xy 427.776788 -382.418859) (xy 427.753115 -382.355853) (xy 427.737141 -382.29047) (xy 427.729097 -382.223646)
			(xy 424.451058 -382.223646) (xy 424.451058 -382.223704) (xy 424.442983 -382.290642) (xy 424.426948 -382.356131)
			(xy 424.403184 -382.419227) (xy 424.372033 -382.479023) (xy 424.333944 -382.534657) (xy 424.31208 -382.560322)
			(xy 424.306289 -382.567471) (xy 424.299772 -382.584659) (xy 424.29938 -382.59385) (xy 424.29938 -383.086356)
			(xy 424.299816 -383.09554) (xy 424.306312 -383.112725) (xy 424.31208 -383.119884) (xy 424.33396 -383.145536)
			(xy 424.37205 -383.201172) (xy 424.403201 -383.26097) (xy 424.426837 -383.323727) (xy 425.528942 -383.323727)
			(xy 425.528946 -383.256419) (xy 425.536993 -383.189594) (xy 425.55297 -383.12421) (xy 425.576646 -383.061204)
			(xy 425.607682 -383.00148) (xy 425.645635 -382.945892) (xy 425.667424 -382.92024) (xy 425.673231 -382.913103)
			(xy 425.679739 -382.895906) (xy 425.680124 -382.886712) (xy 425.680124 -382.728724) (xy 425.680536 -382.7186)
			(xy 425.688281 -382.699892) (xy 425.702599 -382.685576) (xy 425.721308 -382.677834) (xy 425.731432 -382.677416)
			(xy 426.447966 -382.677416) (xy 426.458088 -382.677954) (xy 426.476803 -382.685666) (xy 426.49116 -382.699937)
			(xy 426.498984 -382.718606) (xy 426.499528 -382.728724) (xy 426.499528 -382.886712) (xy 426.499926 -382.895901)
			(xy 426.506447 -382.913085) (xy 426.512228 -382.92024) (xy 426.533981 -382.945921) (xy 426.571933 -383.001502)
			(xy 426.60297 -383.061222) (xy 426.626646 -383.124223) (xy 426.642623 -383.189602) (xy 426.65067 -383.256422)
			(xy 426.650673 -383.323724) (xy 426.642632 -383.390545) (xy 426.626662 -383.455926) (xy 426.602992 -383.518929)
			(xy 426.571961 -383.578651) (xy 426.534014 -383.634236) (xy 426.512228 -383.659888) (xy 426.506403 -383.667013)
			(xy 426.499907 -383.684219) (xy 426.499528 -383.693416) (xy 426.499528 -384.186684) (xy 426.499939 -384.195871)
			(xy 426.506451 -384.213056) (xy 426.512228 -384.220212) (xy 426.534052 -384.245834) (xy 426.572002 -384.301424)
			(xy 426.603036 -384.361152) (xy 426.626708 -384.42416) (xy 426.64268 -384.489546) (xy 426.650721 -384.556373)
			(xy 426.650718 -384.623681) (xy 426.64267 -384.690507) (xy 426.626692 -384.755892) (xy 426.603014 -384.818898)
			(xy 426.571974 -384.878622) (xy 426.534019 -384.934208) (xy 426.512228 -384.95986) (xy 426.506415 -384.966993)
			(xy 426.499912 -384.984193) (xy 426.499528 -384.993388) (xy 426.499528 -385.151376) (xy 426.499065 -385.161494)
			(xy 426.49133 -385.180191) (xy 426.477028 -385.194505) (xy 426.458337 -385.202257) (xy 426.44822 -385.202684)
			(xy 425.731686 -385.202684) (xy 425.721561 -385.202185) (xy 425.702845 -385.194457) (xy 425.68849 -385.180175)
			(xy 425.680667 -385.161498) (xy 425.680124 -385.151376) (xy 425.680124 -384.993388) (xy 425.679714 -384.984201)
			(xy 425.6732 -384.967017) (xy 425.667424 -384.95986) (xy 425.645672 -384.934178) (xy 425.607723 -384.878596)
			(xy 425.576689 -384.818876) (xy 425.553015 -384.755876) (xy 425.53704 -384.690497) (xy 425.528994 -384.623678)
			(xy 425.52899 -384.556376) (xy 425.537031 -384.489556) (xy 425.552999 -384.424176) (xy 425.576667 -384.361173)
			(xy 425.607696 -384.301451) (xy 425.645639 -384.245865) (xy 425.667424 -384.220212) (xy 425.673243 -384.213083)
			(xy 425.679744 -384.19588) (xy 425.680124 -384.186684) (xy 425.680124 -383.693416) (xy 425.679701 -383.68423)
			(xy 425.673195 -383.667046) (xy 425.667424 -383.659888) (xy 425.645601 -383.634265) (xy 425.607655 -383.578674)
			(xy 425.576624 -383.518946) (xy 425.552954 -383.455938) (xy 425.536984 -383.390552) (xy 425.528942 -383.323727)
			(xy 424.426837 -383.323727) (xy 424.426965 -383.324068) (xy 424.443 -383.389559) (xy 424.451075 -383.456499)
			(xy 424.451074 -383.523925) (xy 424.442996 -383.590864) (xy 424.426958 -383.656355) (xy 424.403191 -383.719452)
			(xy 424.372038 -383.779249) (xy 424.333946 -383.834883) (xy 424.31208 -383.860548) (xy 424.306278 -383.867689)
			(xy 424.299767 -383.884883) (xy 424.29938 -383.894076) (xy 424.29938 -384.051556) (xy 424.298947 -384.061678)
			(xy 424.29121 -384.080385) (xy 424.276898 -384.094701) (xy 424.258194 -384.102444) (xy 424.248072 -384.102864)
			(xy 423.531792 -384.102864) (xy 423.521665 -384.10249) (xy 423.502954 -384.094732) (xy 423.488639 -384.080402)
			(xy 423.4809 -384.061684) (xy 423.480484 -384.051556) (xy 423.480484 -383.894076) (xy 423.480089 -383.884887)
			(xy 423.473565 -383.867703) (xy 423.467784 -383.860548) (xy 423.445936 -383.83487) (xy 423.407848 -383.779237)
			(xy 423.376698 -383.719442) (xy 423.352933 -383.656347) (xy 423.336897 -383.59086) (xy 423.32882 -383.523923)
			(xy 423.328819 -383.456501) (xy 423.336893 -383.389564) (xy 423.352926 -383.324076) (xy 423.376688 -383.26098)
			(xy 423.407836 -383.201184) (xy 423.445922 -383.145549) (xy 423.467784 -383.119884) (xy 423.473568 -383.11273)
			(xy 423.480091 -383.095546) (xy 423.480484 -383.086356) (xy 423.480484 -382.59385) (xy 423.480054 -382.584665)
			(xy 423.473554 -382.56748) (xy 423.467784 -382.560322) (xy 423.445911 -382.534665) (xy 423.407823 -382.479029)
			(xy 423.376674 -382.419231) (xy 423.352911 -382.356133) (xy 423.336877 -382.290643) (xy 423.328802 -382.223705)
			(xy 420.050731 -382.223705) (xy 420.042695 -382.290466) (xy 420.026725 -382.355847) (xy 420.003054 -382.418851)
			(xy 419.972024 -382.478574) (xy 419.934078 -382.534161) (xy 419.912292 -382.559814) (xy 419.906506 -382.566967)
			(xy 419.899985 -382.584151) (xy 419.899592 -382.593342) (xy 419.899592 -383.086864) (xy 419.900021 -383.096049)
			(xy 419.906522 -383.113234) (xy 419.912292 -383.120392) (xy 419.934094 -383.146032) (xy 419.972041 -383.201621)
			(xy 420.003072 -383.261346) (xy 420.02653 -383.323787) (xy 421.128623 -383.323787) (xy 421.128626 -383.256359)
			(xy 421.136706 -383.189418) (xy 421.152747 -383.123926) (xy 421.176516 -383.060828) (xy 421.207673 -383.001031)
			(xy 421.245769 -382.945397) (xy 421.267636 -382.919732) (xy 421.273449 -382.912598) (xy 421.279953 -382.895399)
			(xy 421.280336 -382.886204) (xy 421.280336 -382.728724) (xy 421.280736 -382.718599) (xy 421.288483 -382.699889)
			(xy 421.302805 -382.685572) (xy 421.321518 -382.677832) (xy 421.331644 -382.677416) (xy 422.047924 -382.677416)
			(xy 422.058036 -382.677866) (xy 422.076718 -382.685614) (xy 422.091013 -382.699922) (xy 422.098744 -382.718611)
			(xy 422.099232 -382.728724) (xy 422.099232 -382.886204) (xy 422.099656 -382.895389) (xy 422.106162 -382.912573)
			(xy 422.111932 -382.919732) (xy 422.133759 -382.945427) (xy 422.171847 -383.001058) (xy 422.202998 -383.06085)
			(xy 422.226762 -383.123943) (xy 422.242799 -383.189428) (xy 422.250878 -383.256363) (xy 422.250881 -383.323783)
			(xy 422.242809 -383.390718) (xy 422.226778 -383.456205) (xy 422.20302 -383.5193) (xy 422.171875 -383.579096)
			(xy 422.133793 -383.63473) (xy 422.111932 -383.660396) (xy 422.106146 -383.667549) (xy 422.099627 -383.684734)
			(xy 422.099232 -383.693924) (xy 422.099232 -384.186176) (xy 422.099669 -384.19536) (xy 422.106166 -384.212544)
			(xy 422.111932 -384.219704) (xy 422.13383 -384.245341) (xy 422.171916 -384.30098) (xy 422.203063 -384.36078)
			(xy 422.226824 -384.423881) (xy 422.242856 -384.489373) (xy 422.250928 -384.556314) (xy 422.250925 -384.62374)
			(xy 422.242846 -384.69068) (xy 422.226808 -384.756171) (xy 422.203041 -384.819269) (xy 422.171888 -384.879066)
			(xy 422.133797 -384.934702) (xy 422.111932 -384.960368) (xy 422.106116 -384.967499) (xy 422.099615 -384.984701)
			(xy 422.099232 -384.993896) (xy 422.099232 -385.151376) (xy 422.098696 -385.161479) (xy 422.090972 -385.180151)
			(xy 422.076691 -385.194445) (xy 422.058027 -385.202187) (xy 422.047924 -385.202684) (xy 421.331644 -385.202684)
			(xy 421.321522 -385.202247) (xy 421.302817 -385.194511) (xy 421.2885 -385.1802) (xy 421.280756 -385.161497)
			(xy 421.280336 -385.151376) (xy 421.280336 -384.993896) (xy 421.27992 -384.98471) (xy 421.27341 -384.967526)
			(xy 421.267636 -384.960368) (xy 421.245806 -384.934674) (xy 421.207714 -384.879045) (xy 421.17656 -384.819253)
			(xy 421.152792 -384.756159) (xy 421.136753 -384.690673) (xy 421.128674 -384.623738) (xy 421.12867 -384.556316)
			(xy 421.136743 -384.48938) (xy 421.152776 -384.423892) (xy 421.176538 -384.360797) (xy 421.207686 -384.301002)
			(xy 421.245773 -384.245369) (xy 421.267636 -384.219704) (xy 421.273418 -384.212549) (xy 421.27994 -384.195366)
			(xy 421.280336 -384.186176) (xy 421.280336 -383.693924) (xy 421.279906 -383.684739) (xy 421.273405 -383.667555)
			(xy 421.267636 -383.660396) (xy 421.245735 -383.634761) (xy 421.207645 -383.579123) (xy 421.176494 -383.519323)
			(xy 421.152731 -383.456222) (xy 421.136696 -383.390729) (xy 421.128623 -383.323787) (xy 420.02653 -383.323787)
			(xy 420.026742 -383.324352) (xy 420.042713 -383.389736) (xy 420.050756 -383.456559) (xy 420.050754 -383.523865)
			(xy 420.042709 -383.590688) (xy 420.026735 -383.656071) (xy 420.003062 -383.719076) (xy 419.972028 -383.7788)
			(xy 419.93408 -383.834387) (xy 419.912292 -383.86004) (xy 419.906495 -383.867185) (xy 419.899981 -383.884376)
			(xy 419.899592 -383.893568) (xy 419.899592 -384.051556) (xy 419.899148 -384.061677) (xy 419.891413 -384.080381)
			(xy 419.877104 -384.094697) (xy 419.858404 -384.102442) (xy 419.848284 -384.102864) (xy 419.13175 -384.102864)
			(xy 419.121627 -384.102333) (xy 419.102908 -384.094622) (xy 419.08855 -384.080349) (xy 419.080728 -384.061676)
			(xy 419.080188 -384.051556) (xy 419.080188 -383.893568) (xy 419.079796 -383.884379) (xy 419.07327 -383.867194)
			(xy 419.067488 -383.86004) (xy 419.045715 -383.834376) (xy 419.007762 -383.778792) (xy 418.976725 -383.719071)
			(xy 418.95305 -383.656068) (xy 418.937074 -383.590686) (xy 418.929028 -383.523864) (xy 418.929026 -383.45656)
			(xy 418.93707 -383.389737) (xy 418.953042 -383.324355) (xy 418.976716 -383.261351) (xy 419.00775 -383.201629)
			(xy 419.0457 -383.146043) (xy 419.067488 -383.120392) (xy 419.073269 -383.113236) (xy 419.079793 -383.096054)
			(xy 419.080188 -383.086864) (xy 419.080188 -382.593342) (xy 419.07976 -382.584157) (xy 419.073259 -382.566972)
			(xy 419.067488 -382.559814) (xy 419.045689 -382.534171) (xy 419.007737 -382.478584) (xy 418.976702 -382.41886)
			(xy 418.953027 -382.355854) (xy 418.937054 -382.29047) (xy 418.92901 -382.223646) (xy 389.250707 -382.223646)
			(xy 389.242664 -382.290467) (xy 389.226692 -382.355848) (xy 389.20302 -382.418853) (xy 389.171987 -382.478576)
			(xy 389.134039 -382.534162) (xy 389.112252 -382.559814) (xy 389.106461 -382.566963) (xy 389.099944 -382.584151)
			(xy 389.099552 -382.593342) (xy 389.099552 -383.086864) (xy 389.09999 -383.096048) (xy 389.106485 -383.113232)
			(xy 389.112252 -383.120392) (xy 389.134056 -383.146031) (xy 389.172005 -383.201619) (xy 389.203038 -383.261344)
			(xy 389.226475 -383.323726) (xy 390.329121 -383.323726) (xy 390.329125 -383.256419) (xy 390.337172 -383.189595)
			(xy 390.353147 -383.124211) (xy 390.376822 -383.061206) (xy 390.407857 -383.001481) (xy 390.445807 -382.945893)
			(xy 390.467596 -382.92024) (xy 390.4734 -382.9131) (xy 390.47991 -382.895906) (xy 390.480296 -382.886712)
			(xy 390.480296 -382.728724) (xy 390.480741 -382.718572) (xy 390.488528 -382.699821) (xy 390.502918 -382.685497)
			(xy 390.521704 -382.677795) (xy 390.531858 -382.677416) (xy 391.248138 -382.677416) (xy 391.258264 -382.677895)
			(xy 391.276982 -382.685631) (xy 391.291336 -382.699919) (xy 391.299158 -382.7186) (xy 391.2997 -382.728724)
			(xy 391.2997 -382.886712) (xy 391.300105 -382.8959) (xy 391.306622 -382.913084) (xy 391.3124 -382.92024)
			(xy 391.334151 -382.945922) (xy 391.372099 -383.001505) (xy 391.403131 -383.061225) (xy 391.426804 -383.124225)
			(xy 391.442779 -383.189603) (xy 391.450825 -383.256422) (xy 391.450828 -383.323724) (xy 391.442788 -383.390543)
			(xy 391.42682 -383.455923) (xy 391.403153 -383.518926) (xy 391.372126 -383.578649) (xy 391.334184 -383.634235)
			(xy 391.3124 -383.659888) (xy 391.306584 -383.667019) (xy 391.300081 -383.68422) (xy 391.2997 -383.693416)
			(xy 391.2997 -384.186684) (xy 391.300118 -384.19587) (xy 391.306626 -384.213055) (xy 391.3124 -384.220212)
			(xy 391.334222 -384.245836) (xy 391.372167 -384.301427) (xy 391.403197 -384.361155) (xy 391.426866 -384.424163)
			(xy 391.442835 -384.489548) (xy 391.450876 -384.556374) (xy 391.450872 -384.623681) (xy 391.442825 -384.690505)
			(xy 391.42685 -384.755889) (xy 391.403175 -384.818895) (xy 391.372139 -384.878619) (xy 391.334189 -384.934207)
			(xy 391.3124 -384.95986) (xy 391.306595 -384.967) (xy 391.300086 -384.984194) (xy 391.2997 -384.993388)
			(xy 391.2997 -385.151376) (xy 391.299259 -385.161529) (xy 391.291471 -385.180281) (xy 391.27708 -385.194605)
			(xy 391.258292 -385.202305) (xy 391.248138 -385.202684) (xy 390.531858 -385.202684) (xy 390.521732 -385.202209)
			(xy 390.503014 -385.194471) (xy 390.48866 -385.180182) (xy 390.480838 -385.1615) (xy 390.480296 -385.151376)
			(xy 390.480296 -384.993388) (xy 390.479892 -384.9842) (xy 390.473374 -384.967016) (xy 390.467596 -384.95986)
			(xy 390.445845 -384.934178) (xy 390.407898 -384.878595) (xy 390.376865 -384.818875) (xy 390.353192 -384.755875)
			(xy 390.337218 -384.690496) (xy 390.329172 -384.623678) (xy 390.329169 -384.556376) (xy 390.337209 -384.489557)
			(xy 390.353176 -384.424177) (xy 390.376843 -384.361174) (xy 390.40787 -384.301452) (xy 390.445812 -384.245865)
			(xy 390.467596 -384.220212) (xy 390.473412 -384.21308) (xy 390.479915 -384.19588) (xy 390.480296 -384.186684)
			(xy 390.480296 -383.693416) (xy 390.479879 -383.68423) (xy 390.47337 -383.667045) (xy 390.467596 -383.659888)
			(xy 390.445774 -383.634264) (xy 390.407829 -383.578673) (xy 390.3768 -383.518945) (xy 390.353131 -383.455937)
			(xy 390.337162 -383.390552) (xy 390.329121 -383.323726) (xy 389.226475 -383.323726) (xy 389.22671 -383.324351)
			(xy 389.242682 -383.389735) (xy 389.250725 -383.456559) (xy 389.250724 -383.523865) (xy 389.242678 -383.590689)
			(xy 389.226703 -383.656072) (xy 389.203028 -383.719078) (xy 389.171992 -383.778802) (xy 389.134041 -383.834388)
			(xy 389.112252 -383.86004) (xy 389.10645 -383.867181) (xy 389.09994 -383.884375) (xy 389.099552 -383.893568)
			(xy 389.099552 -384.051556) (xy 389.099043 -384.061701) (xy 389.091272 -384.080442) (xy 389.076902 -384.094765)
			(xy 389.058136 -384.102476) (xy 389.04799 -384.102864) (xy 388.33171 -384.102864) (xy 388.321584 -384.102365)
			(xy 388.302864 -384.094642) (xy 388.288508 -384.080359) (xy 388.280687 -384.061679) (xy 388.280148 -384.051556)
			(xy 388.280148 -383.893568) (xy 388.279742 -383.884381) (xy 388.273224 -383.867197) (xy 388.267448 -383.86004)
			(xy 388.245676 -383.834375) (xy 388.207726 -383.778791) (xy 388.176692 -383.719069) (xy 388.153018 -383.656066)
			(xy 388.137043 -383.590685) (xy 388.128998 -383.523864) (xy 388.128996 -383.45656) (xy 388.137039 -383.389738)
			(xy 388.15301 -383.324357) (xy 388.176682 -383.261353) (xy 388.207714 -383.20163) (xy 388.245661 -383.146044)
			(xy 388.267448 -383.120392) (xy 388.273236 -383.113241) (xy 388.279755 -383.096055) (xy 388.280148 -383.086864)
			(xy 388.280148 -382.593342) (xy 388.279707 -382.584158) (xy 388.273213 -382.566974) (xy 388.267448 -382.559814)
			(xy 388.24565 -382.53417) (xy 388.207701 -382.478583) (xy 388.176668 -382.418858) (xy 388.152995 -382.355852)
			(xy 388.137022 -382.290469) (xy 388.128979 -382.223645) (xy 384.850917 -382.223645) (xy 384.842874 -382.290466)
			(xy 384.826902 -382.355848) (xy 384.803231 -382.418852) (xy 384.772199 -382.478576) (xy 384.734251 -382.534162)
			(xy 384.712464 -382.559814) (xy 384.706674 -382.566964) (xy 384.700156 -382.584151) (xy 384.699764 -382.593342)
			(xy 384.699764 -383.086864) (xy 384.7002 -383.096048) (xy 384.706697 -383.113232) (xy 384.712464 -383.120392)
			(xy 384.734267 -383.146031) (xy 384.772216 -383.20162) (xy 384.803248 -383.261345) (xy 384.826708 -383.323786)
			(xy 385.928802 -383.323786) (xy 385.928805 -383.25636) (xy 385.936885 -383.189419) (xy 385.952924 -383.123928)
			(xy 385.976693 -383.060829) (xy 386.007848 -383.001032) (xy 386.045942 -382.945397) (xy 386.067808 -382.919732)
			(xy 386.073617 -382.912596) (xy 386.080124 -382.895398) (xy 386.080508 -382.886204) (xy 386.080508 -382.728724)
			(xy 386.080936 -382.718602) (xy 386.088677 -382.699897) (xy 386.102991 -382.685582) (xy 386.121694 -382.677837)
			(xy 386.131816 -382.677416) (xy 386.848096 -382.677416) (xy 386.85822 -382.67782) (xy 386.876927 -382.685569)
			(xy 386.891242 -382.69989) (xy 386.898984 -382.7186) (xy 386.899404 -382.728724) (xy 386.899404 -382.886204)
			(xy 386.899811 -382.895391) (xy 386.906327 -382.912576) (xy 386.912104 -382.919732) (xy 386.933932 -382.945426)
			(xy 386.972022 -383.001057) (xy 387.003174 -383.060849) (xy 387.02694 -383.123942) (xy 387.042978 -383.189428)
			(xy 387.051057 -383.256363) (xy 387.05106 -383.323783) (xy 387.042988 -383.390719) (xy 387.026956 -383.456206)
			(xy 387.003196 -383.519301) (xy 386.97205 -383.579097) (xy 386.933966 -383.634731) (xy 386.912104 -383.660396)
			(xy 386.906327 -383.667555) (xy 386.899801 -383.684735) (xy 386.899404 -383.693924) (xy 386.899404 -384.186176)
			(xy 386.899825 -384.195362) (xy 386.906331 -384.212547) (xy 386.912104 -384.219704) (xy 386.934003 -384.24534)
			(xy 386.972091 -384.300979) (xy 387.003239 -384.360779) (xy 387.027001 -384.42388) (xy 387.043034 -384.489372)
			(xy 387.051107 -384.556314) (xy 387.051104 -384.62374) (xy 387.043025 -384.690681) (xy 387.026985 -384.756172)
			(xy 387.003217 -384.81927) (xy 386.972063 -384.879068) (xy 386.93397 -384.934703) (xy 386.912104 -384.960368)
			(xy 386.906297 -384.967506) (xy 386.899788 -384.984702) (xy 386.899404 -384.993896) (xy 386.899404 -385.151376)
			(xy 386.898965 -385.161496) (xy 386.891225 -385.180199) (xy 386.876916 -385.194514) (xy 386.858216 -385.202261)
			(xy 386.848096 -385.202684) (xy 386.131816 -385.202684) (xy 386.121693 -385.202271) (xy 386.102986 -385.194525)
			(xy 386.088671 -385.180207) (xy 386.080928 -385.1615) (xy 386.080508 -385.151376) (xy 386.080508 -384.993896)
			(xy 386.080098 -384.984709) (xy 386.073584 -384.967525) (xy 386.067808 -384.960368) (xy 386.045979 -384.934674)
			(xy 386.007889 -384.879044) (xy 385.976736 -384.819251) (xy 385.95297 -384.756158) (xy 385.936931 -384.690673)
			(xy 385.928852 -384.623738) (xy 385.928849 -384.556317) (xy 385.936922 -384.489381) (xy 385.952954 -384.423893)
			(xy 385.976714 -384.360798) (xy 386.007861 -384.301003) (xy 386.045946 -384.245369) (xy 386.067808 -384.219704)
			(xy 386.073586 -384.212546) (xy 386.080112 -384.195365) (xy 386.080508 -384.186176) (xy 386.080508 -383.693924)
			(xy 386.080084 -383.684738) (xy 386.07358 -383.667554) (xy 386.067808 -383.660396) (xy 386.045908 -383.63476)
			(xy 386.00782 -383.579122) (xy 385.976671 -383.519321) (xy 385.952908 -383.456221) (xy 385.936875 -383.390728)
			(xy 385.928802 -383.323786) (xy 384.826708 -383.323786) (xy 384.82692 -383.324351) (xy 384.842892 -383.389735)
			(xy 384.850934 -383.456559) (xy 384.850933 -383.523865) (xy 384.842887 -383.590689) (xy 384.826913 -383.656072)
			(xy 384.803238 -383.719077) (xy 384.772203 -383.778801) (xy 384.734253 -383.834388) (xy 384.712464 -383.86004)
			(xy 384.706663 -383.867182) (xy 384.700152 -383.884375) (xy 384.699764 -383.893568) (xy 384.699764 -384.051556)
			(xy 384.699342 -384.061712) (xy 384.691554 -384.08047) (xy 384.677156 -384.094796) (xy 384.65836 -384.102491)
			(xy 384.648202 -384.102864) (xy 383.931922 -384.102864) (xy 383.921797 -384.102356) (xy 383.903077 -384.094636)
			(xy 383.88872 -384.080356) (xy 383.8809 -384.061678) (xy 383.88036 -384.051556) (xy 383.88036 -383.893568)
			(xy 383.879952 -383.884381) (xy 383.873435 -383.867197) (xy 383.86766 -383.86004) (xy 383.845887 -383.834375)
			(xy 383.807937 -383.778791) (xy 383.776902 -383.719069) (xy 383.753227 -383.656066) (xy 383.737252 -383.590686)
			(xy 383.729207 -383.523864) (xy 383.729205 -383.45656) (xy 383.737248 -383.389738) (xy 383.75322 -383.324357)
			(xy 383.776892 -383.261353) (xy 383.807924 -383.20163) (xy 383.845873 -383.146044) (xy 383.86766 -383.120392)
			(xy 383.87345 -383.113242) (xy 383.879967 -383.096055) (xy 383.88036 -383.086864) (xy 383.88036 -382.593342)
			(xy 383.879916 -382.584159) (xy 383.873425 -382.566975) (xy 383.86766 -382.559814) (xy 383.845862 -382.53417)
			(xy 383.807912 -382.478583) (xy 383.776878 -382.418858) (xy 383.753205 -382.355853) (xy 383.737232 -382.290469)
			(xy 383.729188 -382.223646) (xy 380.451149 -382.223646) (xy 380.451149 -382.223704) (xy 380.443073 -382.290642)
			(xy 380.427038 -382.356131) (xy 380.403273 -382.419228) (xy 380.372122 -382.479024) (xy 380.334032 -382.534657)
			(xy 380.312168 -382.560322) (xy 380.306375 -382.56747) (xy 380.299859 -382.584658) (xy 380.299468 -382.59385)
			(xy 380.299468 -383.086356) (xy 380.299907 -383.09554) (xy 380.306401 -383.112724) (xy 380.312168 -383.119884)
			(xy 380.334049 -383.145536) (xy 380.372139 -383.201171) (xy 380.403291 -383.260969) (xy 380.426928 -383.323727)
			(xy 381.529033 -383.323727) (xy 381.529037 -383.256419) (xy 381.537084 -383.189595) (xy 381.55306 -383.124211)
			(xy 381.576736 -383.061205) (xy 381.607772 -383.00148) (xy 381.645723 -382.945893) (xy 381.667512 -382.92024)
			(xy 381.673318 -382.913101) (xy 381.679827 -382.895906) (xy 381.680212 -382.886712) (xy 381.680212 -382.728724)
			(xy 381.680641 -382.71857) (xy 381.688431 -382.699816) (xy 381.702826 -382.685491) (xy 381.721618 -382.677793)
			(xy 381.731774 -382.677416) (xy 382.448054 -382.677416) (xy 382.458175 -382.677964) (xy 382.47689 -382.685672)
			(xy 382.491247 -382.699939) (xy 382.499072 -382.718606) (xy 382.499616 -382.728724) (xy 382.499616 -382.886712)
			(xy 382.500017 -382.8959) (xy 382.506537 -382.913085) (xy 382.512316 -382.92024) (xy 382.53407 -382.945921)
			(xy 382.572023 -383.001502) (xy 382.60306 -383.061221) (xy 382.626737 -383.124222) (xy 382.642713 -383.189601)
			(xy 382.650761 -383.256421) (xy 382.650764 -383.323724) (xy 382.642723 -383.390545) (xy 382.626753 -383.455926)
			(xy 382.603082 -383.518929) (xy 382.57205 -383.578652) (xy 382.534103 -383.634236) (xy 382.512316 -383.659888)
			(xy 382.506501 -383.667021) (xy 382.499997 -383.684221) (xy 382.499616 -383.693416) (xy 382.499616 -384.186684)
			(xy 382.50003 -384.195871) (xy 382.506541 -384.213055) (xy 382.512316 -384.220212) (xy 382.53414 -384.245834)
			(xy 382.572091 -384.301424) (xy 382.603125 -384.361151) (xy 382.626798 -384.42416) (xy 382.64277 -384.489546)
			(xy 382.650812 -384.556373) (xy 382.650808 -384.623681) (xy 382.64276 -384.690507) (xy 382.626782 -384.755892)
			(xy 382.603103 -384.818898) (xy 382.572063 -384.878622) (xy 382.534107 -384.934208) (xy 382.512316 -384.95986)
			(xy 382.506513 -384.967001) (xy 382.500002 -384.984195) (xy 382.499616 -384.993388) (xy 382.499616 -385.151376)
			(xy 382.499159 -385.161527) (xy 382.491375 -385.180275) (xy 382.476989 -385.194599) (xy 382.458206 -385.202303)
			(xy 382.448054 -385.202684) (xy 381.731774 -385.202684) (xy 381.721649 -385.202196) (xy 381.702931 -385.194464)
			(xy 381.688577 -385.180179) (xy 381.680754 -385.161499) (xy 381.680212 -385.151376) (xy 381.680212 -384.993388)
			(xy 381.679805 -384.984201) (xy 381.673289 -384.967016) (xy 381.667512 -384.95986) (xy 381.64576 -384.934178)
			(xy 381.607812 -384.878596) (xy 381.576779 -384.818876) (xy 381.553105 -384.755875) (xy 381.537131 -384.690497)
			(xy 381.529084 -384.623678) (xy 381.529081 -384.556376) (xy 381.537121 -384.489557) (xy 381.553089 -384.424177)
			(xy 381.576757 -384.361174) (xy 381.607784 -384.301451) (xy 381.645727 -384.245864) (xy 381.667512 -384.220212)
			(xy 381.67333 -384.213082) (xy 381.679831 -384.19588) (xy 381.680212 -384.186684) (xy 381.680212 -383.693416)
			(xy 381.679791 -383.68423) (xy 381.673285 -383.667046) (xy 381.667512 -383.659888) (xy 381.64569 -383.634265)
			(xy 381.607744 -383.578673) (xy 381.576714 -383.518946) (xy 381.553044 -383.455937) (xy 381.537074 -383.390552)
			(xy 381.529033 -383.323727) (xy 380.426928 -383.323727) (xy 380.427056 -383.324068) (xy 380.443091 -383.389559)
			(xy 380.451166 -383.456499) (xy 380.451165 -383.523925) (xy 380.443087 -383.590865) (xy 380.427049 -383.656355)
			(xy 380.403281 -383.719453) (xy 380.372127 -383.779249) (xy 380.334034 -383.834883) (xy 380.312168 -383.860548)
			(xy 380.306364 -383.867688) (xy 380.299855 -383.884883) (xy 380.299468 -383.894076) (xy 380.299468 -384.051556)
			(xy 380.299047 -384.06168) (xy 380.291308 -384.080388) (xy 380.276992 -384.094705) (xy 380.258284 -384.102446)
			(xy 380.24816 -384.102864) (xy 379.53188 -384.102864) (xy 379.521752 -384.1025) (xy 379.503041 -384.094738)
			(xy 379.488726 -384.080405) (xy 379.480988 -384.061685) (xy 379.480572 -384.051556) (xy 379.480572 -383.894076)
			(xy 379.48018 -383.884887) (xy 379.473654 -383.867702) (xy 379.467872 -383.860548) (xy 379.446025 -383.834869)
			(xy 379.407937 -383.779236) (xy 379.376788 -383.719441) (xy 379.353024 -383.656346) (xy 379.336988 -383.590859)
			(xy 379.328911 -383.523923) (xy 379.32891 -383.456501) (xy 379.336984 -383.389564) (xy 379.353017 -383.324077)
			(xy 379.376778 -383.260981) (xy 379.407925 -383.201185) (xy 379.44601 -383.14555) (xy 379.467872 -383.119884)
			(xy 379.473667 -383.112738) (xy 379.48018 -383.095548) (xy 379.480572 -383.086356) (xy 379.480572 -382.59385)
			(xy 379.480144 -382.584665) (xy 379.473643 -382.56748) (xy 379.467872 -382.560322) (xy 379.445999 -382.534664)
			(xy 379.407913 -382.479028) (xy 379.376764 -382.419231) (xy 379.353002 -382.356133) (xy 379.336968 -382.290643)
			(xy 379.328893 -382.223704) (xy 376.050822 -382.223704) (xy 376.042786 -382.290466) (xy 376.026815 -382.355847)
			(xy 376.003144 -382.418851) (xy 375.972113 -382.478575) (xy 375.934167 -382.534162) (xy 375.91238 -382.559814)
			(xy 375.906593 -382.566966) (xy 375.900073 -382.584151) (xy 375.89968 -382.593342) (xy 375.89968 -383.086864)
			(xy 375.900112 -383.096049) (xy 375.906611 -383.113233) (xy 375.91238 -383.120392) (xy 375.934183 -383.146031)
			(xy 375.97213 -383.20162) (xy 376.003162 -383.261346) (xy 376.02662 -383.323786) (xy 377.128714 -383.323786)
			(xy 377.128717 -383.256359) (xy 377.136797 -383.189418) (xy 377.152837 -383.123927) (xy 377.176606 -383.060828)
			(xy 377.207762 -383.001031) (xy 377.245857 -382.945397) (xy 377.267724 -382.919732) (xy 377.273535 -382.912597)
			(xy 377.28004 -382.895399) (xy 377.280424 -382.886204) (xy 377.280424 -382.728724) (xy 377.280836 -382.7186)
			(xy 377.288581 -382.699892) (xy 377.302899 -382.685576) (xy 377.321608 -382.677834) (xy 377.331732 -382.677416)
			(xy 378.048012 -382.677416) (xy 378.058137 -382.677806) (xy 378.076844 -382.685561) (xy 378.091159 -382.699886)
			(xy 378.098901 -382.718598) (xy 378.09932 -382.728724) (xy 378.09932 -382.886204) (xy 378.099724 -382.895392)
			(xy 378.106241 -382.912576) (xy 378.11202 -382.919732) (xy 378.133848 -382.945427) (xy 378.171936 -383.001058)
			(xy 378.203088 -383.06085) (xy 378.226853 -383.123943) (xy 378.24289 -383.189428) (xy 378.250969 -383.256363)
			(xy 378.250972 -383.323783) (xy 378.2429 -383.390719) (xy 378.226869 -383.456205) (xy 378.20311 -383.519301)
			(xy 378.171964 -383.579096) (xy 378.133881 -383.63473) (xy 378.11202 -383.660396) (xy 378.106245 -383.667557)
			(xy 378.099717 -383.684735) (xy 378.09932 -383.693924) (xy 378.09932 -384.186176) (xy 378.099737 -384.195363)
			(xy 378.106245 -384.212547) (xy 378.11202 -384.219704) (xy 378.133919 -384.24534) (xy 378.172005 -384.30098)
			(xy 378.203153 -384.36078) (xy 378.226914 -384.423881) (xy 378.242947 -384.489373) (xy 378.251019 -384.556314)
			(xy 378.251016 -384.62374) (xy 378.242937 -384.69068) (xy 378.226898 -384.756171) (xy 378.203131 -384.81927)
			(xy 378.171977 -384.879067) (xy 378.133885 -384.934702) (xy 378.11202 -384.960368) (xy 378.106214 -384.967507)
			(xy 378.099704 -384.984702) (xy 378.09932 -384.993896) (xy 378.09932 -385.151376) (xy 378.098865 -385.161494)
			(xy 378.091128 -385.180194) (xy 378.076824 -385.194508) (xy 378.05813 -385.202258) (xy 378.048012 -385.202684)
			(xy 377.331732 -385.202684) (xy 377.32161 -385.202258) (xy 377.302903 -385.194517) (xy 377.288587 -385.180203)
			(xy 377.280844 -385.161498) (xy 377.280424 -385.151376) (xy 377.280424 -384.993896) (xy 377.280011 -384.984709)
			(xy 377.273499 -384.967525) (xy 377.267724 -384.960368) (xy 377.245895 -384.934674) (xy 377.207803 -384.879044)
			(xy 377.17665 -384.819252) (xy 377.152882 -384.756159) (xy 377.136844 -384.690673) (xy 377.128765 -384.623738)
			(xy 377.128761 -384.556316) (xy 377.136834 -384.48938) (xy 377.152866 -384.423893) (xy 377.176627 -384.360797)
			(xy 377.207775 -384.301002) (xy 377.245861 -384.245369) (xy 377.267724 -384.219704) (xy 377.273504 -384.212547)
			(xy 377.280028 -384.195365) (xy 377.280424 -384.186176) (xy 377.280424 -383.693924) (xy 377.279997 -383.684739)
			(xy 377.273494 -383.667555) (xy 377.267724 -383.660396) (xy 377.245824 -383.63476) (xy 377.207735 -383.579122)
			(xy 377.176584 -383.519322) (xy 377.152821 -383.456221) (xy 377.136787 -383.390728) (xy 377.128714 -383.323786)
			(xy 376.02662 -383.323786) (xy 376.026833 -383.324352) (xy 376.042804 -383.389735) (xy 376.050846 -383.456559)
			(xy 376.050845 -383.523865) (xy 376.0428 -383.590688) (xy 376.026826 -383.656071) (xy 376.003152 -383.719076)
			(xy 375.972118 -383.778801) (xy 375.934168 -383.834388) (xy 375.91238 -383.86004) (xy 375.906582 -383.867184)
			(xy 375.900069 -383.884375) (xy 375.89968 -383.893568) (xy 375.89968 -384.051556) (xy 375.899242 -384.06171)
			(xy 375.891457 -384.080465) (xy 375.877065 -384.094791) (xy 375.858274 -384.102488) (xy 375.848118 -384.102864)
			(xy 375.131838 -384.102864) (xy 375.121714 -384.102342) (xy 375.102995 -384.094628) (xy 375.088637 -384.080352)
			(xy 375.080816 -384.061677) (xy 375.080276 -384.051556) (xy 375.080276 -383.893568) (xy 375.079886 -383.884379)
			(xy 375.073359 -383.867194) (xy 375.067576 -383.86004) (xy 375.045803 -383.834375) (xy 375.007851 -383.778792)
			(xy 374.976815 -383.71907) (xy 374.95314 -383.656067) (xy 374.937165 -383.590686) (xy 374.929119 -383.523864)
			(xy 374.929117 -383.45656) (xy 374.93716 -383.389738) (xy 374.953133 -383.324356) (xy 374.976805 -383.261352)
			(xy 375.007839 -383.201629) (xy 375.045788 -383.146044) (xy 375.067576 -383.120392) (xy 375.073356 -383.113235)
			(xy 375.079881 -383.096054) (xy 375.080276 -383.086864) (xy 375.080276 -382.593342) (xy 375.079851 -382.584156)
			(xy 375.073348 -382.566971) (xy 375.067576 -382.559814) (xy 375.045777 -382.53417) (xy 375.007826 -382.478584)
			(xy 374.976792 -382.418859) (xy 374.953118 -382.355853) (xy 374.937144 -382.29047) (xy 374.9291 -382.223646)
			(xy 345.250798 -382.223646) (xy 345.242755 -382.290467) (xy 345.226782 -382.355849) (xy 345.20311 -382.418853)
			(xy 345.172077 -382.478576) (xy 345.134128 -382.534162) (xy 345.11234 -382.559814) (xy 345.106548 -382.566962)
			(xy 345.100032 -382.584151) (xy 345.09964 -382.593342) (xy 345.09964 -383.086864) (xy 345.100081 -383.096048)
			(xy 345.106575 -383.113232) (xy 345.11234 -383.120392) (xy 345.134144 -383.146031) (xy 345.172094 -383.201619)
			(xy 345.203127 -383.261344) (xy 345.226566 -383.323727) (xy 346.329188 -383.323727) (xy 346.329192 -383.256419)
			(xy 346.33724 -383.189593) (xy 346.353218 -383.124208) (xy 346.376897 -383.061202) (xy 346.407937 -383.001478)
			(xy 346.445893 -382.945892) (xy 346.467684 -382.92024) (xy 346.473487 -382.913099) (xy 346.479998 -382.895905)
			(xy 346.480384 -382.886712) (xy 346.480384 -382.728724) (xy 346.480841 -382.718573) (xy 346.488625 -382.699825)
			(xy 346.503011 -382.685501) (xy 346.521794 -382.677797) (xy 346.531946 -382.677416) (xy 347.248226 -382.677416)
			(xy 347.258351 -382.677904) (xy 347.277069 -382.685636) (xy 347.291423 -382.699921) (xy 347.299246 -382.718601)
			(xy 347.299788 -382.728724) (xy 347.299788 -382.886712) (xy 347.300195 -382.895899) (xy 347.306711 -382.913084)
			(xy 347.312488 -382.92024) (xy 347.33424 -382.945922) (xy 347.372188 -383.001504) (xy 347.403221 -383.061224)
			(xy 347.426895 -383.124225) (xy 347.442869 -383.189603) (xy 347.450916 -383.256422) (xy 347.450919 -383.323724)
			(xy 347.442879 -383.390543) (xy 347.426911 -383.455923) (xy 347.403243 -383.518926) (xy 347.372216 -383.578649)
			(xy 347.334273 -383.634236) (xy 347.312488 -383.659888) (xy 347.30667 -383.667018) (xy 347.300169 -383.68422)
			(xy 347.299788 -383.693416) (xy 347.299788 -384.186684) (xy 347.300209 -384.19587) (xy 347.306715 -384.213054)
			(xy 347.312488 -384.220212) (xy 347.33431 -384.245835) (xy 347.372256 -384.301427) (xy 347.403286 -384.361154)
			(xy 347.426956 -384.424163) (xy 347.442926 -384.489548) (xy 347.450967 -384.556373) (xy 347.450963 -384.623681)
			(xy 347.442916 -384.690505) (xy 347.42694 -384.755889) (xy 347.403264 -384.818895) (xy 347.372228 -384.87862)
			(xy 347.334277 -384.934207) (xy 347.312488 -384.95986) (xy 347.306682 -384.966999) (xy 347.300173 -384.984194)
			(xy 347.299788 -384.993388) (xy 347.299788 -385.151376) (xy 347.299359 -385.16153) (xy 347.291569 -385.180284)
			(xy 347.277174 -385.194609) (xy 347.258382 -385.202307) (xy 347.248226 -385.202684) (xy 346.531946 -385.202684)
			(xy 346.521825 -385.202136) (xy 346.50311 -385.194428) (xy 346.488753 -385.180161) (xy 346.480928 -385.161494)
			(xy 346.480384 -385.151376) (xy 346.480384 -384.993388) (xy 346.479983 -384.9842) (xy 346.473463 -384.967015)
			(xy 346.467684 -384.95986) (xy 346.44593 -384.934179) (xy 346.407977 -384.878598) (xy 346.37694 -384.818879)
			(xy 346.353263 -384.755878) (xy 346.337287 -384.690499) (xy 346.329239 -384.623679) (xy 346.329236 -384.556376)
			(xy 346.337277 -384.489555) (xy 346.353247 -384.424174) (xy 346.376918 -384.361171) (xy 346.40795 -384.301448)
			(xy 346.445897 -384.245864) (xy 346.467684 -384.220212) (xy 346.473499 -384.213079) (xy 346.480003 -384.195879)
			(xy 346.480384 -384.186684) (xy 346.480384 -383.693416) (xy 346.47997 -383.684229) (xy 346.473459 -383.667045)
			(xy 346.467684 -383.659888) (xy 346.44586 -383.634266) (xy 346.407909 -383.578676) (xy 346.376875 -383.518949)
			(xy 346.353202 -383.45594) (xy 346.33723 -383.390554) (xy 346.329188 -383.323727) (xy 345.226566 -383.323727)
			(xy 345.2268 -383.32435) (xy 345.242773 -383.389734) (xy 345.250816 -383.456559) (xy 345.250814 -383.523865)
			(xy 345.242768 -383.590689) (xy 345.226793 -383.656073) (xy 345.203118 -383.719078) (xy 345.172081 -383.778802)
			(xy 345.134129 -383.834388) (xy 345.11234 -383.86004) (xy 345.106537 -383.86718) (xy 345.100028 -383.884375)
			(xy 345.09964 -383.893568) (xy 345.09964 -384.051556) (xy 345.099143 -384.061702) (xy 345.09137 -384.080446)
			(xy 345.076996 -384.094769) (xy 345.058226 -384.102478) (xy 345.048078 -384.102864) (xy 344.331798 -384.102864)
			(xy 344.321672 -384.102375) (xy 344.302951 -384.094647) (xy 344.288595 -384.080362) (xy 344.280775 -384.06168)
			(xy 344.280236 -384.051556) (xy 344.280236 -383.893568) (xy 344.279833 -383.88438) (xy 344.273313 -383.867196)
			(xy 344.267536 -383.86004) (xy 344.245764 -383.834375) (xy 344.207815 -383.77879) (xy 344.176781 -383.719068)
			(xy 344.153108 -383.656066) (xy 344.137134 -383.590685) (xy 344.129089 -383.523864) (xy 344.129087 -383.45656)
			(xy 344.13713 -383.389739) (xy 344.153101 -383.324358) (xy 344.176772 -383.261354) (xy 344.207803 -383.201631)
			(xy 344.24575 -383.146044) (xy 344.267536 -383.120392) (xy 344.273323 -383.11324) (xy 344.279843 -383.096055)
			(xy 344.280236 -383.086864) (xy 344.280236 -382.593342) (xy 344.279797 -382.584158) (xy 344.273303 -382.566974)
			(xy 344.267536 -382.559814) (xy 344.245738 -382.53417) (xy 344.20779 -382.478582) (xy 344.176757 -382.418858)
			(xy 344.153085 -382.355852) (xy 344.137113 -382.290469) (xy 344.12907 -382.223645) (xy 340.851007 -382.223645)
			(xy 340.842964 -382.290467) (xy 340.826992 -382.355848) (xy 340.80332 -382.418853) (xy 340.772287 -382.478576)
			(xy 340.734339 -382.534162) (xy 340.712552 -382.559814) (xy 340.706761 -382.566963) (xy 340.700244 -382.584151)
			(xy 340.699852 -382.593342) (xy 340.699852 -383.086864) (xy 340.70029 -383.096048) (xy 340.706785 -383.113232)
			(xy 340.712552 -383.120392) (xy 340.734356 -383.146031) (xy 340.772305 -383.201619) (xy 340.803338 -383.261344)
			(xy 340.826798 -383.323786) (xy 341.928893 -383.323786) (xy 341.928896 -383.25636) (xy 341.936975 -383.189419)
			(xy 341.953015 -383.123928) (xy 341.976783 -383.06083) (xy 342.007937 -383.001032) (xy 342.04603 -382.945397)
			(xy 342.067896 -382.919732) (xy 342.073703 -382.912594) (xy 342.080212 -382.895398) (xy 342.080596 -382.886204)
			(xy 342.080596 -382.728724) (xy 342.081035 -382.718604) (xy 342.088775 -382.699901) (xy 342.103084 -382.685586)
			(xy 342.121784 -382.677839) (xy 342.131904 -382.677416) (xy 342.848184 -382.677416) (xy 342.858307 -382.677829)
			(xy 342.877014 -382.685575) (xy 342.891329 -382.699893) (xy 342.899072 -382.7186) (xy 342.899492 -382.728724)
			(xy 342.899492 -382.886204) (xy 342.899902 -382.895391) (xy 342.906416 -382.912575) (xy 342.912192 -382.919732)
			(xy 342.934021 -382.945426) (xy 342.972111 -383.001056) (xy 343.003264 -383.060849) (xy 343.02703 -383.123942)
			(xy 343.043069 -383.189427) (xy 343.051148 -383.256362) (xy 343.051151 -383.323783) (xy 343.043078 -383.390719)
			(xy 343.027046 -383.456207) (xy 343.003286 -383.519302) (xy 342.972139 -383.579097) (xy 342.934054 -383.634731)
			(xy 342.912192 -383.660396) (xy 342.906414 -383.667554) (xy 342.899888 -383.684735) (xy 342.899492 -383.693924)
			(xy 342.899492 -384.186176) (xy 342.899916 -384.195362) (xy 342.90642 -384.212546) (xy 342.912192 -384.219704)
			(xy 342.934092 -384.24534) (xy 342.97218 -384.300978) (xy 343.003329 -384.360779) (xy 343.027092 -384.423879)
			(xy 343.043125 -384.489372) (xy 343.051198 -384.556314) (xy 343.051195 -384.62374) (xy 343.043115 -384.690681)
			(xy 343.027076 -384.756172) (xy 343.003307 -384.819271) (xy 342.972152 -384.879068) (xy 342.934058 -384.934703)
			(xy 342.912192 -384.960368) (xy 342.906383 -384.967504) (xy 342.899876 -384.984702) (xy 342.899492 -384.993896)
			(xy 342.899492 -385.151376) (xy 342.899064 -385.161498) (xy 342.891323 -385.180203) (xy 342.877009 -385.194518)
			(xy 342.858306 -385.202263) (xy 342.848184 -385.202684) (xy 342.131904 -385.202684) (xy 342.12178 -385.20228)
			(xy 342.103073 -385.194531) (xy 342.088758 -385.18021) (xy 342.081016 -385.1615) (xy 342.080596 -385.151376)
			(xy 342.080596 -384.993896) (xy 342.080189 -384.984709) (xy 342.073673 -384.967524) (xy 342.067896 -384.960368)
			(xy 342.046068 -384.934674) (xy 342.007978 -384.879043) (xy 341.976826 -384.819251) (xy 341.95306 -384.756158)
			(xy 341.937022 -384.690672) (xy 341.928943 -384.623737) (xy 341.92894 -384.556317) (xy 341.937012 -384.489381)
			(xy 341.953044 -384.423894) (xy 341.976804 -384.360799) (xy 342.00795 -384.301003) (xy 342.046034 -384.245369)
			(xy 342.067896 -384.219704) (xy 342.073673 -384.212545) (xy 342.080199 -384.195365) (xy 342.080596 -384.186176)
			(xy 342.080596 -383.693924) (xy 342.080175 -383.684738) (xy 342.073669 -383.667553) (xy 342.067896 -383.660396)
			(xy 342.045997 -383.63476) (xy 342.007909 -383.579121) (xy 341.976761 -383.519321) (xy 341.952999 -383.45622)
			(xy 341.936966 -383.390728) (xy 341.928893 -383.323786) (xy 340.826798 -383.323786) (xy 340.82701 -383.324351)
			(xy 340.842982 -383.389735) (xy 340.851025 -383.456559) (xy 340.851024 -383.523865) (xy 340.842978 -383.590689)
			(xy 340.827003 -383.656072) (xy 340.803328 -383.719078) (xy 340.772292 -383.778802) (xy 340.734341 -383.834388)
			(xy 340.712552 -383.86004) (xy 340.70675 -383.867181) (xy 340.70024 -383.884375) (xy 340.699852 -383.893568)
			(xy 340.699852 -384.051556) (xy 340.699343 -384.061701) (xy 340.691572 -384.080442) (xy 340.677202 -384.094765)
			(xy 340.658436 -384.102476) (xy 340.64829 -384.102864) (xy 339.93201 -384.102864) (xy 339.921884 -384.102365)
			(xy 339.903164 -384.094642) (xy 339.888808 -384.080359) (xy 339.880987 -384.061679) (xy 339.880448 -384.051556)
			(xy 339.880448 -383.893568) (xy 339.880042 -383.884381) (xy 339.873524 -383.867197) (xy 339.867748 -383.86004)
			(xy 339.845976 -383.834375) (xy 339.808026 -383.778791) (xy 339.776992 -383.719069) (xy 339.753318 -383.656066)
			(xy 339.737343 -383.590685) (xy 339.729298 -383.523864) (xy 339.729296 -383.45656) (xy 339.737339 -383.389738)
			(xy 339.75331 -383.324357) (xy 339.776982 -383.261353) (xy 339.808014 -383.20163) (xy 339.845961 -383.146044)
			(xy 339.867748 -383.120392) (xy 339.873536 -383.113241) (xy 339.880055 -383.096055) (xy 339.880448 -383.086864)
			(xy 339.880448 -382.593342) (xy 339.880007 -382.584158) (xy 339.873513 -382.566974) (xy 339.867748 -382.559814)
			(xy 339.84595 -382.53417) (xy 339.808001 -382.478583) (xy 339.776968 -382.418858) (xy 339.753295 -382.355852)
			(xy 339.737322 -382.290469) (xy 339.729279 -382.223645) (xy 336.45124 -382.223645) (xy 336.45124 -382.223704)
			(xy 336.443164 -382.290643) (xy 336.427128 -382.356132) (xy 336.403363 -382.419228) (xy 336.372211 -382.479024)
			(xy 336.334121 -382.534658) (xy 336.312256 -382.560322) (xy 336.306462 -382.567469) (xy 336.299947 -382.584658)
			(xy 336.299556 -382.59385) (xy 336.299556 -383.086356) (xy 336.299997 -383.09554) (xy 336.306491 -383.112724)
			(xy 336.312256 -383.119884) (xy 336.334137 -383.145536) (xy 336.372228 -383.201171) (xy 336.403381 -383.260969)
			(xy 336.427018 -383.323726) (xy 337.529124 -383.323726) (xy 337.529128 -383.256419) (xy 337.537175 -383.189595)
			(xy 337.55315 -383.124211) (xy 337.576825 -383.061205) (xy 337.607861 -383.001481) (xy 337.645811 -382.945893)
			(xy 337.6676 -382.92024) (xy 337.673405 -382.9131) (xy 337.679914 -382.895906) (xy 337.6803 -382.886712)
			(xy 337.6803 -382.728724) (xy 337.680741 -382.718571) (xy 337.688529 -382.699819) (xy 337.70292 -382.685495)
			(xy 337.721708 -382.677795) (xy 337.731862 -382.677416) (xy 338.448142 -382.677416) (xy 338.458268 -382.677891)
			(xy 338.476986 -382.685629) (xy 338.49134 -382.699918) (xy 338.499162 -382.7186) (xy 338.499704 -382.728724)
			(xy 338.499704 -382.886712) (xy 338.500108 -382.8959) (xy 338.506626 -382.913084) (xy 338.512404 -382.92024)
			(xy 338.534155 -382.945922) (xy 338.572102 -383.001505) (xy 338.603135 -383.061225) (xy 338.626808 -383.124225)
			(xy 338.642782 -383.189604) (xy 338.650828 -383.256422) (xy 338.650831 -383.323724) (xy 338.642791 -383.390543)
			(xy 338.626824 -383.455923) (xy 338.603157 -383.518926) (xy 338.57213 -383.578648) (xy 338.534188 -383.634235)
			(xy 338.512404 -383.659888) (xy 338.506588 -383.66702) (xy 338.500085 -383.68422) (xy 338.499704 -383.693416)
			(xy 338.499704 -384.186684) (xy 338.500121 -384.19587) (xy 338.50663 -384.213055) (xy 338.512404 -384.220212)
			(xy 338.534226 -384.245836) (xy 338.572171 -384.301427) (xy 338.6032 -384.361155) (xy 338.626869 -384.424163)
			(xy 338.642838 -384.489548) (xy 338.650879 -384.556374) (xy 338.650875 -384.623681) (xy 338.642828 -384.690505)
			(xy 338.626853 -384.755889) (xy 338.603178 -384.818894) (xy 338.572143 -384.878619) (xy 338.534193 -384.934207)
			(xy 338.512404 -384.95986) (xy 338.5066 -384.967) (xy 338.50009 -384.984194) (xy 338.499704 -384.993388)
			(xy 338.499704 -385.151376) (xy 338.499259 -385.161528) (xy 338.491472 -385.180279) (xy 338.477082 -385.194603)
			(xy 338.458296 -385.202305) (xy 338.448142 -385.202684) (xy 337.731862 -385.202684) (xy 337.721736 -385.202205)
			(xy 337.703018 -385.194469) (xy 337.688664 -385.180181) (xy 337.680842 -385.1615) (xy 337.6803 -385.151376)
			(xy 337.6803 -384.993388) (xy 337.679895 -384.9842) (xy 337.673378 -384.967016) (xy 337.6676 -384.95986)
			(xy 337.645849 -384.934178) (xy 337.607901 -384.878595) (xy 337.576869 -384.818875) (xy 337.553196 -384.755875)
			(xy 337.537221 -384.690497) (xy 337.529175 -384.623678) (xy 337.529172 -384.556376) (xy 337.537212 -384.489557)
			(xy 337.55318 -384.424177) (xy 337.576847 -384.361174) (xy 337.607874 -384.301451) (xy 337.645816 -384.245865)
			(xy 337.6676 -384.220212) (xy 337.673416 -384.213081) (xy 337.679919 -384.19588) (xy 337.6803 -384.186684)
			(xy 337.6803 -383.693416) (xy 337.679882 -383.68423) (xy 337.673374 -383.667045) (xy 337.6676 -383.659888)
			(xy 337.645778 -383.634264) (xy 337.607833 -383.578673) (xy 337.576803 -383.518945) (xy 337.553134 -383.455937)
			(xy 337.537165 -383.390552) (xy 337.529124 -383.323726) (xy 336.427018 -383.323726) (xy 336.427146 -383.324067)
			(xy 336.443182 -383.389559) (xy 336.451257 -383.456499) (xy 336.451256 -383.523925) (xy 336.443177 -383.590865)
			(xy 336.427139 -383.656356) (xy 336.403371 -383.719453) (xy 336.372216 -383.77925) (xy 336.334122 -383.834883)
			(xy 336.312256 -383.860548) (xy 336.306451 -383.867687) (xy 336.299943 -383.884882) (xy 336.299556 -383.894076)
			(xy 336.299556 -384.051556) (xy 336.29898 -384.061655) (xy 336.291267 -384.080321) (xy 336.276999 -384.094616)
			(xy 336.258346 -384.102362) (xy 336.248248 -384.102864) (xy 335.531968 -384.102864) (xy 335.521839 -384.102509)
			(xy 335.503128 -384.094744) (xy 335.488813 -384.080408) (xy 335.481076 -384.061686) (xy 335.48066 -384.051556)
			(xy 335.48066 -383.894076) (xy 335.480248 -383.884889) (xy 335.473734 -383.867706) (xy 335.46796 -383.860548)
			(xy 335.446113 -383.834869) (xy 335.408027 -383.779236) (xy 335.376877 -383.719441) (xy 335.353114 -383.656346)
			(xy 335.337079 -383.590859) (xy 335.329002 -383.523923) (xy 335.329001 -383.456501) (xy 335.337074 -383.389565)
			(xy 335.353107 -383.324077) (xy 335.376868 -383.260981) (xy 335.408014 -383.201185) (xy 335.446098 -383.14555)
			(xy 335.46796 -383.119884) (xy 335.473753 -383.112737) (xy 335.480268 -383.095548) (xy 335.48066 -383.086356)
			(xy 335.48066 -382.59385) (xy 335.480213 -382.584667) (xy 335.473723 -382.567483) (xy 335.46796 -382.560322)
			(xy 335.446088 -382.534664) (xy 335.408002 -382.479028) (xy 335.376854 -382.41923) (xy 335.353092 -382.356132)
			(xy 335.337058 -382.290643) (xy 335.328984 -382.223704) (xy 332.050913 -382.223704) (xy 332.042877 -382.290466)
			(xy 332.026905 -382.355848) (xy 332.003234 -382.418852) (xy 331.972202 -382.478575) (xy 331.934255 -382.534162)
			(xy 331.912468 -382.559814) (xy 331.906679 -382.566964) (xy 331.90016 -382.584151) (xy 331.899768 -382.593342)
			(xy 331.899768 -383.086864) (xy 331.900203 -383.096048) (xy 331.9067 -383.113233) (xy 331.912468 -383.120392)
			(xy 331.934271 -383.146031) (xy 331.972219 -383.20162) (xy 332.003251 -383.261345) (xy 332.026711 -383.323786)
			(xy 333.128805 -383.323786) (xy 333.128808 -383.25636) (xy 333.136888 -383.189419) (xy 333.152927 -383.123927)
			(xy 333.176696 -383.060829) (xy 333.207852 -383.001032) (xy 333.245945 -382.945397) (xy 333.267812 -382.919732)
			(xy 333.273621 -382.912596) (xy 333.280128 -382.895398) (xy 333.280512 -382.886204) (xy 333.280512 -382.728724)
			(xy 333.280936 -382.718602) (xy 333.288678 -382.699896) (xy 333.302993 -382.685581) (xy 333.321698 -382.677837)
			(xy 333.33182 -382.677416) (xy 334.0481 -382.677416) (xy 334.058224 -382.677816) (xy 334.076931 -382.685568)
			(xy 334.091246 -382.699889) (xy 334.098988 -382.718599) (xy 334.099408 -382.728724) (xy 334.099408 -382.886204)
			(xy 334.099815 -382.895392) (xy 334.106331 -382.912576) (xy 334.112108 -382.919732) (xy 334.133936 -382.945427)
			(xy 334.172026 -383.001057) (xy 334.203177 -383.060849) (xy 334.226943 -383.123942) (xy 334.242981 -383.189428)
			(xy 334.25106 -383.256363) (xy 334.251063 -383.323783) (xy 334.242991 -383.390719) (xy 334.226959 -383.456206)
			(xy 334.2032 -383.519301) (xy 334.172053 -383.579096) (xy 334.13397 -383.634731) (xy 334.112108 -383.660396)
			(xy 334.106332 -383.667556) (xy 334.099805 -383.684735) (xy 334.099408 -383.693924) (xy 334.099408 -384.186176)
			(xy 334.099828 -384.195362) (xy 334.106335 -384.212547) (xy 334.112108 -384.219704) (xy 334.134007 -384.24534)
			(xy 334.172094 -384.300979) (xy 334.203243 -384.360779) (xy 334.227005 -384.42388) (xy 334.243037 -384.489373)
			(xy 334.25111 -384.556314) (xy 334.251107 -384.62374) (xy 334.243028 -384.690681) (xy 334.226989 -384.756172)
			(xy 334.203221 -384.81927) (xy 334.172066 -384.879067) (xy 334.133974 -384.934703) (xy 334.112108 -384.960368)
			(xy 334.106301 -384.967506) (xy 334.099792 -384.984702) (xy 334.099408 -384.993896) (xy 334.099408 -385.151376)
			(xy 334.098965 -385.161496) (xy 334.091226 -385.180198) (xy 334.076918 -385.194512) (xy 334.05822 -385.20226)
			(xy 334.0481 -385.202684) (xy 333.33182 -385.202684) (xy 333.321697 -385.202267) (xy 333.302991 -385.194523)
			(xy 333.288675 -385.180206) (xy 333.280932 -385.161499) (xy 333.280512 -385.151376) (xy 333.280512 -384.993896)
			(xy 333.280101 -384.984709) (xy 333.273587 -384.967525) (xy 333.267812 -384.960368) (xy 333.245983 -384.934674)
			(xy 333.207892 -384.879044) (xy 333.176739 -384.819252) (xy 333.152973 -384.756158) (xy 333.136934 -384.690673)
			(xy 333.128855 -384.623738) (xy 333.128852 -384.556316) (xy 333.136925 -384.48938) (xy 333.152957 -384.423893)
			(xy 333.176717 -384.360798) (xy 333.207865 -384.301003) (xy 333.24595 -384.245369) (xy 333.267812 -384.219704)
			(xy 333.273591 -384.212546) (xy 333.280116 -384.195365) (xy 333.280512 -384.186176) (xy 333.280512 -383.693924)
			(xy 333.280088 -383.684738) (xy 333.273583 -383.667554) (xy 333.267812 -383.660396) (xy 333.245912 -383.63476)
			(xy 333.207824 -383.579122) (xy 333.176674 -383.519322) (xy 333.152911 -383.456221) (xy 333.136878 -383.390728)
			(xy 333.128805 -383.323786) (xy 332.026711 -383.323786) (xy 332.026923 -383.324351) (xy 332.042895 -383.389735)
			(xy 332.050937 -383.456559) (xy 332.050936 -383.523865) (xy 332.04289 -383.590689) (xy 332.026916 -383.656072)
			(xy 332.003242 -383.719077) (xy 331.972207 -383.778801) (xy 331.934257 -383.834388) (xy 331.912468 -383.86004)
			(xy 331.906668 -383.867183) (xy 331.900156 -383.884375) (xy 331.899768 -383.893568) (xy 331.899768 -384.051556)
			(xy 331.899342 -384.061711) (xy 331.891555 -384.080469) (xy 331.877159 -384.094795) (xy 331.858363 -384.10249)
			(xy 331.848206 -384.102864) (xy 331.131926 -384.102864) (xy 331.121801 -384.102352) (xy 331.103082 -384.094634)
			(xy 331.088724 -384.080355) (xy 331.080904 -384.061678) (xy 331.080364 -384.051556) (xy 331.080364 -383.893568)
			(xy 331.079955 -383.884381) (xy 331.073439 -383.867198) (xy 331.067664 -383.86004) (xy 331.045891 -383.834375)
			(xy 331.00794 -383.778791) (xy 330.976905 -383.71907) (xy 330.95323 -383.656067) (xy 330.937256 -383.590686)
			(xy 330.92921 -383.523864) (xy 330.929208 -383.45656) (xy 330.937251 -383.389738) (xy 330.953223 -383.324356)
			(xy 330.976895 -383.261352) (xy 331.007928 -383.20163) (xy 331.045877 -383.146044) (xy 331.067664 -383.120392)
			(xy 331.073454 -383.113243) (xy 331.079971 -383.096055) (xy 331.080364 -383.086864) (xy 331.080364 -382.593342)
			(xy 331.079919 -382.584159) (xy 331.073428 -382.566975) (xy 331.067664 -382.559814) (xy 331.045866 -382.53417)
			(xy 331.007916 -382.478583) (xy 330.976881 -382.418859) (xy 330.953208 -382.355853) (xy 330.937235 -382.29047)
			(xy 330.929191 -382.223646) (xy 301.250888 -382.223646) (xy 301.250888 -382.223704) (xy 301.242813 -382.290641)
			(xy 301.226779 -382.356129) (xy 301.203017 -382.419226) (xy 301.171869 -382.479022) (xy 301.133783 -382.534656)
			(xy 301.11192 -382.560322) (xy 301.106134 -382.567475) (xy 301.099612 -382.584659) (xy 301.09922 -382.59385)
			(xy 301.09922 -383.086356) (xy 301.099647 -383.095542) (xy 301.106148 -383.112726) (xy 301.11192 -383.119884)
			(xy 301.133799 -383.145537) (xy 301.171886 -383.201173) (xy 301.203035 -383.260972) (xy 301.22669 -383.323786)
			(xy 302.328775 -383.323786) (xy 302.328778 -383.25636) (xy 302.336857 -383.18942) (xy 302.352895 -383.123929)
			(xy 302.376662 -383.060831) (xy 302.407816 -383.001033) (xy 302.445907 -382.945398) (xy 302.467772 -382.919732)
			(xy 302.473589 -382.912601) (xy 302.480089 -382.895399) (xy 302.480472 -382.886204) (xy 302.480472 -382.728724)
			(xy 302.480935 -382.718606) (xy 302.48867 -382.699909) (xy 302.502972 -382.685595) (xy 302.521663 -382.677843)
			(xy 302.53178 -382.677416) (xy 303.24806 -382.677416) (xy 303.258182 -382.677849) (xy 303.276888 -382.685587)
			(xy 303.291204 -382.699899) (xy 303.298948 -382.718602) (xy 303.299368 -382.728724) (xy 303.299368 -382.886204)
			(xy 303.299783 -382.89539) (xy 303.306294 -382.912575) (xy 303.312068 -382.919732) (xy 303.333898 -382.945426)
			(xy 303.37199 -383.001056) (xy 303.403144 -383.060847) (xy 303.426911 -383.123941) (xy 303.44295 -383.189427)
			(xy 303.451029 -383.256362) (xy 303.451033 -383.323784) (xy 303.44296 -383.39072) (xy 303.426927 -383.456208)
			(xy 303.403166 -383.519303) (xy 303.372017 -383.579098) (xy 303.333931 -383.634731) (xy 303.312068 -383.660396)
			(xy 303.306286 -383.667552) (xy 303.299764 -383.684734) (xy 303.299368 -383.693924) (xy 303.299368 -384.186176)
			(xy 303.299797 -384.195361) (xy 303.306299 -384.212545) (xy 303.312068 -384.219704) (xy 303.333968 -384.24534)
			(xy 303.372058 -384.300978) (xy 303.403209 -384.360778) (xy 303.426973 -384.423878) (xy 303.443007 -384.489371)
			(xy 303.45108 -384.556313) (xy 303.451077 -384.623741) (xy 303.442997 -384.690682) (xy 303.426957 -384.756173)
			(xy 303.403187 -384.819272) (xy 303.37203 -384.879069) (xy 303.333935 -384.934703) (xy 303.312068 -384.960368)
			(xy 303.306256 -384.967502) (xy 303.299751 -384.984701) (xy 303.299368 -384.993896) (xy 303.299368 -385.151376)
			(xy 303.298964 -385.161501) (xy 303.291218 -385.18021) (xy 303.276897 -385.194527) (xy 303.258185 -385.202267)
			(xy 303.24806 -385.202684) (xy 302.53178 -385.202684) (xy 302.521654 -385.2023) (xy 302.502947 -385.194542)
			(xy 302.488633 -385.180216) (xy 302.480891 -385.161502) (xy 302.480472 -385.151376) (xy 302.480472 -384.993896)
			(xy 302.48007 -384.984708) (xy 302.473551 -384.967523) (xy 302.467772 -384.960368) (xy 302.445944 -384.934673)
			(xy 302.407856 -384.879042) (xy 302.376706 -384.81925) (xy 302.352941 -384.756157) (xy 302.336904 -384.690672)
			(xy 302.328825 -384.623737) (xy 302.328822 -384.556317) (xy 302.336894 -384.489382) (xy 302.352925 -384.423895)
			(xy 302.376684 -384.3608) (xy 302.407829 -384.301004) (xy 302.445911 -384.24537) (xy 302.467772 -384.219704)
			(xy 302.473558 -384.212552) (xy 302.480077 -384.195366) (xy 302.480472 -384.186176) (xy 302.480472 -383.693924)
			(xy 302.480057 -383.684737) (xy 302.473547 -383.667552) (xy 302.467772 -383.660396) (xy 302.445874 -383.634759)
			(xy 302.407788 -383.57912) (xy 302.37664 -383.51932) (xy 302.352879 -383.456219) (xy 302.336847 -383.390727)
			(xy 302.328775 -383.323786) (xy 301.22669 -383.323786) (xy 301.226797 -383.32407) (xy 301.242831 -383.38956)
			(xy 301.250905 -383.4565) (xy 301.250904 -383.523924) (xy 301.242827 -383.590863) (xy 301.22679 -383.656353)
			(xy 301.203025 -383.71945) (xy 301.171874 -383.779247) (xy 301.133784 -383.834882) (xy 301.11192 -383.860548)
			(xy 301.106123 -383.867693) (xy 301.099608 -383.884884) (xy 301.09922 -383.894076) (xy 301.09922 -384.051556)
			(xy 301.098748 -384.061673) (xy 301.091018 -384.080372) (xy 301.076719 -384.094687) (xy 301.058029 -384.102437)
			(xy 301.047912 -384.102864) (xy 300.331632 -384.102864) (xy 300.321507 -384.102457) (xy 300.302797 -384.094713)
			(xy 300.28848 -384.080393) (xy 300.28074 -384.061681) (xy 300.280324 -384.051556) (xy 300.280324 -383.894076)
			(xy 300.27992 -383.884888) (xy 300.273402 -383.867704) (xy 300.267624 -383.860548) (xy 300.245775 -383.83487)
			(xy 300.207684 -383.779238) (xy 300.176531 -383.719444) (xy 300.152765 -383.656349) (xy 300.136728 -383.590861)
			(xy 300.12865 -383.523923) (xy 300.128649 -383.456501) (xy 300.136724 -383.389563) (xy 300.152758 -383.324074)
			(xy 300.176522 -383.260978) (xy 300.207672 -383.201183) (xy 300.24576 -383.145549) (xy 300.267624 -383.119884)
			(xy 300.273413 -383.112733) (xy 300.279931 -383.095547) (xy 300.280324 -383.086356) (xy 300.280324 -382.59385)
			(xy 300.279884 -382.584666) (xy 300.273391 -382.567482) (xy 300.267624 -382.560322) (xy 300.245749 -382.534665)
			(xy 300.207659 -382.47903) (xy 300.176508 -382.419233) (xy 300.152743 -382.356135) (xy 300.136708 -382.290645)
			(xy 300.128632 -382.223705) (xy 296.851097 -382.223705) (xy 296.843022 -382.290641) (xy 296.826989 -382.356129)
			(xy 296.803227 -382.419225) (xy 296.77208 -382.479021) (xy 296.733994 -382.534656) (xy 296.712132 -382.560322)
			(xy 296.706335 -382.567467) (xy 296.699823 -382.584658) (xy 296.699432 -382.59385) (xy 296.699432 -383.086356)
			(xy 296.699878 -383.095539) (xy 296.706368 -383.112723) (xy 296.712132 -383.119884) (xy 296.734011 -383.145537)
			(xy 296.772097 -383.201174) (xy 296.803245 -383.260972) (xy 296.826877 -383.323727) (xy 297.928982 -383.323727)
			(xy 297.928985 -383.256419) (xy 297.937033 -383.189593) (xy 297.953011 -383.124208) (xy 297.97669 -383.061202)
			(xy 298.007729 -383.001478) (xy 298.045685 -382.945891) (xy 298.067476 -382.92024) (xy 298.073278 -382.913098)
			(xy 298.07979 -382.895905) (xy 298.080176 -382.886712) (xy 298.080176 -382.728724) (xy 298.080641 -382.718574)
			(xy 298.088424 -382.699827) (xy 298.102807 -382.685504) (xy 298.121587 -382.677799) (xy 298.131738 -382.677416)
			(xy 298.848018 -382.677416) (xy 298.858143 -382.677911) (xy 298.87686 -382.68564) (xy 298.891215 -382.699923)
			(xy 298.899038 -382.718602) (xy 298.89958 -382.728724) (xy 298.89958 -382.886712) (xy 298.899989 -382.895899)
			(xy 298.906504 -382.913083) (xy 298.91228 -382.92024) (xy 298.934031 -382.945922) (xy 298.97198 -383.001504)
			(xy 299.003014 -383.061224) (xy 299.026688 -383.124225) (xy 299.042663 -383.189603) (xy 299.050709 -383.256422)
			(xy 299.050713 -383.323724) (xy 299.042672 -383.390544) (xy 299.026704 -383.455924) (xy 299.003036 -383.518926)
			(xy 298.972008 -383.578649) (xy 298.934065 -383.634235) (xy 298.91228 -383.659888) (xy 298.906461 -383.667017)
			(xy 298.89996 -383.68422) (xy 298.89958 -383.693416) (xy 298.89958 -384.186684) (xy 298.900003 -384.19587)
			(xy 298.906508 -384.213054) (xy 298.91228 -384.220212) (xy 298.934103 -384.245835) (xy 298.972049 -384.301426)
			(xy 299.00308 -384.361154) (xy 299.02675 -384.424162) (xy 299.04272 -384.489548) (xy 299.050761 -384.556373)
			(xy 299.050757 -384.623681) (xy 299.04271 -384.690506) (xy 299.026734 -384.75589) (xy 299.003058 -384.818895)
			(xy 298.972021 -384.87862) (xy 298.934069 -384.934208) (xy 298.91228 -384.95986) (xy 298.906473 -384.966998)
			(xy 298.899965 -384.984194) (xy 298.89958 -384.993388) (xy 298.89958 -385.151376) (xy 298.899159 -385.161531)
			(xy 298.891367 -385.180287) (xy 298.87697 -385.194612) (xy 298.858175 -385.202309) (xy 298.848018 -385.202684)
			(xy 298.131738 -385.202684) (xy 298.121617 -385.202143) (xy 298.102901 -385.194432) (xy 298.088544 -385.180162)
			(xy 298.08072 -385.161494) (xy 298.080176 -385.151376) (xy 298.080176 -384.993388) (xy 298.079777 -384.9842)
			(xy 298.073256 -384.967015) (xy 298.067476 -384.95986) (xy 298.045723 -384.934179) (xy 298.00777 -384.878598)
			(xy 297.976733 -384.818878) (xy 297.953057 -384.755878) (xy 297.93708 -384.690499) (xy 297.929033 -384.623679)
			(xy 297.92903 -384.556376) (xy 297.937071 -384.489555) (xy 297.953041 -384.424174) (xy 297.976711 -384.361171)
			(xy 298.007742 -384.301449) (xy 298.045689 -384.245864) (xy 298.067476 -384.220212) (xy 298.07329 -384.213079)
			(xy 298.079795 -384.195879) (xy 298.080176 -384.186684) (xy 298.080176 -383.693416) (xy 298.079764 -383.684229)
			(xy 298.073252 -383.667044) (xy 298.067476 -383.659888) (xy 298.045651 -383.634266) (xy 298.007701 -383.578676)
			(xy 297.976668 -383.518948) (xy 297.952995 -383.45594) (xy 297.937024 -383.390554) (xy 297.928982 -383.323727)
			(xy 296.826877 -383.323727) (xy 296.827007 -383.324071) (xy 296.84304 -383.389561) (xy 296.851114 -383.4565)
			(xy 296.851113 -383.523924) (xy 296.843036 -383.590863) (xy 296.827 -383.656352) (xy 296.803235 -383.71945)
			(xy 296.772084 -383.779247) (xy 296.733996 -383.834882) (xy 296.712132 -383.860548) (xy 296.706324 -383.867685)
			(xy 296.699818 -383.884882) (xy 296.699432 -383.894076) (xy 296.699432 -384.051556) (xy 296.698949 -384.061672)
			(xy 296.691221 -384.080368) (xy 296.676925 -384.094683) (xy 296.658239 -384.102435) (xy 296.648124 -384.102864)
			(xy 295.931844 -384.102864) (xy 295.92172 -384.102447) (xy 295.90301 -384.094707) (xy 295.888693 -384.08039)
			(xy 295.880953 -384.06168) (xy 295.880536 -384.051556) (xy 295.880536 -383.894076) (xy 295.880129 -383.884889)
			(xy 295.873612 -383.867705) (xy 295.867836 -383.860548) (xy 295.845986 -383.83487) (xy 295.807895 -383.779238)
			(xy 295.776742 -383.719444) (xy 295.752975 -383.656349) (xy 295.736937 -383.590861) (xy 295.728859 -383.523924)
			(xy 295.728858 -383.4565) (xy 295.736933 -383.389563) (xy 295.752968 -383.324074) (xy 295.776732 -383.260978)
			(xy 295.807883 -383.201182) (xy 295.845972 -383.145549) (xy 295.867836 -383.119884) (xy 295.873626 -383.112735)
			(xy 295.880144 -383.095547) (xy 295.880536 -383.086356) (xy 295.880536 -382.59385) (xy 295.880094 -382.584666)
			(xy 295.873601 -382.567482) (xy 295.867836 -382.560322) (xy 295.845961 -382.534665) (xy 295.80787 -382.479031)
			(xy 295.776718 -382.419233) (xy 295.752953 -382.356135) (xy 295.736917 -382.290645) (xy 295.728841 -382.223705)
			(xy 292.450794 -382.223705) (xy 292.442758 -382.290467) (xy 292.426786 -382.355849) (xy 292.403113 -382.418853)
			(xy 292.37208 -382.478576) (xy 292.334131 -382.534162) (xy 292.312344 -382.559814) (xy 292.306552 -382.566962)
			(xy 292.300036 -382.584151) (xy 292.299644 -382.593342) (xy 292.299644 -383.086864) (xy 292.300084 -383.096048)
			(xy 292.306578 -383.113232) (xy 292.312344 -383.120392) (xy 292.334148 -383.146031) (xy 292.372098 -383.201619)
			(xy 292.403131 -383.261344) (xy 292.426592 -383.323786) (xy 293.528687 -383.323786) (xy 293.52869 -383.25636)
			(xy 293.536769 -383.189419) (xy 293.552808 -383.123928) (xy 293.576576 -383.06083) (xy 293.60773 -383.001033)
			(xy 293.645822 -382.945397) (xy 293.667688 -382.919732) (xy 293.673495 -382.912594) (xy 293.680004 -382.895398)
			(xy 293.680388 -382.886204) (xy 293.680388 -382.728724) (xy 293.680835 -382.718605) (xy 293.688573 -382.699904)
			(xy 293.70288 -382.685589) (xy 293.721577 -382.677841) (xy 293.731696 -382.677416) (xy 294.447976 -382.677416)
			(xy 294.458099 -382.677836) (xy 294.476805 -382.685579) (xy 294.491121 -382.699895) (xy 294.498864 -382.718601)
			(xy 294.499284 -382.728724) (xy 294.499284 -382.886204) (xy 294.499696 -382.895391) (xy 294.506209 -382.912575)
			(xy 294.511984 -382.919732) (xy 294.533813 -382.945426) (xy 294.571904 -383.001056) (xy 294.603057 -383.060848)
			(xy 294.626824 -383.123941) (xy 294.642863 -383.189427) (xy 294.650942 -383.256362) (xy 294.650945 -383.323784)
			(xy 294.642872 -383.39072) (xy 294.62684 -383.456207) (xy 294.603079 -383.519302) (xy 294.571932 -383.579097)
			(xy 294.533846 -383.634731) (xy 294.511984 -383.660396) (xy 294.506205 -383.667553) (xy 294.49968 -383.684735)
			(xy 294.499284 -383.693924) (xy 294.499284 -384.186176) (xy 294.499709 -384.195361) (xy 294.506213 -384.212546)
			(xy 294.511984 -384.219704) (xy 294.533884 -384.24534) (xy 294.571973 -384.300978) (xy 294.603123 -384.360778)
			(xy 294.626885 -384.423879) (xy 294.642919 -384.489372) (xy 294.650992 -384.556314) (xy 294.650989 -384.62374)
			(xy 294.642909 -384.690681) (xy 294.626869 -384.756173) (xy 294.603101 -384.819271) (xy 294.571945 -384.879068)
			(xy 294.533851 -384.934703) (xy 294.511984 -384.960368) (xy 294.506174 -384.967504) (xy 294.499668 -384.984702)
			(xy 294.499284 -384.993896) (xy 294.499284 -385.151376) (xy 294.498864 -385.161499) (xy 294.491121 -385.180205)
			(xy 294.476805 -385.194521) (xy 294.458099 -385.202264) (xy 294.447976 -385.202684) (xy 293.731696 -385.202684)
			(xy 293.721571 -385.202287) (xy 293.702865 -385.194534) (xy 293.68855 -385.180212) (xy 293.680808 -385.161501)
			(xy 293.680388 -385.151376) (xy 293.680388 -384.993896) (xy 293.679982 -384.984708) (xy 293.673466 -384.967524)
			(xy 293.667688 -384.960368) (xy 293.64586 -384.934673) (xy 293.607771 -384.879043) (xy 293.576619 -384.819251)
			(xy 293.552854 -384.756158) (xy 293.536816 -384.690672) (xy 293.528737 -384.623737) (xy 293.528734 -384.556317)
			(xy 293.536806 -384.489381) (xy 293.552838 -384.423894) (xy 293.576597 -384.360799) (xy 293.607743 -384.301004)
			(xy 293.645827 -384.245369) (xy 293.667688 -384.219704) (xy 293.673464 -384.212544) (xy 293.679991 -384.195365)
			(xy 293.680388 -384.186176) (xy 293.680388 -383.693924) (xy 293.679969 -383.684738) (xy 293.673462 -383.667553)
			(xy 293.667688 -383.660396) (xy 293.645789 -383.63476) (xy 293.607702 -383.579121) (xy 293.576554 -383.51932)
			(xy 293.552792 -383.45622) (xy 293.53676 -383.390727) (xy 293.528687 -383.323786) (xy 292.426592 -383.323786)
			(xy 292.426804 -383.32435) (xy 292.442776 -383.389734) (xy 292.450819 -383.456559) (xy 292.450818 -383.523865)
			(xy 292.442772 -383.590689) (xy 292.426797 -383.656073) (xy 292.403121 -383.719078) (xy 292.372085 -383.778802)
			(xy 292.334133 -383.834388) (xy 292.312344 -383.86004) (xy 292.306541 -383.86718) (xy 292.300032 -383.884375)
			(xy 292.299644 -383.893568) (xy 292.299644 -384.051556) (xy 292.299149 -384.06167) (xy 292.291423 -384.080364)
			(xy 292.277132 -384.094679) (xy 292.258449 -384.102433) (xy 292.248336 -384.102864) (xy 291.531802 -384.102864)
			(xy 291.521676 -384.102372) (xy 291.502956 -384.094645) (xy 291.488599 -384.080361) (xy 291.480779 -384.06168)
			(xy 291.48024 -384.051556) (xy 291.48024 -383.893568) (xy 291.479836 -383.88438) (xy 291.473317 -383.867197)
			(xy 291.46754 -383.86004) (xy 291.445768 -383.834375) (xy 291.407819 -383.77879) (xy 291.376785 -383.719068)
			(xy 291.353111 -383.656066) (xy 291.337137 -383.590685) (xy 291.329092 -383.523864) (xy 291.32909 -383.45656)
			(xy 291.337133 -383.389739) (xy 291.353104 -383.324357) (xy 291.376775 -383.261354) (xy 291.407806 -383.20163)
			(xy 291.445753 -383.146044) (xy 291.46754 -383.120392) (xy 291.473328 -383.113241) (xy 291.479847 -383.096055)
			(xy 291.48024 -383.086864) (xy 291.48024 -382.593342) (xy 291.4798 -382.584158) (xy 291.473306 -382.566974)
			(xy 291.46754 -382.559814) (xy 291.445742 -382.53417) (xy 291.407794 -382.478582) (xy 291.376761 -382.418858)
			(xy 291.353088 -382.355852) (xy 291.337116 -382.290469) (xy 291.329073 -382.223645) (xy 288.051034 -382.223645)
			(xy 288.051034 -382.223704) (xy 288.042958 -382.290643) (xy 288.026922 -382.356132) (xy 288.003157 -382.419229)
			(xy 287.972004 -382.479024) (xy 287.933913 -382.534658) (xy 287.912048 -382.560322) (xy 287.906253 -382.567468)
			(xy 287.899739 -382.584658) (xy 287.899348 -382.59385) (xy 287.899348 -383.086356) (xy 287.899791 -383.095539)
			(xy 287.906283 -383.112723) (xy 287.912048 -383.119884) (xy 287.93393 -383.145535) (xy 287.972021 -383.201171)
			(xy 288.003174 -383.260968) (xy 288.026812 -383.323727) (xy 289.128894 -383.323727) (xy 289.128898 -383.256418)
			(xy 289.136946 -383.189593) (xy 289.152924 -383.124208) (xy 289.176604 -383.061202) (xy 289.207644 -383.001477)
			(xy 289.245601 -382.945891) (xy 289.267392 -382.92024) (xy 289.273196 -382.9131) (xy 289.279706 -382.895905)
			(xy 289.280092 -382.886712) (xy 289.280092 -382.728724) (xy 289.280535 -382.718604) (xy 289.288274 -382.699902)
			(xy 289.302582 -382.685588) (xy 289.32128 -382.67784) (xy 289.3314 -382.677416) (xy 290.047934 -382.677416)
			(xy 290.05806 -382.677898) (xy 290.076777 -382.685632) (xy 290.091132 -382.69992) (xy 290.098954 -382.7186)
			(xy 290.099496 -382.728724) (xy 290.099496 -382.886712) (xy 290.099901 -382.8959) (xy 290.106419 -382.913084)
			(xy 290.112196 -382.92024) (xy 290.133947 -382.945922) (xy 290.171895 -383.001505) (xy 290.202928 -383.061225)
			(xy 290.226601 -383.124225) (xy 290.242576 -383.189603) (xy 290.250622 -383.256422) (xy 290.250625 -383.323724)
			(xy 290.242585 -383.390543) (xy 290.226617 -383.455923) (xy 290.20295 -383.518926) (xy 290.171923 -383.578649)
			(xy 290.133981 -383.634235) (xy 290.112196 -383.659888) (xy 290.106379 -383.667019) (xy 290.099877 -383.68422)
			(xy 290.099496 -383.693416) (xy 290.099496 -384.186684) (xy 290.099915 -384.19587) (xy 290.106423 -384.213055)
			(xy 290.112196 -384.220212) (xy 290.134018 -384.245836) (xy 290.171963 -384.301427) (xy 290.202993 -384.361155)
			(xy 290.226662 -384.424163) (xy 290.242632 -384.489548) (xy 290.250673 -384.556373) (xy 290.250669 -384.623681)
			(xy 290.242622 -384.690505) (xy 290.226646 -384.755889) (xy 290.202971 -384.818895) (xy 290.171936 -384.87862)
			(xy 290.133985 -384.934207) (xy 290.112196 -384.95986) (xy 290.106391 -384.966999) (xy 290.099881 -384.984194)
			(xy 290.099496 -384.993388) (xy 290.099496 -385.151376) (xy 290.099064 -385.161497) (xy 290.091323 -385.180201)
			(xy 290.077011 -385.194517) (xy 290.058309 -385.202262) (xy 290.048188 -385.202684) (xy 289.331654 -385.202684)
			(xy 289.321527 -385.202212) (xy 289.30281 -385.194473) (xy 289.288456 -385.180183) (xy 289.280634 -385.1615)
			(xy 289.280092 -385.151376) (xy 289.280092 -384.993388) (xy 289.279689 -384.9842) (xy 289.273171 -384.967016)
			(xy 289.267392 -384.95986) (xy 289.245638 -384.934179) (xy 289.207685 -384.878598) (xy 289.176647 -384.818879)
			(xy 289.15297 -384.755878) (xy 289.136993 -384.690499) (xy 289.128945 -384.623679) (xy 289.128942 -384.556375)
			(xy 289.136983 -384.489554) (xy 289.152954 -384.424174) (xy 289.176625 -384.36117) (xy 289.207657 -384.301448)
			(xy 289.245605 -384.245863) (xy 289.267392 -384.220212) (xy 289.273208 -384.21308) (xy 289.279711 -384.195879)
			(xy 289.280092 -384.186684) (xy 289.280092 -383.693416) (xy 289.279676 -383.684229) (xy 289.273167 -383.667045)
			(xy 289.267392 -383.659888) (xy 289.245567 -383.634266) (xy 289.207616 -383.578676) (xy 289.176581 -383.518949)
			(xy 289.152908 -383.45594) (xy 289.136936 -383.390554) (xy 289.128894 -383.323727) (xy 288.026812 -383.323727)
			(xy 288.02694 -383.324067) (xy 288.042976 -383.389558) (xy 288.051051 -383.456499) (xy 288.05105 -383.523925)
			(xy 288.042971 -383.590865) (xy 288.026933 -383.656356) (xy 288.003164 -383.719454) (xy 287.972009 -383.77925)
			(xy 287.933915 -383.834884) (xy 287.912048 -383.860548) (xy 287.906242 -383.867686) (xy 287.899734 -383.884882)
			(xy 287.899348 -383.894076) (xy 287.899348 -384.051556) (xy 287.898849 -384.06167) (xy 287.891124 -384.080363)
			(xy 287.876834 -384.094677) (xy 287.858153 -384.102432) (xy 287.84804 -384.102864) (xy 287.13176 -384.102864)
			(xy 287.12163 -384.102516) (xy 287.102919 -384.094748) (xy 287.088605 -384.08041) (xy 287.080868 -384.061686)
			(xy 287.080452 -384.051556) (xy 287.080452 -383.894076) (xy 287.080042 -383.884889) (xy 287.073527 -383.867705)
			(xy 287.067752 -383.860548) (xy 287.045902 -383.834871) (xy 287.007809 -383.779239) (xy 286.976655 -383.719445)
			(xy 286.952888 -383.65635) (xy 286.936849 -383.590862) (xy 286.928772 -383.523924) (xy 286.92877 -383.4565)
			(xy 286.936845 -383.389562) (xy 286.952881 -383.324073) (xy 286.976645 -383.260977) (xy 287.007797 -383.201182)
			(xy 287.045887 -383.145548) (xy 287.067752 -383.119884) (xy 287.073544 -383.112736) (xy 287.08006 -383.095547)
			(xy 287.080452 -383.086356) (xy 287.080452 -382.59385) (xy 287.080006 -382.584667) (xy 287.073516 -382.567483)
			(xy 287.067752 -382.560322) (xy 287.045876 -382.534666) (xy 287.007785 -382.479031) (xy 286.976631 -382.419234)
			(xy 286.952865 -382.356136) (xy 286.936829 -382.290645) (xy 286.928753 -382.223705) (xy 262.274304 -382.223705)
			(xy 262.274304 -385.608376) (xy 454.303373 -385.608376) (xy 454.303373 -385.479236) (xy 454.311323 -385.350341)
			(xy 454.327193 -385.222181) (xy 454.350922 -385.09524) (xy 454.382421 -384.970001) (xy 454.42157 -384.846938)
			(xy 454.468221 -384.726519) (xy 454.522196 -384.6092) (xy 454.583291 -384.495426) (xy 454.651274 -384.385629)
			(xy 454.725888 -384.280226) (xy 454.806849 -384.179616) (xy 454.893849 -384.084181) (xy 454.98656 -383.994282)
			(xy 455.08463 -383.910261) (xy 455.187685 -383.832437) (xy 455.295336 -383.761105) (xy 455.407175 -383.696535)
			(xy 455.522776 -383.638973) (xy 455.641701 -383.588636) (xy 455.7635 -383.545716) (xy 455.88771 -383.510375)
			(xy 456.013859 -383.482748) (xy 456.141471 -383.462939) (xy 456.27006 -383.451023) (xy 456.399138 -383.447047)
			(xy 456.528216 -383.451023) (xy 456.656805 -383.462939) (xy 456.784417 -383.482748) (xy 456.910566 -383.510375)
			(xy 457.034776 -383.545716) (xy 457.156575 -383.588636) (xy 457.2755 -383.638973) (xy 457.391101 -383.696535)
			(xy 457.50294 -383.761105) (xy 457.610591 -383.832437) (xy 457.713646 -383.910261) (xy 457.811716 -383.994282)
			(xy 457.904427 -384.084181) (xy 457.991427 -384.179616) (xy 458.072388 -384.280226) (xy 458.147002 -384.385629)
			(xy 458.214985 -384.495426) (xy 458.27608 -384.6092) (xy 458.330055 -384.726519) (xy 458.376706 -384.846938)
			(xy 458.415855 -384.970001) (xy 458.447354 -385.09524) (xy 458.471083 -385.222181) (xy 458.486953 -385.350341)
			(xy 458.494903 -385.479236) (xy 458.4954 -385.543806) (xy 458.494903 -385.608376) (xy 458.486953 -385.737271)
			(xy 458.471083 -385.865431) (xy 458.447354 -385.992372) (xy 458.415855 -386.117611) (xy 458.376706 -386.240674)
			(xy 458.330055 -386.361093) (xy 458.27608 -386.478412) (xy 458.214985 -386.592186) (xy 458.147002 -386.701983)
			(xy 458.072388 -386.807386) (xy 457.991427 -386.907996) (xy 457.904427 -387.003431) (xy 457.811716 -387.09333)
			(xy 457.713646 -387.177351) (xy 457.610591 -387.255175) (xy 457.50294 -387.326507) (xy 457.391101 -387.391077)
			(xy 457.2755 -387.448639) (xy 457.156575 -387.498976) (xy 457.034776 -387.541896) (xy 456.910566 -387.577237)
			(xy 456.784417 -387.604864) (xy 456.656805 -387.624673) (xy 456.528216 -387.636589) (xy 456.399138 -387.640566)
			(xy 456.27006 -387.636589) (xy 456.141471 -387.624673) (xy 456.013859 -387.604864) (xy 455.88771 -387.577237)
			(xy 455.7635 -387.541896) (xy 455.641701 -387.498976) (xy 455.522776 -387.448639) (xy 455.407175 -387.391077)
			(xy 455.295336 -387.326507) (xy 455.187685 -387.255175) (xy 455.08463 -387.177351) (xy 454.98656 -387.09333)
			(xy 454.893849 -387.003431) (xy 454.806849 -386.907996) (xy 454.725888 -386.807386) (xy 454.651274 -386.701983)
			(xy 454.583291 -386.592186) (xy 454.522196 -386.478412) (xy 454.468221 -386.361093) (xy 454.42157 -386.240674)
			(xy 454.382421 -386.117611) (xy 454.350922 -385.992372) (xy 454.327193 -385.865431) (xy 454.311323 -385.737271)
			(xy 454.303373 -385.608376) (xy 262.274304 -385.608376) (xy 262.274304 -387.892798) (xy 262.273903 -387.902871)
			(xy 262.266168 -387.92147) (xy 262.259318 -387.928866) (xy 259.197602 -390.990582) (xy 259.190193 -390.997411)
			(xy 259.171601 -391.005138) (xy 259.161534 -391.005568) (xy 245.155466 -391.005568) (xy 245.143121 -391.006101)
			(xy 245.120249 -391.015389) (xy 245.111016 -391.023602) (xy 245.110508 -391.02411) (xy 244.084602 -392.050016)
			(xy 244.076151 -392.059207) (xy 244.066584 -392.082246) (xy 244.06606 -392.09472) (xy 244.06606 -397.823885)
			(xy 286.928734 -397.823885) (xy 286.928737 -397.756458) (xy 286.936817 -397.689516) (xy 286.952859 -397.624024)
			(xy 286.976629 -397.560925) (xy 287.007787 -397.501128) (xy 287.045884 -397.445494) (xy 287.067752 -397.41983)
			(xy 287.073567 -397.412698) (xy 287.080069 -397.395497) (xy 287.080452 -397.386302) (xy 287.080452 -396.89405)
			(xy 287.080006 -396.884867) (xy 287.073516 -396.867683) (xy 287.067752 -396.860522) (xy 287.045876 -396.834866)
			(xy 287.007785 -396.779231) (xy 286.976631 -396.719434) (xy 286.952865 -396.656336) (xy 286.936829 -396.590845)
			(xy 286.928753 -396.523905) (xy 286.928754 -396.45648) (xy 286.936832 -396.38954) (xy 286.95287 -396.32405)
			(xy 286.976638 -396.260952) (xy 287.007792 -396.201156) (xy 287.045886 -396.145522) (xy 287.067752 -396.119858)
			(xy 287.073555 -396.112718) (xy 287.080065 -396.095523) (xy 287.080452 -396.08633) (xy 287.080452 -395.92885)
			(xy 287.080968 -395.918725) (xy 287.088682 -395.900003) (xy 287.102959 -395.885644) (xy 287.121638 -395.877825)
			(xy 287.13176 -395.877288) (xy 287.84804 -395.877288) (xy 287.858195 -395.877689) (xy 287.876946 -395.885495)
			(xy 287.891268 -395.899898) (xy 287.898968 -395.918693) (xy 287.899348 -395.92885) (xy 287.899348 -396.08633)
			(xy 287.899755 -396.095517) (xy 287.906272 -396.112701) (xy 287.912048 -396.119858) (xy 287.933904 -396.14553)
			(xy 287.971996 -396.201163) (xy 288.00315 -396.260957) (xy 288.026917 -396.324053) (xy 288.042955 -396.389542)
			(xy 288.051033 -396.456481) (xy 288.051034 -396.523904) (xy 288.042958 -396.590843) (xy 288.026922 -396.656332)
			(xy 288.003157 -396.719429) (xy 287.972004 -396.779224) (xy 287.933913 -396.834858) (xy 287.912048 -396.860522)
			(xy 287.906253 -396.867668) (xy 287.899739 -396.884858) (xy 287.899348 -396.89405) (xy 287.899348 -397.386302)
			(xy 287.899769 -397.395488) (xy 287.906276 -397.412672) (xy 287.912048 -397.41983) (xy 287.933876 -397.445525)
			(xy 287.97197 -397.501154) (xy 288.000733 -397.556355) (xy 289.128926 -397.556355) (xy 289.13697 -397.489532)
			(xy 289.152943 -397.42415) (xy 289.176617 -397.361145) (xy 289.207652 -397.301423) (xy 289.245603 -397.245837)
			(xy 289.267392 -397.220186) (xy 289.273176 -397.213032) (xy 289.279698 -397.195848) (xy 289.280092 -397.186658)
			(xy 289.280092 -397.028924) (xy 289.280541 -397.018772) (xy 289.288327 -397.000022) (xy 289.302715 -396.985698)
			(xy 289.321501 -396.977996) (xy 289.331654 -396.977616) (xy 290.047934 -396.977616) (xy 290.05806 -396.978098)
			(xy 290.076777 -396.985832) (xy 290.091132 -397.00012) (xy 290.098954 -397.0188) (xy 290.099496 -397.028924)
			(xy 290.099496 -397.186658) (xy 290.099927 -397.195843) (xy 290.106426 -397.213027) (xy 290.112196 -397.220186)
			(xy 290.133992 -397.245831) (xy 290.171939 -397.301419) (xy 290.20297 -397.361144) (xy 290.22664 -397.424149)
			(xy 290.242612 -397.489532) (xy 290.250654 -397.556355) (xy 290.250653 -397.62366) (xy 290.242609 -397.690483)
			(xy 290.226636 -397.755865) (xy 290.202963 -397.81887) (xy 290.200388 -397.823825) (xy 291.329053 -397.823825)
			(xy 291.329057 -397.756517) (xy 291.337105 -397.689692) (xy 291.353082 -397.624308) (xy 291.376759 -397.561302)
			(xy 291.407796 -397.501577) (xy 291.44575 -397.44599) (xy 291.46754 -397.420338) (xy 291.47335 -397.413203)
			(xy 291.479856 -397.396004) (xy 291.48024 -397.38681) (xy 291.48024 -396.893542) (xy 291.4798 -396.884358)
			(xy 291.473306 -396.867174) (xy 291.46754 -396.860014) (xy 291.445742 -396.83437) (xy 291.407794 -396.778782)
			(xy 291.376761 -396.719058) (xy 291.353088 -396.656052) (xy 291.337116 -396.590669) (xy 291.329073 -396.523845)
			(xy 291.329074 -396.45654) (xy 291.337119 -396.389716) (xy 291.353093 -396.324333) (xy 291.376767 -396.261328)
			(xy 291.407801 -396.201605) (xy 291.445751 -396.146018) (xy 291.46754 -396.120366) (xy 291.473339 -396.113222)
			(xy 291.479851 -396.096031) (xy 291.48024 -396.086838) (xy 291.48024 -395.92885) (xy 291.480705 -395.918681)
			(xy 291.488474 -395.899887) (xy 291.502847 -395.885501) (xy 291.521634 -395.877714) (xy 291.531802 -395.877288)
			(xy 292.248082 -395.877288) (xy 292.258259 -395.87768) (xy 292.277063 -395.885468) (xy 292.29145 -395.899864)
			(xy 292.299227 -395.918673) (xy 292.299644 -395.92885) (xy 292.299644 -396.086838) (xy 292.300049 -396.096026)
			(xy 292.306568 -396.113209) (xy 292.312344 -396.120366) (xy 292.334122 -396.146026) (xy 292.372072 -396.201611)
			(xy 292.403107 -396.261333) (xy 292.426781 -396.324337) (xy 292.442755 -396.389718) (xy 292.450801 -396.45654)
			(xy 292.450801 -396.523845) (xy 292.442758 -396.590667) (xy 292.426786 -396.656049) (xy 292.403113 -396.719053)
			(xy 292.37208 -396.778776) (xy 292.334131 -396.834362) (xy 292.312344 -396.860014) (xy 292.306552 -396.867162)
			(xy 292.300036 -396.884351) (xy 292.299644 -396.893542) (xy 292.299644 -397.38681) (xy 292.300062 -397.395996)
			(xy 292.306572 -397.41318) (xy 292.312344 -397.420338) (xy 292.334095 -397.446021) (xy 292.372046 -397.501602)
			(xy 292.40047 -397.556296) (xy 293.528718 -397.556296) (xy 293.536793 -397.489359) (xy 293.552827 -397.42387)
			(xy 293.576589 -397.360774) (xy 293.607738 -397.300978) (xy 293.645825 -397.245343) (xy 293.667688 -397.219678)
			(xy 293.673475 -397.212526) (xy 293.679996 -397.195341) (xy 293.680388 -397.18615) (xy 293.680388 -397.028924)
			(xy 293.680835 -397.018805) (xy 293.688573 -397.000104) (xy 293.70288 -396.985789) (xy 293.721577 -396.978041)
			(xy 293.731696 -396.977616) (xy 294.447976 -396.977616) (xy 294.458099 -396.978036) (xy 294.476805 -396.985779)
			(xy 294.491121 -397.000095) (xy 294.498864 -397.018801) (xy 294.499284 -397.028924) (xy 294.499284 -397.18615)
			(xy 294.499722 -397.195334) (xy 294.506217 -397.212519) (xy 294.511984 -397.219678) (xy 294.533858 -397.245335)
			(xy 294.571948 -397.30097) (xy 294.603099 -397.360767) (xy 294.626863 -397.423865) (xy 294.642899 -397.489356)
			(xy 294.650974 -397.556295) (xy 294.650973 -397.62372) (xy 294.642896 -397.690659) (xy 294.626859 -397.756149)
			(xy 294.603093 -397.819246) (xy 294.600676 -397.823885) (xy 295.728821 -397.823885) (xy 295.728825 -397.756458)
			(xy 295.736905 -397.689516) (xy 295.752946 -397.624025) (xy 295.776716 -397.560926) (xy 295.807873 -397.501129)
			(xy 295.845969 -397.445495) (xy 295.867836 -397.41983) (xy 295.873649 -397.412697) (xy 295.880153 -397.395497)
			(xy 295.880536 -397.386302) (xy 295.880536 -396.89405) (xy 295.880094 -396.884866) (xy 295.873601 -396.867682)
			(xy 295.867836 -396.860522) (xy 295.845961 -396.834865) (xy 295.80787 -396.779231) (xy 295.776718 -396.719433)
			(xy 295.752953 -396.656335) (xy 295.736917 -396.590845) (xy 295.728841 -396.523905) (xy 295.728842 -396.45648)
			(xy 295.73692 -396.38954) (xy 295.752957 -396.32405) (xy 295.776724 -396.260953) (xy 295.807878 -396.201157)
			(xy 295.84597 -396.145523) (xy 295.867836 -396.119858) (xy 295.873637 -396.112716) (xy 295.880148 -396.095523)
			(xy 295.880536 -396.08633) (xy 295.880536 -395.92885) (xy 295.881067 -395.918727) (xy 295.888778 -395.900008)
			(xy 295.903051 -395.88565) (xy 295.921724 -395.877828) (xy 295.931844 -395.877288) (xy 296.648124 -395.877288)
			(xy 296.658278 -395.877702) (xy 296.677029 -395.885503) (xy 296.691351 -395.899902) (xy 296.699052 -395.918694)
			(xy 296.699432 -395.92885) (xy 296.699432 -396.08633) (xy 296.699843 -396.095517) (xy 296.706358 -396.1127)
			(xy 296.712132 -396.119858) (xy 296.733985 -396.145532) (xy 296.772072 -396.201166) (xy 296.803221 -396.260961)
			(xy 296.826985 -396.324057) (xy 296.84302 -396.389545) (xy 296.851096 -396.456481) (xy 296.851097 -396.523904)
			(xy 296.843022 -396.590841) (xy 296.826989 -396.656329) (xy 296.803227 -396.719425) (xy 296.77208 -396.779221)
			(xy 296.733994 -396.834856) (xy 296.712132 -396.860522) (xy 296.706335 -396.867667) (xy 296.699823 -396.884858)
			(xy 296.699432 -396.89405) (xy 296.699432 -397.386302) (xy 296.699856 -397.395487) (xy 296.706362 -397.412671)
			(xy 296.712132 -397.41983) (xy 296.733958 -397.445527) (xy 296.772045 -397.501157) (xy 296.800802 -397.556355)
			(xy 297.929014 -397.556355) (xy 297.937057 -397.489532) (xy 297.95303 -397.42415) (xy 297.976704 -397.361146)
			(xy 298.007738 -397.301423) (xy 298.045688 -397.245838) (xy 298.067476 -397.220186) (xy 298.073258 -397.21303)
			(xy 298.079782 -397.195848) (xy 298.080176 -397.186658) (xy 298.080176 -397.028924) (xy 298.080641 -397.018774)
			(xy 298.088424 -397.000027) (xy 298.102807 -396.985704) (xy 298.121587 -396.977999) (xy 298.131738 -396.977616)
			(xy 298.848018 -396.977616) (xy 298.858143 -396.978111) (xy 298.87686 -396.98584) (xy 298.891215 -397.000123)
			(xy 298.899038 -397.018802) (xy 298.89958 -397.028924) (xy 298.89958 -397.186658) (xy 298.900015 -397.195842)
			(xy 298.906512 -397.213027) (xy 298.91228 -397.220186) (xy 298.934077 -397.24583) (xy 298.972024 -397.301418)
			(xy 299.003056 -397.361143) (xy 299.026728 -397.424149) (xy 299.042699 -397.489532) (xy 299.050742 -397.556355)
			(xy 299.050741 -397.62366) (xy 299.042697 -397.690483) (xy 299.026723 -397.755866) (xy 299.00305 -397.818871)
			(xy 299.000445 -397.823885) (xy 300.128612 -397.823885) (xy 300.128616 -397.756458) (xy 300.136696 -397.689517)
			(xy 300.152736 -397.624025) (xy 300.176506 -397.560927) (xy 300.207662 -397.501129) (xy 300.245757 -397.445495)
			(xy 300.267624 -397.41983) (xy 300.273436 -397.412696) (xy 300.27994 -397.395497) (xy 300.280324 -397.386302)
			(xy 300.280324 -396.89405) (xy 300.279884 -396.884866) (xy 300.273391 -396.867682) (xy 300.267624 -396.860522)
			(xy 300.245749 -396.834865) (xy 300.207659 -396.77923) (xy 300.176508 -396.719433) (xy 300.152743 -396.656335)
			(xy 300.136708 -396.590845) (xy 300.128632 -396.523905) (xy 300.128633 -396.45648) (xy 300.13671 -396.389541)
			(xy 300.152748 -396.324051) (xy 300.176514 -396.260953) (xy 300.207667 -396.201157) (xy 300.245759 -396.145523)
			(xy 300.267624 -396.119858) (xy 300.273424 -396.112715) (xy 300.279936 -396.095523) (xy 300.280324 -396.08633)
			(xy 300.280324 -395.92885) (xy 300.280867 -395.918728) (xy 300.288576 -395.900011) (xy 300.302845 -395.885654)
			(xy 300.321514 -395.87783) (xy 300.331632 -395.877288) (xy 301.047912 -395.877288) (xy 301.058065 -395.877711)
			(xy 301.076816 -395.885509) (xy 301.091138 -395.899904) (xy 301.09884 -395.918694) (xy 301.09922 -395.92885)
			(xy 301.09922 -396.08633) (xy 301.099611 -396.095519) (xy 301.106138 -396.112704) (xy 301.11192 -396.119858)
			(xy 301.133773 -396.145532) (xy 301.171861 -396.201165) (xy 301.203011 -396.260961) (xy 301.226775 -396.324056)
			(xy 301.242811 -396.389544) (xy 301.250887 -396.456481) (xy 301.250888 -396.523904) (xy 301.242813 -396.590841)
			(xy 301.226779 -396.656329) (xy 301.203017 -396.719426) (xy 301.171869 -396.779222) (xy 301.133783 -396.834856)
			(xy 301.11192 -396.860522) (xy 301.106134 -396.867675) (xy 301.099612 -396.884859) (xy 301.09922 -396.89405)
			(xy 301.09922 -397.386302) (xy 301.099625 -397.39549) (xy 301.106142 -397.412674) (xy 301.11192 -397.41983)
			(xy 301.133746 -397.445526) (xy 301.171834 -397.501157) (xy 301.200562 -397.556296) (xy 302.328806 -397.556296)
			(xy 302.336881 -397.489359) (xy 302.352914 -397.423871) (xy 302.376676 -397.360775) (xy 302.407824 -397.300979)
			(xy 302.44591 -397.245344) (xy 302.467772 -397.219678) (xy 302.473569 -397.212534) (xy 302.480081 -397.195342)
			(xy 302.480472 -397.18615) (xy 302.480472 -397.028924) (xy 302.480935 -397.018806) (xy 302.48867 -397.000109)
			(xy 302.502972 -396.985795) (xy 302.521663 -396.978043) (xy 302.53178 -396.977616) (xy 303.24806 -396.977616)
			(xy 303.258182 -396.978049) (xy 303.276888 -396.985787) (xy 303.291204 -397.000099) (xy 303.298948 -397.018802)
			(xy 303.299368 -397.028924) (xy 303.299368 -397.18615) (xy 303.299809 -397.195334) (xy 303.306302 -397.212518)
			(xy 303.312068 -397.219678) (xy 303.333943 -397.245335) (xy 303.372033 -397.30097) (xy 303.403185 -397.360767)
			(xy 303.426951 -397.423865) (xy 303.442986 -397.489355) (xy 303.451062 -397.556295) (xy 303.451061 -397.62372)
			(xy 303.442984 -397.69066) (xy 303.426946 -397.75615) (xy 303.403179 -397.819247) (xy 303.372026 -397.879043)
			(xy 303.333934 -397.934677) (xy 303.312068 -397.960342) (xy 303.306267 -397.967484) (xy 303.299756 -397.984677)
			(xy 303.299368 -397.99387) (xy 303.299368 -398.486376) (xy 303.299797 -398.495561) (xy 303.306299 -398.512745)
			(xy 303.312068 -398.519904) (xy 303.333968 -398.54554) (xy 303.372058 -398.601178) (xy 303.403209 -398.660978)
			(xy 303.426973 -398.724078) (xy 303.443007 -398.789571) (xy 303.45108 -398.856513) (xy 303.451077 -398.923941)
			(xy 303.442997 -398.990882) (xy 303.426957 -399.056373) (xy 303.403187 -399.119472) (xy 303.37203 -399.179269)
			(xy 303.333935 -399.234903) (xy 303.312068 -399.260568) (xy 303.306256 -399.267702) (xy 303.299751 -399.284901)
			(xy 303.299368 -399.294096) (xy 303.299368 -399.451576) (xy 303.298964 -399.461701) (xy 303.291218 -399.48041)
			(xy 303.276897 -399.494727) (xy 303.258185 -399.502467) (xy 303.24806 -399.502884) (xy 302.53178 -399.502884)
			(xy 302.521654 -399.5025) (xy 302.502947 -399.494742) (xy 302.488633 -399.480416) (xy 302.480891 -399.461702)
			(xy 302.480472 -399.451576) (xy 302.480472 -399.294096) (xy 302.48007 -399.284908) (xy 302.473551 -399.267723)
			(xy 302.467772 -399.260568) (xy 302.445944 -399.234873) (xy 302.407856 -399.179242) (xy 302.376706 -399.11945)
			(xy 302.352941 -399.056357) (xy 302.336904 -398.990872) (xy 302.328825 -398.923937) (xy 302.328822 -398.856517)
			(xy 302.336894 -398.789582) (xy 302.352925 -398.724095) (xy 302.376684 -398.661) (xy 302.407829 -398.601204)
			(xy 302.445911 -398.54557) (xy 302.467772 -398.519904) (xy 302.473558 -398.512752) (xy 302.480077 -398.495566)
			(xy 302.480472 -398.486376) (xy 302.480472 -397.99387) (xy 302.480082 -397.98468) (xy 302.473555 -397.967496)
			(xy 302.467772 -397.960342) (xy 302.445919 -397.934668) (xy 302.407832 -397.879034) (xy 302.376682 -397.819239)
			(xy 302.352919 -397.756143) (xy 302.336883 -397.690656) (xy 302.328807 -397.623719) (xy 302.328806 -397.556296)
			(xy 301.200562 -397.556296) (xy 301.202986 -397.560949) (xy 301.226751 -397.624042) (xy 301.242789 -397.689527)
			(xy 301.250867 -397.756461) (xy 301.250871 -397.823882) (xy 301.242799 -397.890817) (xy 301.226768 -397.956304)
			(xy 301.203009 -398.019399) (xy 301.171864 -398.079194) (xy 301.133781 -398.134828) (xy 301.11192 -398.160494)
			(xy 301.106146 -398.167655) (xy 301.099617 -398.184833) (xy 301.09922 -398.194022) (xy 301.09922 -398.351502)
			(xy 301.098774 -398.361634) (xy 301.091038 -398.380362) (xy 301.076739 -398.39472) (xy 301.058042 -398.402532)
			(xy 301.047912 -398.403064) (xy 300.331632 -398.403064) (xy 300.321475 -398.402652) (xy 300.302717 -398.39486)
			(xy 300.288391 -398.38046) (xy 300.280696 -398.361661) (xy 300.280324 -398.351502) (xy 300.280324 -398.194022)
			(xy 300.279898 -398.184837) (xy 300.273395 -398.167652) (xy 300.267624 -398.160494) (xy 300.245722 -398.13486)
			(xy 300.207633 -398.079222) (xy 300.176482 -398.019421) (xy 300.152719 -397.95632) (xy 300.136686 -397.890827)
			(xy 300.128612 -397.823885) (xy 299.000445 -397.823885) (xy 298.972017 -397.878595) (xy 298.934068 -397.934182)
			(xy 298.91228 -397.959834) (xy 298.906484 -397.96698) (xy 298.89997 -397.98417) (xy 298.89958 -397.993362)
			(xy 298.89958 -398.486884) (xy 298.900003 -398.49607) (xy 298.906508 -398.513254) (xy 298.91228 -398.520412)
			(xy 298.934103 -398.546035) (xy 298.972049 -398.601626) (xy 299.00308 -398.661354) (xy 299.02675 -398.724362)
			(xy 299.04272 -398.789748) (xy 299.050761 -398.856573) (xy 299.050757 -398.923881) (xy 299.04271 -398.990706)
			(xy 299.026734 -399.05609) (xy 299.003058 -399.119095) (xy 298.972021 -399.17882) (xy 298.934069 -399.234408)
			(xy 298.91228 -399.26006) (xy 298.906473 -399.267198) (xy 298.899965 -399.284394) (xy 298.89958 -399.293588)
			(xy 298.89958 -399.451576) (xy 298.899159 -399.461731) (xy 298.891367 -399.480487) (xy 298.87697 -399.494812)
			(xy 298.858175 -399.502509) (xy 298.848018 -399.502884) (xy 298.131738 -399.502884) (xy 298.121617 -399.502343)
			(xy 298.102901 -399.494632) (xy 298.088544 -399.480362) (xy 298.08072 -399.461694) (xy 298.080176 -399.451576)
			(xy 298.080176 -399.293588) (xy 298.079777 -399.2844) (xy 298.073256 -399.267215) (xy 298.067476 -399.26006)
			(xy 298.045723 -399.234379) (xy 298.00777 -399.178798) (xy 297.976733 -399.119078) (xy 297.953057 -399.056078)
			(xy 297.93708 -398.990699) (xy 297.929033 -398.923879) (xy 297.92903 -398.856576) (xy 297.937071 -398.789755)
			(xy 297.953041 -398.724374) (xy 297.976711 -398.661371) (xy 298.007742 -398.601649) (xy 298.045689 -398.546064)
			(xy 298.067476 -398.520412) (xy 298.07329 -398.513279) (xy 298.079795 -398.496079) (xy 298.080176 -398.486884)
			(xy 298.080176 -397.993362) (xy 298.079789 -397.984172) (xy 298.07326 -397.966988) (xy 298.067476 -397.959834)
			(xy 298.045697 -397.934174) (xy 298.007746 -397.87859) (xy 297.97671 -397.818868) (xy 297.953035 -397.755864)
			(xy 297.93706 -397.690482) (xy 297.929015 -397.62366) (xy 297.929014 -397.556355) (xy 296.800802 -397.556355)
			(xy 296.803196 -397.56095) (xy 296.826961 -397.624042) (xy 296.842998 -397.689527) (xy 296.851076 -397.756461)
			(xy 296.85108 -397.823881) (xy 296.843008 -397.890817) (xy 296.826978 -397.956303) (xy 296.803219 -398.019398)
			(xy 296.772075 -398.079194) (xy 296.733993 -398.134828) (xy 296.712132 -398.160494) (xy 296.706347 -398.167647)
			(xy 296.699827 -398.184832) (xy 296.699432 -398.194022) (xy 296.699432 -398.351502) (xy 296.698974 -398.361632)
			(xy 296.691241 -398.380359) (xy 296.676945 -398.394716) (xy 296.658252 -398.40253) (xy 296.648124 -398.403064)
			(xy 295.931844 -398.403064) (xy 295.921688 -398.402642) (xy 295.90293 -398.394854) (xy 295.888604 -398.380456)
			(xy 295.880909 -398.36166) (xy 295.880536 -398.351502) (xy 295.880536 -398.194022) (xy 295.880107 -398.184837)
			(xy 295.873606 -398.167653) (xy 295.867836 -398.160494) (xy 295.845933 -398.13486) (xy 295.807843 -398.079222)
			(xy 295.776692 -398.019422) (xy 295.752929 -397.956321) (xy 295.736895 -397.890827) (xy 295.728821 -397.823885)
			(xy 294.600676 -397.823885) (xy 294.57194 -397.879043) (xy 294.533849 -397.934677) (xy 294.511984 -397.960342)
			(xy 294.506185 -397.967486) (xy 294.499672 -397.984677) (xy 294.499284 -397.99387) (xy 294.499284 -398.486376)
			(xy 294.499709 -398.495561) (xy 294.506213 -398.512746) (xy 294.511984 -398.519904) (xy 294.533884 -398.54554)
			(xy 294.571973 -398.601178) (xy 294.603123 -398.660978) (xy 294.626885 -398.724079) (xy 294.642919 -398.789572)
			(xy 294.650992 -398.856514) (xy 294.650989 -398.92394) (xy 294.642909 -398.990881) (xy 294.626869 -399.056373)
			(xy 294.603101 -399.119471) (xy 294.571945 -399.179268) (xy 294.533851 -399.234903) (xy 294.511984 -399.260568)
			(xy 294.506174 -399.267704) (xy 294.499668 -399.284902) (xy 294.499284 -399.294096) (xy 294.499284 -399.451576)
			(xy 294.498864 -399.461699) (xy 294.491121 -399.480405) (xy 294.476805 -399.494721) (xy 294.458099 -399.502464)
			(xy 294.447976 -399.502884) (xy 293.731696 -399.502884) (xy 293.721571 -399.502487) (xy 293.702865 -399.494734)
			(xy 293.68855 -399.480412) (xy 293.680808 -399.461701) (xy 293.680388 -399.451576) (xy 293.680388 -399.294096)
			(xy 293.679982 -399.284908) (xy 293.673466 -399.267724) (xy 293.667688 -399.260568) (xy 293.64586 -399.234873)
			(xy 293.607771 -399.179243) (xy 293.576619 -399.119451) (xy 293.552854 -399.056358) (xy 293.536816 -398.990872)
			(xy 293.528737 -398.923937) (xy 293.528734 -398.856517) (xy 293.536806 -398.789581) (xy 293.552838 -398.724094)
			(xy 293.576597 -398.660999) (xy 293.607743 -398.601204) (xy 293.645827 -398.545569) (xy 293.667688 -398.519904)
			(xy 293.673464 -398.512744) (xy 293.679991 -398.495565) (xy 293.680388 -398.486376) (xy 293.680388 -397.99387)
			(xy 293.679995 -397.984681) (xy 293.673469 -397.967497) (xy 293.667688 -397.960342) (xy 293.645834 -397.934668)
			(xy 293.607746 -397.879035) (xy 293.576596 -397.81924) (xy 293.552831 -397.756144) (xy 293.536796 -397.690656)
			(xy 293.528719 -397.623719) (xy 293.528718 -397.556296) (xy 292.40047 -397.556296) (xy 292.403082 -397.561322)
			(xy 292.426757 -397.624322) (xy 292.442733 -397.689701) (xy 292.450781 -397.75652) (xy 292.450784 -397.823823)
			(xy 292.442744 -397.890643) (xy 292.426774 -397.956023) (xy 292.403105 -398.019026) (xy 292.372075 -398.078748)
			(xy 292.33413 -398.134334) (xy 292.312344 -398.159986) (xy 292.306522 -398.167113) (xy 292.300024 -398.184318)
			(xy 292.299644 -398.193514) (xy 292.299644 -398.351502) (xy 292.299237 -398.361676) (xy 292.291448 -398.380474)
			(xy 292.277057 -398.39486) (xy 292.258256 -398.402641) (xy 292.248082 -398.403064) (xy 291.531802 -398.403064)
			(xy 291.521645 -398.402565) (xy 291.502876 -398.394792) (xy 291.488511 -398.380427) (xy 291.480736 -398.361659)
			(xy 291.48024 -398.351502) (xy 291.48024 -398.193514) (xy 291.479814 -398.184329) (xy 291.473311 -398.167145)
			(xy 291.46754 -398.159986) (xy 291.445715 -398.134365) (xy 291.407767 -398.078774) (xy 291.376735 -398.019046)
			(xy 291.353065 -397.956037) (xy 291.337094 -397.890651) (xy 291.329053 -397.823825) (xy 290.200388 -397.823825)
			(xy 290.171931 -397.878594) (xy 290.133983 -397.934181) (xy 290.112196 -397.959834) (xy 290.106402 -397.966981)
			(xy 290.099886 -397.98417) (xy 290.099496 -397.993362) (xy 290.099496 -398.486884) (xy 290.099915 -398.49607)
			(xy 290.106423 -398.513255) (xy 290.112196 -398.520412) (xy 290.134018 -398.546036) (xy 290.171963 -398.601627)
			(xy 290.202993 -398.661355) (xy 290.226662 -398.724363) (xy 290.242632 -398.789748) (xy 290.250673 -398.856573)
			(xy 290.250669 -398.923881) (xy 290.242622 -398.990705) (xy 290.226646 -399.056089) (xy 290.202971 -399.119095)
			(xy 290.171936 -399.17882) (xy 290.133985 -399.234407) (xy 290.112196 -399.26006) (xy 290.106391 -399.267199)
			(xy 290.099881 -399.284394) (xy 290.099496 -399.293588) (xy 290.099496 -399.451576) (xy 290.099059 -399.461729)
			(xy 290.09127 -399.480482) (xy 290.076878 -399.494806) (xy 290.058089 -399.502506) (xy 290.047934 -399.502884)
			(xy 289.331654 -399.502884) (xy 289.321527 -399.502412) (xy 289.30281 -399.494673) (xy 289.288456 -399.480383)
			(xy 289.280634 -399.4617) (xy 289.280092 -399.451576) (xy 289.280092 -399.293588) (xy 289.279689 -399.2844)
			(xy 289.273171 -399.267216) (xy 289.267392 -399.26006) (xy 289.245638 -399.234379) (xy 289.207685 -399.178798)
			(xy 289.176647 -399.119079) (xy 289.15297 -399.056078) (xy 289.136993 -398.990699) (xy 289.128945 -398.923879)
			(xy 289.128942 -398.856575) (xy 289.136983 -398.789754) (xy 289.152954 -398.724374) (xy 289.176625 -398.66137)
			(xy 289.207657 -398.601648) (xy 289.245605 -398.546063) (xy 289.267392 -398.520412) (xy 289.273208 -398.51328)
			(xy 289.279711 -398.496079) (xy 289.280092 -398.486884) (xy 289.280092 -397.993362) (xy 289.279702 -397.984173)
			(xy 289.273175 -397.966988) (xy 289.267392 -397.959834) (xy 289.245612 -397.934174) (xy 289.20766 -397.87859)
			(xy 289.176623 -397.818868) (xy 289.152948 -397.755865) (xy 289.136972 -397.690483) (xy 289.128927 -397.62366)
			(xy 289.128926 -397.556355) (xy 288.000733 -397.556355) (xy 288.003125 -397.560946) (xy 288.026894 -397.624039)
			(xy 288.042933 -397.689525) (xy 288.051013 -397.756461) (xy 288.051016 -397.823882) (xy 288.042944 -397.890819)
			(xy 288.026911 -397.956307) (xy 288.003148 -398.019402) (xy 287.971999 -398.079197) (xy 287.933912 -398.13483)
			(xy 287.912048 -398.160494) (xy 287.906265 -398.167649) (xy 287.899744 -398.184832) (xy 287.899348 -398.194022)
			(xy 287.899348 -398.351502) (xy 287.898875 -398.36163) (xy 287.891144 -398.380354) (xy 287.876853 -398.39471)
			(xy 287.858166 -398.402527) (xy 287.84804 -398.403064) (xy 287.13176 -398.403064) (xy 287.121599 -398.40271)
			(xy 287.102839 -398.394895) (xy 287.088515 -398.380477) (xy 287.080824 -398.361666) (xy 287.080452 -398.351502)
			(xy 287.080452 -398.194022) (xy 287.08002 -398.184837) (xy 287.07352 -398.167653) (xy 287.067752 -398.160494)
			(xy 287.045849 -398.13486) (xy 287.007758 -398.079223) (xy 286.976606 -398.019423) (xy 286.952842 -397.956321)
			(xy 286.936807 -397.890828) (xy 286.928734 -397.823885) (xy 244.06606 -397.823885) (xy 244.06606 -399.830544)
			(xy 244.065668 -399.840617) (xy 244.057925 -399.859215) (xy 244.051074 -399.866612) (xy 243.052346 -400.865594)
			(xy 243.044923 -400.872406) (xy 243.026341 -400.880142) (xy 243.016278 -400.88058) (xy 238.99114 -400.88058)
			(xy 238.978794 -400.881097) (xy 238.955921 -400.890396) (xy 238.94669 -400.898614) (xy 238.946182 -400.899122)
			(xy 238.121507 -401.723797) (xy 286.928745 -401.723797) (xy 286.928747 -401.65637) (xy 286.936826 -401.58943)
			(xy 286.952865 -401.523939) (xy 286.976634 -401.460841) (xy 287.00779 -401.401044) (xy 287.045885 -401.34541)
			(xy 287.067752 -401.319746) (xy 287.07356 -401.312609) (xy 287.080067 -401.295412) (xy 287.080452 -401.286218)
			(xy 287.080452 -400.793966) (xy 287.080046 -400.784779) (xy 287.073528 -400.767595) (xy 287.067752 -400.760438)
			(xy 287.045892 -400.734769) (xy 287.0078 -400.679136) (xy 286.976646 -400.619341) (xy 286.952879 -400.556244)
			(xy 286.936842 -400.490755) (xy 286.928764 -400.423817) (xy 286.928764 -400.356392) (xy 286.93684 -400.289454)
			(xy 286.952876 -400.223964) (xy 286.976642 -400.160867) (xy 287.007795 -400.101072) (xy 287.045887 -400.045438)
			(xy 287.067752 -400.019774) (xy 287.073549 -400.012629) (xy 287.080062 -399.995438) (xy 287.080452 -399.986246)
			(xy 287.080452 -399.828766) (xy 287.080899 -399.818636) (xy 287.08864 -399.799911) (xy 287.102939 -399.785556)
			(xy 287.121632 -399.77774) (xy 287.13176 -399.777204) (xy 287.84804 -399.777204) (xy 287.858197 -399.777589)
			(xy 287.876951 -399.785399) (xy 287.891273 -399.799806) (xy 287.898971 -399.818606) (xy 287.899348 -399.828766)
			(xy 287.899348 -399.986246) (xy 287.899796 -399.995429) (xy 287.906285 -400.012613) (xy 287.912048 -400.019774)
			(xy 287.93392 -400.045433) (xy 287.972012 -400.101068) (xy 288.003165 -400.160864) (xy 288.026931 -400.223962)
			(xy 288.042968 -400.289452) (xy 288.051044 -400.356392) (xy 288.051043 -400.423817) (xy 288.042966 -400.490757)
			(xy 288.026928 -400.556247) (xy 288.003161 -400.619344) (xy 287.972007 -400.67914) (xy 287.933914 -400.734774)
			(xy 287.912048 -400.760438) (xy 287.906246 -400.767579) (xy 287.899736 -400.784773) (xy 287.899348 -400.793966)
			(xy 287.899348 -401.286218) (xy 287.899761 -401.295405) (xy 287.906274 -401.312588) (xy 287.912048 -401.319746)
			(xy 287.933892 -401.345428) (xy 287.971985 -401.401059) (xy 288.00314 -401.460852) (xy 288.026907 -401.523947)
			(xy 288.042946 -401.589435) (xy 288.051024 -401.656372) (xy 288.051026 -401.723795) (xy 288.042952 -401.790733)
			(xy 288.026917 -401.856221) (xy 288.003153 -401.919317) (xy 287.972002 -401.979113) (xy 287.933912 -402.034746)
			(xy 287.912048 -402.06041) (xy 287.906258 -402.06756) (xy 287.899741 -402.084747) (xy 287.899348 -402.093938)
			(xy 287.899348 -402.251418) (xy 287.898888 -402.261547) (xy 287.891152 -402.280271) (xy 287.876858 -402.294627)
			(xy 287.858167 -402.302444) (xy 287.84804 -402.30298) (xy 287.13176 -402.30298) (xy 287.121601 -402.302611)
			(xy 287.102844 -402.294798) (xy 287.088521 -402.280385) (xy 287.080826 -402.26158) (xy 287.080452 -402.251418)
			(xy 287.080452 -402.093938) (xy 287.080012 -402.084754) (xy 287.073518 -402.06757) (xy 287.067752 -402.06041)
			(xy 287.045865 -402.034763) (xy 287.007773 -401.979127) (xy 286.97662 -401.919329) (xy 286.952855 -401.85623)
			(xy 286.93682 -401.790738) (xy 286.928745 -401.723797) (xy 238.121507 -401.723797) (xy 237.044738 -402.800566)
			(xy 237.036256 -402.809732) (xy 237.030424 -402.823819) (xy 289.128886 -402.823819) (xy 289.12889 -402.756509)
			(xy 289.13694 -402.689682) (xy 289.15292 -402.624297) (xy 289.1766 -402.56129) (xy 289.207642 -402.501565)
			(xy 289.2456 -402.445979) (xy 289.267392 -402.420328) (xy 289.273201 -402.413191) (xy 289.279708 -402.395994)
			(xy 289.280092 -402.3868) (xy 289.280092 -401.893532) (xy 289.279668 -401.884346) (xy 289.273164 -401.867162)
			(xy 289.267392 -401.860004) (xy 289.245583 -401.834369) (xy 289.207631 -401.778781) (xy 289.176596 -401.719056)
			(xy 289.152922 -401.656049) (xy 289.136949 -401.590664) (xy 289.128906 -401.523839) (xy 289.128907 -401.456531)
			(xy 289.136954 -401.389706) (xy 289.152931 -401.324322) (xy 289.176608 -401.261317) (xy 289.207647 -401.201593)
			(xy 289.245601 -401.146007) (xy 289.267392 -401.120356) (xy 289.273189 -401.113211) (xy 289.279704 -401.09602)
			(xy 289.280092 -401.086828) (xy 289.280092 -400.92884) (xy 289.280554 -400.918689) (xy 289.288335 -400.89994)
			(xy 289.30272 -400.885615) (xy 289.321502 -400.877913) (xy 289.331654 -400.877532) (xy 290.047934 -400.877532)
			(xy 290.058062 -400.877998) (xy 290.076782 -400.885736) (xy 290.091137 -400.900028) (xy 290.098957 -400.918714)
			(xy 290.099496 -400.92884) (xy 290.099496 -401.086828) (xy 290.099893 -401.096017) (xy 290.106416 -401.113201)
			(xy 290.112196 -401.120356) (xy 290.133963 -401.146025) (xy 290.17191 -401.20161) (xy 290.202942 -401.261331)
			(xy 290.226615 -401.324334) (xy 290.242588 -401.389713) (xy 290.250633 -401.456534) (xy 290.250635 -401.523836)
			(xy 290.242593 -401.590657) (xy 290.226624 -401.656038) (xy 290.202955 -401.719041) (xy 290.200515 -401.723737)
			(xy 291.329064 -401.723737) (xy 291.329066 -401.65643) (xy 291.337113 -401.589606) (xy 291.353088 -401.524222)
			(xy 291.376763 -401.461217) (xy 291.407799 -401.401493) (xy 291.445751 -401.345906) (xy 291.46754 -401.320254)
			(xy 291.473344 -401.313114) (xy 291.479853 -401.295919) (xy 291.48024 -401.286726) (xy 291.48024 -400.793458)
			(xy 291.479841 -400.78427) (xy 291.473319 -400.767086) (xy 291.46754 -400.75993) (xy 291.445758 -400.734273)
			(xy 291.407809 -400.678687) (xy 291.376776 -400.618964) (xy 291.353103 -400.55596) (xy 291.337129 -400.490579)
			(xy 291.329085 -400.423757) (xy 291.329084 -400.356452) (xy 291.337128 -400.28963) (xy 291.3531 -400.224248)
			(xy 291.376772 -400.161244) (xy 291.407805 -400.101521) (xy 291.445753 -400.045934) (xy 291.46754 -400.020282)
			(xy 291.473332 -400.013134) (xy 291.479848 -399.995945) (xy 291.48024 -399.986754) (xy 291.48024 -399.828766)
			(xy 291.480706 -399.818606) (xy 291.488492 -399.799835) (xy 291.502866 -399.785471) (xy 291.521641 -399.777698)
			(xy 291.531802 -399.777204) (xy 292.248082 -399.777204) (xy 292.258234 -399.777747) (xy 292.276997 -399.785509)
			(xy 292.291361 -399.79986) (xy 292.299143 -399.818614) (xy 292.299644 -399.828766) (xy 292.299644 -399.986754)
			(xy 292.300089 -399.995937) (xy 292.30658 -400.013121) (xy 292.312344 -400.020282) (xy 292.334138 -400.045929)
			(xy 292.372088 -400.101516) (xy 292.403122 -400.16124) (xy 292.426795 -400.224245) (xy 292.442768 -400.289628)
			(xy 292.450812 -400.356452) (xy 292.450811 -400.423757) (xy 292.442766 -400.490581) (xy 292.426792 -400.555963)
			(xy 292.403118 -400.618968) (xy 292.372083 -400.678692) (xy 292.334132 -400.734278) (xy 292.312344 -400.75993)
			(xy 292.306545 -400.767073) (xy 292.300033 -400.784266) (xy 292.299644 -400.793458) (xy 292.299644 -401.286726)
			(xy 292.300054 -401.295913) (xy 292.306569 -401.313097) (xy 292.312344 -401.320254) (xy 292.33411 -401.345924)
			(xy 292.372061 -401.401507) (xy 292.403096 -401.461228) (xy 292.426771 -401.524231) (xy 292.442746 -401.589611)
			(xy 292.450792 -401.656432) (xy 292.450794 -401.723735) (xy 292.442752 -401.790557) (xy 292.426781 -401.855938)
			(xy 292.40311 -401.918941) (xy 292.372078 -401.978664) (xy 292.334131 -402.03425) (xy 292.312344 -402.059902)
			(xy 292.306557 -402.067054) (xy 292.300038 -402.084239) (xy 292.299644 -402.09343) (xy 292.299644 -402.251418)
			(xy 292.299181 -402.261579) (xy 292.291397 -402.280352) (xy 292.277022 -402.294718) (xy 292.258244 -402.302488)
			(xy 292.248082 -402.30298) (xy 291.531802 -402.30298) (xy 291.521647 -402.302465) (xy 291.502881 -402.294695)
			(xy 291.488516 -402.280336) (xy 291.480739 -402.261573) (xy 291.48024 -402.251418) (xy 291.48024 -402.09343)
			(xy 291.479806 -402.084246) (xy 291.473308 -402.067061) (xy 291.46754 -402.059902) (xy 291.44573 -402.034268)
			(xy 291.407782 -401.978679) (xy 291.37675 -401.918953) (xy 291.353078 -401.855946) (xy 291.337107 -401.790561)
			(xy 291.329064 -401.723737) (xy 290.200515 -401.723737) (xy 290.171926 -401.778764) (xy 290.133981 -401.834351)
			(xy 290.112196 -401.860004) (xy 290.106415 -401.86716) (xy 290.099891 -401.884342) (xy 290.099496 -401.893532)
			(xy 290.099496 -402.3868) (xy 290.099907 -402.395987) (xy 290.10642 -402.413171) (xy 290.112196 -402.420328)
			(xy 290.133935 -402.44602) (xy 290.171883 -402.501601) (xy 290.202916 -402.56132) (xy 290.22659 -402.624319)
			(xy 290.242566 -402.689696) (xy 290.250613 -402.756514) (xy 290.250617 -402.823814) (xy 290.250609 -402.823878)
			(xy 293.528678 -402.823878) (xy 293.528683 -402.75645) (xy 293.536763 -402.689509) (xy 293.552803 -402.624017)
			(xy 293.576572 -402.560919) (xy 293.607728 -402.501121) (xy 293.645822 -402.445485) (xy 293.667688 -402.41982)
			(xy 293.6735 -402.412685) (xy 293.680006 -402.395487) (xy 293.680388 -402.386292) (xy 293.680388 -401.89404)
			(xy 293.679961 -401.884854) (xy 293.67346 -401.86767) (xy 293.667688 -401.860512) (xy 293.645805 -401.834863)
			(xy 293.607717 -401.779226) (xy 293.576568 -401.719427) (xy 293.552806 -401.656328) (xy 293.536772 -401.590837)
			(xy 293.528698 -401.523897) (xy 293.5287 -401.456472) (xy 293.536777 -401.389533) (xy 293.552815 -401.324043)
			(xy 293.576581 -401.260945) (xy 293.607733 -401.201149) (xy 293.645823 -401.145513) (xy 293.667688 -401.119848)
			(xy 293.673488 -401.112705) (xy 293.680001 -401.095513) (xy 293.680388 -401.08632) (xy 293.680388 -400.92884)
			(xy 293.680849 -400.918722) (xy 293.688581 -400.900021) (xy 293.702884 -400.885706) (xy 293.721578 -400.877957)
			(xy 293.731696 -400.877532) (xy 294.447976 -400.877532) (xy 294.458101 -400.877936) (xy 294.47681 -400.885682)
			(xy 294.491127 -400.900003) (xy 294.498867 -400.918715) (xy 294.499284 -400.92884) (xy 294.499284 -401.08632)
			(xy 294.499688 -401.095508) (xy 294.506206 -401.112692) (xy 294.511984 -401.119848) (xy 294.533829 -401.145529)
			(xy 294.571919 -401.201161) (xy 294.603072 -401.260955) (xy 294.626838 -401.32405) (xy 294.642875 -401.389537)
			(xy 294.650953 -401.456474) (xy 294.650955 -401.523896) (xy 294.64288 -401.590833) (xy 294.626847 -401.656322)
			(xy 294.603084 -401.719418) (xy 294.600803 -401.723797) (xy 295.728833 -401.723797) (xy 295.728835 -401.65637)
			(xy 295.736913 -401.58943) (xy 295.752952 -401.523939) (xy 295.77672 -401.460841) (xy 295.807876 -401.401045)
			(xy 295.845969 -401.345411) (xy 295.867836 -401.319746) (xy 295.873643 -401.312608) (xy 295.88015 -401.295412)
			(xy 295.880536 -401.286218) (xy 295.880536 -400.793966) (xy 295.880134 -400.784778) (xy 295.873614 -400.767594)
			(xy 295.867836 -400.760438) (xy 295.845977 -400.734769) (xy 295.807885 -400.679135) (xy 295.776732 -400.61934)
			(xy 295.752966 -400.556244) (xy 295.736929 -400.490755) (xy 295.728852 -400.423816) (xy 295.728852 -400.356393)
			(xy 295.736928 -400.289454) (xy 295.752964 -400.223965) (xy 295.776729 -400.160868) (xy 295.807881 -400.101072)
			(xy 295.845971 -400.045439) (xy 295.867836 -400.019774) (xy 295.873631 -400.012628) (xy 295.880146 -399.995438)
			(xy 295.880536 -399.986246) (xy 295.880536 -399.828766) (xy 295.880999 -399.818638) (xy 295.888737 -399.799916)
			(xy 295.90303 -399.785561) (xy 295.921718 -399.777743) (xy 295.931844 -399.777204) (xy 296.648124 -399.777204)
			(xy 296.65828 -399.777602) (xy 296.677034 -399.785406) (xy 296.691357 -399.79981) (xy 296.699055 -399.818608)
			(xy 296.699432 -399.828766) (xy 296.699432 -399.986246) (xy 296.699883 -399.995429) (xy 296.70637 -400.012613)
			(xy 296.712132 -400.019774) (xy 296.734001 -400.045435) (xy 296.772087 -400.101071) (xy 296.803236 -400.160868)
			(xy 296.826998 -400.223965) (xy 296.843032 -400.289455) (xy 296.851107 -400.356393) (xy 296.851107 -400.423816)
			(xy 296.843031 -400.490754) (xy 296.826996 -400.556243) (xy 296.803232 -400.61934) (xy 296.772083 -400.679137)
			(xy 296.733995 -400.734772) (xy 296.712132 -400.760438) (xy 296.706329 -400.767578) (xy 296.69982 -400.784773)
			(xy 296.699432 -400.793966) (xy 296.699432 -401.286218) (xy 296.699849 -401.295404) (xy 296.70636 -401.312588)
			(xy 296.712132 -401.319746) (xy 296.733973 -401.34543) (xy 296.77206 -401.401062) (xy 296.80321 -401.460856)
			(xy 296.826974 -401.523951) (xy 296.84301 -401.589437) (xy 296.851088 -401.656373) (xy 296.85109 -401.723794)
			(xy 296.843016 -401.79073) (xy 296.826984 -401.856218) (xy 296.803224 -401.919314) (xy 296.772078 -401.979109)
			(xy 296.733994 -402.034744) (xy 296.712132 -402.06041) (xy 296.70634 -402.067558) (xy 296.699825 -402.084747)
			(xy 296.699432 -402.093938) (xy 296.699432 -402.251418) (xy 296.698988 -402.261549) (xy 296.691249 -402.280276)
			(xy 296.676949 -402.294633) (xy 296.658253 -402.302447) (xy 296.648124 -402.30298) (xy 295.931844 -402.30298)
			(xy 295.92169 -402.302542) (xy 295.902935 -402.294757) (xy 295.888609 -402.280365) (xy 295.880912 -402.261574)
			(xy 295.880536 -402.251418) (xy 295.880536 -402.093938) (xy 295.880099 -402.084754) (xy 295.873603 -402.06757)
			(xy 295.867836 -402.06041) (xy 295.845949 -402.034763) (xy 295.807859 -401.979127) (xy 295.776707 -401.919328)
			(xy 295.752942 -401.856229) (xy 295.736907 -401.790737) (xy 295.728833 -401.723797) (xy 294.600803 -401.723797)
			(xy 294.571935 -401.779213) (xy 294.533847 -401.834847) (xy 294.511984 -401.860512) (xy 294.506198 -401.867665)
			(xy 294.499678 -401.88485) (xy 294.499284 -401.89404) (xy 294.499284 -402.386292) (xy 294.499702 -402.395478)
			(xy 294.506211 -402.412662) (xy 294.511984 -402.41982) (xy 294.533801 -402.445524) (xy 294.571893 -402.501152)
			(xy 294.603046 -402.560943) (xy 294.626814 -402.624035) (xy 294.642853 -402.68952) (xy 294.650933 -402.756454)
			(xy 294.650937 -402.823819) (xy 297.928973 -402.823819) (xy 297.928978 -402.756509) (xy 297.937027 -402.689683)
			(xy 297.953006 -402.624297) (xy 297.976686 -402.561291) (xy 298.007727 -402.501566) (xy 298.045684 -402.445979)
			(xy 298.067476 -402.420328) (xy 298.073283 -402.41319) (xy 298.079792 -402.395994) (xy 298.080176 -402.3868)
			(xy 298.080176 -401.893532) (xy 298.079756 -401.884346) (xy 298.07325 -401.867161) (xy 298.067476 -401.860004)
			(xy 298.045668 -401.834368) (xy 298.007717 -401.77878) (xy 297.976683 -401.719055) (xy 297.953009 -401.656048)
			(xy 297.937037 -401.590664) (xy 297.928993 -401.523839) (xy 297.928995 -401.456531) (xy 297.937042 -401.389707)
			(xy 297.953018 -401.324323) (xy 297.976695 -401.261318) (xy 298.007732 -401.201594) (xy 298.045686 -401.146008)
			(xy 298.067476 -401.120356) (xy 298.073271 -401.113209) (xy 298.079787 -401.09602) (xy 298.080176 -401.086828)
			(xy 298.080176 -400.92884) (xy 298.080654 -400.918691) (xy 298.088432 -400.899945) (xy 298.102811 -400.885621)
			(xy 298.121588 -400.877915) (xy 298.131738 -400.877532) (xy 298.848018 -400.877532) (xy 298.858145 -400.878011)
			(xy 298.876865 -400.885744) (xy 298.89122 -400.900032) (xy 298.89904 -400.918716) (xy 298.89958 -400.92884)
			(xy 298.89958 -401.086828) (xy 298.899981 -401.096016) (xy 298.906502 -401.1132) (xy 298.91228 -401.120356)
			(xy 298.934048 -401.146024) (xy 298.971996 -401.201609) (xy 299.003029 -401.261331) (xy 299.026702 -401.324333)
			(xy 299.042676 -401.389713) (xy 299.050721 -401.456533) (xy 299.050723 -401.523837) (xy 299.042681 -401.590657)
			(xy 299.026711 -401.656038) (xy 299.003041 -401.719042) (xy 299.000571 -401.723796) (xy 300.128624 -401.723796)
			(xy 300.128626 -401.656371) (xy 300.136704 -401.58943) (xy 300.152743 -401.52394) (xy 300.17651 -401.460842)
			(xy 300.207665 -401.401045) (xy 300.245758 -401.345411) (xy 300.267624 -401.319746) (xy 300.273429 -401.312607)
			(xy 300.279938 -401.295412) (xy 300.280324 -401.286218) (xy 300.280324 -400.793966) (xy 300.279925 -400.784778)
			(xy 300.273403 -400.767594) (xy 300.267624 -400.760438) (xy 300.245765 -400.734768) (xy 300.207675 -400.679135)
			(xy 300.176522 -400.61934) (xy 300.152757 -400.556243) (xy 300.13672 -400.490755) (xy 300.128643 -400.423816)
			(xy 300.128643 -400.356393) (xy 300.136719 -400.289454) (xy 300.152754 -400.223965) (xy 300.176519 -400.160869)
			(xy 300.20767 -400.101073) (xy 300.24576 -400.045439) (xy 300.267624 -400.019774) (xy 300.273417 -400.012626)
			(xy 300.279933 -399.995438) (xy 300.280324 -399.986246) (xy 300.280324 -399.828766) (xy 300.280798 -399.818639)
			(xy 300.288534 -399.79992) (xy 300.302824 -399.785566) (xy 300.321507 -399.777745) (xy 300.331632 -399.777204)
			(xy 301.047912 -399.777204) (xy 301.058067 -399.777612) (xy 301.076821 -399.785412) (xy 301.091144 -399.799813)
			(xy 301.098843 -399.818608) (xy 301.09922 -399.828766) (xy 301.09922 -399.986246) (xy 301.099652 -399.995431)
			(xy 301.10615 -400.012616) (xy 301.11192 -400.019774) (xy 301.133789 -400.045435) (xy 301.171876 -400.10107)
			(xy 301.203026 -400.160867) (xy 301.226789 -400.223965) (xy 301.242823 -400.289454) (xy 301.250898 -400.356393)
			(xy 301.250898 -400.423816) (xy 301.242821 -400.490755) (xy 301.226786 -400.556244) (xy 301.203022 -400.619341)
			(xy 301.171872 -400.679137) (xy 301.133784 -400.734772) (xy 301.11192 -400.760438) (xy 301.106127 -400.767586)
			(xy 301.09961 -400.784774) (xy 301.09922 -400.793966) (xy 301.09922 -401.286218) (xy 301.099617 -401.295407)
			(xy 301.106139 -401.312591) (xy 301.11192 -401.319746) (xy 301.133762 -401.345429) (xy 301.17185 -401.401062)
			(xy 301.203 -401.460856) (xy 301.226765 -401.52395) (xy 301.242801 -401.589437) (xy 301.250878 -401.656373)
			(xy 301.25088 -401.723794) (xy 301.242807 -401.790731) (xy 301.226775 -401.856218) (xy 301.203014 -401.919314)
			(xy 301.171867 -401.97911) (xy 301.133782 -402.034744) (xy 301.11192 -402.06041) (xy 301.106139 -402.067566)
			(xy 301.099614 -402.084748) (xy 301.09922 -402.093938) (xy 301.09922 -402.251418) (xy 301.098787 -402.261551)
			(xy 301.091046 -402.28028) (xy 301.076743 -402.294637) (xy 301.058043 -402.302449) (xy 301.047912 -402.30298)
			(xy 300.331632 -402.30298) (xy 300.321477 -402.302552) (xy 300.302722 -402.294763) (xy 300.288396 -402.280368)
			(xy 300.280699 -402.261575) (xy 300.280324 -402.251418) (xy 300.280324 -402.093938) (xy 300.27989 -402.084753)
			(xy 300.273392 -402.067569) (xy 300.267624 -402.06041) (xy 300.245738 -402.034763) (xy 300.207648 -401.979126)
			(xy 300.176497 -401.919328) (xy 300.152733 -401.856229) (xy 300.136698 -401.790737) (xy 300.128624 -401.723796)
			(xy 299.000571 -401.723796) (xy 298.972011 -401.778765) (xy 298.934066 -401.834352) (xy 298.91228 -401.860004)
			(xy 298.906497 -401.867159) (xy 298.899975 -401.884342) (xy 298.89958 -401.893532) (xy 298.89958 -402.3868)
			(xy 298.899994 -402.395987) (xy 298.906505 -402.413171) (xy 298.91228 -402.420328) (xy 298.93402 -402.446019)
			(xy 298.971969 -402.501601) (xy 299.003003 -402.561319) (xy 299.026678 -402.624318) (xy 299.042653 -402.689696)
			(xy 299.050701 -402.756513) (xy 299.050705 -402.823814) (xy 299.050697 -402.823877) (xy 302.328766 -402.823877)
			(xy 302.328771 -402.75645) (xy 302.336851 -402.689509) (xy 302.35289 -402.624018) (xy 302.376659 -402.560919)
			(xy 302.407814 -402.501122) (xy 302.445906 -402.445486) (xy 302.467772 -402.41982) (xy 302.473594 -402.412693)
			(xy 302.480091 -402.395488) (xy 302.480472 -402.386292) (xy 302.480472 -401.89404) (xy 302.480049 -401.884854)
			(xy 302.473545 -401.867669) (xy 302.467772 -401.860512) (xy 302.445889 -401.834863) (xy 302.407803 -401.779225)
			(xy 302.376655 -401.719426) (xy 302.352893 -401.656328) (xy 302.33686 -401.590837) (xy 302.328786 -401.523897)
			(xy 302.328788 -401.456473) (xy 302.336865 -401.389534) (xy 302.352902 -401.324044) (xy 302.376667 -401.260946)
			(xy 302.407819 -401.201149) (xy 302.445908 -401.145514) (xy 302.467772 -401.119848) (xy 302.473582 -401.112713)
			(xy 302.480087 -401.095514) (xy 302.480472 -401.08632) (xy 302.480472 -400.92884) (xy 302.480948 -400.918724)
			(xy 302.488678 -400.900026) (xy 302.502976 -400.885712) (xy 302.521664 -400.87796) (xy 302.53178 -400.877532)
			(xy 303.24806 -400.877532) (xy 303.258184 -400.87795) (xy 303.276893 -400.885691) (xy 303.291209 -400.900007)
			(xy 303.29895 -400.918716) (xy 303.299368 -400.92884) (xy 303.299368 -401.08632) (xy 303.299776 -401.095507)
			(xy 303.306292 -401.112691) (xy 303.312068 -401.119848) (xy 303.333913 -401.145529) (xy 303.372005 -401.20116)
			(xy 303.403158 -401.260954) (xy 303.426925 -401.324049) (xy 303.442963 -401.389537) (xy 303.451041 -401.456474)
			(xy 303.451043 -401.523896) (xy 303.442968 -401.590834) (xy 303.426934 -401.656322) (xy 303.40317 -401.719418)
			(xy 303.37202 -401.779214) (xy 303.333932 -401.834847) (xy 303.312068 -401.860512) (xy 303.30628 -401.867663)
			(xy 303.299761 -401.884849) (xy 303.299368 -401.89404) (xy 303.299368 -402.386292) (xy 303.299789 -402.395478)
			(xy 303.306296 -402.412662) (xy 303.312068 -402.41982) (xy 303.333886 -402.445524) (xy 303.371978 -402.501152)
			(xy 303.403133 -402.560942) (xy 303.426901 -402.624034) (xy 303.442941 -402.689519) (xy 303.451021 -402.756454)
			(xy 303.451025 -402.823874) (xy 303.442954 -402.89081) (xy 303.426922 -402.956297) (xy 303.403162 -403.019392)
			(xy 303.372015 -403.079186) (xy 303.33393 -403.134819) (xy 303.312068 -403.160484) (xy 303.306249 -403.167613)
			(xy 303.299749 -403.184816) (xy 303.299368 -403.194012) (xy 303.299368 -403.351492) (xy 303.298977 -403.361618)
			(xy 303.291225 -403.380328) (xy 303.276901 -403.394643) (xy 303.258186 -403.402383) (xy 303.24806 -403.4028)
			(xy 302.53178 -403.4028) (xy 302.52167 -403.402331) (xy 302.502991 -403.394587) (xy 302.488697 -403.380285)
			(xy 302.480963 -403.361602) (xy 302.480472 -403.351492) (xy 302.480472 -403.194012) (xy 302.480062 -403.184825)
			(xy 302.473549 -403.16764) (xy 302.467772 -403.160484) (xy 302.445862 -403.134857) (xy 302.407776 -403.079216)
			(xy 302.376629 -403.019415) (xy 302.352869 -402.956313) (xy 302.336838 -402.890819) (xy 302.328766 -402.823877)
			(xy 299.050697 -402.823877) (xy 299.042666 -402.890633) (xy 299.026699 -402.956013) (xy 299.003032 -403.019015)
			(xy 298.972006 -403.078737) (xy 298.934064 -403.134323) (xy 298.91228 -403.159976) (xy 298.906466 -403.167109)
			(xy 298.899963 -403.184309) (xy 298.89958 -403.193504) (xy 298.89958 -403.351492) (xy 298.899171 -403.361648)
			(xy 298.891375 -403.380404) (xy 298.876974 -403.394729) (xy 298.858176 -403.402425) (xy 298.848018 -403.4028)
			(xy 298.131738 -403.4028) (xy 298.121619 -403.402243) (xy 298.102906 -403.394535) (xy 298.08855 -403.380271)
			(xy 298.080722 -403.361608) (xy 298.080176 -403.351492) (xy 298.080176 -403.193504) (xy 298.079769 -403.184316)
			(xy 298.073254 -403.167132) (xy 298.067476 -403.159976) (xy 298.04564 -403.134363) (xy 298.00769 -403.078772)
			(xy 297.976657 -403.019043) (xy 297.952985 -402.956034) (xy 297.937014 -402.890646) (xy 297.928973 -402.823819)
			(xy 294.650937 -402.823819) (xy 294.650937 -402.823874) (xy 294.642866 -402.890809) (xy 294.626835 -402.956296)
			(xy 294.603076 -403.019391) (xy 294.57193 -403.079186) (xy 294.533846 -403.134819) (xy 294.511984 -403.160484)
			(xy 294.506167 -403.167615) (xy 294.499665 -403.184816) (xy 294.499284 -403.194012) (xy 294.499284 -403.351492)
			(xy 294.498877 -403.361616) (xy 294.491129 -403.380322) (xy 294.476809 -403.394638) (xy 294.4581 -403.40238)
			(xy 294.447976 -403.4028) (xy 293.731696 -403.4028) (xy 293.721573 -403.402387) (xy 293.70287 -403.394638)
			(xy 293.688556 -403.38032) (xy 293.68081 -403.361615) (xy 293.680388 -403.351492) (xy 293.680388 -403.194012)
			(xy 293.679975 -403.184825) (xy 293.673464 -403.167641) (xy 293.667688 -403.160484) (xy 293.645777 -403.134857)
			(xy 293.607691 -403.079217) (xy 293.576543 -403.019415) (xy 293.552782 -402.956314) (xy 293.53675 -402.89082)
			(xy 293.528678 -402.823878) (xy 290.250609 -402.823878) (xy 290.242579 -402.890633) (xy 290.226612 -402.956012)
			(xy 290.202946 -403.019014) (xy 290.17192 -403.078737) (xy 290.133979 -403.134323) (xy 290.112196 -403.159976)
			(xy 290.106384 -403.16711) (xy 290.099879 -403.184309) (xy 290.099496 -403.193504) (xy 290.099496 -403.351492)
			(xy 290.099072 -403.361646) (xy 290.091278 -403.380399) (xy 290.076882 -403.394723) (xy 290.05809 -403.402422)
			(xy 290.047934 -403.4028) (xy 289.331654 -403.4028) (xy 289.321529 -403.402312) (xy 289.302815 -403.394577)
			(xy 289.288461 -403.380292) (xy 289.280637 -403.361614) (xy 289.280092 -403.351492) (xy 289.280092 -403.193504)
			(xy 289.279682 -403.184317) (xy 289.273168 -403.167132) (xy 289.267392 -403.159976) (xy 289.245556 -403.134363)
			(xy 289.207605 -403.078772) (xy 289.176571 -403.019044) (xy 289.152898 -402.956034) (xy 289.136927 -402.890647)
			(xy 289.128886 -402.823819) (xy 237.030424 -402.823819) (xy 237.026709 -402.832791) (xy 237.026196 -402.84527)
			(xy 237.026196 -405.623708) (xy 286.928756 -405.623708) (xy 286.928757 -405.556283) (xy 286.936834 -405.489343)
			(xy 286.952872 -405.423853) (xy 286.976639 -405.360756) (xy 287.007793 -405.30096) (xy 287.045886 -405.245326)
			(xy 287.067752 -405.219662) (xy 287.073554 -405.212521) (xy 287.080064 -405.195327) (xy 287.080452 -405.186134)
			(xy 287.080452 -404.693882) (xy 287.080039 -404.684695) (xy 287.073526 -404.667512) (xy 287.067752 -404.660354)
			(xy 287.045908 -404.634672) (xy 287.007815 -404.579041) (xy 286.97666 -404.519248) (xy 286.952893 -404.456153)
			(xy 286.936854 -404.390665) (xy 286.928776 -404.323728) (xy 286.928774 -404.256305) (xy 286.936848 -404.189367)
			(xy 286.952883 -404.123879) (xy 286.976647 -404.060783) (xy 287.007798 -404.000987) (xy 287.045888 -403.945354)
			(xy 287.067752 -403.91969) (xy 287.073542 -403.91254) (xy 287.080059 -403.895353) (xy 287.080452 -403.886162)
			(xy 287.080452 -403.728682) (xy 287.080912 -403.718553) (xy 287.088648 -403.699829) (xy 287.102942 -403.685473)
			(xy 287.121633 -403.677656) (xy 287.13176 -403.67712) (xy 287.84804 -403.67712) (xy 287.858199 -403.677489)
			(xy 287.876956 -403.685302) (xy 287.891279 -403.699715) (xy 287.898974 -403.71852) (xy 287.899348 -403.728682)
			(xy 287.899348 -403.886162) (xy 287.899788 -403.895346) (xy 287.906282 -403.91253) (xy 287.912048 -403.91969)
			(xy 287.933935 -403.945337) (xy 287.972027 -404.000973) (xy 288.00318 -404.060771) (xy 288.026945 -404.12387)
			(xy 288.04298 -404.189362) (xy 288.051055 -404.256303) (xy 288.051053 -404.32373) (xy 288.042974 -404.39067)
			(xy 288.026935 -404.456161) (xy 288.003166 -404.519259) (xy 287.97201 -404.579056) (xy 287.933915 -404.63469)
			(xy 287.912048 -404.660354) (xy 287.90624 -404.667491) (xy 287.899733 -404.684688) (xy 287.899348 -404.693882)
			(xy 287.899348 -405.186134) (xy 287.899754 -405.195321) (xy 287.906272 -405.212505) (xy 287.912048 -405.219662)
			(xy 287.933908 -405.245331) (xy 287.972 -405.300964) (xy 288.003154 -405.360759) (xy 288.026921 -405.423856)
			(xy 288.042958 -405.489345) (xy 288.051036 -405.556283) (xy 288.051036 -405.623708) (xy 288.04296 -405.690646)
			(xy 288.026924 -405.756136) (xy 288.003158 -405.819233) (xy 287.972005 -405.879028) (xy 287.933913 -405.934662)
			(xy 287.912048 -405.960326) (xy 287.906251 -405.967471) (xy 287.899738 -405.984662) (xy 287.899348 -405.993854)
			(xy 287.899348 -406.151334) (xy 287.898901 -406.161464) (xy 287.89116 -406.180189) (xy 287.876861 -406.194544)
			(xy 287.858168 -406.20236) (xy 287.84804 -406.202896) (xy 287.13176 -406.202896) (xy 287.121603 -406.202511)
			(xy 287.102849 -406.194701) (xy 287.088527 -406.180294) (xy 287.080829 -406.161494) (xy 287.080452 -406.151334)
			(xy 287.080452 -405.993854) (xy 287.080004 -405.984671) (xy 287.073515 -405.967487) (xy 287.067752 -405.960326)
			(xy 287.04588 -405.934667) (xy 287.007788 -405.879032) (xy 286.976635 -405.819236) (xy 286.952869 -405.756138)
			(xy 286.936832 -405.690648) (xy 286.928756 -405.623708) (xy 237.026196 -405.623708) (xy 237.026196 -406.72373)
			(xy 289.128897 -406.72373) (xy 289.1289 -406.656422) (xy 289.136948 -406.589596) (xy 289.152926 -406.524211)
			(xy 289.176605 -406.461205) (xy 289.207645 -406.401481) (xy 289.245601 -406.345895) (xy 289.267392 -406.320244)
			(xy 289.273194 -406.313103) (xy 289.279706 -406.295909) (xy 289.280092 -406.286716) (xy 289.280092 -405.793448)
			(xy 289.279661 -405.784263) (xy 289.273162 -405.767078) (xy 289.267392 -405.75992) (xy 289.245599 -405.734272)
			(xy 289.207647 -405.678686) (xy 289.176611 -405.618962) (xy 289.152936 -405.555957) (xy 289.136961 -405.490574)
			(xy 289.128917 -405.42375) (xy 289.128917 -405.356444) (xy 289.136962 -405.28962) (xy 289.152937 -405.224237)
			(xy 289.176613 -405.161232) (xy 289.20765 -405.101509) (xy 289.245602 -405.045923) (xy 289.267392 -405.020272)
			(xy 289.273182 -405.013122) (xy 289.279701 -404.995935) (xy 289.280092 -404.986744) (xy 289.280092 -404.828756)
			(xy 289.280486 -404.8186) (xy 289.288294 -404.799848) (xy 289.302699 -404.785527) (xy 289.321496 -404.777827)
			(xy 289.331654 -404.777448) (xy 290.047934 -404.777448) (xy 290.058064 -404.777899) (xy 290.076787 -404.785639)
			(xy 290.091143 -404.799936) (xy 290.098959 -404.818628) (xy 290.099496 -404.828756) (xy 290.099496 -404.986744)
			(xy 290.099886 -404.995933) (xy 290.106414 -405.013117) (xy 290.112196 -405.020272) (xy 290.133979 -405.045928)
			(xy 290.171925 -405.101515) (xy 290.202957 -405.161238) (xy 290.226628 -405.224242) (xy 290.242601 -405.289623)
			(xy 290.250644 -405.356445) (xy 290.250645 -405.423749) (xy 290.242602 -405.490571) (xy 290.22663 -405.555952)
			(xy 290.202959 -405.618957) (xy 290.200522 -405.623648) (xy 291.329076 -405.623648) (xy 291.329076 -405.556343)
			(xy 291.337121 -405.48952) (xy 291.353095 -405.424137) (xy 291.376768 -405.361132) (xy 291.407802 -405.301409)
			(xy 291.445752 -405.245822) (xy 291.46754 -405.22017) (xy 291.473337 -405.213025) (xy 291.47985 -405.195834)
			(xy 291.48024 -405.186642) (xy 291.48024 -404.693374) (xy 291.479833 -404.684187) (xy 291.473316 -404.667003)
			(xy 291.46754 -404.659846) (xy 291.445774 -404.634176) (xy 291.407825 -404.578592) (xy 291.37679 -404.518871)
			(xy 291.353116 -404.455869) (xy 291.337142 -404.390489) (xy 291.329096 -404.323668) (xy 291.329094 -404.256365)
			(xy 291.337136 -404.189544) (xy 291.353106 -404.124163) (xy 291.376777 -404.061159) (xy 291.407808 -404.001436)
			(xy 291.445754 -403.94585) (xy 291.46754 -403.920198) (xy 291.473325 -403.913045) (xy 291.479846 -403.89586)
			(xy 291.48024 -403.88667) (xy 291.48024 -403.728682) (xy 291.480718 -403.718523) (xy 291.488499 -403.699753)
			(xy 291.50287 -403.685388) (xy 291.521643 -403.677615) (xy 291.531802 -403.67712) (xy 292.248082 -403.67712)
			(xy 292.258236 -403.677648) (xy 292.277002 -403.685413) (xy 292.291367 -403.699768) (xy 292.299145 -403.718528)
			(xy 292.299644 -403.728682) (xy 292.299644 -403.88667) (xy 292.300081 -403.895854) (xy 292.306577 -403.913038)
			(xy 292.312344 -403.920198) (xy 292.334154 -403.945832) (xy 292.372103 -404.001421) (xy 292.403137 -404.061147)
			(xy 292.426809 -404.124153) (xy 292.442781 -404.189538) (xy 292.450824 -404.256363) (xy 292.450822 -404.32367)
			(xy 292.442775 -404.390495) (xy 292.426799 -404.455878) (xy 292.403123 -404.518884) (xy 292.372086 -404.578608)
			(xy 292.334134 -404.634194) (xy 292.312344 -404.659846) (xy 292.306539 -404.666985) (xy 292.300031 -404.68418)
			(xy 292.299644 -404.693374) (xy 292.299644 -405.186642) (xy 292.300047 -405.19583) (xy 292.306567 -405.213013)
			(xy 292.312344 -405.22017) (xy 292.334126 -405.245827) (xy 292.372076 -405.301412) (xy 292.403111 -405.361135)
			(xy 292.426785 -405.424139) (xy 292.442758 -405.489521) (xy 292.450803 -405.556343) (xy 292.450804 -405.623648)
			(xy 292.44276 -405.69047) (xy 292.426787 -405.755852) (xy 292.403114 -405.818857) (xy 292.372081 -405.87858)
			(xy 292.334132 -405.934166) (xy 292.312344 -405.959818) (xy 292.30655 -405.966965) (xy 292.300035 -405.984154)
			(xy 292.299644 -405.993346) (xy 292.299644 -406.151334) (xy 292.299194 -406.161496) (xy 292.291405 -406.18027)
			(xy 292.277026 -406.194634) (xy 292.258245 -406.202404) (xy 292.248082 -406.202896) (xy 291.531802 -406.202896)
			(xy 291.521649 -406.202366) (xy 291.502886 -406.194598) (xy 291.488522 -406.180244) (xy 291.480741 -406.161487)
			(xy 291.48024 -406.151334) (xy 291.48024 -405.993346) (xy 291.479799 -405.984162) (xy 291.473306 -405.966978)
			(xy 291.46754 -405.959818) (xy 291.445746 -405.934171) (xy 291.407797 -405.878584) (xy 291.376764 -405.818859)
			(xy 291.353092 -405.755854) (xy 291.337119 -405.690471) (xy 291.329076 -405.623648) (xy 290.200522 -405.623648)
			(xy 290.171928 -405.67868) (xy 290.133982 -405.734267) (xy 290.112196 -405.75992) (xy 290.106408 -405.767071)
			(xy 290.099888 -405.784257) (xy 290.099496 -405.793448) (xy 290.099496 -406.286716) (xy 290.099899 -406.295904)
			(xy 290.106418 -406.313088) (xy 290.112196 -406.320244) (xy 290.133951 -406.345922) (xy 290.171899 -406.401506)
			(xy 290.202931 -406.461226) (xy 290.226605 -406.524227) (xy 290.242579 -406.589606) (xy 290.250625 -406.656425)
			(xy 290.250628 -406.723727) (xy 290.250621 -406.723789) (xy 293.52869 -406.723789) (xy 293.528692 -406.656363)
			(xy 293.536771 -406.589423) (xy 293.55281 -406.523932) (xy 293.576577 -406.460834) (xy 293.607731 -406.401037)
			(xy 293.645823 -406.345401) (xy 293.667688 -406.319736) (xy 293.673493 -406.312597) (xy 293.680003 -406.295402)
			(xy 293.680388 -406.286208) (xy 293.680388 -405.793956) (xy 293.680002 -405.784766) (xy 293.673472 -405.767582)
			(xy 293.667688 -405.760428) (xy 293.645821 -405.734766) (xy 293.607733 -405.679131) (xy 293.576583 -405.619334)
			(xy 293.552819 -405.556237) (xy 293.536785 -405.490747) (xy 293.528709 -405.423809) (xy 293.52871 -405.356385)
			(xy 293.536786 -405.289447) (xy 293.552821 -405.223958) (xy 293.576585 -405.160861) (xy 293.607736 -405.101064)
			(xy 293.645824 -405.045429) (xy 293.667688 -405.019764) (xy 293.673481 -405.012616) (xy 293.679998 -404.995428)
			(xy 293.680388 -404.986236) (xy 293.680388 -404.828756) (xy 293.680849 -404.818646) (xy 293.688599 -404.799969)
			(xy 293.702903 -404.785676) (xy 293.721586 -404.777941) (xy 293.731696 -404.777448) (xy 294.447976 -404.777448)
			(xy 294.458077 -404.778003) (xy 294.476745 -404.785723) (xy 294.491038 -404.799998) (xy 294.498783 -404.818656)
			(xy 294.499284 -404.828756) (xy 294.499284 -404.986236) (xy 294.49968 -404.995425) (xy 294.506204 -405.012609)
			(xy 294.511984 -405.019764) (xy 294.533845 -405.045432) (xy 294.571934 -405.101066) (xy 294.603086 -405.160862)
			(xy 294.626851 -405.223958) (xy 294.642888 -405.289447) (xy 294.650964 -405.356385) (xy 294.650964 -405.423809)
			(xy 294.642889 -405.490747) (xy 294.626853 -405.556236) (xy 294.603089 -405.619333) (xy 294.60081 -405.623708)
			(xy 295.728844 -405.623708) (xy 295.728845 -405.556283) (xy 295.736922 -405.489344) (xy 295.752959 -405.423854)
			(xy 295.776725 -405.360757) (xy 295.807879 -405.30096) (xy 295.84597 -405.245327) (xy 295.867836 -405.219662)
			(xy 295.873636 -405.212519) (xy 295.880148 -405.195327) (xy 295.880536 -405.186134) (xy 295.880536 -404.693882)
			(xy 295.880126 -404.684695) (xy 295.873611 -404.667511) (xy 295.867836 -404.660354) (xy 295.845992 -404.634672)
			(xy 295.807901 -404.57904) (xy 295.776747 -404.519247) (xy 295.75298 -404.456152) (xy 295.736942 -404.390665)
			(xy 295.728864 -404.323728) (xy 295.728862 -404.256305) (xy 295.736936 -404.189368) (xy 295.75297 -404.123879)
			(xy 295.776733 -404.060783) (xy 295.807884 -404.000988) (xy 295.845972 -403.945355) (xy 295.867836 -403.91969)
			(xy 295.873624 -403.912539) (xy 295.880143 -403.895353) (xy 295.880536 -403.886162) (xy 295.880536 -403.728682)
			(xy 295.881011 -403.718555) (xy 295.888744 -403.699834) (xy 295.903034 -403.685478) (xy 295.921719 -403.677659)
			(xy 295.931844 -403.67712) (xy 296.648124 -403.67712) (xy 296.658282 -403.677502) (xy 296.677039 -403.685309)
			(xy 296.691362 -403.699718) (xy 296.699058 -403.718521) (xy 296.699432 -403.728682) (xy 296.699432 -403.886162)
			(xy 296.699876 -403.895345) (xy 296.706368 -403.912529) (xy 296.712132 -403.91969) (xy 296.734016 -403.945338)
			(xy 296.772102 -404.000976) (xy 296.80325 -404.060775) (xy 296.827012 -404.123874) (xy 296.843045 -404.189364)
			(xy 296.851118 -404.256304) (xy 296.851117 -404.323729) (xy 296.843039 -404.390668) (xy 296.827002 -404.456158)
			(xy 296.803237 -404.519256) (xy 296.772085 -404.579053) (xy 296.733996 -404.634688) (xy 296.712132 -404.660354)
			(xy 296.706322 -404.667489) (xy 296.699817 -404.684688) (xy 296.699432 -404.693882) (xy 296.699432 -405.186134)
			(xy 296.699841 -405.195321) (xy 296.706357 -405.212505) (xy 296.712132 -405.219662) (xy 296.733989 -405.245333)
			(xy 296.772076 -405.300967) (xy 296.803225 -405.360763) (xy 296.826988 -405.423859) (xy 296.843023 -405.489347)
			(xy 296.851099 -405.556284) (xy 296.851099 -405.623707) (xy 296.843025 -405.690644) (xy 296.826991 -405.756132)
			(xy 296.803229 -405.819229) (xy 296.77208 -405.879025) (xy 296.733994 -405.93466) (xy 296.712132 -405.960326)
			(xy 296.706334 -405.96747) (xy 296.699822 -405.984662) (xy 296.699432 -405.993854) (xy 296.699432 -406.151334)
			(xy 296.699001 -406.161466) (xy 296.691256 -406.180194) (xy 296.676953 -406.19455) (xy 296.658254 -406.202363)
			(xy 296.648124 -406.202896) (xy 295.931844 -406.202896) (xy 295.921692 -406.202442) (xy 295.90294 -406.19466)
			(xy 295.888615 -406.180273) (xy 295.880915 -406.161487) (xy 295.880536 -406.151334) (xy 295.880536 -405.993854)
			(xy 295.880092 -405.984671) (xy 295.873601 -405.967486) (xy 295.867836 -405.960326) (xy 295.845965 -405.934666)
			(xy 295.807874 -405.879032) (xy 295.776722 -405.819235) (xy 295.752956 -405.756137) (xy 295.73692 -405.690647)
			(xy 295.728844 -405.623708) (xy 294.60081 -405.623708) (xy 294.571938 -405.679129) (xy 294.533848 -405.734763)
			(xy 294.511984 -405.760428) (xy 294.506191 -405.767576) (xy 294.499675 -405.784764) (xy 294.499284 -405.793956)
			(xy 294.499284 -406.286208) (xy 294.499694 -406.295395) (xy 294.506208 -406.312579) (xy 294.511984 -406.319736)
			(xy 294.533817 -406.345427) (xy 294.571908 -406.401057) (xy 294.603061 -406.46085) (xy 294.626827 -406.523943)
			(xy 294.642866 -406.58943) (xy 294.650944 -406.656365) (xy 294.650947 -406.72373) (xy 297.928985 -406.72373)
			(xy 297.928988 -406.656422) (xy 297.937036 -406.589596) (xy 297.953013 -406.524212) (xy 297.976691 -406.461206)
			(xy 298.00773 -406.401482) (xy 298.045685 -406.345896) (xy 298.067476 -406.320244) (xy 298.073276 -406.313101)
			(xy 298.079789 -406.295909) (xy 298.080176 -406.286716) (xy 298.080176 -405.793448) (xy 298.079748 -405.784263)
			(xy 298.073247 -405.767078) (xy 298.067476 -405.75992) (xy 298.045683 -405.734272) (xy 298.007732 -405.678685)
			(xy 297.976697 -405.618962) (xy 297.953023 -405.555957) (xy 297.937049 -405.490574) (xy 297.929005 -405.42375)
			(xy 297.929005 -405.356444) (xy 297.93705 -405.28962) (xy 297.953025 -405.224238) (xy 297.9767 -405.161233)
			(xy 298.007735 -405.101509) (xy 298.045687 -405.045924) (xy 298.067476 -405.020272) (xy 298.073264 -405.013121)
			(xy 298.079785 -404.995935) (xy 298.080176 -404.986744) (xy 298.080176 -404.828756) (xy 298.080585 -404.818602)
			(xy 298.088391 -404.799853) (xy 298.102791 -404.785532) (xy 298.121582 -404.77783) (xy 298.131738 -404.777448)
			(xy 298.848018 -404.777448) (xy 298.858147 -404.777912) (xy 298.87687 -404.785647) (xy 298.891226 -404.79994)
			(xy 298.899043 -404.818629) (xy 298.89958 -404.828756) (xy 298.89958 -404.986744) (xy 298.899973 -404.995933)
			(xy 298.906499 -405.013117) (xy 298.91228 -405.020272) (xy 298.934063 -405.045928) (xy 298.972011 -405.101514)
			(xy 299.003043 -405.161237) (xy 299.026716 -405.224241) (xy 299.042688 -405.289623) (xy 299.050732 -405.356445)
			(xy 299.050733 -405.423749) (xy 299.042689 -405.490571) (xy 299.026717 -405.555953) (xy 299.003046 -405.618957)
			(xy 299.000577 -405.623708) (xy 300.128635 -405.623708) (xy 300.128635 -405.556283) (xy 300.136712 -405.489344)
			(xy 300.152749 -405.423854) (xy 300.176515 -405.360757) (xy 300.207668 -405.300961) (xy 300.245759 -405.245327)
			(xy 300.267624 -405.219662) (xy 300.273422 -405.212518) (xy 300.279935 -405.195326) (xy 300.280324 -405.186134)
			(xy 300.280324 -404.693882) (xy 300.279917 -404.684695) (xy 300.273401 -404.66751) (xy 300.267624 -404.660354)
			(xy 300.245781 -404.634671) (xy 300.20769 -404.57904) (xy 300.176537 -404.519246) (xy 300.15277 -404.456152)
			(xy 300.136733 -404.390664) (xy 300.128655 -404.323728) (xy 300.128653 -404.256305) (xy 300.136727 -404.189368)
			(xy 300.152761 -404.12388) (xy 300.176523 -404.060784) (xy 300.207673 -404.000989) (xy 300.245761 -403.945355)
			(xy 300.267624 -403.91969) (xy 300.27341 -403.912538) (xy 300.27993 -403.895352) (xy 300.280324 -403.886162)
			(xy 300.280324 -403.728682) (xy 300.280811 -403.718556) (xy 300.288542 -403.699837) (xy 300.302828 -403.685482)
			(xy 300.321509 -403.677661) (xy 300.331632 -403.67712) (xy 301.047912 -403.67712) (xy 301.058069 -403.677512)
			(xy 301.076826 -403.685315) (xy 301.09115 -403.699721) (xy 301.098846 -403.718522) (xy 301.09922 -403.728682)
			(xy 301.09922 -403.886162) (xy 301.099644 -403.895348) (xy 301.106147 -403.912533) (xy 301.11192 -403.91969)
			(xy 301.133805 -403.945338) (xy 301.171892 -404.000975) (xy 301.20304 -404.060774) (xy 301.226802 -404.123873)
			(xy 301.242836 -404.189364) (xy 301.250909 -404.256304) (xy 301.250907 -404.323729) (xy 301.24283 -404.390668)
			(xy 301.226793 -404.456158) (xy 301.203027 -404.519256) (xy 301.171875 -404.579053) (xy 301.133785 -404.634688)
			(xy 301.11192 -404.660354) (xy 301.10612 -404.667497) (xy 301.099607 -404.684689) (xy 301.09922 -404.693882)
			(xy 301.09922 -405.186134) (xy 301.099609 -405.195323) (xy 301.106137 -405.212508) (xy 301.11192 -405.219662)
			(xy 301.133777 -405.245332) (xy 301.171865 -405.300967) (xy 301.203015 -405.360762) (xy 301.226778 -405.423859)
			(xy 301.242814 -405.489347) (xy 301.25089 -405.556284) (xy 301.25089 -405.623707) (xy 301.242815 -405.690644)
			(xy 301.226781 -405.756133) (xy 301.203018 -405.819229) (xy 301.17187 -405.879026) (xy 301.133783 -405.93466)
			(xy 301.11192 -405.960326) (xy 301.106132 -405.967478) (xy 301.099612 -405.984663) (xy 301.09922 -405.993854)
			(xy 301.09922 -406.151334) (xy 301.0988 -406.161468) (xy 301.091054 -406.180197) (xy 301.076747 -406.194554)
			(xy 301.058044 -406.202365) (xy 301.047912 -406.202896) (xy 300.331632 -406.202896) (xy 300.321479 -406.202452)
			(xy 300.302727 -406.194667) (xy 300.288402 -406.180276) (xy 300.280702 -406.161488) (xy 300.280324 -406.151334)
			(xy 300.280324 -405.993854) (xy 300.279882 -405.98467) (xy 300.27339 -405.967486) (xy 300.267624 -405.960326)
			(xy 300.245753 -405.934666) (xy 300.207663 -405.879031) (xy 300.176511 -405.819235) (xy 300.152747 -405.756137)
			(xy 300.136711 -405.690647) (xy 300.128635 -405.623708) (xy 299.000577 -405.623708) (xy 298.972014 -405.678681)
			(xy 298.934067 -405.734268) (xy 298.91228 -405.75992) (xy 298.90649 -405.76707) (xy 298.899972 -405.784257)
			(xy 298.89958 -405.793448) (xy 298.89958 -406.286716) (xy 298.899987 -406.295903) (xy 298.906503 -406.313088)
			(xy 298.91228 -406.320244) (xy 298.934035 -406.345922) (xy 298.971984 -406.401506) (xy 299.003018 -406.461226)
			(xy 299.026691 -406.524227) (xy 299.042666 -406.589606) (xy 299.050712 -406.656425) (xy 299.050715 -406.723727)
			(xy 299.050708 -406.723789) (xy 302.328777 -406.723789) (xy 302.32878 -406.656363) (xy 302.336859 -406.589423)
			(xy 302.352897 -406.523933) (xy 302.376664 -406.460835) (xy 302.407816 -406.401037) (xy 302.445907 -406.345402)
			(xy 302.467772 -406.319736) (xy 302.473587 -406.312604) (xy 302.480089 -406.295403) (xy 302.480472 -406.286208)
			(xy 302.480472 -405.793956) (xy 302.480089 -405.784766) (xy 302.473557 -405.767581) (xy 302.467772 -405.760428)
			(xy 302.445905 -405.734766) (xy 302.407818 -405.67913) (xy 302.376669 -405.619333) (xy 302.352907 -405.556236)
			(xy 302.336872 -405.490747) (xy 302.328797 -405.423809) (xy 302.328798 -405.356385) (xy 302.336873 -405.289447)
			(xy 302.352908 -405.223958) (xy 302.376672 -405.160861) (xy 302.407821 -405.101065) (xy 302.445909 -405.04543)
			(xy 302.467772 -405.019764) (xy 302.473575 -405.012624) (xy 302.480084 -404.995429) (xy 302.480472 -404.986236)
			(xy 302.480472 -404.828756) (xy 302.480948 -404.818648) (xy 302.488695 -404.799974) (xy 302.502994 -404.785682)
			(xy 302.521672 -404.777944) (xy 302.53178 -404.777448) (xy 303.24806 -404.777448) (xy 303.25816 -404.778017)
			(xy 303.276827 -404.785732) (xy 303.291121 -404.800002) (xy 303.298867 -404.818657) (xy 303.299368 -404.828756)
			(xy 303.299368 -404.986236) (xy 303.299768 -404.995424) (xy 303.30629 -405.012608) (xy 303.312068 -405.019764)
			(xy 303.333929 -405.045432) (xy 303.37202 -405.101065) (xy 303.403173 -405.160861) (xy 303.426939 -405.223957)
			(xy 303.442975 -405.289447) (xy 303.451052 -405.356385) (xy 303.451052 -405.423809) (xy 303.442976 -405.490748)
			(xy 303.42694 -405.556237) (xy 303.403175 -405.619334) (xy 303.372023 -405.67913) (xy 303.333933 -405.734763)
			(xy 303.312068 -405.760428) (xy 303.306273 -405.767574) (xy 303.299758 -405.784764) (xy 303.299368 -405.793956)
			(xy 303.299368 -406.286208) (xy 303.299781 -406.295395) (xy 303.306294 -406.312579) (xy 303.312068 -406.319736)
			(xy 303.333902 -406.345427) (xy 303.371993 -406.401057) (xy 303.403147 -406.460849) (xy 303.426915 -406.523943)
			(xy 303.442953 -406.589429) (xy 303.451032 -406.656365) (xy 303.451035 -406.723787) (xy 303.442962 -406.790724)
			(xy 303.426929 -406.856211) (xy 303.403167 -406.919307) (xy 303.372018 -406.979102) (xy 303.333931 -407.034735)
			(xy 303.312068 -407.0604) (xy 303.306285 -407.067555) (xy 303.299763 -407.084738) (xy 303.299368 -407.093928)
			(xy 303.299368 -407.251408) (xy 303.29899 -407.261535) (xy 303.291233 -407.280245) (xy 303.276904 -407.29456)
			(xy 303.258187 -407.302299) (xy 303.24806 -407.302716) (xy 302.53178 -407.302716) (xy 302.521672 -407.302232)
			(xy 302.502996 -407.294491) (xy 302.488703 -407.280194) (xy 302.480966 -407.261516) (xy 302.480472 -407.251408)
			(xy 302.480472 -407.093928) (xy 302.480055 -407.084741) (xy 302.473547 -407.067557) (xy 302.467772 -407.0604)
			(xy 302.445878 -407.03476) (xy 302.407792 -406.979121) (xy 302.376644 -406.919321) (xy 302.352883 -406.856221)
			(xy 302.33685 -406.790729) (xy 302.328777 -406.723789) (xy 299.050708 -406.723789) (xy 299.042674 -406.790547)
			(xy 299.026705 -406.855927) (xy 299.003037 -406.91893) (xy 298.972009 -406.978653) (xy 298.934065 -407.034239)
			(xy 298.91228 -407.059892) (xy 298.906502 -407.06705) (xy 298.899977 -407.084231) (xy 298.89958 -407.09342)
			(xy 298.89958 -407.251408) (xy 298.899184 -407.261565) (xy 298.891382 -407.280321) (xy 298.876978 -407.294645)
			(xy 298.858177 -407.302341) (xy 298.848018 -407.302716) (xy 298.131738 -407.302716) (xy 298.121608 -407.302241)
			(xy 298.10288 -407.294517) (xy 298.088521 -407.280227) (xy 298.080708 -407.261535) (xy 298.080176 -407.251408)
			(xy 298.080176 -407.09342) (xy 298.079762 -407.084233) (xy 298.073252 -407.067048) (xy 298.067476 -407.059892)
			(xy 298.045656 -407.034266) (xy 298.007706 -406.978677) (xy 297.976672 -406.91895) (xy 297.952999 -406.855942)
			(xy 297.937027 -406.790556) (xy 297.928985 -406.72373) (xy 294.650947 -406.72373) (xy 294.650947 -406.723787)
			(xy 294.642874 -406.790723) (xy 294.626842 -406.856211) (xy 294.60308 -406.919306) (xy 294.571933 -406.979101)
			(xy 294.533847 -407.034735) (xy 294.511984 -407.0604) (xy 294.506203 -407.067556) (xy 294.49968 -407.084738)
			(xy 294.499284 -407.093928) (xy 294.499284 -407.251408) (xy 294.49889 -407.261533) (xy 294.491136 -407.28024)
			(xy 294.476813 -407.294554) (xy 294.458101 -407.302296) (xy 294.447976 -407.302716) (xy 293.731696 -407.302716)
			(xy 293.721589 -407.302218) (xy 293.702914 -407.294482) (xy 293.68862 -407.28019) (xy 293.680882 -407.261515)
			(xy 293.680388 -407.251408) (xy 293.680388 -407.093928) (xy 293.679967 -407.084742) (xy 293.673461 -407.067557)
			(xy 293.667688 -407.0604) (xy 293.645793 -407.03476) (xy 293.607706 -406.979122) (xy 293.576557 -406.919322)
			(xy 293.552796 -406.856222) (xy 293.536763 -406.79073) (xy 293.52869 -406.723789) (xy 290.250621 -406.723789)
			(xy 290.242587 -406.790547) (xy 290.226619 -406.855927) (xy 290.202951 -406.91893) (xy 290.171924 -406.978653)
			(xy 290.133981 -407.034239) (xy 290.112196 -407.059892) (xy 290.10642 -407.067052) (xy 290.099893 -407.084231)
			(xy 290.099496 -407.09342) (xy 290.099496 -407.251408) (xy 290.099085 -407.261563) (xy 290.091286 -407.280316)
			(xy 290.076886 -407.29464) (xy 290.058091 -407.302338) (xy 290.047934 -407.302716) (xy 289.331654 -407.302716)
			(xy 289.321519 -407.30231) (xy 289.302788 -407.294559) (xy 289.288432 -407.280248) (xy 289.280622 -407.261541)
			(xy 289.280092 -407.251408) (xy 289.280092 -407.09342) (xy 289.279674 -407.084234) (xy 289.273166 -407.067049)
			(xy 289.267392 -407.059892) (xy 289.245571 -407.034266) (xy 289.20762 -406.978677) (xy 289.176585 -406.918951)
			(xy 289.152912 -406.855943) (xy 289.136939 -406.790557) (xy 289.128897 -406.72373) (xy 237.026196 -406.72373)
			(xy 237.026196 -409.523887) (xy 286.928735 -409.523887) (xy 286.928738 -409.456459) (xy 286.936818 -409.389518)
			(xy 286.952859 -409.324026) (xy 286.97663 -409.260927) (xy 287.007788 -409.20113) (xy 287.045884 -409.145496)
			(xy 287.067752 -409.119832) (xy 287.073566 -409.1127) (xy 287.080069 -409.095499) (xy 287.080452 -409.086304)
			(xy 287.080452 -408.594052) (xy 287.080005 -408.584869) (xy 287.073516 -408.567685) (xy 287.067752 -408.560524)
			(xy 287.045878 -408.534866) (xy 287.007786 -408.479232) (xy 286.976633 -408.419435) (xy 286.952867 -408.356337)
			(xy 286.936831 -408.290847) (xy 286.928755 -408.223907) (xy 286.928755 -408.156481) (xy 286.936833 -408.089542)
			(xy 286.952871 -408.024051) (xy 286.976638 -407.960954) (xy 287.007793 -407.901158) (xy 287.045886 -407.845524)
			(xy 287.067752 -407.81986) (xy 287.073554 -407.812719) (xy 287.080064 -407.795525) (xy 287.080452 -407.786332)
			(xy 287.080452 -407.628852) (xy 287.080945 -407.618746) (xy 287.088689 -407.600076) (xy 287.102983 -407.585785)
			(xy 287.121654 -407.578043) (xy 287.13176 -407.577544) (xy 287.84804 -407.577544) (xy 287.858144 -407.578051)
			(xy 287.876813 -407.585791) (xy 287.891104 -407.600081) (xy 287.898847 -407.618748) (xy 287.899348 -407.628852)
			(xy 287.899348 -407.786332) (xy 287.899755 -407.795519) (xy 287.906272 -407.812703) (xy 287.912048 -407.81986)
			(xy 287.933906 -407.845531) (xy 287.971998 -407.901163) (xy 288.003152 -407.960958) (xy 288.026919 -408.024055)
			(xy 288.042957 -408.089543) (xy 288.051034 -408.156482) (xy 288.051035 -408.223906) (xy 288.042959 -408.290845)
			(xy 288.026923 -408.356334) (xy 288.003157 -408.419431) (xy 287.972004 -408.479226) (xy 287.933913 -408.53486)
			(xy 287.912048 -408.560524) (xy 287.906252 -408.56767) (xy 287.899739 -408.58486) (xy 287.899348 -408.594052)
			(xy 287.899348 -409.086304) (xy 287.899768 -409.09549) (xy 287.906276 -409.112674) (xy 287.912048 -409.119832)
			(xy 287.933878 -409.145526) (xy 287.971972 -409.201155) (xy 288.003127 -409.260947) (xy 288.026895 -409.32404)
			(xy 288.042935 -409.389526) (xy 288.051014 -409.456462) (xy 288.051018 -409.523884) (xy 288.042945 -409.590821)
			(xy 288.026911 -409.656308) (xy 288.003149 -409.719404) (xy 287.971999 -409.779199) (xy 287.933912 -409.834832)
			(xy 287.912048 -409.860496) (xy 287.906264 -409.86765) (xy 287.899743 -409.884834) (xy 287.899348 -409.894024)
			(xy 287.899348 -410.051504) (xy 287.898819 -410.061607) (xy 287.891089 -410.080276) (xy 287.876806 -410.094569)
			(xy 287.858143 -410.102312) (xy 287.84804 -410.102812) (xy 287.13176 -410.102812) (xy 287.12165 -410.102348)
			(xy 287.102973 -410.094599) (xy 287.08868 -410.080296) (xy 287.080945 -410.061614) (xy 287.080452 -410.051504)
			(xy 287.080452 -409.894024) (xy 287.080019 -409.884839) (xy 287.07352 -409.867655) (xy 287.067752 -409.860496)
			(xy 287.045851 -409.834861) (xy 287.00776 -409.779223) (xy 286.976608 -409.719423) (xy 286.952843 -409.656322)
			(xy 286.936809 -409.590829) (xy 286.928735 -409.523887) (xy 237.026196 -409.523887) (xy 237.026196 -410.623642)
			(xy 289.128908 -410.623642) (xy 289.12891 -410.556334) (xy 289.136956 -410.48951) (xy 289.152933 -410.424126)
			(xy 289.176609 -410.361121) (xy 289.207648 -410.301397) (xy 289.245602 -410.245811) (xy 289.267392 -410.22016)
			(xy 289.273187 -410.213014) (xy 289.279703 -410.195824) (xy 289.280092 -410.186632) (xy 289.280092 -409.693364)
			(xy 289.279701 -409.684175) (xy 289.273174 -409.66699) (xy 289.267392 -409.659836) (xy 289.245614 -409.634175)
			(xy 289.207662 -409.578591) (xy 289.176625 -409.518869) (xy 289.152949 -409.455866) (xy 289.136974 -409.390484)
			(xy 289.128928 -409.323662) (xy 289.128927 -409.256356) (xy 289.136971 -409.189534) (xy 289.152944 -409.124152)
			(xy 289.176618 -409.061147) (xy 289.207653 -409.001425) (xy 289.245603 -408.945839) (xy 289.267392 -408.920188)
			(xy 289.273175 -408.913033) (xy 289.279698 -408.89585) (xy 289.280092 -408.88666) (xy 289.280092 -408.728672)
			(xy 289.280498 -408.718517) (xy 289.288302 -408.699766) (xy 289.302703 -408.685443) (xy 289.321497 -408.677743)
			(xy 289.331654 -408.677364) (xy 290.047934 -408.677364) (xy 290.058066 -408.677799) (xy 290.076792 -408.685543)
			(xy 290.091148 -408.699845) (xy 290.098962 -408.718542) (xy 290.099496 -408.728672) (xy 290.099496 -408.88666)
			(xy 290.099926 -408.895845) (xy 290.106426 -408.91303) (xy 290.112196 -408.920188) (xy 290.133994 -408.945831)
			(xy 290.171941 -409.00142) (xy 290.202971 -409.061145) (xy 290.226642 -409.12415) (xy 290.242613 -409.189533)
			(xy 290.250656 -409.256356) (xy 290.250655 -409.323662) (xy 290.24261 -409.390484) (xy 290.226637 -409.455867)
			(xy 290.202964 -409.518872) (xy 290.200389 -409.523827) (xy 291.329055 -409.523827) (xy 291.329058 -409.456519)
			(xy 291.337106 -409.389694) (xy 291.353082 -409.32431) (xy 291.376759 -409.261304) (xy 291.407797 -409.201579)
			(xy 291.44575 -409.145992) (xy 291.46754 -409.12034) (xy 291.47335 -409.113204) (xy 291.479855 -409.096006)
			(xy 291.48024 -409.086812) (xy 291.48024 -408.593544) (xy 291.4798 -408.58436) (xy 291.473306 -408.567176)
			(xy 291.46754 -408.560016) (xy 291.445744 -408.53437) (xy 291.407796 -408.478783) (xy 291.376763 -408.419059)
			(xy 291.35309 -408.356053) (xy 291.337118 -408.29067) (xy 291.329074 -408.223847) (xy 291.329075 -408.156541)
			(xy 291.33712 -408.089718) (xy 291.353094 -408.024335) (xy 291.376767 -407.96133) (xy 291.407802 -407.901607)
			(xy 291.445752 -407.84602) (xy 291.46754 -407.820368) (xy 291.473338 -407.813224) (xy 291.479851 -407.796032)
			(xy 291.48024 -407.78684) (xy 291.48024 -407.628852) (xy 291.480583 -407.61869) (xy 291.488402 -407.599929)
			(xy 291.502823 -407.585606) (xy 291.521637 -407.577915) (xy 291.531802 -407.577544) (xy 292.248082 -407.577544)
			(xy 292.258208 -407.578041) (xy 292.27693 -407.585764) (xy 292.291287 -407.600047) (xy 292.299106 -407.618729)
			(xy 292.299644 -407.628852) (xy 292.299644 -407.78684) (xy 292.300048 -407.796028) (xy 292.306567 -407.813211)
			(xy 292.312344 -407.820368) (xy 292.334124 -407.846026) (xy 292.372074 -407.901612) (xy 292.403109 -407.961334)
			(xy 292.426783 -408.024338) (xy 292.442757 -408.089719) (xy 292.450802 -408.156542) (xy 292.450803 -408.223846)
			(xy 292.442759 -408.290669) (xy 292.426786 -408.356051) (xy 292.403114 -408.419055) (xy 292.372081 -408.478778)
			(xy 292.334132 -408.534364) (xy 292.312344 -408.560016) (xy 292.306551 -408.567164) (xy 292.300036 -408.584353)
			(xy 292.299644 -408.593544) (xy 292.299644 -409.086812) (xy 292.300061 -409.095998) (xy 292.306571 -409.113182)
			(xy 292.312344 -409.12034) (xy 292.334097 -409.146021) (xy 292.372048 -409.201603) (xy 292.403083 -409.261322)
			(xy 292.426759 -409.324323) (xy 292.442735 -409.389702) (xy 292.450782 -409.456522) (xy 292.450786 -409.523824)
			(xy 292.442745 -409.590645) (xy 292.426775 -409.656025) (xy 292.403106 -409.719028) (xy 292.372076 -409.77875)
			(xy 292.33413 -409.834336) (xy 292.312344 -409.859988) (xy 292.306521 -409.867114) (xy 292.300024 -409.884319)
			(xy 292.299644 -409.893516) (xy 292.299644 -410.051504) (xy 292.299182 -410.061653) (xy 292.291394 -410.080397)
			(xy 292.27701 -410.094718) (xy 292.258233 -410.102426) (xy 292.248082 -410.102812) (xy 291.531802 -410.102812)
			(xy 291.521682 -410.102273) (xy 291.502971 -410.094556) (xy 291.488616 -410.080286) (xy 291.480788 -410.061621)
			(xy 291.48024 -410.051504) (xy 291.48024 -409.893516) (xy 291.479813 -409.884331) (xy 291.47331 -409.867147)
			(xy 291.46754 -409.859988) (xy 291.445717 -409.834365) (xy 291.407769 -409.778774) (xy 291.376737 -409.719047)
			(xy 291.353066 -409.656039) (xy 291.337096 -409.590653) (xy 291.329055 -409.523827) (xy 290.200389 -409.523827)
			(xy 290.171931 -409.578596) (xy 290.133983 -409.634183) (xy 290.112196 -409.659836) (xy 290.106401 -409.666982)
			(xy 290.099886 -409.684172) (xy 290.099496 -409.693364) (xy 290.099496 -410.186632) (xy 290.099891 -410.195821)
			(xy 290.106415 -410.213005) (xy 290.112196 -410.22016) (xy 290.133967 -410.245826) (xy 290.171914 -410.301411)
			(xy 290.202946 -410.361133) (xy 290.226618 -410.424136) (xy 290.242591 -410.489516) (xy 290.250636 -410.556336)
			(xy 290.250638 -410.62364) (xy 290.250631 -410.6237) (xy 293.528701 -410.6237) (xy 293.528702 -410.556276)
			(xy 293.53678 -410.489336) (xy 293.552816 -410.423847) (xy 293.576582 -410.360749) (xy 293.607734 -410.300952)
			(xy 293.645824 -410.245317) (xy 293.667688 -410.219652) (xy 293.673486 -410.212508) (xy 293.68 -410.195317)
			(xy 293.680388 -410.186124) (xy 293.680388 -409.693872) (xy 293.679994 -409.684683) (xy 293.673469 -409.667499)
			(xy 293.667688 -409.660344) (xy 293.645836 -409.634669) (xy 293.607748 -409.579035) (xy 293.576597 -409.519241)
			(xy 293.552833 -409.456145) (xy 293.536797 -409.390657) (xy 293.52872 -409.32372) (xy 293.528719 -409.256298)
			(xy 293.536794 -409.189361) (xy 293.552828 -409.123872) (xy 293.57659 -409.060776) (xy 293.607739 -409.00098)
			(xy 293.645825 -408.945345) (xy 293.667688 -408.91968) (xy 293.673474 -408.912527) (xy 293.679995 -408.895343)
			(xy 293.680388 -408.886152) (xy 293.680388 -408.728672) (xy 293.680862 -408.718563) (xy 293.688606 -408.699886)
			(xy 293.702907 -408.685593) (xy 293.721587 -408.677857) (xy 293.731696 -408.677364) (xy 294.447976 -408.677364)
			(xy 294.458079 -408.677904) (xy 294.47675 -408.685627) (xy 294.491044 -408.699907) (xy 294.498786 -408.71857)
			(xy 294.499284 -408.728672) (xy 294.499284 -408.886152) (xy 294.499721 -408.895336) (xy 294.506216 -408.912521)
			(xy 294.511984 -408.91968) (xy 294.53386 -408.945335) (xy 294.57195 -409.000971) (xy 294.603101 -409.060768)
			(xy 294.626865 -409.123866) (xy 294.6429 -409.189357) (xy 294.650975 -409.256297) (xy 294.650974 -409.323721)
			(xy 294.642897 -409.390661) (xy 294.62686 -409.456151) (xy 294.603093 -409.519248) (xy 294.600676 -409.523887)
			(xy 295.728823 -409.523887) (xy 295.728826 -409.456459) (xy 295.736906 -409.389518) (xy 295.752947 -409.324026)
			(xy 295.776716 -409.260928) (xy 295.807873 -409.201131) (xy 295.845969 -409.145497) (xy 295.867836 -409.119832)
			(xy 295.873649 -409.112698) (xy 295.880153 -409.095499) (xy 295.880536 -409.086304) (xy 295.880536 -408.594052)
			(xy 295.880093 -408.584869) (xy 295.873601 -408.567684) (xy 295.867836 -408.560524) (xy 295.845963 -408.534866)
			(xy 295.807872 -408.479231) (xy 295.77672 -408.419434) (xy 295.752954 -408.356336) (xy 295.736918 -408.290846)
			(xy 295.728843 -408.223907) (xy 295.728843 -408.156481) (xy 295.736921 -408.089542) (xy 295.752958 -408.024052)
			(xy 295.776725 -407.960955) (xy 295.807878 -407.901159) (xy 295.84597 -407.845525) (xy 295.867836 -407.81986)
			(xy 295.873637 -407.812718) (xy 295.880148 -407.795525) (xy 295.880536 -407.786332) (xy 295.880536 -407.628852)
			(xy 295.880947 -407.618736) (xy 295.888707 -407.60005) (xy 295.903027 -407.585755) (xy 295.921727 -407.578029)
			(xy 295.931844 -407.577544) (xy 296.648124 -407.577544) (xy 296.658227 -407.578064) (xy 296.676895 -407.585799)
			(xy 296.691187 -407.600084) (xy 296.698931 -407.618749) (xy 296.699432 -407.628852) (xy 296.699432 -407.786332)
			(xy 296.699842 -407.795519) (xy 296.706357 -407.812703) (xy 296.712132 -407.81986) (xy 296.733987 -407.845532)
			(xy 296.772074 -407.901167) (xy 296.803223 -407.960962) (xy 296.826986 -408.024058) (xy 296.843021 -408.089546)
			(xy 296.851097 -408.156483) (xy 296.851098 -408.223905) (xy 296.843024 -408.290842) (xy 296.82699 -408.356331)
			(xy 296.803228 -408.419427) (xy 296.77208 -408.479223) (xy 296.733994 -408.534858) (xy 296.712132 -408.560524)
			(xy 296.706334 -408.567668) (xy 296.699822 -408.58486) (xy 296.699432 -408.594052) (xy 296.699432 -409.086304)
			(xy 296.699856 -409.095489) (xy 296.706362 -409.112673) (xy 296.712132 -409.119832) (xy 296.733959 -409.145527)
			(xy 296.772047 -409.201158) (xy 296.803198 -409.26095) (xy 296.826962 -409.324043) (xy 296.842999 -409.389528)
			(xy 296.851078 -409.456463) (xy 296.851081 -409.523883) (xy 296.843009 -409.590818) (xy 296.826978 -409.656305)
			(xy 296.80322 -409.7194) (xy 296.772075 -409.779196) (xy 296.733993 -409.83483) (xy 296.712132 -409.860496)
			(xy 296.706346 -409.867649) (xy 296.699827 -409.884834) (xy 296.699432 -409.894024) (xy 296.699432 -410.051504)
			(xy 296.698919 -410.061609) (xy 296.691186 -410.080281) (xy 296.676898 -410.094575) (xy 296.658229 -410.102315)
			(xy 296.648124 -410.102812) (xy 295.931844 -410.102812) (xy 295.921726 -410.102348) (xy 295.903026 -410.094617)
			(xy 295.88871 -410.080315) (xy 295.880961 -410.061622) (xy 295.880536 -410.051504) (xy 295.880536 -409.894024)
			(xy 295.880106 -409.884839) (xy 295.873605 -409.867655) (xy 295.867836 -409.860496) (xy 295.845935 -409.834861)
			(xy 295.807845 -409.779223) (xy 295.776694 -409.719423) (xy 295.752931 -409.656322) (xy 295.736896 -409.590829)
			(xy 295.728823 -409.523887) (xy 294.600676 -409.523887) (xy 294.57194 -409.579045) (xy 294.533849 -409.634679)
			(xy 294.511984 -409.660344) (xy 294.506184 -409.667487) (xy 294.499672 -409.684679) (xy 294.499284 -409.693872)
			(xy 294.499284 -410.186124) (xy 294.499686 -410.195312) (xy 294.506206 -410.212496) (xy 294.511984 -410.219652)
			(xy 294.533833 -410.24533) (xy 294.571923 -410.300962) (xy 294.603075 -410.360757) (xy 294.626841 -410.423852)
			(xy 294.642878 -410.489339) (xy 294.650956 -410.556277) (xy 294.650957 -410.623641) (xy 297.928996 -410.623641)
			(xy 297.928998 -410.556334) (xy 297.937044 -410.48951) (xy 297.95302 -410.424127) (xy 297.976696 -410.361121)
			(xy 298.007733 -410.301398) (xy 298.045686 -410.245812) (xy 298.067476 -410.22016) (xy 298.073269 -410.213012)
			(xy 298.079787 -410.195824) (xy 298.080176 -410.186632) (xy 298.080176 -409.693364) (xy 298.079788 -409.684174)
			(xy 298.07326 -409.66699) (xy 298.067476 -409.659836) (xy 298.045699 -409.634175) (xy 298.007747 -409.57859)
			(xy 297.976712 -409.518868) (xy 297.953037 -409.455865) (xy 297.937062 -409.390484) (xy 297.929016 -409.323661)
			(xy 297.929015 -409.256357) (xy 297.937058 -409.189534) (xy 297.953031 -409.124152) (xy 297.976704 -409.061148)
			(xy 298.007738 -409.001425) (xy 298.045688 -408.94584) (xy 298.067476 -408.920188) (xy 298.073257 -408.913032)
			(xy 298.079782 -408.89585) (xy 298.080176 -408.88666) (xy 298.080176 -408.728672) (xy 298.080598 -408.718519)
			(xy 298.088398 -408.699771) (xy 298.102794 -408.685449) (xy 298.121583 -408.677746) (xy 298.131738 -408.677364)
			(xy 298.848018 -408.677364) (xy 298.858149 -408.677812) (xy 298.876875 -408.68555) (xy 298.891232 -408.699849)
			(xy 298.899046 -408.718543) (xy 298.89958 -408.728672) (xy 298.89958 -408.88666) (xy 298.900014 -408.895845)
			(xy 298.906512 -408.913029) (xy 298.91228 -408.920188) (xy 298.934079 -408.945831) (xy 298.972026 -409.001419)
			(xy 299.003058 -409.061144) (xy 299.026729 -409.12415) (xy 299.042701 -409.189533) (xy 299.050744 -409.256356)
			(xy 299.050743 -409.323662) (xy 299.042698 -409.390485) (xy 299.026724 -409.455868) (xy 299.003051 -409.518873)
			(xy 299.000446 -409.523886) (xy 300.128614 -409.523886) (xy 300.128617 -409.456459) (xy 300.136697 -409.389518)
			(xy 300.152737 -409.324027) (xy 300.176506 -409.260928) (xy 300.207662 -409.201131) (xy 300.245757 -409.145497)
			(xy 300.267624 -409.119832) (xy 300.273435 -409.112697) (xy 300.27994 -409.095499) (xy 300.280324 -409.086304)
			(xy 300.280324 -408.594052) (xy 300.279883 -408.584868) (xy 300.27339 -408.567684) (xy 300.267624 -408.560524)
			(xy 300.245751 -408.534866) (xy 300.207661 -408.479231) (xy 300.17651 -408.419434) (xy 300.152745 -408.356336)
			(xy 300.136709 -408.290846) (xy 300.128634 -408.223906) (xy 300.128634 -408.156482) (xy 300.136711 -408.089542)
			(xy 300.152748 -408.024053) (xy 300.176514 -407.960955) (xy 300.207667 -407.901159) (xy 300.245759 -407.845525)
			(xy 300.267624 -407.81986) (xy 300.273423 -407.812717) (xy 300.279935 -407.795525) (xy 300.280324 -407.786332)
			(xy 300.280324 -407.628852) (xy 300.280747 -407.618737) (xy 300.288504 -407.600053) (xy 300.302821 -407.585759)
			(xy 300.321516 -407.578031) (xy 300.331632 -407.577544) (xy 301.047912 -407.577544) (xy 301.058015 -407.578074)
			(xy 301.076682 -407.585805) (xy 301.090975 -407.600088) (xy 301.098719 -407.61875) (xy 301.09922 -407.628852)
			(xy 301.09922 -407.786332) (xy 301.09961 -407.795521) (xy 301.106137 -407.812706) (xy 301.11192 -407.81986)
			(xy 301.133775 -407.845532) (xy 301.171863 -407.901166) (xy 301.203013 -407.960962) (xy 301.226777 -408.024057)
			(xy 301.242812 -408.089545) (xy 301.250888 -408.156483) (xy 301.250889 -408.223905) (xy 301.242814 -408.290843)
			(xy 301.22678 -408.356331) (xy 301.203018 -408.419427) (xy 301.171869 -408.479224) (xy 301.133783 -408.534858)
			(xy 301.11192 -408.560524) (xy 301.106133 -408.567676) (xy 301.099612 -408.584861) (xy 301.09922 -408.594052)
			(xy 301.09922 -409.086304) (xy 301.099624 -409.095492) (xy 301.106141 -409.112676) (xy 301.11192 -409.119832)
			(xy 301.133748 -409.145527) (xy 301.171836 -409.201158) (xy 301.202988 -409.26095) (xy 301.226753 -409.324043)
			(xy 301.24279 -409.389528) (xy 301.250869 -409.456463) (xy 301.250872 -409.523883) (xy 301.2428 -409.590819)
			(xy 301.226769 -409.656305) (xy 301.20301 -409.719401) (xy 301.171864 -409.779196) (xy 301.133781 -409.83483)
			(xy 301.11192 -409.860496) (xy 301.106145 -409.867657) (xy 301.099617 -409.884835) (xy 301.09922 -409.894024)
			(xy 301.09922 -410.051504) (xy 301.098719 -410.06161) (xy 301.090983 -410.080285) (xy 301.076692 -410.094579)
			(xy 301.058018 -410.102317) (xy 301.047912 -410.102812) (xy 300.331632 -410.102812) (xy 300.321513 -410.102358)
			(xy 300.302812 -410.094623) (xy 300.288497 -410.080318) (xy 300.280749 -410.061623) (xy 300.280324 -410.051504)
			(xy 300.280324 -409.894024) (xy 300.279897 -409.884839) (xy 300.273394 -409.867655) (xy 300.267624 -409.860496)
			(xy 300.245724 -409.83486) (xy 300.207635 -409.779222) (xy 300.176484 -409.719422) (xy 300.152721 -409.656321)
			(xy 300.136687 -409.590828) (xy 300.128614 -409.523886) (xy 299.000446 -409.523886) (xy 298.972017 -409.578597)
			(xy 298.934068 -409.634184) (xy 298.91228 -409.659836) (xy 298.906483 -409.666981) (xy 298.899969 -409.684172)
			(xy 298.89958 -409.693364) (xy 298.89958 -410.186632) (xy 298.899979 -410.19582) (xy 298.906501 -410.213004)
			(xy 298.91228 -410.22016) (xy 298.934052 -410.245825) (xy 298.972 -410.30141) (xy 299.003032 -410.361132)
			(xy 299.026705 -410.424135) (xy 299.042679 -410.489515) (xy 299.050724 -410.556336) (xy 299.050725 -410.62364)
			(xy 299.050718 -410.6237) (xy 302.328789 -410.6237) (xy 302.32879 -410.556276) (xy 302.336867 -410.489337)
			(xy 302.352904 -410.423847) (xy 302.376668 -410.36075) (xy 302.407819 -410.300953) (xy 302.445908 -410.245318)
			(xy 302.467772 -410.219652) (xy 302.47358 -410.212515) (xy 302.480086 -410.195318) (xy 302.480472 -410.186124)
			(xy 302.480472 -409.693872) (xy 302.480082 -409.684683) (xy 302.473555 -409.667498) (xy 302.467772 -409.660344)
			(xy 302.445921 -409.634669) (xy 302.407834 -409.579035) (xy 302.376684 -409.51924) (xy 302.35292 -409.456144)
			(xy 302.336885 -409.390657) (xy 302.328808 -409.32372) (xy 302.328807 -409.256298) (xy 302.336882 -409.189361)
			(xy 302.352915 -409.123873) (xy 302.376677 -409.060777) (xy 302.407824 -409.000981) (xy 302.44591 -408.945346)
			(xy 302.467772 -408.91968) (xy 302.473568 -408.912535) (xy 302.480081 -408.895344) (xy 302.480472 -408.886152)
			(xy 302.480472 -408.728672) (xy 302.480961 -408.718565) (xy 302.488703 -408.699891) (xy 302.502998 -408.685599)
			(xy 302.521673 -408.67786) (xy 302.53178 -408.677364) (xy 303.24806 -408.677364) (xy 303.258175 -408.677848)
			(xy 303.276871 -408.685576) (xy 303.291186 -408.699872) (xy 303.298939 -408.718557) (xy 303.299368 -408.728672)
			(xy 303.299368 -408.886152) (xy 303.299809 -408.895336) (xy 303.306302 -408.91252) (xy 303.312068 -408.91968)
			(xy 303.333945 -408.945335) (xy 303.372035 -409.00097) (xy 303.403187 -409.060768) (xy 303.426952 -409.123866)
			(xy 303.442988 -409.189356) (xy 303.451063 -409.256296) (xy 303.451062 -409.323722) (xy 303.442985 -409.390661)
			(xy 303.426947 -409.456151) (xy 303.40318 -409.519249) (xy 303.372026 -409.579045) (xy 303.333934 -409.634679)
			(xy 303.312068 -409.660344) (xy 303.306266 -409.667485) (xy 303.299755 -409.684679) (xy 303.299368 -409.693872)
			(xy 303.299368 -410.186124) (xy 303.299774 -410.195312) (xy 303.306291 -410.212495) (xy 303.312068 -410.219652)
			(xy 303.333917 -410.24533) (xy 303.372009 -410.300962) (xy 303.403162 -410.360756) (xy 303.426928 -410.423851)
			(xy 303.442966 -410.489339) (xy 303.451044 -410.556276) (xy 303.451045 -410.6237) (xy 303.44297 -410.690637)
			(xy 303.426935 -410.756126) (xy 303.403172 -410.819222) (xy 303.372021 -410.879018) (xy 303.333932 -410.934651)
			(xy 303.312068 -410.960316) (xy 303.306278 -410.967466) (xy 303.29976 -410.984653) (xy 303.299368 -410.993844)
			(xy 303.299368 -411.151324) (xy 303.299003 -411.161452) (xy 303.291241 -411.180162) (xy 303.276909 -411.194477)
			(xy 303.258189 -411.202216) (xy 303.24806 -411.202632) (xy 302.53178 -411.202632) (xy 302.521674 -411.202132)
			(xy 302.503001 -411.194394) (xy 302.488708 -411.180102) (xy 302.480969 -411.16143) (xy 302.480472 -411.151324)
			(xy 302.480472 -410.993844) (xy 302.480047 -410.984658) (xy 302.473544 -410.967474) (xy 302.467772 -410.960316)
			(xy 302.445893 -410.934663) (xy 302.407807 -410.879026) (xy 302.376658 -410.819228) (xy 302.352896 -410.75613)
			(xy 302.336863 -410.690639) (xy 302.328789 -410.6237) (xy 299.050718 -410.6237) (xy 299.042683 -410.690461)
			(xy 299.026712 -410.755842) (xy 299.003042 -410.818846) (xy 298.972012 -410.878569) (xy 298.934066 -410.934156)
			(xy 298.91228 -410.959808) (xy 298.906495 -410.966961) (xy 298.899974 -410.984146) (xy 298.89958 -410.993336)
			(xy 298.89958 -411.151324) (xy 298.899198 -411.161482) (xy 298.891391 -411.180239) (xy 298.876982 -411.194562)
			(xy 298.858179 -411.202258) (xy 298.848018 -411.202632) (xy 298.131738 -411.202632) (xy 298.12161 -411.202141)
			(xy 298.102885 -411.194421) (xy 298.088526 -411.180135) (xy 298.080711 -411.161449) (xy 298.080176 -411.151324)
			(xy 298.080176 -410.993336) (xy 298.079754 -410.98415) (xy 298.073249 -410.966965) (xy 298.067476 -410.959808)
			(xy 298.045672 -410.934169) (xy 298.007721 -410.878582) (xy 297.976686 -410.818857) (xy 297.953013 -410.75585)
			(xy 297.93704 -410.690466) (xy 297.928996 -410.623641) (xy 294.650957 -410.623641) (xy 294.650957 -410.623699)
			(xy 294.642883 -410.690637) (xy 294.626848 -410.756125) (xy 294.603085 -410.819221) (xy 294.571935 -410.879017)
			(xy 294.533848 -410.934651) (xy 294.511984 -410.960316) (xy 294.506196 -410.967467) (xy 294.499677 -410.984653)
			(xy 294.499284 -410.993844) (xy 294.499284 -411.151324) (xy 294.498834 -411.161436) (xy 294.491086 -411.180118)
			(xy 294.476778 -411.194413) (xy 294.458089 -411.202144) (xy 294.447976 -411.202632) (xy 293.731696 -411.202632)
			(xy 293.721591 -411.202119) (xy 293.702919 -411.194386) (xy 293.688625 -411.180098) (xy 293.680885 -411.161429)
			(xy 293.680388 -411.151324) (xy 293.680388 -410.993844) (xy 293.679959 -410.984659) (xy 293.673459 -410.967474)
			(xy 293.667688 -410.960316) (xy 293.645809 -410.934664) (xy 293.607721 -410.879027) (xy 293.576572 -410.819229)
			(xy 293.552809 -410.75613) (xy 293.536775 -410.69064) (xy 293.528701 -410.6237) (xy 290.250631 -410.6237)
			(xy 290.242595 -410.69046) (xy 290.226625 -410.755841) (xy 290.202956 -410.818845) (xy 290.171926 -410.878568)
			(xy 290.133982 -410.934155) (xy 290.112196 -410.959808) (xy 290.106413 -410.966963) (xy 290.09989 -410.984146)
			(xy 290.099496 -410.993336) (xy 290.099496 -411.151324) (xy 290.099098 -411.16148) (xy 290.091294 -411.180234)
			(xy 290.07689 -411.194557) (xy 290.058092 -411.202255) (xy 290.047934 -411.202632) (xy 289.331654 -411.202632)
			(xy 289.321521 -411.20221) (xy 289.302793 -411.194462) (xy 289.288438 -411.180156) (xy 289.280625 -411.161455)
			(xy 289.280092 -411.151324) (xy 289.280092 -410.993336) (xy 289.279666 -410.98415) (xy 289.273164 -410.966966)
			(xy 289.267392 -410.959808) (xy 289.245587 -410.934169) (xy 289.207635 -410.878582) (xy 289.1766 -410.818857)
			(xy 289.152925 -410.755851) (xy 289.136952 -410.690467) (xy 289.128908 -410.623642) (xy 237.026196 -410.623642)
			(xy 237.026196 -412.022036) (xy 237.025817 -412.032111) (xy 237.018067 -412.05071) (xy 237.01121 -412.058104)
			(xy 235.742988 -413.326326) (xy 235.735589 -413.333168) (xy 235.716989 -413.340886) (xy 235.70692 -413.341312)
			(xy 208.85277 -413.341312) (xy 208.842696 -413.340925) (xy 208.824097 -413.33318) (xy 208.816702 -413.326326)
			(xy 207.328262 -411.83814) (xy 207.321442 -411.830725) (xy 207.313712 -411.812137) (xy 207.313276 -411.802072)
			(xy 207.313276 -389.778748) (xy 207.312741 -389.766404) (xy 207.303453 -389.743532) (xy 207.295242 -389.734298)
			(xy 207.294734 -389.73379) (xy 204.725778 -387.165088) (xy 204.718937 -387.157689) (xy 204.711218 -387.139089)
			(xy 204.710792 -387.12902) (xy 204.710792 -374.725946) (xy 204.710253 -374.713602) (xy 204.700967 -374.690731)
			(xy 204.692758 -374.681496) (xy 204.69225 -374.680988) (xy 204.627226 -374.615964) (xy 204.620381 -374.608567)
			(xy 204.612664 -374.589966) (xy 204.61224 -374.579896) (xy 204.61224 -371.090444) (xy 204.611612 -371.07799)
			(xy 204.602074 -371.054978) (xy 204.593698 -371.04574) (xy 204.485494 -370.93779) (xy 204.478656 -370.930388)
			(xy 204.470935 -370.91179) (xy 204.470508 -370.901722) (xy 173.519592 -370.901722) (xy 173.519592 -371.386862)
			(xy 173.520022 -371.396047) (xy 173.526522 -371.413231) (xy 173.532292 -371.42039) (xy 173.554093 -371.446031)
			(xy 173.592039 -371.50162) (xy 173.62307 -371.561345) (xy 173.646506 -371.623725) (xy 174.74915 -371.623725)
			(xy 174.749154 -371.556417) (xy 174.757201 -371.489592) (xy 174.773178 -371.424208) (xy 174.796855 -371.361202)
			(xy 174.827893 -371.301477) (xy 174.865846 -371.24589) (xy 174.887636 -371.220238) (xy 174.893446 -371.213102)
			(xy 174.899952 -371.195904) (xy 174.900336 -371.18671) (xy 174.900336 -371.028722) (xy 174.900782 -371.018552)
			(xy 174.908559 -370.999758) (xy 174.922938 -370.985373) (xy 174.941728 -370.977587) (xy 174.951898 -370.97716)
			(xy 175.668178 -370.97716) (xy 175.678351 -370.977583) (xy 175.697149 -370.985364) (xy 175.711536 -370.999751)
			(xy 175.719317 -371.018549) (xy 175.71974 -371.028722) (xy 175.71974 -371.18671) (xy 175.720159 -371.195896)
			(xy 175.726668 -371.21308) (xy 175.73244 -371.220238) (xy 175.754191 -371.245921) (xy 175.792142 -371.301502)
			(xy 175.823178 -371.361221) (xy 175.846854 -371.424222) (xy 175.86283 -371.489601) (xy 175.870878 -371.55642)
			(xy 175.870881 -371.623723) (xy 175.862841 -371.690543) (xy 175.846871 -371.755923) (xy 175.823202 -371.818926)
			(xy 175.792172 -371.878649) (xy 175.754226 -371.934234) (xy 175.73244 -371.959886) (xy 175.726617 -371.967012)
			(xy 175.72012 -371.984218) (xy 175.71974 -371.993414) (xy 175.71974 -372.486682) (xy 175.720172 -372.495867)
			(xy 175.726672 -372.51305) (xy 175.73244 -372.52021) (xy 175.754262 -372.545834) (xy 175.792211 -372.601424)
			(xy 175.823244 -372.661151) (xy 175.846916 -372.72416) (xy 175.862887 -372.789545) (xy 175.870929 -372.856371)
			(xy 175.870926 -372.92368) (xy 175.862878 -372.990505) (xy 175.846901 -373.055889) (xy 175.823223 -373.118895)
			(xy 175.792185 -373.17862) (xy 175.754231 -373.234206) (xy 175.73244 -373.259858) (xy 175.726629 -373.266993)
			(xy 175.720125 -373.284191) (xy 175.71974 -373.293386) (xy 175.71974 -373.451374) (xy 175.719314 -373.461547)
			(xy 175.711534 -373.480345) (xy 175.697148 -373.494731) (xy 175.678351 -373.502513) (xy 175.668178 -373.502936)
			(xy 174.951898 -373.502936) (xy 174.941723 -373.502537) (xy 174.922923 -373.494747) (xy 174.908538 -373.480353)
			(xy 174.900757 -373.461549) (xy 174.900336 -373.451374) (xy 174.900336 -373.293386) (xy 174.899925 -373.284199)
			(xy 174.893411 -373.267015) (xy 174.887636 -373.259858) (xy 174.865882 -373.234178) (xy 174.827932 -373.178596)
			(xy 174.796898 -373.118876) (xy 174.773223 -373.055875) (xy 174.757248 -372.990496) (xy 174.749201 -372.923677)
			(xy 174.749198 -372.856374) (xy 174.757239 -372.789554) (xy 174.773208 -372.724174) (xy 174.796877 -372.661171)
			(xy 174.827906 -372.601448) (xy 174.865851 -372.545862) (xy 174.887636 -372.52021) (xy 174.893458 -372.513083)
			(xy 174.899957 -372.495878) (xy 174.900336 -372.486682) (xy 174.900336 -371.993414) (xy 174.899911 -371.984229)
			(xy 174.893407 -371.967044) (xy 174.887636 -371.959886) (xy 174.865811 -371.934265) (xy 174.827863 -371.878674)
			(xy 174.796832 -371.818946) (xy 174.773161 -371.755937) (xy 174.757191 -371.690551) (xy 174.74915 -371.623725)
			(xy 173.646506 -371.623725) (xy 173.646741 -371.624351) (xy 173.662712 -371.689734) (xy 173.670754 -371.756558)
			(xy 173.670753 -371.823863) (xy 173.662708 -371.890686) (xy 173.646734 -371.956069) (xy 173.623061 -372.019074)
			(xy 173.592028 -372.078798) (xy 173.55408 -372.134385) (xy 173.532292 -372.160038) (xy 173.526496 -372.167183)
			(xy 173.519981 -372.184374) (xy 173.519592 -372.193566) (xy 173.519592 -372.351554) (xy 173.519099 -372.361719)
			(xy 173.511335 -372.380507) (xy 173.496971 -372.394892) (xy 173.478194 -372.402684) (xy 173.46803 -372.403116)
			(xy 172.75175 -372.403116) (xy 172.741576 -372.402694) (xy 172.722773 -372.394917) (xy 172.708385 -372.38053)
			(xy 172.700607 -372.361728) (xy 172.700188 -372.351554) (xy 172.700188 -372.193566) (xy 172.699797 -372.184377)
			(xy 172.69327 -372.167192) (xy 172.687488 -372.160038) (xy 172.665713 -372.134375) (xy 172.62776 -372.078791)
			(xy 172.596724 -372.01907) (xy 172.573048 -371.956067) (xy 172.557072 -371.890685) (xy 172.549026 -371.823863)
			(xy 172.549025 -371.756558) (xy 172.557069 -371.689736) (xy 172.573042 -371.624354) (xy 172.596715 -371.561349)
			(xy 172.627749 -371.501627) (xy 172.6657 -371.446041) (xy 172.687488 -371.42039) (xy 172.69327 -371.413234)
			(xy 172.699794 -371.396052) (xy 172.700188 -371.386862) (xy 172.700188 -370.89334) (xy 172.699761 -370.884154)
			(xy 172.69326 -370.86697) (xy 172.687488 -370.859812) (xy 172.665687 -370.83417) (xy 172.627735 -370.778583)
			(xy 172.5967 -370.718859) (xy 172.573026 -370.655853) (xy 172.557052 -370.590469) (xy 172.549008 -370.523644)
			(xy 169.270946 -370.523644) (xy 169.262904 -370.590464) (xy 169.246933 -370.655845) (xy 169.223264 -370.718849)
			(xy 169.192234 -370.778572) (xy 169.15429 -370.834159) (xy 169.132504 -370.859812) (xy 169.12672 -370.866966)
			(xy 169.120198 -370.88415) (xy 169.119804 -370.89334) (xy 169.119804 -371.386862) (xy 169.120231 -371.396047)
			(xy 169.126733 -371.413232) (xy 169.132504 -371.42039) (xy 169.154304 -371.446031) (xy 169.19225 -371.50162)
			(xy 169.22328 -371.561346) (xy 169.246737 -371.623785) (xy 170.348831 -371.623785) (xy 170.348834 -371.556358)
			(xy 170.356914 -371.489416) (xy 170.372955 -371.423924) (xy 170.396726 -371.360825) (xy 170.427884 -371.301029)
			(xy 170.46598 -371.245394) (xy 170.487848 -371.21973) (xy 170.493663 -371.212598) (xy 170.500165 -371.195397)
			(xy 170.500548 -371.186202) (xy 170.500548 -371.028722) (xy 170.501045 -371.018596) (xy 170.508767 -370.999873)
			(xy 170.52305 -370.985516) (xy 170.541732 -370.977698) (xy 170.551856 -370.97716) (xy 171.268136 -370.97716)
			(xy 171.278287 -370.977591) (xy 171.297033 -370.985391) (xy 171.311354 -370.999784) (xy 171.319059 -371.018568)
			(xy 171.319444 -371.028722) (xy 171.319444 -371.186202) (xy 171.319866 -371.195388) (xy 171.326373 -371.212571)
			(xy 171.332144 -371.21973) (xy 171.353973 -371.245425) (xy 171.392066 -371.301054) (xy 171.423222 -371.360846)
			(xy 171.44699 -371.423939) (xy 171.46303 -371.489425) (xy 171.47111 -371.556361) (xy 171.471113 -371.623782)
			(xy 171.46304 -371.690719) (xy 171.447007 -371.756207) (xy 171.423245 -371.819302) (xy 171.392096 -371.879097)
			(xy 171.354008 -371.93473) (xy 171.332144 -371.960394) (xy 171.326361 -371.967548) (xy 171.31984 -371.984732)
			(xy 171.319444 -371.993922) (xy 171.319444 -372.486174) (xy 171.319879 -372.495358) (xy 171.326377 -372.512542)
			(xy 171.332144 -372.519702) (xy 171.354043 -372.545339) (xy 171.392135 -372.600976) (xy 171.423287 -372.660776)
			(xy 171.447052 -372.723876) (xy 171.463087 -372.789369) (xy 171.471161 -372.856312) (xy 171.471158 -372.923739)
			(xy 171.463077 -372.990681) (xy 171.447037 -373.056172) (xy 171.423266 -373.119271) (xy 171.392108 -373.179068)
			(xy 171.354012 -373.234702) (xy 171.332144 -373.260366) (xy 171.32633 -373.267499) (xy 171.319827 -373.284699)
			(xy 171.319444 -373.293894) (xy 171.319444 -373.451374) (xy 171.318952 -373.461501) (xy 171.31123 -373.480225)
			(xy 171.296945 -373.494583) (xy 171.27826 -373.5024) (xy 171.268136 -373.502936) (xy 170.551856 -373.502936)
			(xy 170.541704 -373.502515) (xy 170.522957 -373.494712) (xy 170.508637 -373.480316) (xy 170.500932 -373.461529)
			(xy 170.500548 -373.451374) (xy 170.500548 -373.293894) (xy 170.50013 -373.284708) (xy 170.493621 -373.267524)
			(xy 170.487848 -373.260366) (xy 170.466016 -373.234674) (xy 170.427923 -373.179044) (xy 170.396768 -373.119252)
			(xy 170.373 -373.056159) (xy 170.356961 -372.990673) (xy 170.348881 -372.923736) (xy 170.348878 -372.856315)
			(xy 170.356951 -372.789378) (xy 170.372985 -372.72389) (xy 170.396747 -372.660794) (xy 170.427897 -372.600999)
			(xy 170.465984 -372.545366) (xy 170.487848 -372.519702) (xy 170.493632 -372.512548) (xy 170.500153 -372.495364)
			(xy 170.500548 -372.486174) (xy 170.500548 -371.993922) (xy 170.500117 -371.984737) (xy 170.493617 -371.967553)
			(xy 170.487848 -371.960394) (xy 170.465945 -371.93476) (xy 170.427854 -371.879122) (xy 170.396703 -371.819322)
			(xy 170.372938 -371.756221) (xy 170.356904 -371.690728) (xy 170.348831 -371.623785) (xy 169.246737 -371.623785)
			(xy 169.24695 -371.624352) (xy 169.262921 -371.689735) (xy 169.270963 -371.756558) (xy 169.270962 -371.823863)
			(xy 169.262917 -371.890686) (xy 169.246944 -371.956068) (xy 169.223271 -372.019073) (xy 169.192239 -372.078798)
			(xy 169.154291 -372.134385) (xy 169.132504 -372.160038) (xy 169.126709 -372.167185) (xy 169.120193 -372.184374)
			(xy 169.119804 -372.193566) (xy 169.119804 -372.351554) (xy 169.1193 -372.361717) (xy 169.111537 -372.380503)
			(xy 169.097177 -372.394888) (xy 169.078405 -372.402682) (xy 169.068242 -372.403116) (xy 168.351962 -372.403116)
			(xy 168.341782 -372.402766) (xy 168.322978 -372.39496) (xy 168.308593 -372.380552) (xy 168.300817 -372.361734)
			(xy 168.3004 -372.351554) (xy 168.3004 -372.193566) (xy 168.300006 -372.184377) (xy 168.293481 -372.167193)
			(xy 168.2877 -372.160038) (xy 168.265927 -372.134374) (xy 168.227981 -372.078788) (xy 168.196949 -372.019066)
			(xy 168.173277 -371.956063) (xy 168.157304 -371.890683) (xy 168.14926 -371.823862) (xy 168.149258 -371.756559)
			(xy 168.1573 -371.689738) (xy 168.173271 -371.624357) (xy 168.19694 -371.561353) (xy 168.22797 -371.50163)
			(xy 168.265914 -371.446043) (xy 168.2877 -371.42039) (xy 168.293483 -371.413235) (xy 168.300006 -371.396052)
			(xy 168.3004 -371.386862) (xy 168.3004 -370.89334) (xy 168.299971 -370.884155) (xy 168.29347 -370.86697)
			(xy 168.2877 -370.859812) (xy 168.265902 -370.834169) (xy 168.227956 -370.77858) (xy 168.196925 -370.718855)
			(xy 168.173255 -370.65585) (xy 168.157284 -370.590467) (xy 168.149241 -370.523644) (xy 164.871178 -370.523644)
			(xy 164.871178 -370.523702) (xy 164.863103 -370.59064) (xy 164.847069 -370.656128) (xy 164.823307 -370.719224)
			(xy 164.792158 -370.77902) (xy 164.754071 -370.834655) (xy 164.732208 -370.86032) (xy 164.726421 -370.867472)
			(xy 164.7199 -370.884657) (xy 164.719508 -370.893848) (xy 164.719508 -371.386354) (xy 164.719938 -371.395539)
			(xy 164.726438 -371.412724) (xy 164.732208 -371.419882) (xy 164.754085 -371.445536) (xy 164.792173 -371.501172)
			(xy 164.823323 -371.56097) (xy 164.846957 -371.623726) (xy 165.949062 -371.623726) (xy 165.949066 -371.556417)
			(xy 165.957114 -371.489592) (xy 165.973091 -371.424207) (xy 165.996769 -371.361201) (xy 166.027807 -371.301477)
			(xy 166.065761 -371.24589) (xy 166.087552 -371.220238) (xy 166.093364 -371.213104) (xy 166.099868 -371.195905)
			(xy 166.100252 -371.18671) (xy 166.100252 -371.028722) (xy 166.100682 -371.01855) (xy 166.108463 -370.999753)
			(xy 166.122847 -370.985367) (xy 166.141642 -370.977584) (xy 166.151814 -370.97716) (xy 166.868094 -370.97716)
			(xy 166.878268 -370.977569) (xy 166.897067 -370.985356) (xy 166.911453 -370.999747) (xy 166.919234 -371.018548)
			(xy 166.919656 -371.028722) (xy 166.919656 -371.18671) (xy 166.920071 -371.195896) (xy 166.926582 -371.21308)
			(xy 166.932356 -371.220238) (xy 166.954106 -371.245921) (xy 166.992057 -371.301503) (xy 167.023092 -371.361222)
			(xy 167.046767 -371.424223) (xy 167.062743 -371.489601) (xy 167.07079 -371.55642) (xy 167.070793 -371.623722)
			(xy 167.062753 -371.690543) (xy 167.046784 -371.755923) (xy 167.023115 -371.818926) (xy 166.992086 -371.878648)
			(xy 166.954141 -371.934234) (xy 166.932356 -371.959886) (xy 166.926535 -371.967014) (xy 166.920036 -371.984218)
			(xy 166.919656 -371.993414) (xy 166.919656 -372.486682) (xy 166.920085 -372.495867) (xy 166.926586 -372.513051)
			(xy 166.932356 -372.52021) (xy 166.954177 -372.545834) (xy 166.992126 -372.601425) (xy 167.023158 -372.661152)
			(xy 167.046829 -372.72416) (xy 167.0628 -372.789546) (xy 167.070841 -372.856372) (xy 167.070838 -372.923679)
			(xy 167.06279 -372.990504) (xy 167.046814 -373.055889) (xy 167.023137 -373.118895) (xy 166.992099 -373.178619)
			(xy 166.954146 -373.234206) (xy 166.932356 -373.259858) (xy 166.926547 -373.266994) (xy 166.920041 -373.284192)
			(xy 166.919656 -373.293386) (xy 166.919656 -373.451374) (xy 166.919215 -373.461545) (xy 166.911437 -373.48034)
			(xy 166.897057 -373.494726) (xy 166.878264 -373.502511) (xy 166.868094 -373.502936) (xy 166.151814 -373.502936)
			(xy 166.14164 -373.502524) (xy 166.122841 -373.494739) (xy 166.108454 -373.480349) (xy 166.100673 -373.461548)
			(xy 166.100252 -373.451374) (xy 166.100252 -373.293386) (xy 166.099837 -373.2842) (xy 166.093325 -373.267016)
			(xy 166.087552 -373.259858) (xy 166.065797 -373.234178) (xy 166.027847 -373.178596) (xy 165.996811 -373.118877)
			(xy 165.973136 -373.055876) (xy 165.95716 -372.990497) (xy 165.949113 -372.923677) (xy 165.94911 -372.856374)
			(xy 165.957151 -372.789554) (xy 165.973121 -372.724173) (xy 165.99679 -372.66117) (xy 166.02782 -372.601448)
			(xy 166.065766 -372.545862) (xy 166.087552 -372.52021) (xy 166.093376 -372.513084) (xy 166.099873 -372.495879)
			(xy 166.100252 -372.486682) (xy 166.100252 -371.993414) (xy 166.099824 -371.984229) (xy 166.093321 -371.967045)
			(xy 166.087552 -371.959886) (xy 166.065726 -371.934265) (xy 166.027778 -371.878674) (xy 165.996745 -371.818947)
			(xy 165.973074 -371.755938) (xy 165.957104 -371.690552) (xy 165.949062 -371.623726) (xy 164.846957 -371.623726)
			(xy 164.847086 -371.624068) (xy 164.86312 -371.689559) (xy 164.871195 -371.756498) (xy 164.871194 -371.823923)
			(xy 164.863116 -371.890862) (xy 164.84708 -371.956352) (xy 164.823314 -372.019449) (xy 164.792162 -372.079246)
			(xy 164.754073 -372.134881) (xy 164.732208 -372.160546) (xy 164.72641 -372.16769) (xy 164.719896 -372.184881)
			(xy 164.719508 -372.194074) (xy 164.719508 -372.351554) (xy 164.718937 -372.361672) (xy 164.711233 -372.380383)
			(xy 164.696973 -372.394739) (xy 164.678314 -372.402568) (xy 164.6682 -372.403116) (xy 163.95192 -372.403116)
			(xy 163.941769 -372.402662) (xy 163.92302 -372.394876) (xy 163.908697 -372.38049) (xy 163.900993 -372.361707)
			(xy 163.900612 -372.351554) (xy 163.900612 -372.194074) (xy 163.900212 -372.184886) (xy 163.893691 -372.167702)
			(xy 163.887912 -372.160546) (xy 163.866061 -372.13487) (xy 163.827971 -372.079237) (xy 163.796819 -372.019442)
			(xy 163.773054 -371.956347) (xy 163.757017 -371.890859) (xy 163.74894 -371.823922) (xy 163.748939 -371.756499)
			(xy 163.757013 -371.689562) (xy 163.773048 -371.624073) (xy 163.796811 -371.560977) (xy 163.827961 -371.501181)
			(xy 163.866048 -371.445547) (xy 163.887912 -371.419882) (xy 163.8937 -371.412731) (xy 163.900219 -371.395545)
			(xy 163.900612 -371.386354) (xy 163.900612 -370.893848) (xy 163.900176 -370.884664) (xy 163.89368 -370.867479)
			(xy 163.887912 -370.86032) (xy 163.866036 -370.834665) (xy 163.827947 -370.779029) (xy 163.796796 -370.719232)
			(xy 163.773032 -370.656133) (xy 163.756997 -370.590643) (xy 163.748922 -370.523703) (xy 160.470875 -370.523703)
			(xy 160.462839 -370.590466) (xy 160.446866 -370.655848) (xy 160.423192 -370.718852) (xy 160.392158 -370.778575)
			(xy 160.354208 -370.83416) (xy 160.33242 -370.859812) (xy 160.326638 -370.866968) (xy 160.320114 -370.88415)
			(xy 160.31972 -370.89334) (xy 160.31972 -371.386862) (xy 160.320144 -371.396048) (xy 160.326647 -371.413233)
			(xy 160.33242 -371.42039) (xy 160.354223 -371.44603) (xy 160.392174 -371.501618) (xy 160.423209 -371.561342)
			(xy 160.44667 -371.623784) (xy 161.548767 -371.623784) (xy 161.548771 -371.556358) (xy 161.55685 -371.489418)
			(xy 161.572888 -371.423928) (xy 161.596655 -371.360829) (xy 161.627808 -371.301032) (xy 161.665899 -371.245396)
			(xy 161.687764 -371.21973) (xy 161.693581 -371.212599) (xy 161.700082 -371.195397) (xy 161.700464 -371.186202)
			(xy 161.700464 -371.028722) (xy 161.700945 -371.018594) (xy 161.70867 -370.999868) (xy 161.722959 -370.985511)
			(xy 161.741646 -370.977695) (xy 161.751772 -370.97716) (xy 162.468052 -370.97716) (xy 162.478166 -370.977654)
			(xy 162.496861 -370.985379) (xy 162.511176 -370.999671) (xy 162.51893 -371.018354) (xy 162.51936 -371.028468)
			(xy 162.51936 -371.186202) (xy 162.519778 -371.195388) (xy 162.526287 -371.212572) (xy 162.53206 -371.21973)
			(xy 162.553888 -371.245425) (xy 162.591981 -371.301055) (xy 162.623135 -371.360846) (xy 162.646903 -371.423939)
			(xy 162.662942 -371.489425) (xy 162.671022 -371.556361) (xy 162.671025 -371.623782) (xy 162.662953 -371.690719)
			(xy 162.64692 -371.756206) (xy 162.623158 -371.819302) (xy 162.59201 -371.879096) (xy 162.553923 -371.934729)
			(xy 162.53206 -371.960394) (xy 162.526278 -371.96755) (xy 162.519756 -371.984732) (xy 162.51936 -371.993922)
			(xy 162.51936 -372.486174) (xy 162.519791 -372.495359) (xy 162.526291 -372.512543) (xy 162.53206 -372.519702)
			(xy 162.553959 -372.545339) (xy 162.592049 -372.600977) (xy 162.623201 -372.660776) (xy 162.646965 -372.723877)
			(xy 162.662999 -372.78937) (xy 162.671073 -372.856312) (xy 162.67107 -372.923739) (xy 162.66299 -372.99068)
			(xy 162.646949 -373.056172) (xy 162.62318 -373.11927) (xy 162.592023 -373.179067) (xy 162.553927 -373.234701)
			(xy 162.53206 -373.260366) (xy 162.526248 -373.2675) (xy 162.519743 -373.284699) (xy 162.51936 -373.293894)
			(xy 162.51936 -373.451374) (xy 162.518852 -373.461499) (xy 162.511133 -373.48022) (xy 162.496853 -373.494577)
			(xy 162.478174 -373.502397) (xy 162.468052 -373.502936) (xy 161.751772 -373.502936) (xy 161.741666 -373.502439)
			(xy 161.722994 -373.494699) (xy 161.708701 -373.480406) (xy 161.700961 -373.461734) (xy 161.700464 -373.451628)
			(xy 161.700464 -373.293894) (xy 161.700042 -373.284708) (xy 161.693535 -373.267525) (xy 161.687764 -373.260366)
			(xy 161.665935 -373.234673) (xy 161.627847 -373.179041) (xy 161.596697 -373.119249) (xy 161.572933 -373.056155)
			(xy 161.556896 -372.99067) (xy 161.548818 -372.923736) (xy 161.548815 -372.856315) (xy 161.556887 -372.78938)
			(xy 161.572918 -372.723893) (xy 161.596676 -372.660798) (xy 161.627821 -372.601003) (xy 161.665903 -372.545368)
			(xy 161.687764 -372.519702) (xy 161.69355 -372.51255) (xy 161.700069 -372.495364) (xy 161.700464 -372.486174)
			(xy 161.700464 -371.993922) (xy 161.700029 -371.984738) (xy 161.693531 -371.967554) (xy 161.687764 -371.960394)
			(xy 161.665864 -371.934759) (xy 161.627779 -371.879119) (xy 161.596632 -371.819319) (xy 161.572871 -371.756218)
			(xy 161.55684 -371.690725) (xy 161.548767 -371.623784) (xy 160.44667 -371.623784) (xy 160.446882 -371.624348)
			(xy 160.462856 -371.689733) (xy 160.470899 -371.756557) (xy 160.470898 -371.823864) (xy 160.462852 -371.890688)
			(xy 160.446876 -371.956072) (xy 160.4232 -372.019077) (xy 160.392163 -372.078801) (xy 160.35421 -372.134386)
			(xy 160.33242 -372.160038) (xy 160.326627 -372.167186) (xy 160.32011 -372.184374) (xy 160.31972 -372.193566)
			(xy 160.31972 -372.351554) (xy 160.319297 -372.361728) (xy 160.31152 -372.38053) (xy 160.297133 -372.394918)
			(xy 160.278332 -372.402697) (xy 160.268158 -372.403116) (xy 159.551878 -372.403116) (xy 159.541699 -372.402753)
			(xy 159.522895 -372.394952) (xy 159.50851 -372.380547) (xy 159.500734 -372.361733) (xy 159.500316 -372.351554)
			(xy 159.500316 -372.193566) (xy 159.499919 -372.184378) (xy 159.493396 -372.167193) (xy 159.487616 -372.160038)
			(xy 159.465843 -372.134374) (xy 159.427895 -372.078789) (xy 159.396862 -372.019067) (xy 159.37319 -371.956064)
			(xy 159.357216 -371.890683) (xy 159.349172 -371.823862) (xy 159.34917 -371.756559) (xy 159.357213 -371.689738)
			(xy 159.373184 -371.624356) (xy 159.396854 -371.561353) (xy 159.427884 -371.501629) (xy 159.46583 -371.446042)
			(xy 159.487616 -371.42039) (xy 159.493401 -371.413237) (xy 159.499922 -371.396052) (xy 159.500316 -371.386862)
			(xy 159.500316 -370.89334) (xy 159.499883 -370.884155) (xy 159.493385 -370.866971) (xy 159.487616 -370.859812)
			(xy 159.465817 -370.834169) (xy 159.42787 -370.778581) (xy 159.396839 -370.718856) (xy 159.373168 -370.65585)
			(xy 159.357196 -370.590467) (xy 159.349153 -370.523644) (xy 129.670828 -370.523644) (xy 129.662785 -370.590464)
			(xy 129.646814 -370.655846) (xy 129.623143 -370.71885) (xy 129.592113 -370.778573) (xy 129.554166 -370.83416)
			(xy 129.53238 -370.859812) (xy 129.526594 -370.866964) (xy 129.520073 -370.884149) (xy 129.51968 -370.89334)
			(xy 129.51968 -371.386862) (xy 129.520113 -371.396047) (xy 129.526611 -371.413231) (xy 129.53238 -371.42039)
			(xy 129.554181 -371.446031) (xy 129.592128 -371.50162) (xy 129.62316 -371.561345) (xy 129.646596 -371.623725)
			(xy 130.749241 -371.623725) (xy 130.749245 -371.556418) (xy 130.757292 -371.489593) (xy 130.773269 -371.424208)
			(xy 130.796945 -371.361202) (xy 130.827982 -371.301478) (xy 130.865934 -371.24589) (xy 130.887724 -371.220238)
			(xy 130.893532 -371.213101) (xy 130.900039 -371.195904) (xy 130.900424 -371.18671) (xy 130.900424 -371.028722)
			(xy 130.900882 -371.018554) (xy 130.908657 -370.999762) (xy 130.923032 -370.985377) (xy 130.941818 -370.977589)
			(xy 130.951986 -370.97716) (xy 131.668266 -370.97716) (xy 131.678438 -370.977592) (xy 131.697236 -370.98537)
			(xy 131.711623 -370.999754) (xy 131.719405 -371.01855) (xy 131.719828 -371.028722) (xy 131.719828 -371.18671)
			(xy 131.720227 -371.195898) (xy 131.726748 -371.213083) (xy 131.732528 -371.220238) (xy 131.754279 -371.24592)
			(xy 131.792231 -371.301502) (xy 131.823268 -371.361221) (xy 131.846945 -371.424221) (xy 131.862921 -371.4896)
			(xy 131.870969 -371.55642) (xy 131.870972 -371.623723) (xy 131.862931 -371.690543) (xy 131.846961 -371.755924)
			(xy 131.823291 -371.818927) (xy 131.792261 -371.878649) (xy 131.754314 -371.934234) (xy 131.732528 -371.959886)
			(xy 131.726704 -371.967011) (xy 131.720208 -371.984217) (xy 131.719828 -371.993414) (xy 131.719828 -372.486682)
			(xy 131.72024 -372.495869) (xy 131.726752 -372.513054) (xy 131.732528 -372.52021) (xy 131.75435 -372.545834)
			(xy 131.7923 -372.601424) (xy 131.823334 -372.661151) (xy 131.847006 -372.724159) (xy 131.862978 -372.789545)
			(xy 131.87102 -372.856371) (xy 131.871017 -372.92368) (xy 131.862969 -372.990505) (xy 131.846991 -373.05589)
			(xy 131.823313 -373.118896) (xy 131.792274 -373.17862) (xy 131.754319 -373.234206) (xy 131.732528 -373.259858)
			(xy 131.726716 -373.266992) (xy 131.720212 -373.284191) (xy 131.719828 -373.293386) (xy 131.719828 -373.451374)
			(xy 131.719414 -373.461548) (xy 131.711631 -373.480349) (xy 131.697242 -373.494736) (xy 131.67844 -373.502515)
			(xy 131.668266 -373.502936) (xy 130.951986 -373.502936) (xy 130.94181 -373.502547) (xy 130.92301 -373.494752)
			(xy 130.908625 -373.480356) (xy 130.900845 -373.46155) (xy 130.900424 -373.451374) (xy 130.900424 -373.293386)
			(xy 130.900015 -373.284199) (xy 130.8935 -373.267015) (xy 130.887724 -373.259858) (xy 130.86597 -373.234178)
			(xy 130.828022 -373.178595) (xy 130.796988 -373.118875) (xy 130.773314 -373.055874) (xy 130.757339 -372.990496)
			(xy 130.749292 -372.923677) (xy 130.749289 -372.856375) (xy 130.75733 -372.789555) (xy 130.773299 -372.724174)
			(xy 130.796967 -372.661171) (xy 130.827995 -372.601449) (xy 130.865939 -372.545863) (xy 130.887724 -372.52021)
			(xy 130.893544 -372.513082) (xy 130.900044 -372.495878) (xy 130.900424 -372.486682) (xy 130.900424 -371.993414)
			(xy 130.900002 -371.984228) (xy 130.893496 -371.967044) (xy 130.887724 -371.959886) (xy 130.865899 -371.934264)
			(xy 130.827953 -371.878673) (xy 130.796922 -371.818945) (xy 130.773252 -371.755937) (xy 130.757282 -371.690551)
			(xy 130.749241 -371.623725) (xy 129.646596 -371.623725) (xy 129.646831 -371.624351) (xy 129.662802 -371.689734)
			(xy 129.670845 -371.756558) (xy 129.670844 -371.823863) (xy 129.662799 -371.890687) (xy 129.646825 -371.956069)
			(xy 129.623151 -372.019074) (xy 129.592117 -372.078799) (xy 129.554168 -372.134386) (xy 129.53238 -372.160038)
			(xy 129.526582 -372.167182) (xy 129.520069 -372.184374) (xy 129.51968 -372.193566) (xy 129.51968 -372.351554)
			(xy 129.519199 -372.36172) (xy 129.511432 -372.380511) (xy 129.497064 -372.394896) (xy 129.478284 -372.402686)
			(xy 129.468118 -372.403116) (xy 128.751838 -372.403116) (xy 128.741663 -372.402704) (xy 128.722861 -372.394923)
			(xy 128.708473 -372.380533) (xy 128.700695 -372.361729) (xy 128.700276 -372.351554) (xy 128.700276 -372.193566)
			(xy 128.699887 -372.184376) (xy 128.693359 -372.167192) (xy 128.687576 -372.160038) (xy 128.665801 -372.134375)
			(xy 128.627849 -372.078791) (xy 128.596813 -372.019069) (xy 128.573138 -371.956066) (xy 128.557163 -371.890685)
			(xy 128.549117 -371.823863) (xy 128.549116 -371.756558) (xy 128.557159 -371.689736) (xy 128.573132 -371.624354)
			(xy 128.596805 -371.56135) (xy 128.627838 -371.501627) (xy 128.665788 -371.446042) (xy 128.687576 -371.42039)
			(xy 128.693357 -371.413233) (xy 128.699882 -371.396052) (xy 128.700276 -371.386862) (xy 128.700276 -370.89334)
			(xy 128.699852 -370.884154) (xy 128.693349 -370.866969) (xy 128.687576 -370.859812) (xy 128.665775 -370.83417)
			(xy 128.627825 -370.778583) (xy 128.59679 -370.718858) (xy 128.573116 -370.655852) (xy 128.557143 -370.590469)
			(xy 128.549099 -370.523644) (xy 125.271037 -370.523644) (xy 125.262994 -370.590464) (xy 125.247024 -370.655845)
			(xy 125.223354 -370.718849) (xy 125.192323 -370.778573) (xy 125.154378 -370.834159) (xy 125.132592 -370.859812)
			(xy 125.126807 -370.866965) (xy 125.120286 -370.88415) (xy 125.119892 -370.89334) (xy 125.119892 -371.386862)
			(xy 125.120322 -371.396047) (xy 125.126822 -371.413231) (xy 125.132592 -371.42039) (xy 125.154393 -371.446031)
			(xy 125.192339 -371.50162) (xy 125.22337 -371.561345) (xy 125.246828 -371.623785) (xy 126.348921 -371.623785)
			(xy 126.348925 -371.556358) (xy 126.357005 -371.489416) (xy 126.373046 -371.423925) (xy 126.396816 -371.360826)
			(xy 126.427973 -371.301029) (xy 126.466069 -371.245395) (xy 126.487936 -371.21973) (xy 126.493749 -371.212597)
			(xy 126.500253 -371.195397) (xy 126.500636 -371.186202) (xy 126.500636 -371.028722) (xy 126.501144 -371.018597)
			(xy 126.508864 -370.999877) (xy 126.523144 -370.98552) (xy 126.541822 -370.9777) (xy 126.551944 -370.97716)
			(xy 127.268224 -370.97716) (xy 127.278375 -370.977601) (xy 127.29712 -370.985397) (xy 127.311441 -370.999787)
			(xy 127.319147 -371.018569) (xy 127.319532 -371.028722) (xy 127.319532 -371.186202) (xy 127.319956 -371.195387)
			(xy 127.326462 -371.212571) (xy 127.332232 -371.21973) (xy 127.354058 -371.245427) (xy 127.392145 -371.301057)
			(xy 127.423296 -371.36085) (xy 127.447061 -371.423942) (xy 127.463098 -371.489427) (xy 127.471176 -371.556361)
			(xy 127.47118 -371.623781) (xy 127.463108 -371.690717) (xy 127.447078 -371.756203) (xy 127.423319 -371.819298)
			(xy 127.392175 -371.879094) (xy 127.354093 -371.934728) (xy 127.332232 -371.960394) (xy 127.326447 -371.967547)
			(xy 127.319927 -371.984732) (xy 127.319532 -371.993922) (xy 127.319532 -372.486174) (xy 127.31997 -372.495358)
			(xy 127.326466 -372.512542) (xy 127.332232 -372.519702) (xy 127.354128 -372.54534) (xy 127.392214 -372.600979)
			(xy 127.423361 -372.66078) (xy 127.447122 -372.72388) (xy 127.463154 -372.789372) (xy 127.471227 -372.856313)
			(xy 127.471224 -372.923738) (xy 127.463145 -372.990678) (xy 127.447107 -373.056169) (xy 127.42334 -373.119267)
			(xy 127.392188 -373.179064) (xy 127.354097 -373.2347) (xy 127.332232 -373.260366) (xy 127.326417 -373.267498)
			(xy 127.319915 -373.284699) (xy 127.319532 -373.293894) (xy 127.319532 -373.451374) (xy 127.319051 -373.461503)
			(xy 127.311327 -373.480228) (xy 127.297038 -373.494587) (xy 127.27835 -373.502402) (xy 127.268224 -373.502936)
			(xy 126.551944 -373.502936) (xy 126.541797 -373.502443) (xy 126.523053 -373.494669) (xy 126.508729 -373.480294)
			(xy 126.501021 -373.461522) (xy 126.500636 -373.451374) (xy 126.500636 -373.293894) (xy 126.500221 -373.284708)
			(xy 126.49371 -373.267524) (xy 126.487936 -373.260366) (xy 126.466104 -373.234674) (xy 126.428012 -373.179044)
			(xy 126.396858 -373.119252) (xy 126.37309 -373.056158) (xy 126.357051 -372.990672) (xy 126.348972 -372.923736)
			(xy 126.348969 -372.856315) (xy 126.357042 -372.789378) (xy 126.373075 -372.72389) (xy 126.396837 -372.660795)
			(xy 126.427986 -372.601) (xy 126.466073 -372.545367) (xy 126.487936 -372.519702) (xy 126.493719 -372.512547)
			(xy 126.500241 -372.495364) (xy 126.500636 -372.486174) (xy 126.500636 -371.993922) (xy 126.500207 -371.984737)
			(xy 126.493706 -371.967553) (xy 126.487936 -371.960394) (xy 126.466033 -371.93476) (xy 126.427943 -371.879122)
			(xy 126.396792 -371.819322) (xy 126.373029 -371.756221) (xy 126.356995 -371.690727) (xy 126.348921 -371.623785)
			(xy 125.246828 -371.623785) (xy 125.247041 -371.624351) (xy 125.263012 -371.689734) (xy 125.271054 -371.756558)
			(xy 125.271053 -371.823863) (xy 125.263008 -371.890686) (xy 125.247034 -371.956069) (xy 125.223361 -372.019074)
			(xy 125.192328 -372.078798) (xy 125.15438 -372.134385) (xy 125.132592 -372.160038) (xy 125.126796 -372.167183)
			(xy 125.120281 -372.184374) (xy 125.119892 -372.193566) (xy 125.119892 -372.351554) (xy 125.119399 -372.361719)
			(xy 125.111635 -372.380507) (xy 125.097271 -372.394892) (xy 125.078494 -372.402684) (xy 125.06833 -372.403116)
			(xy 124.35205 -372.403116) (xy 124.341876 -372.402694) (xy 124.323073 -372.394917) (xy 124.308685 -372.38053)
			(xy 124.300907 -372.361728) (xy 124.300488 -372.351554) (xy 124.300488 -372.193566) (xy 124.300097 -372.184377)
			(xy 124.29357 -372.167192) (xy 124.287788 -372.160038) (xy 124.266013 -372.134375) (xy 124.22806 -372.078791)
			(xy 124.197024 -372.01907) (xy 124.173348 -371.956067) (xy 124.157372 -371.890685) (xy 124.149326 -371.823863)
			(xy 124.149325 -371.756558) (xy 124.157369 -371.689736) (xy 124.173342 -371.624354) (xy 124.197015 -371.561349)
			(xy 124.228049 -371.501627) (xy 124.266 -371.446041) (xy 124.287788 -371.42039) (xy 124.29357 -371.413234)
			(xy 124.300094 -371.396052) (xy 124.300488 -371.386862) (xy 124.300488 -370.89334) (xy 124.300061 -370.884154)
			(xy 124.29356 -370.86697) (xy 124.287788 -370.859812) (xy 124.265987 -370.83417) (xy 124.228035 -370.778583)
			(xy 124.197 -370.718859) (xy 124.173326 -370.655853) (xy 124.157352 -370.590469) (xy 124.149308 -370.523644)
			(xy 120.871269 -370.523644) (xy 120.871269 -370.523702) (xy 120.863194 -370.59064) (xy 120.847159 -370.656128)
			(xy 120.823396 -370.719225) (xy 120.792247 -370.779021) (xy 120.754159 -370.834655) (xy 120.732296 -370.86032)
			(xy 120.726508 -370.867471) (xy 120.719988 -370.884657) (xy 120.719596 -370.893848) (xy 120.719596 -371.386354)
			(xy 120.720029 -371.395539) (xy 120.726527 -371.412723) (xy 120.732296 -371.419882) (xy 120.754174 -371.445536)
			(xy 120.792262 -371.501172) (xy 120.823413 -371.56097) (xy 120.847047 -371.623725) (xy 121.949153 -371.623725)
			(xy 121.949157 -371.556417) (xy 121.957205 -371.489592) (xy 121.973182 -371.424208) (xy 121.996859 -371.361202)
			(xy 122.027896 -371.301477) (xy 122.06585 -371.24589) (xy 122.08764 -371.220238) (xy 122.09345 -371.213103)
			(xy 122.099956 -371.195904) (xy 122.10034 -371.18671) (xy 122.10034 -371.028722) (xy 122.100782 -371.018552)
			(xy 122.10856 -370.999757) (xy 122.12294 -370.985371) (xy 122.141732 -370.977586) (xy 122.151902 -370.97716)
			(xy 122.868182 -370.97716) (xy 122.878355 -370.977579) (xy 122.897154 -370.985362) (xy 122.91154 -370.99975)
			(xy 122.919322 -371.018549) (xy 122.919744 -371.028722) (xy 122.919744 -371.18671) (xy 122.920162 -371.195896)
			(xy 122.926672 -371.21308) (xy 122.932444 -371.220238) (xy 122.954195 -371.245921) (xy 122.992146 -371.301502)
			(xy 123.023182 -371.361222) (xy 123.046857 -371.424222) (xy 123.062833 -371.489601) (xy 123.070881 -371.55642)
			(xy 123.070884 -371.623723) (xy 123.062844 -371.690543) (xy 123.046874 -371.755923) (xy 123.023205 -371.818926)
			(xy 122.992175 -371.878648) (xy 122.95423 -371.934234) (xy 122.932444 -371.959886) (xy 122.926622 -371.967013)
			(xy 122.920124 -371.984218) (xy 122.919744 -371.993414) (xy 122.919744 -372.486682) (xy 122.920175 -372.495867)
			(xy 122.926676 -372.513051) (xy 122.932444 -372.52021) (xy 122.954266 -372.545834) (xy 122.992215 -372.601424)
			(xy 123.023248 -372.661152) (xy 123.046919 -372.72416) (xy 123.06289 -372.789546) (xy 123.070932 -372.856372)
			(xy 123.070929 -372.92368) (xy 123.062881 -372.990505) (xy 123.046904 -373.055889) (xy 123.023227 -373.118895)
			(xy 122.992188 -373.17862) (xy 122.954234 -373.234206) (xy 122.932444 -373.259858) (xy 122.926633 -373.266993)
			(xy 122.920129 -373.284192) (xy 122.919744 -373.293386) (xy 122.919744 -373.451374) (xy 122.919314 -373.461546)
			(xy 122.911534 -373.480344) (xy 122.89715 -373.49473) (xy 122.878354 -373.502513) (xy 122.868182 -373.502936)
			(xy 122.151902 -373.502936) (xy 122.141727 -373.502534) (xy 122.122928 -373.494745) (xy 122.108542 -373.480352)
			(xy 122.100761 -373.461549) (xy 122.10034 -373.451374) (xy 122.10034 -373.293386) (xy 122.099928 -373.284199)
			(xy 122.093415 -373.267015) (xy 122.08764 -373.259858) (xy 122.065886 -373.234178) (xy 122.027936 -373.178596)
			(xy 121.996901 -373.118876) (xy 121.973226 -373.055875) (xy 121.957251 -372.990496) (xy 121.949204 -372.923677)
			(xy 121.949201 -372.856374) (xy 121.957242 -372.789554) (xy 121.973211 -372.724174) (xy 121.99688 -372.661171)
			(xy 122.02791 -372.601448) (xy 122.065855 -372.545862) (xy 122.08764 -372.52021) (xy 122.093462 -372.513083)
			(xy 122.099961 -372.495878) (xy 122.10034 -372.486682) (xy 122.10034 -371.993414) (xy 122.099914 -371.984229)
			(xy 122.093411 -371.967045) (xy 122.08764 -371.959886) (xy 122.065815 -371.934265) (xy 122.027867 -371.878674)
			(xy 121.996835 -371.818946) (xy 121.973165 -371.755937) (xy 121.957194 -371.690551) (xy 121.949153 -371.623725)
			(xy 120.847047 -371.623725) (xy 120.847176 -371.624068) (xy 120.863211 -371.689558) (xy 120.871286 -371.756498)
			(xy 120.871284 -371.823923) (xy 120.863207 -371.890862) (xy 120.84717 -371.956352) (xy 120.823404 -372.01945)
			(xy 120.792252 -372.079246) (xy 120.754161 -372.134881) (xy 120.732296 -372.160546) (xy 120.726497 -372.167689)
			(xy 120.719984 -372.184881) (xy 120.719596 -372.194074) (xy 120.719596 -372.351554) (xy 120.719037 -372.361673)
			(xy 120.711331 -372.380387) (xy 120.697067 -372.394743) (xy 120.678404 -372.40257) (xy 120.668288 -372.403116)
			(xy 119.952008 -372.403116) (xy 119.941856 -372.402672) (xy 119.923107 -372.394882) (xy 119.908784 -372.380493)
			(xy 119.901081 -372.361707) (xy 119.9007 -372.351554) (xy 119.9007 -372.194074) (xy 119.900303 -372.184885)
			(xy 119.89378 -372.167701) (xy 119.888 -372.160546) (xy 119.86615 -372.134869) (xy 119.828061 -372.079237)
			(xy 119.796909 -372.019442) (xy 119.773144 -371.956346) (xy 119.757108 -371.890859) (xy 119.749031 -371.823922)
			(xy 119.74903 -371.756499) (xy 119.757104 -371.689562) (xy 119.773138 -371.624074) (xy 119.796901 -371.560977)
			(xy 119.82805 -371.501182) (xy 119.866137 -371.445547) (xy 119.888 -371.419882) (xy 119.893787 -371.41273)
			(xy 119.900307 -371.395545) (xy 119.9007 -371.386354) (xy 119.9007 -370.893848) (xy 119.900267 -370.884663)
			(xy 119.893769 -370.867479) (xy 119.888 -370.86032) (xy 119.866124 -370.834664) (xy 119.828036 -370.779029)
			(xy 119.796886 -370.719231) (xy 119.773122 -370.656133) (xy 119.757088 -370.590643) (xy 119.749013 -370.523703)
			(xy 116.470966 -370.523703) (xy 116.462929 -370.590466) (xy 116.446956 -370.655848) (xy 116.423282 -370.718853)
			(xy 116.392247 -370.778575) (xy 116.354297 -370.834161) (xy 116.332508 -370.859812) (xy 116.326725 -370.866967)
			(xy 116.320202 -370.88415) (xy 116.319808 -370.89334) (xy 116.319808 -371.386862) (xy 116.320235 -371.396047)
			(xy 116.326737 -371.413232) (xy 116.332508 -371.42039) (xy 116.354311 -371.44603) (xy 116.392263 -371.501617)
			(xy 116.423299 -371.561342) (xy 116.446761 -371.623785) (xy 117.548834 -371.623785) (xy 117.548837 -371.556358)
			(xy 117.556917 -371.489416) (xy 117.572959 -371.423924) (xy 117.596729 -371.360825) (xy 117.627887 -371.301028)
			(xy 117.665984 -371.245394) (xy 117.687852 -371.21973) (xy 117.693667 -371.212598) (xy 117.700169 -371.195397)
			(xy 117.700552 -371.186202) (xy 117.700552 -371.028722) (xy 117.701045 -371.018595) (xy 117.708768 -370.999872)
			(xy 117.723052 -370.985515) (xy 117.741736 -370.977697) (xy 117.75186 -370.97716) (xy 118.46814 -370.97716)
			(xy 118.478292 -370.977588) (xy 118.497037 -370.985389) (xy 118.511358 -370.999783) (xy 118.519063 -371.018568)
			(xy 118.519448 -371.028722) (xy 118.519448 -371.186202) (xy 118.519869 -371.195388) (xy 118.526376 -371.212572)
			(xy 118.532148 -371.21973) (xy 118.553976 -371.245425) (xy 118.59207 -371.301054) (xy 118.623225 -371.360846)
			(xy 118.646994 -371.423939) (xy 118.663033 -371.489425) (xy 118.671113 -371.556361) (xy 118.671116 -371.623782)
			(xy 118.663044 -371.690719) (xy 118.647011 -371.756207) (xy 118.623248 -371.819302) (xy 118.592099 -371.879097)
			(xy 118.554012 -371.93473) (xy 118.532148 -371.960394) (xy 118.526365 -371.967549) (xy 118.519844 -371.984732)
			(xy 118.519448 -371.993922) (xy 118.519448 -372.486174) (xy 118.519882 -372.495358) (xy 118.52638 -372.512542)
			(xy 118.532148 -372.519702) (xy 118.554047 -372.545339) (xy 118.592138 -372.600976) (xy 118.62329 -372.660776)
			(xy 118.647055 -372.723877) (xy 118.66309 -372.78937) (xy 118.671164 -372.856312) (xy 118.671161 -372.923739)
			(xy 118.663081 -372.990681) (xy 118.64704 -373.056172) (xy 118.62327 -373.119271) (xy 118.592112 -373.179068)
			(xy 118.554016 -373.234702) (xy 118.532148 -373.260366) (xy 118.526334 -373.267499) (xy 118.519831 -373.284699)
			(xy 118.519448 -373.293894) (xy 118.519448 -373.451374) (xy 118.518952 -373.461501) (xy 118.51123 -373.480223)
			(xy 118.496947 -373.494581) (xy 118.478264 -373.502399) (xy 118.46814 -373.502936) (xy 117.75186 -373.502936)
			(xy 117.741708 -373.502512) (xy 117.722961 -373.49471) (xy 117.708641 -373.480315) (xy 117.700936 -373.461528)
			(xy 117.700552 -373.451374) (xy 117.700552 -373.293894) (xy 117.700133 -373.284708) (xy 117.693624 -373.267524)
			(xy 117.687852 -373.260366) (xy 117.66602 -373.234674) (xy 117.627926 -373.179045) (xy 117.596771 -373.119253)
			(xy 117.573003 -373.056159) (xy 117.556964 -372.990673) (xy 117.548884 -372.923737) (xy 117.548881 -372.856315)
			(xy 117.556954 -372.789378) (xy 117.572988 -372.72389) (xy 117.596751 -372.660794) (xy 117.6279 -372.600999)
			(xy 117.665988 -372.545366) (xy 117.687852 -372.519702) (xy 117.693637 -372.512549) (xy 117.700157 -372.495364)
			(xy 117.700552 -372.486174) (xy 117.700552 -371.993922) (xy 117.70012 -371.984737) (xy 117.69362 -371.967553)
			(xy 117.687852 -371.960394) (xy 117.665949 -371.93476) (xy 117.627858 -371.879123) (xy 117.596706 -371.819323)
			(xy 117.572942 -371.756221) (xy 117.556907 -371.690728) (xy 117.548834 -371.623785) (xy 116.446761 -371.623785)
			(xy 116.446973 -371.624348) (xy 116.462946 -371.689732) (xy 116.47099 -371.756557) (xy 116.470989 -371.823864)
			(xy 116.462943 -371.890689) (xy 116.446967 -371.956072) (xy 116.42329 -372.019077) (xy 116.392252 -372.078801)
			(xy 116.354298 -372.134387) (xy 116.332508 -372.160038) (xy 116.326714 -372.167185) (xy 116.320197 -372.184374)
			(xy 116.319808 -372.193566) (xy 116.319808 -372.351554) (xy 116.31923 -372.361703) (xy 116.311479 -372.380462)
			(xy 116.29714 -372.394828) (xy 116.278394 -372.402612) (xy 116.268246 -372.403116) (xy 115.551966 -372.403116)
			(xy 115.541786 -372.402763) (xy 115.522982 -372.394958) (xy 115.508597 -372.380551) (xy 115.500821 -372.361734)
			(xy 115.500404 -372.351554) (xy 115.500404 -372.193566) (xy 115.500009 -372.184377) (xy 115.493485 -372.167193)
			(xy 115.487704 -372.160038) (xy 115.465931 -372.134374) (xy 115.427984 -372.078788) (xy 115.396952 -372.019066)
			(xy 115.37328 -371.956063) (xy 115.357307 -371.890683) (xy 115.349263 -371.823862) (xy 115.349261 -371.756559)
			(xy 115.357303 -371.689738) (xy 115.373274 -371.624357) (xy 115.396944 -371.561353) (xy 115.427973 -371.50163)
			(xy 115.465918 -371.446043) (xy 115.487704 -371.42039) (xy 115.493488 -371.413236) (xy 115.50001 -371.396052)
			(xy 115.500404 -371.386862) (xy 115.500404 -370.89334) (xy 115.499974 -370.884155) (xy 115.493474 -370.86697)
			(xy 115.487704 -370.859812) (xy 115.465906 -370.834169) (xy 115.427959 -370.77858) (xy 115.396929 -370.718855)
			(xy 115.373258 -370.65585) (xy 115.357287 -370.590467) (xy 115.349244 -370.523644) (xy 85.670941 -370.523644)
			(xy 85.670941 -370.523703) (xy 85.662866 -370.590641) (xy 85.646831 -370.65613) (xy 85.623066 -370.719226)
			(xy 85.591915 -370.779022) (xy 85.553825 -370.834655) (xy 85.53196 -370.86032) (xy 85.526167 -370.867468)
			(xy 85.519651 -370.884656) (xy 85.51926 -370.893848) (xy 85.51926 -371.386354) (xy 85.519701 -371.395538)
			(xy 85.526194 -371.412722) (xy 85.53196 -371.419882) (xy 85.553839 -371.445535) (xy 85.59193 -371.501171)
			(xy 85.623082 -371.560968) (xy 85.646742 -371.623785) (xy 86.748803 -371.623785) (xy 86.748807 -371.556358)
			(xy 86.756887 -371.489417) (xy 86.772927 -371.423926) (xy 86.796696 -371.360827) (xy 86.827851 -371.30103)
			(xy 86.865945 -371.245395) (xy 86.887812 -371.21973) (xy 86.893622 -371.212594) (xy 86.900128 -371.195397)
			(xy 86.900512 -371.186202) (xy 86.900512 -371.028722) (xy 86.901044 -371.0186) (xy 86.908759 -370.999885)
			(xy 86.923031 -370.985529) (xy 86.941701 -370.977704) (xy 86.95182 -370.97716) (xy 87.6681 -370.97716)
			(xy 87.678204 -370.977684) (xy 87.696874 -370.985414) (xy 87.711168 -370.999699) (xy 87.718909 -371.018365)
			(xy 87.719408 -371.028468) (xy 87.719408 -371.186202) (xy 87.719815 -371.195389) (xy 87.726331 -371.212574)
			(xy 87.732108 -371.21973) (xy 87.753934 -371.245426) (xy 87.792024 -371.301056) (xy 87.823176 -371.360848)
			(xy 87.846942 -371.423941) (xy 87.862979 -371.489426) (xy 87.871058 -371.556361) (xy 87.871062 -371.623782)
			(xy 87.86299 -371.690717) (xy 87.846958 -371.756204) (xy 87.823199 -371.819299) (xy 87.792053 -371.879095)
			(xy 87.753969 -371.934729) (xy 87.732108 -371.960394) (xy 87.726332 -371.967554) (xy 87.719805 -371.984733)
			(xy 87.719408 -371.993922) (xy 87.719408 -372.486174) (xy 87.719829 -372.49536) (xy 87.726335 -372.512545)
			(xy 87.732108 -372.519702) (xy 87.754005 -372.54534) (xy 87.792092 -372.600978) (xy 87.823241 -372.660779)
			(xy 87.847003 -372.723879) (xy 87.863036 -372.789371) (xy 87.871109 -372.856312) (xy 87.871106 -372.923739)
			(xy 87.863027 -372.990679) (xy 87.846988 -373.05617) (xy 87.82322 -373.119268) (xy 87.792066 -373.179065)
			(xy 87.753974 -373.234701) (xy 87.732108 -373.260366) (xy 87.726302 -373.267504) (xy 87.719793 -373.2847)
			(xy 87.719408 -373.293894) (xy 87.719408 -373.451374) (xy 87.718854 -373.461493) (xy 87.711143 -373.480205)
			(xy 87.696878 -373.49456) (xy 87.678216 -373.502389) (xy 87.6681 -373.502936) (xy 86.95182 -373.502936)
			(xy 86.941717 -373.502399) (xy 86.923046 -373.494675) (xy 86.908752 -373.480394) (xy 86.90101 -373.461731)
			(xy 86.900512 -373.451628) (xy 86.900512 -373.293894) (xy 86.900102 -373.284707) (xy 86.893588 -373.267523)
			(xy 86.887812 -373.260366) (xy 86.865981 -373.234673) (xy 86.82789 -373.179043) (xy 86.796738 -373.119251)
			(xy 86.772971 -373.056157) (xy 86.756933 -372.990672) (xy 86.748854 -372.923736) (xy 86.748851 -372.856315)
			(xy 86.756924 -372.789379) (xy 86.772956 -372.723891) (xy 86.796717 -372.660796) (xy 86.827864 -372.601001)
			(xy 86.86595 -372.545367) (xy 86.887812 -372.519702) (xy 86.893592 -372.512545) (xy 86.900116 -372.495363)
			(xy 86.900512 -372.486174) (xy 86.900512 -371.993922) (xy 86.900088 -371.984736) (xy 86.893584 -371.967552)
			(xy 86.887812 -371.960394) (xy 86.86591 -371.93476) (xy 86.827822 -371.879121) (xy 86.796672 -371.819321)
			(xy 86.77291 -371.75622) (xy 86.756876 -371.690727) (xy 86.748803 -371.623785) (xy 85.646742 -371.623785)
			(xy 85.646848 -371.624067) (xy 85.662883 -371.689557) (xy 85.670959 -371.756498) (xy 85.670957 -371.823923)
			(xy 85.662879 -371.890863) (xy 85.646841 -371.956354) (xy 85.623074 -372.019451) (xy 85.591919 -372.079248)
			(xy 85.553826 -372.134881) (xy 85.53196 -372.160546) (xy 85.526156 -372.167686) (xy 85.519647 -372.184881)
			(xy 85.51926 -372.194074) (xy 85.51926 -372.351554) (xy 85.518736 -372.361678) (xy 85.511023 -372.380398)
			(xy 85.496748 -372.394756) (xy 85.478073 -372.402576) (xy 85.467952 -372.403116) (xy 84.751672 -372.403116)
			(xy 84.741563 -372.402638) (xy 84.722888 -372.394894) (xy 84.708594 -372.380596) (xy 84.700858 -372.361917)
			(xy 84.700364 -372.351808) (xy 84.700364 -372.194074) (xy 84.699952 -372.184887) (xy 84.693438 -372.167704)
			(xy 84.687664 -372.160546) (xy 84.665815 -372.134869) (xy 84.627728 -372.079235) (xy 84.596579 -372.01944)
			(xy 84.572816 -371.956345) (xy 84.55678 -371.890858) (xy 84.548704 -371.823921) (xy 84.548703 -371.7565)
			(xy 84.556776 -371.689563) (xy 84.572809 -371.624075) (xy 84.59657 -371.560979) (xy 84.627717 -371.501183)
			(xy 84.665802 -371.445548) (xy 84.687664 -371.419882) (xy 84.693459 -371.412736) (xy 84.699973 -371.395546)
			(xy 84.700364 -371.386354) (xy 84.700364 -370.893848) (xy 84.699917 -370.884665) (xy 84.693427 -370.867481)
			(xy 84.687664 -370.86032) (xy 84.66579 -370.834664) (xy 84.627704 -370.779027) (xy 84.596555 -370.719229)
			(xy 84.572793 -370.656131) (xy 84.55676 -370.590642) (xy 84.548686 -370.523703) (xy 81.27115 -370.523703)
			(xy 81.263075 -370.590641) (xy 81.24704 -370.656129) (xy 81.223276 -370.719226) (xy 81.192125 -370.779021)
			(xy 81.154036 -370.834655) (xy 81.132172 -370.86032) (xy 81.126381 -370.867469) (xy 81.119864 -370.884657)
			(xy 81.119472 -370.893848) (xy 81.119472 -371.386354) (xy 81.119911 -371.395538) (xy 81.126405 -371.412722)
			(xy 81.132172 -371.419882) (xy 81.154051 -371.445535) (xy 81.192141 -371.501171) (xy 81.223293 -371.560969)
			(xy 81.246928 -371.623725) (xy 82.349035 -371.623725) (xy 82.349038 -371.556418) (xy 82.357086 -371.489593)
			(xy 82.373062 -371.424209) (xy 82.396738 -371.361203) (xy 82.427775 -371.301478) (xy 82.465727 -371.24589)
			(xy 82.487516 -371.220238) (xy 82.493323 -371.2131) (xy 82.499831 -371.195904) (xy 82.500216 -371.18671)
			(xy 82.500216 -371.028722) (xy 82.500751 -371.018568) (xy 82.508514 -370.999804) (xy 82.522867 -370.985439)
			(xy 82.541625 -370.977659) (xy 82.551778 -370.97716) (xy 83.268058 -370.97716) (xy 83.27823 -370.977599)
			(xy 83.297028 -370.985374) (xy 83.311415 -370.999756) (xy 83.319197 -371.018551) (xy 83.31962 -371.028722)
			(xy 83.31962 -371.18671) (xy 83.320021 -371.195898) (xy 83.326541 -371.213083) (xy 83.33232 -371.220238)
			(xy 83.354072 -371.24592) (xy 83.392024 -371.301501) (xy 83.423061 -371.361221) (xy 83.446738 -371.424221)
			(xy 83.462715 -371.4896) (xy 83.470763 -371.55642) (xy 83.470766 -371.623723) (xy 83.462725 -371.690544)
			(xy 83.446755 -371.755924) (xy 83.423085 -371.818927) (xy 83.392054 -371.878649) (xy 83.354107 -371.934234)
			(xy 83.33232 -371.959886) (xy 83.326507 -371.96702) (xy 83.320001 -371.984219) (xy 83.31962 -371.993414)
			(xy 83.31962 -372.486682) (xy 83.320034 -372.495869) (xy 83.326545 -372.513054) (xy 83.33232 -372.52021)
			(xy 83.354142 -372.545834) (xy 83.392093 -372.601424) (xy 83.423127 -372.661151) (xy 83.446799 -372.724159)
			(xy 83.462771 -372.789545) (xy 83.470813 -372.856371) (xy 83.47081 -372.92368) (xy 83.462762 -372.990505)
			(xy 83.446784 -373.05589) (xy 83.423106 -373.118896) (xy 83.392066 -373.17862) (xy 83.354111 -373.234206)
			(xy 83.33232 -373.259858) (xy 83.326519 -373.267) (xy 83.320006 -373.284193) (xy 83.31962 -373.293386)
			(xy 83.31962 -373.451374) (xy 83.319214 -373.461549) (xy 83.311429 -373.480351) (xy 83.297038 -373.494738)
			(xy 83.278233 -373.502517) (xy 83.268058 -373.502936) (xy 82.551778 -373.502936) (xy 82.541602 -373.502553)
			(xy 82.522802 -373.494756) (xy 82.508417 -373.480358) (xy 82.500637 -373.461551) (xy 82.500216 -373.451374)
			(xy 82.500216 -373.293386) (xy 82.499809 -373.284199) (xy 82.493293 -373.267014) (xy 82.487516 -373.259858)
			(xy 82.465763 -373.234178) (xy 82.427814 -373.178595) (xy 82.396781 -373.118875) (xy 82.373107 -373.055874)
			(xy 82.357133 -372.990496) (xy 82.349086 -372.923677) (xy 82.349083 -372.856375) (xy 82.357123 -372.789555)
			(xy 82.373092 -372.724175) (xy 82.39676 -372.661172) (xy 82.427788 -372.601449) (xy 82.465731 -372.545863)
			(xy 82.487516 -372.52021) (xy 82.493335 -372.513081) (xy 82.499836 -372.495878) (xy 82.500216 -372.486682)
			(xy 82.500216 -371.993414) (xy 82.499795 -371.984228) (xy 82.493288 -371.967044) (xy 82.487516 -371.959886)
			(xy 82.465692 -371.934264) (xy 82.427745 -371.878673) (xy 82.396715 -371.818945) (xy 82.373045 -371.755936)
			(xy 82.357076 -371.690551) (xy 82.349035 -371.623725) (xy 81.246928 -371.623725) (xy 81.247057 -371.624067)
			(xy 81.263092 -371.689558) (xy 81.271168 -371.756498) (xy 81.271166 -371.823923) (xy 81.263089 -371.890863)
			(xy 81.247051 -371.956353) (xy 81.223284 -372.019451) (xy 81.19213 -372.079247) (xy 81.154038 -372.134881)
			(xy 81.132172 -372.160546) (xy 81.12637 -372.167687) (xy 81.119859 -372.184881) (xy 81.119472 -372.194074)
			(xy 81.119472 -372.351554) (xy 81.118936 -372.361676) (xy 81.111226 -372.380394) (xy 81.096954 -372.394752)
			(xy 81.078283 -372.402574) (xy 81.068164 -372.403116) (xy 80.351884 -372.403116) (xy 80.341776 -372.402628)
			(xy 80.323101 -372.394888) (xy 80.308807 -372.380592) (xy 80.30107 -372.361916) (xy 80.300576 -372.351808)
			(xy 80.300576 -372.194074) (xy 80.300184 -372.184885) (xy 80.293658 -372.1677) (xy 80.287876 -372.160546)
			(xy 80.266027 -372.134869) (xy 80.227939 -372.079236) (xy 80.196789 -372.019441) (xy 80.173025 -371.956346)
			(xy 80.156989 -371.890858) (xy 80.148913 -371.823922) (xy 80.148912 -371.756499) (xy 80.156986 -371.689563)
			(xy 80.173019 -371.624075) (xy 80.196781 -371.560978) (xy 80.227928 -371.501182) (xy 80.266014 -371.445548)
			(xy 80.287876 -371.419882) (xy 80.29366 -371.412728) (xy 80.300183 -371.395544) (xy 80.300576 -371.386354)
			(xy 80.300576 -370.893848) (xy 80.300148 -370.884663) (xy 80.293647 -370.867478) (xy 80.287876 -370.86032)
			(xy 80.266001 -370.834664) (xy 80.227914 -370.779028) (xy 80.196765 -370.71923) (xy 80.173003 -370.656132)
			(xy 80.156969 -370.590642) (xy 80.148895 -370.523703) (xy 76.870824 -370.523703) (xy 76.862788 -370.590464)
			(xy 76.846817 -370.655845) (xy 76.823147 -370.718849) (xy 76.792116 -370.778573) (xy 76.75417 -370.83416)
			(xy 76.732384 -370.859812) (xy 76.726598 -370.866965) (xy 76.720078 -370.88415) (xy 76.719684 -370.89334)
			(xy 76.719684 -371.386862) (xy 76.720116 -371.396047) (xy 76.726615 -371.413231) (xy 76.732384 -371.42039)
			(xy 76.754185 -371.446031) (xy 76.792132 -371.50162) (xy 76.823163 -371.561345) (xy 76.846621 -371.623785)
			(xy 77.948715 -371.623785) (xy 77.948719 -371.556358) (xy 77.956799 -371.489417) (xy 77.972839 -371.423925)
			(xy 77.996609 -371.360826) (xy 78.027766 -371.301029) (xy 78.065861 -371.245395) (xy 78.087728 -371.21973)
			(xy 78.09354 -371.212596) (xy 78.100045 -371.195397) (xy 78.100428 -371.186202) (xy 78.100428 -371.028722)
			(xy 78.100944 -371.018598) (xy 78.108662 -370.99988) (xy 78.12294 -370.985523) (xy 78.141615 -370.977701)
			(xy 78.151736 -370.97716) (xy 78.868016 -370.97716) (xy 78.878121 -370.977671) (xy 78.896792 -370.985407)
			(xy 78.911084 -370.999695) (xy 78.918826 -371.018363) (xy 78.919324 -371.028468) (xy 78.919324 -371.186202)
			(xy 78.919728 -371.19539) (xy 78.926245 -371.212575) (xy 78.932024 -371.21973) (xy 78.95385 -371.245426)
			(xy 78.991938 -371.301057) (xy 79.023089 -371.360849) (xy 79.046854 -371.423942) (xy 79.062892 -371.489427)
			(xy 79.07097 -371.556361) (xy 79.070974 -371.623782) (xy 79.062902 -371.690717) (xy 79.046871 -371.756203)
			(xy 79.023112 -371.819299) (xy 78.991967 -371.879094) (xy 78.953885 -371.934728) (xy 78.932024 -371.960394)
			(xy 78.92625 -371.967556) (xy 78.919721 -371.984733) (xy 78.919324 -371.993922) (xy 78.919324 -372.486174)
			(xy 78.919741 -372.495361) (xy 78.926249 -372.512545) (xy 78.932024 -372.519702) (xy 78.953921 -372.54534)
			(xy 78.992007 -372.600979) (xy 79.023155 -372.660779) (xy 79.046916 -372.72388) (xy 79.062948 -372.789372)
			(xy 79.071021 -372.856313) (xy 79.071018 -372.923738) (xy 79.062939 -372.990679) (xy 79.046901 -373.056169)
			(xy 79.023134 -373.119267) (xy 78.99198 -373.179065) (xy 78.953889 -373.2347) (xy 78.932024 -373.260366)
			(xy 78.92622 -373.267506) (xy 78.919709 -373.2847) (xy 78.919324 -373.293894) (xy 78.919324 -373.451374)
			(xy 78.918851 -373.461504) (xy 78.911125 -373.480231) (xy 78.896834 -373.49459) (xy 78.878143 -373.502403)
			(xy 78.868016 -373.502936) (xy 78.151736 -373.502936) (xy 78.14162 -373.502455) (xy 78.122924 -373.494726)
			(xy 78.10861 -373.480429) (xy 78.100857 -373.461743) (xy 78.100428 -373.451628) (xy 78.100428 -373.293894)
			(xy 78.100015 -373.284707) (xy 78.093503 -373.267523) (xy 78.087728 -373.260366) (xy 78.065896 -373.234674)
			(xy 78.027805 -373.179044) (xy 77.996651 -373.119251) (xy 77.972884 -373.056158) (xy 77.956845 -372.990672)
			(xy 77.948766 -372.923736) (xy 77.948763 -372.856315) (xy 77.956836 -372.789378) (xy 77.972869 -372.723891)
			(xy 77.99663 -372.660795) (xy 78.027779 -372.601) (xy 78.065865 -372.545367) (xy 78.087728 -372.519702)
			(xy 78.09351 -372.512547) (xy 78.100033 -372.495364) (xy 78.100428 -372.486174) (xy 78.100428 -371.993922)
			(xy 78.100001 -371.984737) (xy 78.093498 -371.967553) (xy 78.087728 -371.960394) (xy 78.065826 -371.93476)
			(xy 78.027736 -371.879122) (xy 77.996586 -371.819321) (xy 77.972822 -371.75622) (xy 77.956789 -371.690727)
			(xy 77.948715 -371.623785) (xy 76.846621 -371.623785) (xy 76.846834 -371.624351) (xy 76.862805 -371.689734)
			(xy 76.870848 -371.756558) (xy 76.870847 -371.823863) (xy 76.862802 -371.890687) (xy 76.846828 -371.956069)
			(xy 76.823155 -372.019074) (xy 76.792121 -372.078798) (xy 76.754172 -372.134386) (xy 76.732384 -372.160038)
			(xy 76.726587 -372.167183) (xy 76.720073 -372.184374) (xy 76.719684 -372.193566) (xy 76.719684 -372.351554)
			(xy 76.719199 -372.36172) (xy 76.711433 -372.380509) (xy 76.697067 -372.394895) (xy 76.678287 -372.402686)
			(xy 76.668122 -372.403116) (xy 75.951842 -372.403116) (xy 75.941667 -372.402701) (xy 75.922865 -372.394921)
			(xy 75.908477 -372.380532) (xy 75.900699 -372.361729) (xy 75.90028 -372.351554) (xy 75.90028 -372.193566)
			(xy 75.899891 -372.184377) (xy 75.893363 -372.167192) (xy 75.88758 -372.160038) (xy 75.865805 -372.134375)
			(xy 75.827853 -372.078791) (xy 75.796817 -372.019069) (xy 75.773141 -371.956066) (xy 75.757166 -371.890685)
			(xy 75.74912 -371.823863) (xy 75.749119 -371.756558) (xy 75.757162 -371.689736) (xy 75.773135 -371.624354)
			(xy 75.796808 -371.56135) (xy 75.827842 -371.501627) (xy 75.865792 -371.446042) (xy 75.88758 -371.42039)
			(xy 75.893361 -371.413234) (xy 75.899886 -371.396052) (xy 75.90028 -371.386862) (xy 75.90028 -370.89334)
			(xy 75.899855 -370.884154) (xy 75.893352 -370.866969) (xy 75.88758 -370.859812) (xy 75.865779 -370.83417)
			(xy 75.827828 -370.778583) (xy 75.796793 -370.718859) (xy 75.773119 -370.655853) (xy 75.757146 -370.590469)
			(xy 75.749102 -370.523644) (xy 72.471063 -370.523644) (xy 72.471063 -370.523702) (xy 72.462988 -370.59064)
			(xy 72.446953 -370.656129) (xy 72.42319 -370.719225) (xy 72.39204 -370.779021) (xy 72.353952 -370.834655)
			(xy 72.332088 -370.86032) (xy 72.326299 -370.867471) (xy 72.31978 -370.884657) (xy 72.319388 -370.893848)
			(xy 72.319388 -371.386354) (xy 72.319823 -371.395539) (xy 72.32632 -371.412723) (xy 72.332088 -371.419882)
			(xy 72.353966 -371.445536) (xy 72.392055 -371.501172) (xy 72.423206 -371.560969) (xy 72.446841 -371.623725)
			(xy 73.548947 -371.623725) (xy 73.548951 -371.556417) (xy 73.556998 -371.489592) (xy 73.572975 -371.424208)
			(xy 73.596652 -371.361202) (xy 73.627689 -371.301477) (xy 73.665642 -371.24589) (xy 73.687432 -371.220238)
			(xy 73.693242 -371.213102) (xy 73.699748 -371.195904) (xy 73.700132 -371.18671) (xy 73.700132 -371.028722)
			(xy 73.700582 -371.018553) (xy 73.708359 -370.99976) (xy 73.722736 -370.985374) (xy 73.741525 -370.977587)
			(xy 73.751694 -370.97716) (xy 74.467974 -370.97716) (xy 74.478147 -370.977586) (xy 74.496945 -370.985366)
			(xy 74.511331 -370.999752) (xy 74.519113 -371.018549) (xy 74.519536 -371.028722) (xy 74.519536 -371.18671)
			(xy 74.519956 -371.195896) (xy 74.526464 -371.21308) (xy 74.532236 -371.220238) (xy 74.553987 -371.245921)
			(xy 74.591939 -371.301502) (xy 74.622975 -371.361221) (xy 74.646651 -371.424222) (xy 74.662627 -371.489601)
			(xy 74.670675 -371.55642) (xy 74.670678 -371.623723) (xy 74.662638 -371.690543) (xy 74.646668 -371.755924)
			(xy 74.622998 -371.818926) (xy 74.591968 -371.878649) (xy 74.554022 -371.934234) (xy 74.532236 -371.959886)
			(xy 74.526413 -371.967012) (xy 74.519916 -371.984217) (xy 74.519536 -371.993414) (xy 74.519536 -372.486682)
			(xy 74.519969 -372.495866) (xy 74.526468 -372.51305) (xy 74.532236 -372.52021) (xy 74.554058 -372.545834)
			(xy 74.592008 -372.601424) (xy 74.623041 -372.661151) (xy 74.646713 -372.724159) (xy 74.662684 -372.789545)
			(xy 74.670726 -372.856371) (xy 74.670723 -372.92368) (xy 74.662675 -372.990505) (xy 74.646698 -373.055889)
			(xy 74.62302 -373.118896) (xy 74.591981 -373.17862) (xy 74.554027 -373.234206) (xy 74.532236 -373.259858)
			(xy 74.526425 -373.266992) (xy 74.519921 -373.284191) (xy 74.519536 -373.293386) (xy 74.519536 -373.451374)
			(xy 74.519114 -373.461547) (xy 74.511333 -373.480346) (xy 74.496946 -373.494733) (xy 74.478147 -373.502514)
			(xy 74.467974 -373.502936) (xy 73.751694 -373.502936) (xy 73.741519 -373.50254) (xy 73.722719 -373.494749)
			(xy 73.708333 -373.480354) (xy 73.700553 -373.461549) (xy 73.700132 -373.451374) (xy 73.700132 -373.293386)
			(xy 73.699722 -373.284199) (xy 73.693207 -373.267015) (xy 73.687432 -373.259858) (xy 73.665678 -373.234178)
			(xy 73.627729 -373.178595) (xy 73.596694 -373.118876) (xy 73.57302 -373.055875) (xy 73.557045 -372.990496)
			(xy 73.548998 -372.923677) (xy 73.548995 -372.856374) (xy 73.557036 -372.789554) (xy 73.573005 -372.724174)
			(xy 73.596674 -372.661171) (xy 73.627702 -372.601448) (xy 73.665647 -372.545862) (xy 73.687432 -372.52021)
			(xy 73.693253 -372.513083) (xy 73.699753 -372.495878) (xy 73.700132 -372.486682) (xy 73.700132 -371.993414)
			(xy 73.699708 -371.984228) (xy 73.693203 -371.967044) (xy 73.687432 -371.959886) (xy 73.665607 -371.934265)
			(xy 73.62766 -371.878674) (xy 73.596629 -371.818946) (xy 73.572958 -371.755937) (xy 73.556988 -371.690551)
			(xy 73.548947 -371.623725) (xy 72.446841 -371.623725) (xy 72.44697 -371.624068) (xy 72.463005 -371.689558)
			(xy 72.47108 -371.756498) (xy 72.471078 -371.823923) (xy 72.463001 -371.890862) (xy 72.446964 -371.956352)
			(xy 72.423197 -372.01945) (xy 72.392044 -372.079246) (xy 72.353953 -372.134881) (xy 72.332088 -372.160546)
			(xy 72.326288 -372.167689) (xy 72.319776 -372.184881) (xy 72.319388 -372.194074) (xy 72.319388 -372.351554)
			(xy 72.318836 -372.361674) (xy 72.311129 -372.380389) (xy 72.296863 -372.394746) (xy 72.278197 -372.402572)
			(xy 72.26808 -372.403116) (xy 71.5518 -372.403116) (xy 71.541648 -372.402679) (xy 71.522899 -372.394886)
			(xy 71.508576 -372.380494) (xy 71.500873 -372.361708) (xy 71.500492 -372.351554) (xy 71.500492 -372.194074)
			(xy 71.500096 -372.184885) (xy 71.493573 -372.167701) (xy 71.487792 -372.160546) (xy 71.465942 -372.134869)
			(xy 71.427853 -372.079236) (xy 71.396703 -372.019442) (xy 71.372938 -371.956346) (xy 71.356902 -371.890859)
			(xy 71.348825 -371.823922) (xy 71.348824 -371.756499) (xy 71.356898 -371.689562) (xy 71.372932 -371.624074)
			(xy 71.396694 -371.560978) (xy 71.427843 -371.501182) (xy 71.465929 -371.445547) (xy 71.487792 -371.419882)
			(xy 71.493578 -371.412729) (xy 71.500099 -371.395545) (xy 71.500492 -371.386354) (xy 71.500492 -370.893848)
			(xy 71.500061 -370.884663) (xy 71.493562 -370.867478) (xy 71.487792 -370.86032) (xy 71.465917 -370.834664)
			(xy 71.427829 -370.779028) (xy 71.396679 -370.719231) (xy 71.372916 -370.656133) (xy 71.356881 -370.590642)
			(xy 71.348807 -370.523703) (xy 58.103008 -370.523703) (xy 58.103008 -371.310662) (xy 58.102522 -371.337931)
			(xy 58.09476 -371.391915) (xy 58.079395 -371.444245) (xy 58.056738 -371.493855) (xy 58.027252 -371.539736)
			(xy 57.991537 -371.580953) (xy 57.95032 -371.616668) (xy 57.904439 -371.646154) (xy 57.854829 -371.668811)
			(xy 57.802499 -371.684176) (xy 57.748515 -371.691938) (xy 57.693977 -371.691938) (xy 57.639993 -371.684176)
			(xy 57.587663 -371.668811) (xy 57.538053 -371.646154) (xy 57.492172 -371.616668) (xy 57.450955 -371.580953)
			(xy 57.41524 -371.539736) (xy 57.385754 -371.493855) (xy 57.363097 -371.444245) (xy 57.347732 -371.391915)
			(xy 57.33997 -371.337931) (xy 57.339484 -371.310662) (xy 54.729888 -371.310662) (xy 54.729402 -371.337931)
			(xy 54.72164 -371.391915) (xy 54.706275 -371.444245) (xy 54.683618 -371.493855) (xy 54.654132 -371.539736)
			(xy 54.618417 -371.580953) (xy 54.5772 -371.616668) (xy 54.531319 -371.646154) (xy 54.481709 -371.668811)
			(xy 54.429379 -371.684176) (xy 54.375395 -371.691938) (xy 54.320857 -371.691938) (xy 54.266873 -371.684176)
			(xy 54.214543 -371.668811) (xy 54.164933 -371.646154) (xy 54.119052 -371.616668) (xy 54.077835 -371.580953)
			(xy 54.04212 -371.539736) (xy 54.012634 -371.493855) (xy 53.989977 -371.444245) (xy 53.974612 -371.391915)
			(xy 53.96685 -371.337931) (xy 53.966364 -371.310662) (xy 48.196948 -371.310662) (xy 48.223223 -371.361224)
			(xy 48.246896 -371.424224) (xy 48.262871 -371.489602) (xy 48.270918 -371.556421) (xy 48.270921 -371.623722)
			(xy 48.262881 -371.690542) (xy 48.246913 -371.755921) (xy 48.223246 -371.818924) (xy 48.192219 -371.878647)
			(xy 48.154277 -371.934234) (xy 48.132492 -371.959886) (xy 48.126675 -371.967017) (xy 48.120173 -371.984218)
			(xy 48.119792 -371.993414) (xy 48.119792 -372.486682) (xy 48.120213 -372.495868) (xy 48.126719 -372.513052)
			(xy 48.132492 -372.52021) (xy 48.154312 -372.545835) (xy 48.192258 -372.601426) (xy 48.223288 -372.661154)
			(xy 48.246958 -372.724162) (xy 48.262927 -372.789547) (xy 48.270968 -372.856372) (xy 48.270965 -372.923679)
			(xy 48.262918 -372.990504) (xy 48.246942 -373.055887) (xy 48.223267 -373.118893) (xy 48.192232 -373.178618)
			(xy 48.154281 -373.234205) (xy 48.132492 -373.259858) (xy 48.126687 -373.266997) (xy 48.120178 -373.284192)
			(xy 48.119792 -373.293386) (xy 48.119792 -373.451374) (xy 48.119246 -373.461526) (xy 48.111486 -373.480289)
			(xy 48.097136 -373.494655) (xy 48.078382 -373.502435) (xy 48.06823 -373.502936) (xy 47.35195 -373.502936)
			(xy 47.341778 -373.502495) (xy 47.32298 -373.494721) (xy 47.308592 -373.48034) (xy 47.30081 -373.461545)
			(xy 47.300388 -373.451374) (xy 47.300388 -373.293386) (xy 47.299987 -373.284198) (xy 47.293467 -373.267013)
			(xy 47.287688 -373.259858) (xy 47.265932 -373.234179) (xy 47.227979 -373.178598) (xy 47.196942 -373.118878)
			(xy 47.173265 -373.055877) (xy 47.157288 -372.990498) (xy 47.14924 -372.923677) (xy 47.149237 -372.856374)
			(xy 47.157279 -372.789553) (xy 47.17325 -372.724172) (xy 47.196921 -372.661169) (xy 47.227953 -372.601446)
			(xy 47.265901 -372.545861) (xy 47.287688 -372.52021) (xy 47.293504 -372.513078) (xy 47.300007 -372.495878)
			(xy 47.300388 -372.486682) (xy 47.300388 -371.993414) (xy 47.299974 -371.984227) (xy 47.293463 -371.967043)
			(xy 47.287688 -371.959886) (xy 47.265861 -371.934265) (xy 47.227911 -371.878675) (xy 47.196876 -371.818948)
			(xy 47.173204 -371.755939) (xy 47.157232 -371.690553) (xy 47.14919 -371.623726) (xy 46.046568 -371.623726)
			(xy 46.046802 -371.624349) (xy 46.062775 -371.689733) (xy 46.070818 -371.756557) (xy 46.070817 -371.823864)
			(xy 46.062771 -371.890688) (xy 46.046796 -371.956071) (xy 46.023121 -372.019076) (xy 45.992085 -372.0788)
			(xy 45.954133 -372.134386) (xy 45.932344 -372.160038) (xy 45.926542 -372.167179) (xy 45.920032 -372.184373)
			(xy 45.919644 -372.193566) (xy 45.919644 -372.351554) (xy 45.919198 -372.361725) (xy 45.911425 -372.380522)
			(xy 45.897046 -372.394909) (xy 45.878253 -372.402693) (xy 45.868082 -372.403116) (xy 45.151802 -372.403116)
			(xy 45.141625 -372.402733) (xy 45.122821 -372.394941) (xy 45.108435 -372.380542) (xy 45.100658 -372.361732)
			(xy 45.10024 -372.351554) (xy 45.10024 -372.193566) (xy 45.099837 -372.184378) (xy 45.093317 -372.167194)
			(xy 45.08754 -372.160038) (xy 45.065766 -372.134374) (xy 45.027817 -372.07879) (xy 44.996783 -372.019068)
			(xy 44.973109 -371.956065) (xy 44.957135 -371.890684) (xy 44.94909 -371.823862) (xy 44.949089 -371.756559)
			(xy 44.957132 -371.689737) (xy 44.973103 -371.624356) (xy 44.996774 -371.561352) (xy 45.027806 -371.501628)
			(xy 45.065753 -371.446042) (xy 45.08754 -371.42039) (xy 45.093328 -371.413239) (xy 45.099847 -371.396053)
			(xy 45.10024 -371.386862) (xy 45.10024 -370.89334) (xy 45.099801 -370.884156) (xy 45.093306 -370.866972)
			(xy 45.08754 -370.859812) (xy 45.06574 -370.83417) (xy 45.027792 -370.778582) (xy 44.996759 -370.718857)
			(xy 44.973087 -370.655851) (xy 44.957115 -370.590468) (xy 44.949071 -370.523644) (xy 41.671032 -370.523644)
			(xy 41.671032 -370.523703) (xy 41.662957 -370.590641) (xy 41.646921 -370.65613) (xy 41.623156 -370.719227)
			(xy 41.592004 -370.779022) (xy 41.553913 -370.834656) (xy 41.532048 -370.86032) (xy 41.526254 -370.867467)
			(xy 41.519739 -370.884656) (xy 41.519348 -370.893848) (xy 41.519348 -371.386354) (xy 41.519792 -371.395537)
			(xy 41.526284 -371.412721) (xy 41.532048 -371.419882) (xy 41.553928 -371.445535) (xy 41.592019 -371.50117)
			(xy 41.623172 -371.560967) (xy 41.646832 -371.623785) (xy 42.748894 -371.623785) (xy 42.748898 -371.556358)
			(xy 42.756977 -371.489417) (xy 42.773017 -371.423926) (xy 42.796785 -371.360828) (xy 42.827941 -371.30103)
			(xy 42.866034 -371.245395) (xy 42.8879 -371.21973) (xy 42.893709 -371.212593) (xy 42.900216 -371.195396)
			(xy 42.9006 -371.186202) (xy 42.9006 -371.028722) (xy 42.901143 -371.018602) (xy 42.908856 -370.999888)
			(xy 42.923125 -370.985533) (xy 42.941791 -370.977706) (xy 42.951908 -370.97716) (xy 43.668188 -370.97716)
			(xy 43.678336 -370.977631) (xy 43.697081 -370.985415) (xy 43.711403 -370.999796) (xy 43.71911 -371.018572)
			(xy 43.719496 -371.028722) (xy 43.719496 -371.186202) (xy 43.719906 -371.195389) (xy 43.72642 -371.212573)
			(xy 43.732196 -371.21973) (xy 43.754023 -371.245426) (xy 43.792113 -371.301056) (xy 43.823265 -371.360848)
			(xy 43.847032 -371.423941) (xy 43.86307 -371.489426) (xy 43.871149 -371.556361) (xy 43.871153 -371.623782)
			(xy 43.86308 -371.690718) (xy 43.847049 -371.756205) (xy 43.823289 -371.8193) (xy 43.792142 -371.879095)
			(xy 43.754058 -371.934729) (xy 43.732196 -371.960394) (xy 43.726419 -371.967553) (xy 43.719893 -371.984733)
			(xy 43.719496 -371.993922) (xy 43.719496 -372.486174) (xy 43.71992 -372.49536) (xy 43.726424 -372.512544)
			(xy 43.732196 -372.519702) (xy 43.754094 -372.54534) (xy 43.792181 -372.600978) (xy 43.823331 -372.660778)
			(xy 43.847093 -372.723878) (xy 43.863127 -372.789371) (xy 43.8712 -372.856312) (xy 43.871197 -372.923739)
			(xy 43.863117 -372.990679) (xy 43.847078 -373.05617) (xy 43.82331 -373.119269) (xy 43.792155 -373.179066)
			(xy 43.754062 -373.234701) (xy 43.732196 -373.260366) (xy 43.726388 -373.267503) (xy 43.71988 -373.2847)
			(xy 43.719496 -373.293894) (xy 43.719496 -373.451374) (xy 43.718953 -373.461495) (xy 43.711241 -373.480208)
			(xy 43.696972 -373.494564) (xy 43.678306 -373.502391) (xy 43.668188 -373.502936) (xy 42.951908 -373.502936)
			(xy 42.941759 -373.502473) (xy 42.923014 -373.494686) (xy 42.908691 -373.480303) (xy 42.900985 -373.461525)
			(xy 42.9006 -373.451374) (xy 42.9006 -373.293894) (xy 42.900193 -373.284707) (xy 42.893677 -373.267522)
			(xy 42.8879 -373.260366) (xy 42.866069 -373.234673) (xy 42.82798 -373.179043) (xy 42.796828 -373.11925)
			(xy 42.773061 -373.056157) (xy 42.757024 -372.990671) (xy 42.748945 -372.923736) (xy 42.748942 -372.856315)
			(xy 42.757014 -372.789379) (xy 42.773046 -372.723892) (xy 42.796807 -372.660796) (xy 42.827953 -372.601001)
			(xy 42.866038 -372.545367) (xy 42.8879 -372.519702) (xy 42.893678 -372.512544) (xy 42.900204 -372.495363)
			(xy 42.9006 -372.486174) (xy 42.9006 -371.993922) (xy 42.900179 -371.984736) (xy 42.893673 -371.967551)
			(xy 42.8879 -371.960394) (xy 42.865999 -371.93476) (xy 42.827911 -371.879121) (xy 42.796762 -371.81932)
			(xy 42.773 -371.756219) (xy 42.756967 -371.690726) (xy 42.748894 -371.623785) (xy 41.646832 -371.623785)
			(xy 41.646938 -371.624066) (xy 41.662974 -371.689557) (xy 41.67105 -371.756498) (xy 41.671048 -371.823923)
			(xy 41.66297 -371.890864) (xy 41.646932 -371.956354) (xy 41.623164 -372.019452) (xy 41.592008 -372.079248)
			(xy 41.553915 -372.134882) (xy 41.532048 -372.160546) (xy 41.526243 -372.167685) (xy 41.519735 -372.18488)
			(xy 41.519348 -372.194074) (xy 41.519348 -372.351554) (xy 41.518835 -372.361679) (xy 41.51112 -372.380402)
			(xy 41.496842 -372.39476) (xy 41.478162 -372.402579) (xy 41.46804 -372.403116) (xy 40.75176 -372.403116)
			(xy 40.741605 -372.402711) (xy 40.722855 -372.394906) (xy 40.708534 -372.380504) (xy 40.700833 -372.361711)
			(xy 40.700452 -372.351554) (xy 40.700452 -372.194074) (xy 40.700043 -372.184887) (xy 40.693527 -372.167703)
			(xy 40.687752 -372.160546) (xy 40.6659 -372.13487) (xy 40.627807 -372.079238) (xy 40.596653 -372.019444)
			(xy 40.572886 -371.956349) (xy 40.556848 -371.89086) (xy 40.54877 -371.823922) (xy 40.548769 -371.756499)
			(xy 40.556844 -371.68956) (xy 40.57288 -371.624072) (xy 40.596645 -371.560975) (xy 40.627797 -371.50118)
			(xy 40.665887 -371.445546) (xy 40.687752 -371.419882) (xy 40.693545 -371.412735) (xy 40.70006 -371.395546)
			(xy 40.700452 -371.386354) (xy 40.700452 -370.893848) (xy 40.700007 -370.884665) (xy 40.693516 -370.867481)
			(xy 40.687752 -370.86032) (xy 40.665874 -370.834665) (xy 40.627783 -370.779031) (xy 40.59663 -370.719233)
			(xy 40.572864 -370.656135) (xy 40.556828 -370.590644) (xy 40.548752 -370.523704) (xy 37.271241 -370.523704)
			(xy 37.263166 -370.590641) (xy 37.247131 -370.65613) (xy 37.223366 -370.719226) (xy 37.192215 -370.779022)
			(xy 37.154125 -370.834655) (xy 37.13226 -370.86032) (xy 37.126467 -370.867468) (xy 37.119951 -370.884656)
			(xy 37.11956 -370.893848) (xy 37.11956 -371.386354) (xy 37.120001 -371.395538) (xy 37.126494 -371.412722)
			(xy 37.13226 -371.419882) (xy 37.154139 -371.445535) (xy 37.19223 -371.501171) (xy 37.223382 -371.560968)
			(xy 37.247019 -371.623725) (xy 38.349126 -371.623725) (xy 38.349129 -371.556418) (xy 38.357177 -371.489593)
			(xy 38.373153 -371.424209) (xy 38.396828 -371.361203) (xy 38.427864 -371.301478) (xy 38.465815 -371.245891)
			(xy 38.487604 -371.220238) (xy 38.49341 -371.213099) (xy 38.499919 -371.195904) (xy 38.500304 -371.18671)
			(xy 38.500304 -371.028722) (xy 38.50085 -371.01857) (xy 38.508611 -370.999808) (xy 38.522961 -370.985443)
			(xy 38.541714 -370.977661) (xy 38.551866 -370.97716) (xy 39.268146 -370.97716) (xy 39.278309 -370.977596)
			(xy 39.297084 -370.98539) (xy 39.311448 -370.999773) (xy 39.319217 -371.018558) (xy 39.319708 -371.028722)
			(xy 39.319708 -371.18671) (xy 39.320112 -371.195898) (xy 39.32663 -371.213082) (xy 39.332408 -371.220238)
			(xy 39.35416 -371.24592) (xy 39.392113 -371.301501) (xy 39.423151 -371.36122) (xy 39.446829 -371.424221)
			(xy 39.462806 -371.4896) (xy 39.470854 -371.55642) (xy 39.470857 -371.623723) (xy 39.462816 -371.690544)
			(xy 39.446845 -371.755925) (xy 39.423175 -371.818928) (xy 39.392143 -371.87865) (xy 39.354195 -371.934235)
			(xy 39.332408 -371.959886) (xy 39.326593 -371.967018) (xy 39.320089 -371.984219) (xy 39.319708 -371.993414)
			(xy 39.319708 -372.486682) (xy 39.320125 -372.495868) (xy 39.326634 -372.513053) (xy 39.332408 -372.52021)
			(xy 39.354231 -372.545834) (xy 39.392182 -372.601423) (xy 39.423217 -372.66115) (xy 39.44689 -372.724158)
			(xy 39.462862 -372.789545) (xy 39.470904 -372.856371) (xy 39.470901 -372.92368) (xy 39.462853 -372.990506)
			(xy 39.446875 -373.05589) (xy 39.423196 -373.118897) (xy 39.392156 -373.178621) (xy 39.354199 -373.234207)
			(xy 39.332408 -373.259858) (xy 39.326605 -373.266999) (xy 39.320094 -373.284193) (xy 39.319708 -373.293386)
			(xy 39.319708 -373.451374) (xy 39.319147 -373.461525) (xy 39.311389 -373.480284) (xy 39.297045 -373.494649)
			(xy 39.278296 -373.502432) (xy 39.268146 -373.502936) (xy 38.551866 -373.502936) (xy 38.541703 -373.502494)
			(xy 38.522928 -373.494703) (xy 38.508563 -373.480322) (xy 38.500794 -373.461538) (xy 38.500304 -373.451374)
			(xy 38.500304 -373.293386) (xy 38.4999 -373.284198) (xy 38.493382 -373.267014) (xy 38.487604 -373.259858)
			(xy 38.465851 -373.234178) (xy 38.427903 -373.178595) (xy 38.39687 -373.118875) (xy 38.373197 -373.055874)
			(xy 38.357223 -372.990495) (xy 38.349177 -372.923676) (xy 38.349174 -372.856375) (xy 38.357214 -372.789555)
			(xy 38.373182 -372.724175) (xy 38.396849 -372.661172) (xy 38.427877 -372.601449) (xy 38.465819 -372.545863)
			(xy 38.487604 -372.52021) (xy 38.493422 -372.51308) (xy 38.499924 -372.495878) (xy 38.500304 -372.486682)
			(xy 38.500304 -371.993414) (xy 38.499886 -371.984228) (xy 38.493378 -371.967043) (xy 38.487604 -371.959886)
			(xy 38.46578 -371.934264) (xy 38.427835 -371.878672) (xy 38.396805 -371.818944) (xy 38.373136 -371.755936)
			(xy 38.357167 -371.69055) (xy 38.349126 -371.623725) (xy 37.247019 -371.623725) (xy 37.247148 -371.624067)
			(xy 37.263183 -371.689557) (xy 37.271259 -371.756498) (xy 37.271257 -371.823923) (xy 37.263179 -371.890863)
			(xy 37.247141 -371.956354) (xy 37.223374 -372.019451) (xy 37.192219 -372.079248) (xy 37.154126 -372.134881)
			(xy 37.13226 -372.160546) (xy 37.126456 -372.167686) (xy 37.119947 -372.184881) (xy 37.11956 -372.194074)
			(xy 37.11956 -372.351554) (xy 37.119036 -372.361678) (xy 37.111323 -372.380398) (xy 37.097048 -372.394756)
			(xy 37.078373 -372.402576) (xy 37.068252 -372.403116) (xy 36.351972 -372.403116) (xy 36.341818 -372.402702)
			(xy 36.323068 -372.3949) (xy 36.308746 -372.380501) (xy 36.301045 -372.36171) (xy 36.300664 -372.351554)
			(xy 36.300664 -372.194074) (xy 36.300252 -372.184887) (xy 36.293738 -372.167704) (xy 36.287964 -372.160546)
			(xy 36.266115 -372.134869) (xy 36.228028 -372.079235) (xy 36.196879 -372.01944) (xy 36.173116 -371.956345)
			(xy 36.15708 -371.890858) (xy 36.149004 -371.823921) (xy 36.149003 -371.7565) (xy 36.157076 -371.689563)
			(xy 36.173109 -371.624075) (xy 36.19687 -371.560979) (xy 36.228017 -371.501183) (xy 36.266102 -371.445548)
			(xy 36.287964 -371.419882) (xy 36.293759 -371.412736) (xy 36.300273 -371.395546) (xy 36.300664 -371.386354)
			(xy 36.300664 -370.893848) (xy 36.300217 -370.884665) (xy 36.293727 -370.867481) (xy 36.287964 -370.86032)
			(xy 36.26609 -370.834664) (xy 36.228004 -370.779027) (xy 36.196855 -370.719229) (xy 36.173093 -370.656131)
			(xy 36.15706 -370.590642) (xy 36.148986 -370.523703) (xy 32.870915 -370.523703) (xy 32.862879 -370.590465)
			(xy 32.846908 -370.655846) (xy 32.823237 -370.71885) (xy 32.792205 -370.778573) (xy 32.754259 -370.83416)
			(xy 32.732472 -370.859812) (xy 32.726684 -370.866963) (xy 32.720165 -370.884149) (xy 32.719772 -370.89334)
			(xy 32.719772 -371.386862) (xy 32.720207 -371.396046) (xy 32.726704 -371.413231) (xy 32.732472 -371.42039)
			(xy 32.754273 -371.446031) (xy 32.792221 -371.501619) (xy 32.823253 -371.561344) (xy 32.846713 -371.623785)
			(xy 33.948806 -371.623785) (xy 33.94881 -371.556358) (xy 33.95689 -371.489417) (xy 33.97293 -371.423925)
			(xy 33.996699 -371.360827) (xy 34.027855 -371.30103) (xy 34.065949 -371.245395) (xy 34.087816 -371.21973)
			(xy 34.093627 -371.212595) (xy 34.100132 -371.195397) (xy 34.100516 -371.186202) (xy 34.100516 -371.028722)
			(xy 34.101044 -371.0186) (xy 34.10876 -370.999883) (xy 34.123033 -370.985527) (xy 34.141705 -370.977703)
			(xy 34.151824 -370.97716) (xy 34.868104 -370.97716) (xy 34.878253 -370.977618) (xy 34.896998 -370.985407)
			(xy 34.91132 -370.999792) (xy 34.919027 -371.018571) (xy 34.919412 -371.028722) (xy 34.919412 -371.186202)
			(xy 34.919819 -371.19539) (xy 34.926334 -371.212574) (xy 34.932112 -371.21973) (xy 34.953938 -371.245426)
			(xy 34.992027 -371.301057) (xy 35.023179 -371.360849) (xy 35.046945 -371.423941) (xy 35.062982 -371.489427)
			(xy 35.071061 -371.556361) (xy 35.071065 -371.623782) (xy 35.062993 -371.690717) (xy 35.046962 -371.756204)
			(xy 35.023202 -371.819299) (xy 34.992057 -371.879094) (xy 34.953973 -371.934729) (xy 34.932112 -371.960394)
			(xy 34.926337 -371.967555) (xy 34.919809 -371.984733) (xy 34.919412 -371.993922) (xy 34.919412 -372.486174)
			(xy 34.919832 -372.49536) (xy 34.926338 -372.512545) (xy 34.932112 -372.519702) (xy 34.954009 -372.54534)
			(xy 34.992096 -372.600979) (xy 35.023244 -372.660779) (xy 35.047006 -372.723879) (xy 35.063039 -372.789371)
			(xy 35.071112 -372.856312) (xy 35.071109 -372.923739) (xy 35.06303 -372.990679) (xy 35.046991 -373.05617)
			(xy 35.023224 -373.119268) (xy 34.99207 -373.179065) (xy 34.953978 -373.234701) (xy 34.932112 -373.260366)
			(xy 34.926306 -373.267505) (xy 34.919797 -373.2847) (xy 34.919412 -373.293894) (xy 34.919412 -373.451374)
			(xy 34.918854 -373.461493) (xy 34.911144 -373.480203) (xy 34.89688 -373.494559) (xy 34.878219 -373.502388)
			(xy 34.868104 -373.502936) (xy 34.151824 -373.502936) (xy 34.141676 -373.50246) (xy 34.122931 -373.494679)
			(xy 34.108608 -373.480299) (xy 34.100901 -373.461524) (xy 34.100516 -373.451374) (xy 34.100516 -373.293894)
			(xy 34.100105 -373.284707) (xy 34.093592 -373.267523) (xy 34.087816 -373.260366) (xy 34.065985 -373.234673)
			(xy 34.027894 -373.179043) (xy 33.996741 -373.119251) (xy 33.972974 -373.056158) (xy 33.956936 -372.990672)
			(xy 33.948857 -372.923736) (xy 33.948854 -372.856315) (xy 33.956927 -372.789379) (xy 33.972959 -372.723891)
			(xy 33.99672 -372.660796) (xy 34.027868 -372.601001) (xy 34.065953 -372.545367) (xy 34.087816 -372.519702)
			(xy 34.093596 -372.512545) (xy 34.10012 -372.495364) (xy 34.100516 -372.486174) (xy 34.100516 -371.993922)
			(xy 34.100092 -371.984736) (xy 34.093587 -371.967552) (xy 34.087816 -371.960394) (xy 34.065914 -371.93476)
			(xy 34.027826 -371.879121) (xy 33.996676 -371.819321) (xy 33.972913 -371.75622) (xy 33.956879 -371.690727)
			(xy 33.948806 -371.623785) (xy 32.846713 -371.623785) (xy 32.846925 -371.62435) (xy 32.862896 -371.689734)
			(xy 32.870939 -371.756558) (xy 32.870938 -371.823864) (xy 32.862892 -371.890687) (xy 32.846918 -371.95607)
			(xy 32.823244 -372.019075) (xy 32.79221 -372.078799) (xy 32.75426 -372.134386) (xy 32.732472 -372.160038)
			(xy 32.726673 -372.167181) (xy 32.72016 -372.184373) (xy 32.719772 -372.193566) (xy 32.719772 -372.351554)
			(xy 32.719299 -372.361721) (xy 32.711531 -372.380513) (xy 32.69716 -372.394899) (xy 32.678377 -372.402688)
			(xy 32.66821 -372.403116) (xy 31.95193 -372.403116) (xy 31.941755 -372.40271) (xy 31.922952 -372.394927)
			(xy 31.908564 -372.380535) (xy 31.900787 -372.361729) (xy 31.900368 -372.351554) (xy 31.900368 -372.193566)
			(xy 31.899959 -372.184379) (xy 31.893443 -372.167195) (xy 31.887668 -372.160038) (xy 31.865893 -372.134375)
			(xy 31.827942 -372.078791) (xy 31.796907 -372.019069) (xy 31.773232 -371.956066) (xy 31.757257 -371.890685)
			(xy 31.749211 -371.823863) (xy 31.74921 -371.756558) (xy 31.757253 -371.689736) (xy 31.773226 -371.624354)
			(xy 31.796898 -371.56135) (xy 31.827931 -371.501627) (xy 31.86588 -371.446042) (xy 31.887668 -371.42039)
			(xy 31.89346 -371.413242) (xy 31.899975 -371.396053) (xy 31.900368 -371.386862) (xy 31.900368 -370.89334)
			(xy 31.899923 -370.884157) (xy 31.893432 -370.866973) (xy 31.887668 -370.859812) (xy 31.865868 -370.83417)
			(xy 31.827917 -370.778583) (xy 31.796883 -370.718858) (xy 31.77321 -370.655852) (xy 31.757237 -370.590468)
			(xy 31.749193 -370.523644) (xy 28.471153 -370.523644) (xy 28.471153 -370.523703) (xy 28.463078 -370.59064)
			(xy 28.447043 -370.656129) (xy 28.42328 -370.719226) (xy 28.392129 -370.779021) (xy 28.35404 -370.834655)
			(xy 28.332176 -370.86032) (xy 28.326386 -370.867469) (xy 28.319868 -370.884657) (xy 28.319476 -370.893848)
			(xy 28.319476 -371.386354) (xy 28.319914 -371.395538) (xy 28.326409 -371.412722) (xy 28.332176 -371.419882)
			(xy 28.354055 -371.445535) (xy 28.392144 -371.501171) (xy 28.423296 -371.560969) (xy 28.446931 -371.623725)
			(xy 29.549038 -371.623725) (xy 29.549042 -371.556418) (xy 29.557089 -371.489593) (xy 29.573066 -371.424209)
			(xy 29.596742 -371.361203) (xy 29.627778 -371.301478) (xy 29.665731 -371.24589) (xy 29.68752 -371.220238)
			(xy 29.693328 -371.213101) (xy 29.699835 -371.195904) (xy 29.70022 -371.18671) (xy 29.70022 -371.028722)
			(xy 29.700682 -371.018554) (xy 29.708456 -370.999763) (xy 29.72283 -370.985378) (xy 29.741614 -370.97759)
			(xy 29.751782 -370.97716) (xy 30.468062 -370.97716) (xy 30.478234 -370.977596) (xy 30.497032 -370.985372)
			(xy 30.511419 -370.999755) (xy 30.519201 -371.01855) (xy 30.519624 -371.028722) (xy 30.519624 -371.18671)
			(xy 30.520024 -371.195898) (xy 30.526544 -371.213083) (xy 30.532324 -371.220238) (xy 30.554075 -371.24592)
			(xy 30.592028 -371.301502) (xy 30.623065 -371.361221) (xy 30.646741 -371.424221) (xy 30.662718 -371.4896)
			(xy 30.670766 -371.55642) (xy 30.670769 -371.623723) (xy 30.662728 -371.690543) (xy 30.646758 -371.755924)
			(xy 30.623088 -371.818927) (xy 30.592057 -371.878649) (xy 30.554111 -371.934234) (xy 30.532324 -371.959886)
			(xy 30.526511 -371.96702) (xy 30.520005 -371.984219) (xy 30.519624 -371.993414) (xy 30.519624 -372.486682)
			(xy 30.520037 -372.495869) (xy 30.526548 -372.513054) (xy 30.532324 -372.52021) (xy 30.554146 -372.545834)
			(xy 30.592096 -372.601424) (xy 30.62313 -372.661151) (xy 30.646803 -372.724159) (xy 30.662774 -372.789545)
			(xy 30.670816 -372.856371) (xy 30.670813 -372.92368) (xy 30.662765 -372.990505) (xy 30.646788 -373.05589)
			(xy 30.623109 -373.118896) (xy 30.59207 -373.17862) (xy 30.554115 -373.234206) (xy 30.532324 -373.259858)
			(xy 30.526523 -373.267) (xy 30.52001 -373.284193) (xy 30.519624 -373.293386) (xy 30.519624 -373.451374)
			(xy 30.519214 -373.461549) (xy 30.51143 -373.48035) (xy 30.49704 -373.494737) (xy 30.478237 -373.502516)
			(xy 30.468062 -373.502936) (xy 29.751782 -373.502936) (xy 29.741606 -373.50255) (xy 29.722806 -373.494754)
			(xy 29.708421 -373.480357) (xy 29.700641 -373.46155) (xy 29.70022 -373.451374) (xy 29.70022 -373.293386)
			(xy 29.699812 -373.284199) (xy 29.693297 -373.267015) (xy 29.68752 -373.259858) (xy 29.665767 -373.234178)
			(xy 29.627818 -373.178595) (xy 29.596784 -373.118875) (xy 29.57311 -373.055874) (xy 29.557136 -372.990496)
			(xy 29.549089 -372.923677) (xy 29.549086 -372.856375) (xy 29.557127 -372.789555) (xy 29.573095 -372.724175)
			(xy 29.596763 -372.661172) (xy 29.627792 -372.601449) (xy 29.665735 -372.545863) (xy 29.68752 -372.52021)
			(xy 29.69334 -372.513081) (xy 29.69984 -372.495878) (xy 29.70022 -372.486682) (xy 29.70022 -371.993414)
			(xy 29.699798 -371.984228) (xy 29.693292 -371.967044) (xy 29.68752 -371.959886) (xy 29.665695 -371.934264)
			(xy 29.627749 -371.878673) (xy 29.596718 -371.818945) (xy 29.573049 -371.755937) (xy 29.557079 -371.690551)
			(xy 29.549038 -371.623725) (xy 28.446931 -371.623725) (xy 28.44706 -371.624067) (xy 28.463096 -371.689558)
			(xy 28.471171 -371.756498) (xy 28.471169 -371.823923) (xy 28.463092 -371.890863) (xy 28.447054 -371.956353)
			(xy 28.423287 -372.01945) (xy 28.392134 -372.079247) (xy 28.354042 -372.134881) (xy 28.332176 -372.160546)
			(xy 28.326375 -372.167688) (xy 28.319864 -372.184881) (xy 28.319476 -372.194074) (xy 28.319476 -372.351554)
			(xy 28.318936 -372.361676) (xy 28.311226 -372.380393) (xy 28.296956 -372.39475) (xy 28.278287 -372.402574)
			(xy 28.268168 -372.403116) (xy 27.551888 -372.403116) (xy 27.541781 -372.402625) (xy 27.523105 -372.394886)
			(xy 27.508811 -372.380591) (xy 27.501074 -372.361916) (xy 27.50058 -372.351808) (xy 27.50058 -372.194074)
			(xy 27.500187 -372.184885) (xy 27.493662 -372.167701) (xy 27.48788 -372.160546) (xy 27.46603 -372.134869)
			(xy 27.427943 -372.079236) (xy 27.396792 -372.019441) (xy 27.373028 -371.956346) (xy 27.356993 -371.890858)
			(xy 27.348916 -371.823922) (xy 27.348915 -371.756499) (xy 27.356989 -371.689562) (xy 27.373022 -371.624074)
			(xy 27.396784 -371.560978) (xy 27.427932 -371.501182) (xy 27.466018 -371.445548) (xy 27.48788 -371.419882)
			(xy 27.493664 -371.412728) (xy 27.500187 -371.395544) (xy 27.50058 -371.386354) (xy 27.50058 -370.893848)
			(xy 27.500151 -370.884663) (xy 27.493651 -370.867478) (xy 27.48788 -370.86032) (xy 27.466005 -370.834664)
			(xy 27.427918 -370.779028) (xy 27.396769 -370.71923) (xy 27.373006 -370.656132) (xy 27.356972 -370.590642)
			(xy 27.348898 -370.523703) (xy 0.508 -370.523703) (xy 0.508 -372.100847) (xy 8.642336 -372.100847)
			(xy 8.642336 -372.040913) (xy 8.650159 -371.981491) (xy 8.665671 -371.923598) (xy 8.688607 -371.868226)
			(xy 8.718575 -371.81632) (xy 8.755061 -371.768771) (xy 8.797441 -371.726391) (xy 8.84499 -371.689905)
			(xy 8.896896 -371.659937) (xy 8.952268 -371.637001) (xy 9.010161 -371.621489) (xy 9.069583 -371.613666)
			(xy 9.09955 -371.613176) (xy 9.96315 -371.613176) (xy 9.993118 -371.613658) (xy 10.052541 -371.621481)
			(xy 10.110435 -371.636994) (xy 10.165808 -371.65993) (xy 10.217714 -371.689898) (xy 10.265264 -371.726385)
			(xy 10.307645 -371.768766) (xy 10.344132 -371.816316) (xy 10.3741 -371.868222) (xy 10.397036 -371.923595)
			(xy 10.412549 -371.981489) (xy 10.420372 -372.040912) (xy 10.420372 -372.100848) (xy 10.412549 -372.160271)
			(xy 10.397036 -372.218165) (xy 10.3741 -372.273538) (xy 10.344132 -372.325444) (xy 10.307645 -372.372994)
			(xy 10.265264 -372.415375) (xy 10.217714 -372.451862) (xy 10.165808 -372.48183) (xy 10.110435 -372.504766)
			(xy 10.052541 -372.520279) (xy 9.993118 -372.528102) (xy 9.96315 -372.528592) (xy 9.09955 -372.528592)
			(xy 9.069583 -372.528094) (xy 9.010161 -372.520271) (xy 8.952268 -372.504759) (xy 8.896896 -372.481823)
			(xy 8.84499 -372.451855) (xy 8.797441 -372.415369) (xy 8.755061 -372.372989) (xy 8.718575 -372.32544)
			(xy 8.688607 -372.273534) (xy 8.665671 -372.218162) (xy 8.650159 -372.160269) (xy 8.642336 -372.100847)
			(xy 0.508 -372.100847) (xy 0.508 -374.423871) (xy 27.348897 -374.423871) (xy 27.348897 -374.356446)
			(xy 27.356974 -374.289508) (xy 27.37301 -374.224019) (xy 27.396774 -374.160922) (xy 27.427926 -374.101125)
			(xy 27.466016 -374.045491) (xy 27.48788 -374.019826) (xy 27.493688 -374.012689) (xy 27.500197 -373.995492)
			(xy 27.50058 -373.986298) (xy 27.50058 -373.828818) (xy 27.501042 -373.818688) (xy 27.508772 -373.799959)
			(xy 27.523066 -373.785601) (xy 27.54176 -373.777788) (xy 27.551888 -373.777256) (xy 28.268168 -373.777256)
			(xy 28.278269 -373.77781) (xy 28.296938 -373.785529) (xy 28.311233 -373.799804) (xy 28.318977 -373.818463)
			(xy 28.319476 -373.828564) (xy 28.319476 -373.986298) (xy 28.319892 -373.995484) (xy 28.326402 -374.012669)
			(xy 28.332176 -374.019826) (xy 28.354038 -374.045493) (xy 28.392127 -374.101127) (xy 28.423278 -374.160923)
			(xy 28.447043 -374.22402) (xy 28.463078 -374.289509) (xy 28.471154 -374.356447) (xy 28.471155 -374.423823)
			(xy 31.749171 -374.423823) (xy 31.749175 -374.356514) (xy 31.757224 -374.289688) (xy 31.773202 -374.224303)
			(xy 31.796881 -374.161297) (xy 31.827921 -374.101572) (xy 31.865877 -374.045986) (xy 31.887668 -374.020334)
			(xy 31.893483 -374.013202) (xy 31.899985 -373.996001) (xy 31.900368 -373.986806) (xy 31.900368 -373.828818)
			(xy 31.900779 -373.818644) (xy 31.908564 -373.799844) (xy 31.922954 -373.785457) (xy 31.941756 -373.777677)
			(xy 31.95193 -373.777256) (xy 32.66821 -373.777256) (xy 32.678384 -373.777656) (xy 32.697183 -373.785448)
			(xy 32.711568 -373.799841) (xy 32.719349 -373.818643) (xy 32.719772 -373.828818) (xy 32.719772 -373.986806)
			(xy 32.720185 -373.995993) (xy 32.726697 -374.013177) (xy 32.732472 -374.020334) (xy 32.754218 -374.04602)
			(xy 32.792167 -374.101602) (xy 32.823202 -374.161321) (xy 32.846876 -374.224321) (xy 32.862852 -374.289699)
			(xy 32.870899 -374.356518) (xy 32.870903 -374.423819) (xy 32.870895 -374.423882) (xy 36.148964 -374.423882)
			(xy 36.148968 -374.356455) (xy 36.157048 -374.289515) (xy 36.173087 -374.224024) (xy 36.196854 -374.160925)
			(xy 36.228007 -374.101128) (xy 36.266099 -374.045492) (xy 36.287964 -374.019826) (xy 36.293782 -374.012697)
			(xy 36.300282 -373.995494) (xy 36.300664 -373.986298) (xy 36.300664 -373.828818) (xy 36.301142 -373.818689)
			(xy 36.308868 -373.799964) (xy 36.323158 -373.785606) (xy 36.341846 -373.777791) (xy 36.351972 -373.777256)
			(xy 37.068252 -373.777256) (xy 37.078398 -373.77776) (xy 37.09714 -373.785532) (xy 37.111464 -373.799903)
			(xy 37.119173 -373.818671) (xy 37.11956 -373.828818) (xy 37.11956 -373.986298) (xy 37.11998 -373.995484)
			(xy 37.126488 -374.012668) (xy 37.13226 -374.019826) (xy 37.154084 -374.045525) (xy 37.192177 -374.101153)
			(xy 37.223331 -374.160945) (xy 37.2471 -374.224037) (xy 37.263139 -374.289523) (xy 37.271219 -374.356458)
			(xy 37.271223 -374.423879) (xy 37.271223 -374.423882) (xy 40.548731 -374.423882) (xy 40.548735 -374.356454)
			(xy 40.556815 -374.289512) (xy 40.572857 -374.22402) (xy 40.596628 -374.160921) (xy 40.627787 -374.101124)
			(xy 40.665884 -374.04549) (xy 40.687752 -374.019826) (xy 40.693569 -374.012695) (xy 40.70007 -373.995494)
			(xy 40.700452 -373.986298) (xy 40.700452 -373.828818) (xy 40.700942 -373.818691) (xy 40.708666 -373.799968)
			(xy 40.722951 -373.785611) (xy 40.741636 -373.777793) (xy 40.75176 -373.777256) (xy 41.46804 -373.777256)
			(xy 41.478191 -373.777688) (xy 41.496936 -373.785489) (xy 41.511256 -373.799881) (xy 41.518963 -373.818665)
			(xy 41.519348 -373.828818) (xy 41.519348 -373.986298) (xy 41.519771 -373.995484) (xy 41.526277 -374.012667)
			(xy 41.532048 -374.019826) (xy 41.553873 -374.045524) (xy 41.591966 -374.101153) (xy 41.623121 -374.160944)
			(xy 41.64689 -374.224037) (xy 41.66293 -374.289522) (xy 41.67101 -374.356458) (xy 41.671014 -374.423823)
			(xy 44.94905 -374.423823) (xy 44.949054 -374.356514) (xy 44.957102 -374.289689) (xy 44.97308 -374.224304)
			(xy 44.996757 -374.161298) (xy 45.027796 -374.101573) (xy 45.06575 -374.045986) (xy 45.08754 -374.020334)
			(xy 45.093352 -374.0132) (xy 45.099857 -373.996001) (xy 45.10024 -373.986806) (xy 45.10024 -373.828818)
			(xy 45.100678 -373.818647) (xy 45.108458 -373.799853) (xy 45.122839 -373.785467) (xy 45.141631 -373.777682)
			(xy 45.151802 -373.777256) (xy 45.868082 -373.777256) (xy 45.878255 -373.777679) (xy 45.897053 -373.785461)
			(xy 45.911439 -373.799847) (xy 45.919221 -373.818645) (xy 45.919644 -373.828818) (xy 45.919644 -373.986806)
			(xy 45.920064 -373.995992) (xy 45.926572 -374.013176) (xy 45.932344 -374.020334) (xy 45.954091 -374.04602)
			(xy 45.992042 -374.101601) (xy 46.023078 -374.16132) (xy 46.046754 -374.22432) (xy 46.06273 -374.289698)
			(xy 46.070778 -374.356517) (xy 46.070782 -374.423819) (xy 46.070774 -374.423882) (xy 71.348786 -374.423882)
			(xy 71.348789 -374.356455) (xy 71.356869 -374.289514) (xy 71.372909 -374.224023) (xy 71.396677 -374.160924)
			(xy 71.427833 -374.101127) (xy 71.465926 -374.045491) (xy 71.487792 -374.019826) (xy 71.493602 -374.01269)
			(xy 71.500109 -373.995492) (xy 71.500492 -373.986298) (xy 71.500492 -373.828818) (xy 71.50104 -373.818698)
			(xy 71.508753 -373.799987) (xy 71.52302 -373.785631) (xy 71.541684 -373.777803) (xy 71.5518 -373.777256)
			(xy 72.26808 -373.777256) (xy 72.278227 -373.777737) (xy 72.296971 -373.785518) (xy 72.311293 -373.799896)
			(xy 72.319002 -373.818669) (xy 72.319388 -373.828818) (xy 72.319388 -373.986298) (xy 72.319802 -373.995485)
			(xy 72.326313 -374.012669) (xy 72.332088 -374.019826) (xy 72.353911 -374.045525) (xy 72.392002 -374.101154)
			(xy 72.423155 -374.160946) (xy 72.446922 -374.224038) (xy 72.462961 -374.289523) (xy 72.47104 -374.356458)
			(xy 72.471044 -374.423823) (xy 75.749081 -374.423823) (xy 75.749084 -374.356514) (xy 75.757133 -374.289688)
			(xy 75.773112 -374.224303) (xy 75.796791 -374.161296) (xy 75.827832 -374.101572) (xy 75.865788 -374.045985)
			(xy 75.88758 -374.020334) (xy 75.893385 -374.013194) (xy 75.899895 -373.996) (xy 75.90028 -373.986806)
			(xy 75.90028 -373.828818) (xy 75.900679 -373.818642) (xy 75.908466 -373.79984) (xy 75.92286 -373.785453)
			(xy 75.941666 -373.777675) (xy 75.951842 -373.777256) (xy 76.668122 -373.777256) (xy 76.678283 -373.777716)
			(xy 76.697057 -373.785501) (xy 76.711422 -373.799877) (xy 76.719192 -373.818656) (xy 76.719684 -373.828818)
			(xy 76.719684 -373.986806) (xy 76.720095 -373.995993) (xy 76.726608 -374.013177) (xy 76.732384 -374.020334)
			(xy 76.754129 -374.046021) (xy 76.792078 -374.101603) (xy 76.823112 -374.161322) (xy 76.846786 -374.224322)
			(xy 76.862761 -374.289699) (xy 76.870808 -374.356518) (xy 76.870812 -374.423819) (xy 76.870804 -374.423882)
			(xy 80.148873 -374.423882) (xy 80.148877 -374.356455) (xy 80.156957 -374.289515) (xy 80.172996 -374.224023)
			(xy 80.196764 -374.160925) (xy 80.227918 -374.101127) (xy 80.26601 -374.045492) (xy 80.287876 -374.019826)
			(xy 80.293684 -374.012689) (xy 80.300193 -373.995492) (xy 80.300576 -373.986298) (xy 80.300576 -373.828818)
			(xy 80.301042 -373.818688) (xy 80.308771 -373.79996) (xy 80.323064 -373.785602) (xy 80.341756 -373.777789)
			(xy 80.351884 -373.777256) (xy 81.068164 -373.777256) (xy 81.078265 -373.777814) (xy 81.096934 -373.785531)
			(xy 81.111228 -373.799806) (xy 81.118972 -373.818464) (xy 81.119472 -373.828564) (xy 81.119472 -373.986298)
			(xy 81.119889 -373.995484) (xy 81.126399 -374.012668) (xy 81.132172 -374.019826) (xy 81.153996 -374.045525)
			(xy 81.192087 -374.101154) (xy 81.223242 -374.160945) (xy 81.247009 -374.224038) (xy 81.263049 -374.289523)
			(xy 81.271128 -374.356458) (xy 81.271132 -374.423879) (xy 81.271132 -374.423882) (xy 84.548664 -374.423882)
			(xy 84.548668 -374.356455) (xy 84.556748 -374.289515) (xy 84.572787 -374.224024) (xy 84.596554 -374.160925)
			(xy 84.627707 -374.101128) (xy 84.665799 -374.045492) (xy 84.687664 -374.019826) (xy 84.693482 -374.012697)
			(xy 84.699982 -373.995494) (xy 84.700364 -373.986298) (xy 84.700364 -373.828818) (xy 84.700842 -373.818689)
			(xy 84.708568 -373.799964) (xy 84.722858 -373.785606) (xy 84.741546 -373.777791) (xy 84.751672 -373.777256)
			(xy 85.467952 -373.777256) (xy 85.478066 -373.777754) (xy 85.49676 -373.785478) (xy 85.511074 -373.799769)
			(xy 85.518829 -373.818451) (xy 85.51926 -373.828564) (xy 85.51926 -373.986298) (xy 85.51968 -373.995484)
			(xy 85.526188 -374.012668) (xy 85.53196 -374.019826) (xy 85.553784 -374.045525) (xy 85.591877 -374.101153)
			(xy 85.623031 -374.160945) (xy 85.6468 -374.224037) (xy 85.662839 -374.289523) (xy 85.670919 -374.356458)
			(xy 85.670923 -374.423822) (xy 115.349223 -374.423822) (xy 115.349227 -374.356515) (xy 115.357275 -374.28969)
			(xy 115.373251 -374.224306) (xy 115.396927 -374.1613) (xy 115.427963 -374.101574) (xy 115.465915 -374.045987)
			(xy 115.487704 -374.020334) (xy 115.493512 -374.013197) (xy 115.50002 -373.996) (xy 115.500404 -373.986806)
			(xy 115.500404 -373.828818) (xy 115.500947 -373.818666) (xy 115.508709 -373.799903) (xy 115.52306 -373.785539)
			(xy 115.541814 -373.777757) (xy 115.551966 -373.777256) (xy 116.268246 -373.777256) (xy 116.278409 -373.777696)
			(xy 116.297183 -373.785489) (xy 116.311547 -373.799871) (xy 116.319316 -373.818654) (xy 116.319808 -373.828818)
			(xy 116.319808 -373.986806) (xy 116.320214 -373.995994) (xy 116.32673 -374.013178) (xy 116.332508 -374.020334)
			(xy 116.354256 -374.046019) (xy 116.39221 -374.1016) (xy 116.423248 -374.161318) (xy 116.446925 -374.224319)
			(xy 116.462903 -374.289697) (xy 116.470951 -374.356517) (xy 116.470955 -374.42382) (xy 116.470948 -374.423882)
			(xy 119.748992 -374.423882) (xy 119.748995 -374.356455) (xy 119.757075 -374.289514) (xy 119.773115 -374.224022)
			(xy 119.796884 -374.160924) (xy 119.82804 -374.101126) (xy 119.866134 -374.045491) (xy 119.888 -374.019826)
			(xy 119.89381 -374.012691) (xy 119.900317 -373.995493) (xy 119.9007 -373.986298) (xy 119.9007 -373.828818)
			(xy 119.90124 -373.818697) (xy 119.908955 -373.799984) (xy 119.923224 -373.785629) (xy 119.94189 -373.777802)
			(xy 119.952008 -373.777256) (xy 120.668288 -373.777256) (xy 120.678436 -373.777731) (xy 120.69718 -373.785514)
			(xy 120.711502 -373.799894) (xy 120.71921 -373.818669) (xy 120.719596 -373.828818) (xy 120.719596 -373.986298)
			(xy 120.720008 -373.995485) (xy 120.726521 -374.012669) (xy 120.732296 -374.019826) (xy 120.754119 -374.045525)
			(xy 120.792209 -374.101155) (xy 120.823362 -374.160946) (xy 120.847129 -374.224039) (xy 120.863167 -374.289524)
			(xy 120.871246 -374.356458) (xy 120.87125 -374.423823) (xy 124.149287 -374.423823) (xy 124.149291 -374.356514)
			(xy 124.15734 -374.289688) (xy 124.173319 -374.224302) (xy 124.196998 -374.161296) (xy 124.228039 -374.101572)
			(xy 124.265996 -374.045986) (xy 124.287788 -374.020334) (xy 124.293594 -374.013195) (xy 124.300103 -373.996)
			(xy 124.300488 -373.986806) (xy 124.300488 -373.828818) (xy 124.30088 -373.818641) (xy 124.308668 -373.799837)
			(xy 124.323064 -373.78545) (xy 124.341873 -373.777673) (xy 124.35205 -373.777256) (xy 125.06833 -373.777256)
			(xy 125.078492 -373.777709) (xy 125.097265 -373.785497) (xy 125.11163 -373.799875) (xy 125.1194 -373.818656)
			(xy 125.119892 -373.828818) (xy 125.119892 -373.986806) (xy 125.120301 -373.995993) (xy 125.126816 -374.013177)
			(xy 125.132592 -374.020334) (xy 125.154338 -374.04602) (xy 125.192286 -374.101603) (xy 125.223319 -374.161322)
			(xy 125.246993 -374.224322) (xy 125.262968 -374.2897) (xy 125.271015 -374.356518) (xy 125.271019 -374.423819)
			(xy 125.271019 -374.423823) (xy 128.549078 -374.423823) (xy 128.549081 -374.356514) (xy 128.55713 -374.289688)
			(xy 128.573109 -374.224303) (xy 128.596788 -374.161296) (xy 128.627828 -374.101572) (xy 128.665784 -374.045985)
			(xy 128.687576 -374.020334) (xy 128.69338 -374.013194) (xy 128.699891 -373.996) (xy 128.700276 -373.986806)
			(xy 128.700276 -373.828818) (xy 128.700679 -373.818643) (xy 128.708465 -373.799841) (xy 128.722858 -373.785454)
			(xy 128.741663 -373.777675) (xy 128.751838 -373.777256) (xy 129.468118 -373.777256) (xy 129.478279 -373.777719)
			(xy 129.497052 -373.785503) (xy 129.511418 -373.799878) (xy 129.519188 -373.818656) (xy 129.51968 -373.828818)
			(xy 129.51968 -373.986806) (xy 129.520092 -373.995993) (xy 129.526605 -374.013177) (xy 129.53238 -374.020334)
			(xy 129.554126 -374.046021) (xy 129.592074 -374.101603) (xy 129.623108 -374.161322) (xy 129.646783 -374.224321)
			(xy 129.662758 -374.289699) (xy 129.670805 -374.356518) (xy 129.670809 -374.423819) (xy 129.670809 -374.423822)
			(xy 159.349132 -374.423822) (xy 159.349136 -374.356514) (xy 159.357184 -374.289689) (xy 159.373161 -374.224305)
			(xy 159.396837 -374.161299) (xy 159.427874 -374.101574) (xy 159.465826 -374.045986) (xy 159.487616 -374.020334)
			(xy 159.493425 -374.013198) (xy 159.499932 -373.996) (xy 159.500316 -373.986806) (xy 159.500316 -373.828818)
			(xy 159.500847 -373.818664) (xy 159.508612 -373.799899) (xy 159.522966 -373.785534) (xy 159.541724 -373.777755)
			(xy 159.551878 -373.777256) (xy 160.268158 -373.777256) (xy 160.278329 -373.777699) (xy 160.297126 -373.785473)
			(xy 160.311513 -373.799854) (xy 160.319297 -373.818647) (xy 160.31972 -373.828818) (xy 160.31972 -373.986806)
			(xy 160.320123 -373.995994) (xy 160.326641 -374.013179) (xy 160.33242 -374.020334) (xy 160.354168 -374.04602)
			(xy 160.39212 -374.1016) (xy 160.423158 -374.161319) (xy 160.446835 -374.224319) (xy 160.462812 -374.289698)
			(xy 160.47086 -374.356517) (xy 160.470864 -374.42382) (xy 160.470857 -374.423882) (xy 163.748901 -374.423882)
			(xy 163.748904 -374.356455) (xy 163.756985 -374.289514) (xy 163.773025 -374.224022) (xy 163.796794 -374.160923)
			(xy 163.827951 -374.101126) (xy 163.866045 -374.045491) (xy 163.887912 -374.019826) (xy 163.893724 -374.012692)
			(xy 163.900229 -373.995493) (xy 163.900612 -373.986298) (xy 163.900612 -373.828818) (xy 163.90114 -373.818696)
			(xy 163.908857 -373.79998) (xy 163.92313 -373.785624) (xy 163.941801 -373.7778) (xy 163.95192 -373.777256)
			(xy 164.6682 -373.777256) (xy 164.678349 -373.777721) (xy 164.697092 -373.785508) (xy 164.711414 -373.799891)
			(xy 164.719122 -373.818668) (xy 164.719508 -373.828818) (xy 164.719508 -373.986298) (xy 164.719917 -373.995485)
			(xy 164.726431 -374.01267) (xy 164.732208 -374.019826) (xy 164.75403 -374.045525) (xy 164.79212 -374.101155)
			(xy 164.823272 -374.160947) (xy 164.847038 -374.224039) (xy 164.863076 -374.289524) (xy 164.871155 -374.356458)
			(xy 164.871159 -374.423822) (xy 168.14922 -374.423822) (xy 168.149224 -374.356515) (xy 168.157272 -374.28969)
			(xy 168.173248 -374.224306) (xy 168.196924 -374.1613) (xy 168.22796 -374.101575) (xy 168.265911 -374.045987)
			(xy 168.2877 -374.020334) (xy 168.293507 -374.013196) (xy 168.300015 -373.996) (xy 168.3004 -373.986806)
			(xy 168.3004 -373.828818) (xy 168.300947 -373.818666) (xy 168.308709 -373.799905) (xy 168.323058 -373.78554)
			(xy 168.341811 -373.777758) (xy 168.351962 -373.777256) (xy 169.068242 -373.777256) (xy 169.078405 -373.777699)
			(xy 169.097178 -373.785491) (xy 169.111543 -373.799872) (xy 169.119312 -373.818655) (xy 169.119804 -373.828818)
			(xy 169.119804 -373.986806) (xy 169.120211 -373.995994) (xy 169.126727 -374.013178) (xy 169.132504 -374.020334)
			(xy 169.154249 -374.046021) (xy 169.192196 -374.101603) (xy 169.223229 -374.161322) (xy 169.246902 -374.224322)
			(xy 169.262877 -374.2897) (xy 169.270924 -374.356518) (xy 169.270928 -374.423819) (xy 169.270928 -374.423823)
			(xy 172.548987 -374.423823) (xy 172.548991 -374.356514) (xy 172.55704 -374.289688) (xy 172.573019 -374.224302)
			(xy 172.596698 -374.161296) (xy 172.627739 -374.101572) (xy 172.665696 -374.045986) (xy 172.687488 -374.020334)
			(xy 172.693294 -374.013195) (xy 172.699803 -373.996) (xy 172.700188 -373.986806) (xy 172.700188 -373.828818)
			(xy 172.70058 -373.818641) (xy 172.708368 -373.799837) (xy 172.722764 -373.78545) (xy 172.741573 -373.777673)
			(xy 172.75175 -373.777256) (xy 173.46803 -373.777256) (xy 173.478192 -373.777709) (xy 173.496965 -373.785497)
			(xy 173.51133 -373.799875) (xy 173.5191 -373.818656) (xy 173.519592 -373.828818) (xy 173.519592 -373.986806)
			(xy 173.520001 -373.995993) (xy 173.526516 -374.013177) (xy 173.532292 -374.020334) (xy 173.554038 -374.04602)
			(xy 173.591986 -374.101603) (xy 173.623019 -374.161322) (xy 173.646693 -374.224322) (xy 173.662668 -374.2897)
			(xy 173.670715 -374.356518) (xy 173.670719 -374.423819) (xy 173.662679 -374.490638) (xy 173.646712 -374.556018)
			(xy 173.623045 -374.61902) (xy 173.592018 -374.678743) (xy 173.554076 -374.73433) (xy 173.532292 -374.759982)
			(xy 173.526477 -374.767114) (xy 173.519974 -374.784315) (xy 173.519592 -374.79351) (xy 173.519592 -375.286778)
			(xy 173.520015 -375.295964) (xy 173.52652 -375.313148) (xy 173.532292 -375.320306) (xy 173.554108 -375.345934)
			(xy 173.592054 -375.401525) (xy 173.623084 -375.461252) (xy 173.646754 -375.52426) (xy 173.662724 -375.589644)
			(xy 173.670765 -375.656469) (xy 173.670763 -375.723776) (xy 173.662716 -375.7906) (xy 173.646741 -375.855984)
			(xy 173.623066 -375.918989) (xy 173.592031 -375.978714) (xy 173.554081 -376.034301) (xy 173.532292 -376.059954)
			(xy 173.526489 -376.067095) (xy 173.519978 -376.084289) (xy 173.519592 -376.093482) (xy 173.519592 -376.25147)
			(xy 173.519043 -376.261622) (xy 173.511284 -376.280385) (xy 173.496935 -376.29475) (xy 173.478182 -376.302531)
			(xy 173.46803 -376.303032) (xy 172.75175 -376.303032) (xy 172.741578 -376.302595) (xy 172.722779 -376.29482)
			(xy 172.708391 -376.280438) (xy 172.700609 -376.261642) (xy 172.700188 -376.25147) (xy 172.700188 -376.093482)
			(xy 172.699789 -376.084294) (xy 172.693268 -376.067109) (xy 172.687488 -376.059954) (xy 172.665728 -376.034278)
			(xy 172.627775 -375.978696) (xy 172.596738 -375.918976) (xy 172.573061 -375.855975) (xy 172.557085 -375.790595)
			(xy 172.549038 -375.723774) (xy 172.549035 -375.656471) (xy 172.557077 -375.589649) (xy 172.573048 -375.524268)
			(xy 172.59672 -375.461265) (xy 172.627752 -375.401542) (xy 172.665701 -375.345957) (xy 172.687488 -375.320306)
			(xy 172.693263 -375.313145) (xy 172.699791 -375.295967) (xy 172.700188 -375.286778) (xy 172.700188 -374.79351)
			(xy 172.699776 -374.784323) (xy 172.693264 -374.767138) (xy 172.687488 -374.759982) (xy 172.665658 -374.734364)
			(xy 172.627707 -374.678774) (xy 172.596673 -374.619046) (xy 172.573 -374.556037) (xy 172.557029 -374.49065)
			(xy 172.548987 -374.423823) (xy 169.270928 -374.423823) (xy 169.262888 -374.490638) (xy 169.246921 -374.556017)
			(xy 169.223255 -374.61902) (xy 169.192229 -374.678743) (xy 169.154288 -374.734329) (xy 169.132504 -374.759982)
			(xy 169.126691 -374.767115) (xy 169.120186 -374.784315) (xy 169.119804 -374.79351) (xy 169.119804 -375.286778)
			(xy 169.120224 -375.295964) (xy 169.126731 -375.313149) (xy 169.132504 -375.320306) (xy 169.15432 -375.345935)
			(xy 169.192265 -375.401525) (xy 169.223295 -375.461253) (xy 169.246964 -375.52426) (xy 169.262933 -375.589645)
			(xy 169.270974 -375.656469) (xy 169.270972 -375.723776) (xy 169.262925 -375.7906) (xy 169.24695 -375.855983)
			(xy 169.223276 -375.918989) (xy 169.192242 -375.978713) (xy 169.154292 -376.034301) (xy 169.132504 -376.059954)
			(xy 169.126702 -376.067096) (xy 169.120191 -376.084289) (xy 169.119804 -376.093482) (xy 169.119804 -376.25147)
			(xy 169.119243 -376.261621) (xy 169.111487 -376.280381) (xy 169.097142 -376.294746) (xy 169.078392 -376.302529)
			(xy 169.068242 -376.303032) (xy 168.351962 -376.303032) (xy 168.341798 -376.302597) (xy 168.323022 -376.294804)
			(xy 168.308657 -376.280421) (xy 168.30089 -376.261635) (xy 168.3004 -376.25147) (xy 168.3004 -376.093482)
			(xy 168.299998 -376.084294) (xy 168.293479 -376.06711) (xy 168.2877 -376.059954) (xy 168.265943 -376.034277)
			(xy 168.227996 -375.978693) (xy 168.196963 -375.918973) (xy 168.173291 -375.855972) (xy 168.157317 -375.790593)
			(xy 168.149271 -375.723774) (xy 168.149268 -375.656472) (xy 168.157309 -375.589652) (xy 168.173277 -375.524272)
			(xy 168.196945 -375.461269) (xy 168.227973 -375.401546) (xy 168.265915 -375.345959) (xy 168.2877 -375.320306)
			(xy 168.293477 -375.313147) (xy 168.300003 -375.295967) (xy 168.3004 -375.286778) (xy 168.3004 -374.79351)
			(xy 168.299985 -374.784323) (xy 168.293475 -374.767139) (xy 168.2877 -374.759982) (xy 168.265872 -374.734363)
			(xy 168.227927 -374.678771) (xy 168.196898 -374.619043) (xy 168.173229 -374.556034) (xy 168.15726 -374.490648)
			(xy 168.14922 -374.423822) (xy 164.871159 -374.423822) (xy 164.871159 -374.423879) (xy 164.863088 -374.490814)
			(xy 164.847057 -374.5563) (xy 164.823298 -374.619396) (xy 164.792152 -374.679191) (xy 164.754069 -374.734825)
			(xy 164.732208 -374.76049) (xy 164.726392 -374.767621) (xy 164.719889 -374.784822) (xy 164.719508 -374.794018)
			(xy 164.719508 -375.28627) (xy 164.719931 -375.295456) (xy 164.726435 -375.31264) (xy 164.732208 -375.319798)
			(xy 164.754101 -375.345439) (xy 164.792188 -375.401077) (xy 164.823337 -375.460877) (xy 164.8471 -375.523977)
			(xy 164.863133 -375.589469) (xy 164.871206 -375.65641) (xy 164.871203 -375.723835) (xy 164.863125 -375.790776)
			(xy 164.847086 -375.856266) (xy 164.823319 -375.919364) (xy 164.792165 -375.979161) (xy 164.754073 -376.034797)
			(xy 164.732208 -376.060462) (xy 164.726404 -376.067602) (xy 164.719893 -376.084796) (xy 164.719508 -376.09399)
			(xy 164.719508 -376.25147) (xy 164.71895 -376.261589) (xy 164.711241 -376.2803) (xy 164.696977 -376.294656)
			(xy 164.678316 -376.302485) (xy 164.6682 -376.303032) (xy 163.95192 -376.303032) (xy 163.941771 -376.302563)
			(xy 163.923025 -376.29478) (xy 163.908702 -376.280398) (xy 163.900996 -376.26162) (xy 163.900612 -376.25147)
			(xy 163.900612 -376.09399) (xy 163.900204 -376.084803) (xy 163.893689 -376.067618) (xy 163.887912 -376.060462)
			(xy 163.866077 -376.034773) (xy 163.827987 -375.979142) (xy 163.796834 -375.919349) (xy 163.773068 -375.856255)
			(xy 163.75703 -375.790769) (xy 163.748951 -375.723833) (xy 163.748949 -375.656412) (xy 163.757022 -375.589475)
			(xy 163.773054 -375.523988) (xy 163.796816 -375.460892) (xy 163.827963 -375.401097) (xy 163.866049 -375.345463)
			(xy 163.887912 -375.319798) (xy 163.893693 -375.312642) (xy 163.900217 -375.29546) (xy 163.900612 -375.28627)
			(xy 163.900612 -374.794018) (xy 163.90019 -374.784832) (xy 163.893684 -374.767648) (xy 163.887912 -374.76049)
			(xy 163.866006 -374.734859) (xy 163.827918 -374.67922) (xy 163.796769 -374.619419) (xy 163.773006 -374.556318)
			(xy 163.756973 -374.490824) (xy 163.748901 -374.423882) (xy 160.470857 -374.423882) (xy 160.462823 -374.49064)
			(xy 160.446853 -374.556021) (xy 160.423184 -374.619023) (xy 160.392153 -374.678745) (xy 160.354206 -374.73433)
			(xy 160.33242 -374.759982) (xy 160.326608 -374.767117) (xy 160.320102 -374.784315) (xy 160.31972 -374.79351)
			(xy 160.31972 -375.286778) (xy 160.320136 -375.295965) (xy 160.326645 -375.313149) (xy 160.33242 -375.320306)
			(xy 160.354238 -375.345933) (xy 160.392189 -375.401522) (xy 160.423223 -375.461249) (xy 160.446896 -375.524257)
			(xy 160.462868 -375.589643) (xy 160.470911 -375.656468) (xy 160.470908 -375.723777) (xy 160.46286 -375.790602)
			(xy 160.446883 -375.855986) (xy 160.423205 -375.918992) (xy 160.392166 -375.978716) (xy 160.354211 -376.034302)
			(xy 160.33242 -376.059954) (xy 160.32662 -376.067097) (xy 160.320107 -376.084289) (xy 160.31972 -376.093482)
			(xy 160.31972 -376.25147) (xy 160.31931 -376.261645) (xy 160.311528 -376.280447) (xy 160.297137 -376.294834)
			(xy 160.278333 -376.302613) (xy 160.268158 -376.303032) (xy 159.551878 -376.303032) (xy 159.541701 -376.302653)
			(xy 159.5229 -376.294855) (xy 159.508515 -376.280456) (xy 159.500737 -376.261647) (xy 159.500316 -376.25147)
			(xy 159.500316 -376.093482) (xy 159.499911 -376.084294) (xy 159.493393 -376.06711) (xy 159.487616 -376.059954)
			(xy 159.465858 -376.034277) (xy 159.42791 -375.978694) (xy 159.396877 -375.918973) (xy 159.373203 -375.855972)
			(xy 159.357229 -375.790593) (xy 159.349183 -375.723774) (xy 159.34918 -375.656471) (xy 159.357221 -375.589651)
			(xy 159.37319 -375.524271) (xy 159.396858 -375.461268) (xy 159.427887 -375.401545) (xy 159.465831 -375.345958)
			(xy 159.487616 -375.320306) (xy 159.493394 -375.313148) (xy 159.499919 -375.295967) (xy 159.500316 -375.286778)
			(xy 159.500316 -374.79351) (xy 159.499897 -374.784324) (xy 159.493389 -374.76714) (xy 159.487616 -374.759982)
			(xy 159.465788 -374.734364) (xy 159.427842 -374.678772) (xy 159.396811 -374.619043) (xy 159.373142 -374.556034)
			(xy 159.357173 -374.490648) (xy 159.349132 -374.423822) (xy 129.670809 -374.423822) (xy 129.662769 -374.490638)
			(xy 129.646801 -374.556018) (xy 129.623134 -374.619021) (xy 129.592107 -374.678743) (xy 129.554164 -374.734329)
			(xy 129.53238 -374.759982) (xy 129.526564 -374.767113) (xy 129.520062 -374.784315) (xy 129.51968 -374.79351)
			(xy 129.51968 -375.286778) (xy 129.520105 -375.295963) (xy 129.526609 -375.313148) (xy 129.53238 -375.320306)
			(xy 129.554197 -375.345934) (xy 129.592143 -375.401524) (xy 129.623174 -375.461252) (xy 129.646845 -375.524259)
			(xy 129.662815 -375.589644) (xy 129.670856 -375.656469) (xy 129.670854 -375.723776) (xy 129.662807 -375.7906)
			(xy 129.646831 -375.855984) (xy 129.623156 -375.91899) (xy 129.59212 -375.978714) (xy 129.554169 -376.034302)
			(xy 129.53238 -376.059954) (xy 129.526576 -376.067094) (xy 129.520066 -376.084288) (xy 129.51968 -376.093482)
			(xy 129.51968 -376.25147) (xy 129.519212 -376.261637) (xy 129.51144 -376.280428) (xy 129.497068 -376.294813)
			(xy 129.478285 -376.302602) (xy 129.468118 -376.303032) (xy 128.751838 -376.303032) (xy 128.741665 -376.302604)
			(xy 128.722866 -376.294826) (xy 128.708478 -376.280441) (xy 128.700697 -376.261643) (xy 128.700276 -376.25147)
			(xy 128.700276 -376.093482) (xy 128.69988 -376.084293) (xy 128.693357 -376.067109) (xy 128.687576 -376.059954)
			(xy 128.665817 -376.034278) (xy 128.627865 -375.978696) (xy 128.596828 -375.918976) (xy 128.573152 -375.855974)
			(xy 128.557176 -375.790595) (xy 128.549129 -375.723774) (xy 128.549126 -375.656471) (xy 128.557168 -375.58965)
			(xy 128.573138 -375.524269) (xy 128.59681 -375.461265) (xy 128.627841 -375.401543) (xy 128.665789 -375.345958)
			(xy 128.687576 -375.320306) (xy 128.69335 -375.313144) (xy 128.699879 -375.295967) (xy 128.700276 -375.286778)
			(xy 128.700276 -374.79351) (xy 128.699866 -374.784323) (xy 128.693353 -374.767138) (xy 128.687576 -374.759982)
			(xy 128.665746 -374.734365) (xy 128.627796 -374.678774) (xy 128.596762 -374.619046) (xy 128.57309 -374.556037)
			(xy 128.557119 -374.49065) (xy 128.549078 -374.423823) (xy 125.271019 -374.423823) (xy 125.262979 -374.490638)
			(xy 125.247012 -374.556018) (xy 125.223345 -374.61902) (xy 125.192318 -374.678743) (xy 125.154376 -374.73433)
			(xy 125.132592 -374.759982) (xy 125.126777 -374.767114) (xy 125.120274 -374.784315) (xy 125.119892 -374.79351)
			(xy 125.119892 -375.286778) (xy 125.120315 -375.295964) (xy 125.12682 -375.313148) (xy 125.132592 -375.320306)
			(xy 125.154408 -375.345934) (xy 125.192354 -375.401525) (xy 125.223384 -375.461252) (xy 125.247054 -375.52426)
			(xy 125.263024 -375.589644) (xy 125.271065 -375.656469) (xy 125.271063 -375.723776) (xy 125.263016 -375.7906)
			(xy 125.247041 -375.855984) (xy 125.223366 -375.918989) (xy 125.192331 -375.978714) (xy 125.154381 -376.034301)
			(xy 125.132592 -376.059954) (xy 125.126789 -376.067095) (xy 125.120278 -376.084289) (xy 125.119892 -376.093482)
			(xy 125.119892 -376.25147) (xy 125.119343 -376.261622) (xy 125.111584 -376.280385) (xy 125.097235 -376.29475)
			(xy 125.078482 -376.302531) (xy 125.06833 -376.303032) (xy 124.35205 -376.303032) (xy 124.341878 -376.302595)
			(xy 124.323079 -376.29482) (xy 124.308691 -376.280438) (xy 124.300909 -376.261642) (xy 124.300488 -376.25147)
			(xy 124.300488 -376.093482) (xy 124.300089 -376.084294) (xy 124.293568 -376.067109) (xy 124.287788 -376.059954)
			(xy 124.266028 -376.034278) (xy 124.228075 -375.978696) (xy 124.197038 -375.918976) (xy 124.173361 -375.855975)
			(xy 124.157385 -375.790595) (xy 124.149338 -375.723774) (xy 124.149335 -375.656471) (xy 124.157377 -375.589649)
			(xy 124.173348 -375.524268) (xy 124.19702 -375.461265) (xy 124.228052 -375.401542) (xy 124.266001 -375.345957)
			(xy 124.287788 -375.320306) (xy 124.293563 -375.313145) (xy 124.300091 -375.295967) (xy 124.300488 -375.286778)
			(xy 124.300488 -374.79351) (xy 124.300076 -374.784323) (xy 124.293564 -374.767138) (xy 124.287788 -374.759982)
			(xy 124.265958 -374.734364) (xy 124.228007 -374.678774) (xy 124.196973 -374.619046) (xy 124.1733 -374.556037)
			(xy 124.157329 -374.49065) (xy 124.149287 -374.423823) (xy 120.87125 -374.423823) (xy 120.87125 -374.423879)
			(xy 120.863178 -374.490814) (xy 120.847147 -374.556301) (xy 120.823388 -374.619396) (xy 120.792242 -374.679191)
			(xy 120.754158 -374.734825) (xy 120.732296 -374.76049) (xy 120.726478 -374.76762) (xy 120.719976 -374.784822)
			(xy 120.719596 -374.794018) (xy 120.719596 -375.28627) (xy 120.720022 -375.295456) (xy 120.726525 -375.31264)
			(xy 120.732296 -375.319798) (xy 120.75419 -375.345439) (xy 120.792278 -375.401077) (xy 120.823427 -375.460876)
			(xy 120.84719 -375.523976) (xy 120.863223 -375.589468) (xy 120.871297 -375.656409) (xy 120.871294 -375.723836)
			(xy 120.863215 -375.790776) (xy 120.847177 -375.856267) (xy 120.823409 -375.919365) (xy 120.792254 -375.979162)
			(xy 120.754162 -376.034797) (xy 120.732296 -376.060462) (xy 120.72649 -376.067601) (xy 120.719981 -376.084796)
			(xy 120.719596 -376.09399) (xy 120.719596 -376.25147) (xy 120.71905 -376.26159) (xy 120.711339 -376.280304)
			(xy 120.697071 -376.29466) (xy 120.678405 -376.302487) (xy 120.668288 -376.303032) (xy 119.952008 -376.303032)
			(xy 119.941858 -376.302572) (xy 119.923112 -376.294786) (xy 119.90879 -376.280401) (xy 119.901084 -376.261621)
			(xy 119.9007 -376.25147) (xy 119.9007 -376.09399) (xy 119.900294 -376.084802) (xy 119.893777 -376.067618)
			(xy 119.888 -376.060462) (xy 119.866166 -376.034772) (xy 119.828076 -375.979141) (xy 119.796924 -375.919349)
			(xy 119.773158 -375.856255) (xy 119.75712 -375.790769) (xy 119.749042 -375.723833) (xy 119.749039 -375.656412)
			(xy 119.757112 -375.589476) (xy 119.773145 -375.523988) (xy 119.796905 -375.460893) (xy 119.828053 -375.401097)
			(xy 119.866138 -375.345463) (xy 119.888 -375.319798) (xy 119.89378 -375.312641) (xy 119.900305 -375.29546)
			(xy 119.9007 -375.28627) (xy 119.9007 -374.794018) (xy 119.900281 -374.784832) (xy 119.893773 -374.767647)
			(xy 119.888 -374.76049) (xy 119.866095 -374.734859) (xy 119.828007 -374.679219) (xy 119.796858 -374.619418)
			(xy 119.773097 -374.556317) (xy 119.757064 -374.490824) (xy 119.748992 -374.423882) (xy 116.470948 -374.423882)
			(xy 116.462914 -374.49064) (xy 116.446944 -374.556021) (xy 116.423273 -374.619024) (xy 116.392242 -374.678746)
			(xy 116.354295 -374.734331) (xy 116.332508 -374.759982) (xy 116.326695 -374.767116) (xy 116.32019 -374.784315)
			(xy 116.319808 -374.79351) (xy 116.319808 -375.286778) (xy 116.320227 -375.295964) (xy 116.326734 -375.313149)
			(xy 116.332508 -375.320306) (xy 116.354327 -375.345933) (xy 116.392278 -375.401522) (xy 116.423313 -375.461249)
			(xy 116.446986 -375.524256) (xy 116.462959 -375.589642) (xy 116.471001 -375.656468) (xy 116.470999 -375.723777)
			(xy 116.462951 -375.790602) (xy 116.446973 -375.855987) (xy 116.423295 -375.918993) (xy 116.392255 -375.978717)
			(xy 116.354299 -376.034303) (xy 116.332508 -376.059954) (xy 116.326707 -376.067096) (xy 116.320195 -376.084289)
			(xy 116.319808 -376.093482) (xy 116.319808 -376.25147) (xy 116.319243 -376.26162) (xy 116.311487 -376.28038)
			(xy 116.297144 -376.294745) (xy 116.278395 -376.302528) (xy 116.268246 -376.303032) (xy 115.551966 -376.303032)
			(xy 115.541802 -376.302594) (xy 115.523027 -376.294803) (xy 115.508662 -376.28042) (xy 115.500894 -376.261634)
			(xy 115.500404 -376.25147) (xy 115.500404 -376.093482) (xy 115.500002 -376.084294) (xy 115.493483 -376.06711)
			(xy 115.487704 -376.059954) (xy 115.465947 -376.034277) (xy 115.427999 -375.978693) (xy 115.396967 -375.918973)
			(xy 115.373294 -375.855972) (xy 115.35732 -375.790593) (xy 115.349274 -375.723774) (xy 115.349271 -375.656472)
			(xy 115.357312 -375.589652) (xy 115.37328 -375.524271) (xy 115.396948 -375.461268) (xy 115.427976 -375.401545)
			(xy 115.465919 -375.345959) (xy 115.487704 -375.320306) (xy 115.493481 -375.313147) (xy 115.500007 -375.295967)
			(xy 115.500404 -375.286778) (xy 115.500404 -374.79351) (xy 115.499988 -374.784323) (xy 115.493478 -374.767139)
			(xy 115.487704 -374.759982) (xy 115.465876 -374.734363) (xy 115.427931 -374.678771) (xy 115.396901 -374.619043)
			(xy 115.373232 -374.556034) (xy 115.357263 -374.490648) (xy 115.349223 -374.423822) (xy 85.670923 -374.423822)
			(xy 85.670923 -374.423879) (xy 85.662851 -374.490815) (xy 85.646818 -374.556302) (xy 85.623057 -374.619398)
			(xy 85.591909 -374.679192) (xy 85.553823 -374.734826) (xy 85.53196 -374.76049) (xy 85.526138 -374.767617)
			(xy 85.519639 -374.784822) (xy 85.51926 -374.794018) (xy 85.51926 -375.28627) (xy 85.519694 -375.295454)
			(xy 85.526192 -375.312639) (xy 85.53196 -375.319798) (xy 85.553855 -375.345438) (xy 85.591945 -375.401075)
			(xy 85.623097 -375.460875) (xy 85.646861 -375.523975) (xy 85.662896 -375.589467) (xy 85.67097 -375.656409)
			(xy 85.670967 -375.723836) (xy 85.662888 -375.790777) (xy 85.646848 -375.856268) (xy 85.623079 -375.919367)
			(xy 85.591922 -375.979163) (xy 85.553827 -376.034797) (xy 85.53196 -376.060462) (xy 85.52615 -376.067597)
			(xy 85.519644 -376.084796) (xy 85.51926 -376.09399) (xy 85.51926 -376.25147) (xy 85.518749 -376.261595)
			(xy 85.511031 -376.280315) (xy 85.496752 -376.294673) (xy 85.478074 -376.302493) (xy 85.467952 -376.303032)
			(xy 84.751672 -376.303032) (xy 84.741565 -376.302539) (xy 84.722893 -376.294798) (xy 84.7086 -376.280504)
			(xy 84.700861 -376.261831) (xy 84.700364 -376.251724) (xy 84.700364 -376.09399) (xy 84.699944 -376.084804)
			(xy 84.693436 -376.06762) (xy 84.687664 -376.060462) (xy 84.665831 -376.034772) (xy 84.627744 -375.97914)
			(xy 84.596594 -375.919347) (xy 84.572829 -375.856253) (xy 84.556793 -375.790768) (xy 84.548715 -375.723833)
			(xy 84.548712 -375.656412) (xy 84.556785 -375.589477) (xy 84.572816 -375.52399) (xy 84.596575 -375.460894)
			(xy 84.62772 -375.401099) (xy 84.665803 -375.345464) (xy 84.687664 -375.319798) (xy 84.693452 -375.312647)
			(xy 84.69997 -375.295461) (xy 84.700364 -375.28627) (xy 84.700364 -374.794018) (xy 84.699931 -374.784834)
			(xy 84.693432 -374.76765) (xy 84.687664 -374.76049) (xy 84.66576 -374.734858) (xy 84.627675 -374.679218)
			(xy 84.596528 -374.619417) (xy 84.572768 -374.556316) (xy 84.556736 -374.490823) (xy 84.548664 -374.423882)
			(xy 81.271132 -374.423882) (xy 81.26306 -374.490815) (xy 81.247028 -374.556302) (xy 81.223267 -374.619397)
			(xy 81.19212 -374.679192) (xy 81.154034 -374.734825) (xy 81.132172 -374.76049) (xy 81.126351 -374.767618)
			(xy 81.119852 -374.784822) (xy 81.119472 -374.794018) (xy 81.119472 -375.28627) (xy 81.119903 -375.295455)
			(xy 81.126403 -375.312639) (xy 81.132172 -375.319798) (xy 81.154066 -375.345438) (xy 81.192156 -375.401076)
			(xy 81.223307 -375.460875) (xy 81.247071 -375.523975) (xy 81.263105 -375.589468) (xy 81.271179 -375.656409)
			(xy 81.271176 -375.723836) (xy 81.263097 -375.790777) (xy 81.247057 -375.856268) (xy 81.223289 -375.919366)
			(xy 81.192133 -375.979163) (xy 81.154039 -376.034797) (xy 81.132172 -376.060462) (xy 81.126363 -376.067598)
			(xy 81.119856 -376.084796) (xy 81.119472 -376.09399) (xy 81.119472 -376.25147) (xy 81.118949 -376.261593)
			(xy 81.111234 -376.280312) (xy 81.096958 -376.294669) (xy 81.078284 -376.302491) (xy 81.068164 -376.303032)
			(xy 80.351884 -376.303032) (xy 80.341778 -376.302529) (xy 80.323106 -376.294792) (xy 80.308813 -376.280501)
			(xy 80.301073 -376.26183) (xy 80.300576 -376.251724) (xy 80.300576 -376.09399) (xy 80.300176 -376.084802)
			(xy 80.293656 -376.067617) (xy 80.287876 -376.060462) (xy 80.266042 -376.034772) (xy 80.227954 -375.97914)
			(xy 80.196804 -375.919347) (xy 80.173039 -375.856254) (xy 80.157002 -375.790768) (xy 80.148924 -375.723833)
			(xy 80.148921 -375.656412) (xy 80.156994 -375.589476) (xy 80.173025 -375.523989) (xy 80.196785 -375.460894)
			(xy 80.227931 -375.401098) (xy 80.266015 -375.345464) (xy 80.287876 -375.319798) (xy 80.293653 -375.312639)
			(xy 80.30018 -375.295459) (xy 80.300576 -375.28627) (xy 80.300576 -374.794018) (xy 80.300163 -374.784831)
			(xy 80.293652 -374.767646) (xy 80.287876 -374.76049) (xy 80.265972 -374.734858) (xy 80.227886 -374.679218)
			(xy 80.196738 -374.619417) (xy 80.172977 -374.556316) (xy 80.156946 -374.490823) (xy 80.148873 -374.423882)
			(xy 76.870804 -374.423882) (xy 76.862772 -374.490638) (xy 76.846805 -374.556018) (xy 76.823138 -374.619021)
			(xy 76.79211 -374.678743) (xy 76.754168 -374.734329) (xy 76.732384 -374.759982) (xy 76.726568 -374.767114)
			(xy 76.720066 -374.784315) (xy 76.719684 -374.79351) (xy 76.719684 -375.286778) (xy 76.720108 -375.295964)
			(xy 76.726613 -375.313148) (xy 76.732384 -375.320306) (xy 76.754201 -375.345934) (xy 76.792147 -375.401525)
			(xy 76.823178 -375.461252) (xy 76.846848 -375.524259) (xy 76.862818 -375.589644) (xy 76.870859 -375.656469)
			(xy 76.870857 -375.723776) (xy 76.86281 -375.7906) (xy 76.846834 -375.855984) (xy 76.823159 -375.91899)
			(xy 76.792124 -375.978714) (xy 76.754173 -376.034302) (xy 76.732384 -376.059954) (xy 76.72658 -376.067094)
			(xy 76.72007 -376.084289) (xy 76.719684 -376.093482) (xy 76.719684 -376.25147) (xy 76.719212 -376.261637)
			(xy 76.711441 -376.280427) (xy 76.69707 -376.294812) (xy 76.678288 -376.302602) (xy 76.668122 -376.303032)
			(xy 75.951842 -376.303032) (xy 75.941669 -376.302601) (xy 75.92287 -376.294824) (xy 75.908482 -376.28044)
			(xy 75.900701 -376.261643) (xy 75.90028 -376.25147) (xy 75.90028 -376.093482) (xy 75.899883 -376.084293)
			(xy 75.893361 -376.067109) (xy 75.88758 -376.059954) (xy 75.865821 -376.034278) (xy 75.827868 -375.978696)
			(xy 75.796831 -375.918976) (xy 75.773155 -375.855975) (xy 75.757179 -375.790595) (xy 75.749132 -375.723774)
			(xy 75.749129 -375.656471) (xy 75.757171 -375.58965) (xy 75.773142 -375.524269) (xy 75.796813 -375.461265)
			(xy 75.827845 -375.401543) (xy 75.865793 -375.345958) (xy 75.88758 -375.320306) (xy 75.893354 -375.313145)
			(xy 75.899883 -375.295967) (xy 75.90028 -375.286778) (xy 75.90028 -374.79351) (xy 75.89987 -374.784323)
			(xy 75.893357 -374.767138) (xy 75.88758 -374.759982) (xy 75.865749 -374.734365) (xy 75.827799 -374.678774)
			(xy 75.796765 -374.619046) (xy 75.773093 -374.556037) (xy 75.757122 -374.49065) (xy 75.749081 -374.423823)
			(xy 72.471044 -374.423823) (xy 72.471044 -374.423879) (xy 72.462972 -374.490814) (xy 72.446941 -374.556301)
			(xy 72.423181 -374.619396) (xy 72.392034 -374.679191) (xy 72.35395 -374.734825) (xy 72.332088 -374.76049)
			(xy 72.326269 -374.76762) (xy 72.319768 -374.784822) (xy 72.319388 -374.794018) (xy 72.319388 -375.28627)
			(xy 72.319815 -375.295455) (xy 72.326317 -375.31264) (xy 72.332088 -375.319798) (xy 72.353982 -375.345439)
			(xy 72.39207 -375.401076) (xy 72.423221 -375.460876) (xy 72.446984 -375.523976) (xy 72.463017 -375.589468)
			(xy 72.471091 -375.656409) (xy 72.471088 -375.723836) (xy 72.463009 -375.790776) (xy 72.44697 -375.856267)
			(xy 72.423202 -375.919365) (xy 72.392047 -375.979162) (xy 72.353954 -376.034797) (xy 72.332088 -376.060462)
			(xy 72.326281 -376.0676) (xy 72.319773 -376.084796) (xy 72.319388 -376.09399) (xy 72.319388 -376.25147)
			(xy 72.31885 -376.261591) (xy 72.311137 -376.280307) (xy 72.296867 -376.294663) (xy 72.278198 -376.302488)
			(xy 72.26808 -376.303032) (xy 71.5518 -376.303032) (xy 71.54165 -376.302579) (xy 71.522904 -376.294789)
			(xy 71.508582 -376.280403) (xy 71.500876 -376.261622) (xy 71.500492 -376.25147) (xy 71.500492 -376.09399)
			(xy 71.500088 -376.084802) (xy 71.49357 -376.067618) (xy 71.487792 -376.060462) (xy 71.465958 -376.034772)
			(xy 71.427869 -375.979141) (xy 71.396717 -375.919348) (xy 71.372952 -375.856255) (xy 71.356914 -375.790769)
			(xy 71.348836 -375.723833) (xy 71.348833 -375.656412) (xy 71.356906 -375.589476) (xy 71.372938 -375.523989)
			(xy 71.396699 -375.460893) (xy 71.427845 -375.401098) (xy 71.46593 -375.345463) (xy 71.487792 -375.319798)
			(xy 71.493571 -375.31264) (xy 71.500096 -375.295459) (xy 71.500492 -375.28627) (xy 71.500492 -374.794018)
			(xy 71.500075 -374.784832) (xy 71.493566 -374.767647) (xy 71.487792 -374.76049) (xy 71.465887 -374.734859)
			(xy 71.4278 -374.679219) (xy 71.396652 -374.619418) (xy 71.37289 -374.556317) (xy 71.356858 -374.490824)
			(xy 71.348786 -374.423882) (xy 46.070774 -374.423882) (xy 46.062742 -374.490639) (xy 46.046773 -374.55602)
			(xy 46.023104 -374.619022) (xy 45.992075 -374.678745) (xy 45.95413 -374.73433) (xy 45.932344 -374.759982)
			(xy 45.926523 -374.76711) (xy 45.920025 -374.784314) (xy 45.919644 -374.79351) (xy 45.919644 -375.286778)
			(xy 45.920077 -375.295962) (xy 45.926576 -375.313146) (xy 45.932344 -375.320306) (xy 45.954162 -375.345934)
			(xy 45.992111 -375.401523) (xy 46.023144 -375.46125) (xy 46.046816 -375.524258) (xy 46.062787 -375.589643)
			(xy 46.070829 -375.656469) (xy 46.070826 -375.723776) (xy 46.062779 -375.790601) (xy 46.046802 -375.855985)
			(xy 46.023125 -375.918991) (xy 45.992088 -375.978716) (xy 45.954134 -376.034302) (xy 45.932344 -376.059954)
			(xy 45.926535 -376.06709) (xy 45.920029 -376.084288) (xy 45.919644 -376.093482) (xy 45.919644 -376.25147)
			(xy 45.919211 -376.261642) (xy 45.911433 -376.280439) (xy 45.897049 -376.294826) (xy 45.878254 -376.302609)
			(xy 45.868082 -376.303032) (xy 45.151802 -376.303032) (xy 45.141627 -376.302634) (xy 45.122826 -376.294844)
			(xy 45.10844 -376.28045) (xy 45.100661 -376.261645) (xy 45.10024 -376.25147) (xy 45.10024 -376.093482)
			(xy 45.09983 -376.084295) (xy 45.093315 -376.067111) (xy 45.08754 -376.059954) (xy 45.065782 -376.034277)
			(xy 45.027832 -375.978695) (xy 44.996798 -375.918974) (xy 44.973123 -375.855973) (xy 44.957148 -375.790594)
			(xy 44.949101 -375.723774) (xy 44.949099 -375.656471) (xy 44.95714 -375.589651) (xy 44.97311 -375.52427)
			(xy 44.996779 -375.461267) (xy 45.027809 -375.401544) (xy 45.065754 -375.345958) (xy 45.08754 -375.320306)
			(xy 45.093322 -375.31315) (xy 45.099844 -375.295968) (xy 45.10024 -375.286778) (xy 45.10024 -374.79351)
			(xy 45.099816 -374.784324) (xy 45.093311 -374.76714) (xy 45.08754 -374.759982) (xy 45.065711 -374.734364)
			(xy 45.027763 -374.678773) (xy 44.996732 -374.619044) (xy 44.973061 -374.556035) (xy 44.957091 -374.490649)
			(xy 44.94905 -374.423823) (xy 41.671014 -374.423823) (xy 41.671014 -374.423879) (xy 41.662941 -374.490816)
			(xy 41.646909 -374.556303) (xy 41.623147 -374.619398) (xy 41.591998 -374.679193) (xy 41.553911 -374.734826)
			(xy 41.532048 -374.76049) (xy 41.526224 -374.767616) (xy 41.519727 -374.784821) (xy 41.519348 -374.794018)
			(xy 41.519348 -375.28627) (xy 41.519784 -375.295454) (xy 41.526281 -375.312638) (xy 41.532048 -375.319798)
			(xy 41.553943 -375.345438) (xy 41.592035 -375.401075) (xy 41.623187 -375.460874) (xy 41.646952 -375.523974)
			(xy 41.662987 -375.589467) (xy 41.671061 -375.656409) (xy 41.671058 -375.723836) (xy 41.662978 -375.790777)
			(xy 41.646938 -375.856269) (xy 41.623168 -375.919367) (xy 41.592011 -375.979164) (xy 41.553916 -376.034798)
			(xy 41.532048 -376.060462) (xy 41.526236 -376.067596) (xy 41.519732 -376.084795) (xy 41.519348 -376.09399)
			(xy 41.519348 -376.25147) (xy 41.518849 -376.261596) (xy 41.511129 -376.280319) (xy 41.496846 -376.294677)
			(xy 41.478164 -376.302495) (xy 41.46804 -376.303032) (xy 40.75176 -376.303032) (xy 40.741607 -376.302612)
			(xy 40.72286 -376.294809) (xy 40.708539 -376.280413) (xy 40.700835 -376.261625) (xy 40.700452 -376.25147)
			(xy 40.700452 -376.09399) (xy 40.700035 -376.084804) (xy 40.693525 -376.06762) (xy 40.687752 -376.060462)
			(xy 40.665916 -376.034773) (xy 40.627823 -375.979143) (xy 40.596668 -375.919351) (xy 40.5729 -375.856257)
			(xy 40.55686 -375.79077) (xy 40.548781 -375.723834) (xy 40.548779 -375.656411) (xy 40.556852 -375.589474)
			(xy 40.572886 -375.523986) (xy 40.596649 -375.46089) (xy 40.627799 -375.401095) (xy 40.665888 -375.345462)
			(xy 40.687752 -375.319798) (xy 40.693538 -375.312646) (xy 40.700058 -375.29546) (xy 40.700452 -375.28627)
			(xy 40.700452 -374.794018) (xy 40.700022 -374.784833) (xy 40.693521 -374.767649) (xy 40.687752 -374.76049)
			(xy 40.665845 -374.73486) (xy 40.627754 -374.679221) (xy 40.596602 -374.619421) (xy 40.572838 -374.556319)
			(xy 40.556804 -374.490825) (xy 40.548731 -374.423882) (xy 37.271223 -374.423882) (xy 37.263151 -374.490815)
			(xy 37.247118 -374.556302) (xy 37.223357 -374.619398) (xy 37.192209 -374.679192) (xy 37.154123 -374.734826)
			(xy 37.13226 -374.76049) (xy 37.126438 -374.767617) (xy 37.119939 -374.784822) (xy 37.11956 -374.794018)
			(xy 37.11956 -375.28627) (xy 37.119994 -375.295454) (xy 37.126492 -375.312639) (xy 37.13226 -375.319798)
			(xy 37.154155 -375.345438) (xy 37.192245 -375.401075) (xy 37.223397 -375.460875) (xy 37.247161 -375.523975)
			(xy 37.263196 -375.589467) (xy 37.27127 -375.656409) (xy 37.271267 -375.723836) (xy 37.263188 -375.790777)
			(xy 37.247148 -375.856268) (xy 37.223379 -375.919367) (xy 37.192222 -375.979163) (xy 37.154127 -376.034797)
			(xy 37.13226 -376.060462) (xy 37.12645 -376.067597) (xy 37.119944 -376.084796) (xy 37.11956 -376.09399)
			(xy 37.11956 -376.25147) (xy 37.119049 -376.261595) (xy 37.111331 -376.280315) (xy 37.097052 -376.294673)
			(xy 37.078374 -376.302493) (xy 37.068252 -376.303032) (xy 36.351972 -376.303032) (xy 36.34182 -376.302602)
			(xy 36.323073 -376.294803) (xy 36.308752 -376.28041) (xy 36.301047 -376.261624) (xy 36.300664 -376.25147)
			(xy 36.300664 -376.09399) (xy 36.300244 -376.084804) (xy 36.293736 -376.06762) (xy 36.287964 -376.060462)
			(xy 36.266131 -376.034772) (xy 36.228044 -375.97914) (xy 36.196894 -375.919347) (xy 36.173129 -375.856253)
			(xy 36.157093 -375.790768) (xy 36.149015 -375.723833) (xy 36.149012 -375.656412) (xy 36.157085 -375.589477)
			(xy 36.173116 -375.52399) (xy 36.196875 -375.460894) (xy 36.22802 -375.401099) (xy 36.266103 -375.345464)
			(xy 36.287964 -375.319798) (xy 36.293752 -375.312647) (xy 36.30027 -375.295461) (xy 36.300664 -375.28627)
			(xy 36.300664 -374.794018) (xy 36.300231 -374.784834) (xy 36.293732 -374.76765) (xy 36.287964 -374.76049)
			(xy 36.26606 -374.734858) (xy 36.227975 -374.679218) (xy 36.196828 -374.619417) (xy 36.173068 -374.556316)
			(xy 36.157036 -374.490823) (xy 36.148964 -374.423882) (xy 32.870895 -374.423882) (xy 32.862863 -374.490639)
			(xy 32.846895 -374.556018) (xy 32.823227 -374.619021) (xy 32.7922 -374.678743) (xy 32.754257 -374.73433)
			(xy 32.732472 -374.759982) (xy 32.726654 -374.767112) (xy 32.720153 -374.784314) (xy 32.719772 -374.79351)
			(xy 32.719772 -375.286778) (xy 32.720199 -375.295963) (xy 32.726702 -375.313147) (xy 32.732472 -375.320306)
			(xy 32.754289 -375.345934) (xy 32.792236 -375.401524) (xy 32.823268 -375.461251) (xy 32.846938 -375.524259)
			(xy 32.862909 -375.589644) (xy 32.87095 -375.656469) (xy 32.870948 -375.723776) (xy 32.862901 -375.790601)
			(xy 32.846925 -375.855984) (xy 32.823249 -375.91899) (xy 32.792213 -375.978715) (xy 32.754261 -376.034302)
			(xy 32.732472 -376.059954) (xy 32.726666 -376.067093) (xy 32.720158 -376.084288) (xy 32.719772 -376.093482)
			(xy 32.719772 -376.25147) (xy 32.719312 -376.261638) (xy 32.711538 -376.28043) (xy 32.697164 -376.294816)
			(xy 32.678378 -376.302604) (xy 32.66821 -376.303032) (xy 31.95193 -376.303032) (xy 31.941757 -376.302611)
			(xy 31.922957 -376.29483) (xy 31.90857 -376.280443) (xy 31.900789 -376.261643) (xy 31.900368 -376.25147)
			(xy 31.900368 -376.093482) (xy 31.899951 -376.084296) (xy 31.89344 -376.067112) (xy 31.887668 -376.059954)
			(xy 31.865909 -376.034278) (xy 31.827957 -375.978696) (xy 31.796921 -375.918976) (xy 31.773245 -375.855974)
			(xy 31.75727 -375.790595) (xy 31.749223 -375.723774) (xy 31.74922 -375.656471) (xy 31.757261 -375.58965)
			(xy 31.773232 -375.524269) (xy 31.796903 -375.461266) (xy 31.827934 -375.401543) (xy 31.865881 -375.345958)
			(xy 31.887668 -375.320306) (xy 31.893453 -375.313153) (xy 31.899973 -375.295968) (xy 31.900368 -375.286778)
			(xy 31.900368 -374.79351) (xy 31.899938 -374.784325) (xy 31.893436 -374.767142) (xy 31.887668 -374.759982)
			(xy 31.865838 -374.734364) (xy 31.827888 -374.678774) (xy 31.796855 -374.619046) (xy 31.773184 -374.556036)
			(xy 31.757213 -374.49065) (xy 31.749171 -374.423823) (xy 28.471155 -374.423823) (xy 28.471155 -374.42387)
			(xy 28.463079 -374.490809) (xy 28.447044 -374.556297) (xy 28.423279 -374.619394) (xy 28.392129 -374.67919)
			(xy 28.35404 -374.734825) (xy 28.332176 -374.76049) (xy 28.326356 -374.767618) (xy 28.319856 -374.784822)
			(xy 28.319476 -374.794018) (xy 28.319476 -375.28627) (xy 28.319906 -375.295455) (xy 28.326407 -375.312639)
			(xy 28.332176 -375.319798) (xy 28.35407 -375.345439) (xy 28.39216 -375.401076) (xy 28.42331 -375.460875)
			(xy 28.447074 -375.523976) (xy 28.463108 -375.589468) (xy 28.471182 -375.656409) (xy 28.471179 -375.723836)
			(xy 28.4631 -375.790777) (xy 28.447061 -375.856268) (xy 28.423292 -375.919366) (xy 28.392136 -375.979163)
			(xy 28.354043 -376.034797) (xy 28.332176 -376.060462) (xy 28.326368 -376.067599) (xy 28.319861 -376.084796)
			(xy 28.319476 -376.09399) (xy 28.319476 -376.25147) (xy 28.31895 -376.261593) (xy 28.311235 -376.28031)
			(xy 28.29696 -376.294667) (xy 28.278288 -376.30249) (xy 28.268168 -376.303032) (xy 27.551888 -376.303032)
			(xy 27.541783 -376.302525) (xy 27.52311 -376.29479) (xy 27.508817 -376.2805) (xy 27.501077 -376.261829)
			(xy 27.50058 -376.251724) (xy 27.50058 -376.09399) (xy 27.500179 -376.084802) (xy 27.493659 -376.067617)
			(xy 27.48788 -376.060462) (xy 27.466046 -376.034772) (xy 27.427958 -375.979141) (xy 27.396807 -375.919348)
			(xy 27.373042 -375.856254) (xy 27.357005 -375.790768) (xy 27.348927 -375.723833) (xy 27.348924 -375.656412)
			(xy 27.356997 -375.589476) (xy 27.373029 -375.523989) (xy 27.396789 -375.460894) (xy 27.427935 -375.401098)
			(xy 27.466019 -375.345464) (xy 27.48788 -375.319798) (xy 27.493658 -375.312639) (xy 27.500184 -375.295459)
			(xy 27.50058 -375.28627) (xy 27.50058 -374.794018) (xy 27.500166 -374.784831) (xy 27.493655 -374.767646)
			(xy 27.48788 -374.76049) (xy 27.466014 -374.734827) (xy 27.427924 -374.679192) (xy 27.396773 -374.619396)
			(xy 27.373009 -374.556299) (xy 27.356973 -374.490809) (xy 27.348897 -374.423871) (xy 0.508 -374.423871)
			(xy 0.508 -376.756551) (xy 29.549067 -376.756551) (xy 29.557111 -376.689729) (xy 29.573083 -376.624347)
			(xy 29.596754 -376.561343) (xy 29.627786 -376.501619) (xy 29.665733 -376.446032) (xy 29.68752 -376.42038)
			(xy 29.69331 -376.41323) (xy 29.699828 -376.396043) (xy 29.70022 -376.386852) (xy 29.70022 -375.893584)
			(xy 29.699813 -375.884397) (xy 29.693297 -375.867212) (xy 29.68752 -375.860056) (xy 29.665765 -375.834378)
			(xy 29.627816 -375.778794) (xy 29.596782 -375.719074) (xy 29.573109 -375.656073) (xy 29.557134 -375.590694)
			(xy 29.549088 -375.523875) (xy 29.549085 -375.456573) (xy 29.557126 -375.389753) (xy 29.573095 -375.324373)
			(xy 29.596763 -375.26137) (xy 29.627791 -375.201647) (xy 29.665735 -375.146061) (xy 29.68752 -375.120408)
			(xy 29.693298 -375.11325) (xy 29.699823 -375.096069) (xy 29.70022 -375.08688) (xy 29.70022 -374.928638)
			(xy 29.700695 -374.918471) (xy 29.708464 -374.899681) (xy 29.722834 -374.885295) (xy 29.741616 -374.877506)
			(xy 29.751782 -374.877076) (xy 30.468062 -374.877076) (xy 30.478236 -374.877496) (xy 30.497037 -374.885276)
			(xy 30.511424 -374.899663) (xy 30.519204 -374.918464) (xy 30.519624 -374.928638) (xy 30.519624 -375.08688)
			(xy 30.520038 -375.096067) (xy 30.526548 -375.113252) (xy 30.532324 -375.120408) (xy 30.554144 -375.146034)
			(xy 30.592094 -375.201623) (xy 30.623128 -375.26135) (xy 30.646801 -375.324358) (xy 30.662773 -375.389744)
			(xy 30.670815 -375.45657) (xy 30.670812 -375.523878) (xy 30.662764 -375.590704) (xy 30.646787 -375.656088)
			(xy 30.623109 -375.719094) (xy 30.59207 -375.778818) (xy 30.554115 -375.834404) (xy 30.532324 -375.860056)
			(xy 30.526524 -375.867199) (xy 30.520011 -375.884391) (xy 30.519624 -375.893584) (xy 30.519624 -376.386852)
			(xy 30.520052 -376.396037) (xy 30.526553 -376.413222) (xy 30.532324 -376.42038) (xy 30.554117 -376.446028)
			(xy 30.592068 -376.501615) (xy 30.623103 -376.561338) (xy 30.646777 -376.624343) (xy 30.662751 -376.689726)
			(xy 30.670795 -376.75655) (xy 30.670795 -376.823856) (xy 30.670788 -376.823915) (xy 33.948836 -376.823915)
			(xy 33.948836 -376.756491) (xy 33.956911 -376.689553) (xy 33.972947 -376.624064) (xy 33.996711 -376.560967)
			(xy 34.027862 -376.501171) (xy 34.065952 -376.445537) (xy 34.087816 -376.419872) (xy 34.093609 -376.412724)
			(xy 34.100125 -376.395536) (xy 34.100516 -376.386344) (xy 34.100516 -375.894092) (xy 34.100106 -375.884905)
			(xy 34.093592 -375.867721) (xy 34.087816 -375.860564) (xy 34.065983 -375.834873) (xy 34.027892 -375.779243)
			(xy 33.996739 -375.71945) (xy 33.972973 -375.656357) (xy 33.956934 -375.59087) (xy 33.948856 -375.523935)
			(xy 33.948853 -375.456513) (xy 33.956926 -375.389577) (xy 33.972958 -375.324089) (xy 33.99672 -375.260994)
			(xy 34.027867 -375.201199) (xy 34.065953 -375.145565) (xy 34.087816 -375.1199) (xy 34.093597 -375.112744)
			(xy 34.10012 -375.095562) (xy 34.100516 -375.086372) (xy 34.100516 -374.928638) (xy 34.101057 -374.918517)
			(xy 34.108768 -374.899801) (xy 34.123038 -374.885444) (xy 34.141706 -374.87762) (xy 34.151824 -374.877076)
			(xy 34.868104 -374.877076) (xy 34.878255 -374.877518) (xy 34.897003 -374.88531) (xy 34.911325 -374.8997)
			(xy 34.919029 -374.918485) (xy 34.919412 -374.928638) (xy 34.919412 -375.086372) (xy 34.919833 -375.095558)
			(xy 34.926339 -375.112743) (xy 34.932112 -375.1199) (xy 34.954007 -375.14554) (xy 34.992094 -375.201178)
			(xy 35.023243 -375.260978) (xy 35.047004 -375.324078) (xy 35.063037 -375.38957) (xy 35.07111 -375.456511)
			(xy 35.071108 -375.523937) (xy 35.063029 -375.590877) (xy 35.04699 -375.656368) (xy 35.023223 -375.719466)
			(xy 34.992069 -375.779263) (xy 34.953977 -375.834899) (xy 34.932112 -375.860564) (xy 34.926307 -375.867703)
			(xy 34.919797 -375.884898) (xy 34.919412 -375.894092) (xy 34.919412 -376.386344) (xy 34.919798 -376.395534)
			(xy 34.926328 -376.412718) (xy 34.932112 -376.419872) (xy 34.953979 -376.445534) (xy 34.992067 -376.501169)
			(xy 35.023217 -376.560966) (xy 35.046981 -376.624063) (xy 35.063015 -376.689553) (xy 35.071091 -376.756491)
			(xy 35.071091 -376.756551) (xy 38.349155 -376.756551) (xy 38.357198 -376.689729) (xy 38.37317 -376.624348)
			(xy 38.396841 -376.561343) (xy 38.427872 -376.50162) (xy 38.465818 -376.446033) (xy 38.487604 -376.42038)
			(xy 38.493392 -376.413229) (xy 38.499912 -376.396043) (xy 38.500304 -376.386852) (xy 38.500304 -375.893584)
			(xy 38.499901 -375.884396) (xy 38.493382 -375.867212) (xy 38.487604 -375.860056) (xy 38.465849 -375.834378)
			(xy 38.427901 -375.778794) (xy 38.396869 -375.719074) (xy 38.373195 -375.656073) (xy 38.357221 -375.590694)
			(xy 38.349175 -375.523875) (xy 38.349172 -375.456573) (xy 38.357213 -375.389753) (xy 38.373181 -375.324373)
			(xy 38.396849 -375.26137) (xy 38.427876 -375.201647) (xy 38.465819 -375.146061) (xy 38.487604 -375.120408)
			(xy 38.49338 -375.113248) (xy 38.499907 -375.096069) (xy 38.500304 -375.08688) (xy 38.500304 -374.928638)
			(xy 38.500794 -374.918473) (xy 38.50856 -374.899686) (xy 38.522925 -374.885301) (xy 38.541702 -374.877508)
			(xy 38.551866 -374.877076) (xy 39.268146 -374.877076) (xy 39.278311 -374.877497) (xy 39.297089 -374.885293)
			(xy 39.311454 -374.899682) (xy 39.31922 -374.918472) (xy 39.319708 -374.928638) (xy 39.319708 -375.08688)
			(xy 39.320126 -375.096066) (xy 39.326634 -375.113251) (xy 39.332408 -375.120408) (xy 39.354229 -375.146034)
			(xy 39.39218 -375.201623) (xy 39.423215 -375.261349) (xy 39.446888 -375.324357) (xy 39.462861 -375.389743)
			(xy 39.470903 -375.45657) (xy 39.4709 -375.523878) (xy 39.462852 -375.590704) (xy 39.446874 -375.656089)
			(xy 39.423195 -375.719095) (xy 39.392155 -375.778819) (xy 39.354199 -375.834405) (xy 39.332408 -375.860056)
			(xy 39.326606 -375.867197) (xy 39.320094 -375.884391) (xy 39.319708 -375.893584) (xy 39.319708 -376.386852)
			(xy 39.320139 -376.396037) (xy 39.326638 -376.413222) (xy 39.332408 -376.42038) (xy 39.354201 -376.446028)
			(xy 39.392153 -376.501614) (xy 39.423189 -376.561338) (xy 39.446864 -376.624343) (xy 39.462839 -376.689726)
			(xy 39.470883 -376.75655) (xy 39.470883 -376.823856) (xy 39.470876 -376.823915) (xy 42.748924 -376.823915)
			(xy 42.748924 -376.756491) (xy 42.756999 -376.689553) (xy 42.773034 -376.624064) (xy 42.796798 -376.560968)
			(xy 42.827948 -376.501172) (xy 42.866036 -376.445537) (xy 42.8879 -376.419872) (xy 42.893691 -376.412723)
			(xy 42.900209 -376.395535) (xy 42.9006 -376.386344) (xy 42.9006 -375.894092) (xy 42.900194 -375.884904)
			(xy 42.893677 -375.86772) (xy 42.8879 -375.860564) (xy 42.866067 -375.834873) (xy 42.827978 -375.779242)
			(xy 42.796826 -375.719449) (xy 42.77306 -375.656356) (xy 42.757022 -375.59087) (xy 42.748944 -375.523935)
			(xy 42.748941 -375.456513) (xy 42.757013 -375.389577) (xy 42.773045 -375.32409) (xy 42.796806 -375.260995)
			(xy 42.827953 -375.201199) (xy 42.866038 -375.145565) (xy 42.8879 -375.1199) (xy 42.893679 -375.112742)
			(xy 42.900204 -375.095561) (xy 42.9006 -375.086372) (xy 42.9006 -374.928638) (xy 42.901157 -374.918519)
			(xy 42.908865 -374.899806) (xy 42.923129 -374.88545) (xy 42.941792 -374.877622) (xy 42.951908 -374.877076)
			(xy 43.668188 -374.877076) (xy 43.678338 -374.877531) (xy 43.697086 -374.885318) (xy 43.711409 -374.899704)
			(xy 43.719113 -374.918486) (xy 43.719496 -374.928638) (xy 43.719496 -375.086372) (xy 43.719921 -375.095558)
			(xy 43.726424 -375.112742) (xy 43.732196 -375.1199) (xy 43.754092 -375.145539) (xy 43.79218 -375.201177)
			(xy 43.823329 -375.260977) (xy 43.847092 -375.324077) (xy 43.863125 -375.38957) (xy 43.871198 -375.456511)
			(xy 43.871196 -375.523937) (xy 43.863116 -375.590878) (xy 43.847077 -375.656369) (xy 43.823309 -375.719467)
			(xy 43.792155 -375.779264) (xy 43.754062 -375.834899) (xy 43.732196 -375.860564) (xy 43.726389 -375.867702)
			(xy 43.719881 -375.884898) (xy 43.719496 -375.894092) (xy 43.719496 -376.386344) (xy 43.719886 -376.395533)
			(xy 43.726414 -376.412717) (xy 43.732196 -376.419872) (xy 43.754064 -376.445534) (xy 43.792153 -376.501169)
			(xy 43.823304 -376.560965) (xy 43.847068 -376.624063) (xy 43.863103 -376.689552) (xy 43.871179 -376.756491)
			(xy 43.871178 -376.823856) (xy 47.149219 -376.823856) (xy 47.149219 -376.75655) (xy 47.157264 -376.689727)
			(xy 47.173238 -376.624344) (xy 47.196912 -376.56134) (xy 47.227948 -376.501617) (xy 47.265899 -376.446031)
			(xy 47.287688 -376.42038) (xy 47.293474 -376.413227) (xy 47.299995 -376.396043) (xy 47.300388 -376.386852)
			(xy 47.300388 -375.893584) (xy 47.299988 -375.884396) (xy 47.293468 -375.867211) (xy 47.287688 -375.860056)
			(xy 47.26593 -375.834379) (xy 47.227977 -375.778797) (xy 47.19694 -375.719077) (xy 47.173263 -375.656076)
			(xy 47.157287 -375.590696) (xy 47.149239 -375.523876) (xy 47.149236 -375.456572) (xy 47.157278 -375.389751)
			(xy 47.173249 -375.32437) (xy 47.19692 -375.261367) (xy 47.227952 -375.201644) (xy 47.265901 -375.146059)
			(xy 47.287688 -375.120408) (xy 47.293462 -375.113247) (xy 47.299991 -375.096069) (xy 47.300388 -375.08688)
			(xy 47.300388 -374.928892) (xy 47.300815 -374.918739) (xy 47.308611 -374.899989) (xy 47.323006 -374.885666)
			(xy 47.341795 -374.877965) (xy 47.35195 -374.877584) (xy 48.06823 -374.877584) (xy 48.078364 -374.878003)
			(xy 48.097094 -374.885749) (xy 48.111451 -374.900056) (xy 48.119261 -374.91876) (xy 48.119792 -374.928892)
			(xy 48.119792 -375.08688) (xy 48.120214 -375.096066) (xy 48.12672 -375.11325) (xy 48.132492 -375.120408)
			(xy 48.15431 -375.146035) (xy 48.192256 -375.201626) (xy 48.223286 -375.261353) (xy 48.246956 -375.324361)
			(xy 48.262926 -375.389746) (xy 48.270967 -375.456571) (xy 48.270964 -375.523878) (xy 48.262917 -375.590702)
			(xy 48.246942 -375.656085) (xy 48.223267 -375.719091) (xy 48.192231 -375.778816) (xy 48.154281 -375.834403)
			(xy 48.132492 -375.860056) (xy 48.126688 -375.867196) (xy 48.120178 -375.884391) (xy 48.119792 -375.893584)
			(xy 48.119792 -376.386852) (xy 48.120227 -376.396037) (xy 48.126724 -376.413221) (xy 48.132492 -376.42038)
			(xy 48.154283 -376.446029) (xy 48.192229 -376.501617) (xy 48.223261 -376.561341) (xy 48.246932 -376.624346)
			(xy 48.262904 -376.689728) (xy 48.270947 -376.756551) (xy 73.548976 -376.756551) (xy 73.55702 -376.689728)
			(xy 73.572992 -376.624347) (xy 73.596664 -376.561342) (xy 73.627697 -376.501619) (xy 73.665645 -376.446032)
			(xy 73.687432 -376.42038) (xy 73.693224 -376.413231) (xy 73.699741 -376.396043) (xy 73.700132 -376.386852)
			(xy 73.700132 -375.893584) (xy 73.699722 -375.884397) (xy 73.693208 -375.867213) (xy 73.687432 -375.860056)
			(xy 73.665676 -375.834378) (xy 73.627727 -375.778795) (xy 73.596693 -375.719075) (xy 73.573018 -375.656074)
			(xy 73.557043 -375.590695) (xy 73.548997 -375.523875) (xy 73.548994 -375.456573) (xy 73.557035 -375.389753)
			(xy 73.573004 -375.324372) (xy 73.596673 -375.261369) (xy 73.627702 -375.201647) (xy 73.665647 -375.14606)
			(xy 73.687432 -375.120408) (xy 73.693212 -375.113251) (xy 73.699736 -375.096069) (xy 73.700132 -375.08688)
			(xy 73.700132 -374.928638) (xy 73.700595 -374.91847) (xy 73.708366 -374.899677) (xy 73.72274 -374.885291)
			(xy 73.741526 -374.877504) (xy 73.751694 -374.877076) (xy 74.467974 -374.877076) (xy 74.478149 -374.877486)
			(xy 74.49695 -374.88527) (xy 74.511337 -374.89966) (xy 74.519116 -374.918463) (xy 74.519536 -374.928638)
			(xy 74.519536 -375.08688) (xy 74.51997 -375.096064) (xy 74.526469 -375.113248) (xy 74.532236 -375.120408)
			(xy 74.554056 -375.146034) (xy 74.592006 -375.201623) (xy 74.623039 -375.26135) (xy 74.646711 -375.324358)
			(xy 74.662683 -375.389744) (xy 74.670725 -375.45657) (xy 74.670722 -375.523878) (xy 74.662674 -375.590703)
			(xy 74.646697 -375.656088) (xy 74.623019 -375.719094) (xy 74.591981 -375.778818) (xy 74.554027 -375.834404)
			(xy 74.532236 -375.860056) (xy 74.526425 -375.867191) (xy 74.519921 -375.88439) (xy 74.519536 -375.893584)
			(xy 74.519536 -376.386852) (xy 74.519983 -376.396035) (xy 74.526473 -376.413219) (xy 74.532236 -376.42038)
			(xy 74.554028 -376.446029) (xy 74.591979 -376.501615) (xy 74.623013 -376.561339) (xy 74.646687 -376.624344)
			(xy 74.66266 -376.689727) (xy 74.670704 -376.75655) (xy 74.670704 -376.823856) (xy 74.670697 -376.823915)
			(xy 77.948745 -376.823915) (xy 77.948745 -376.756491) (xy 77.956821 -376.689553) (xy 77.972856 -376.624063)
			(xy 77.996621 -376.560967) (xy 78.027773 -376.501171) (xy 78.065863 -376.445537) (xy 78.087728 -376.419872)
			(xy 78.093523 -376.412726) (xy 78.100038 -376.395536) (xy 78.100428 -376.386344) (xy 78.100428 -375.894092)
			(xy 78.100016 -375.884905) (xy 78.093503 -375.867721) (xy 78.087728 -375.860564) (xy 78.065894 -375.834873)
			(xy 78.027803 -375.779243) (xy 77.996649 -375.719451) (xy 77.972882 -375.656357) (xy 77.956844 -375.590871)
			(xy 77.948765 -375.523935) (xy 77.948762 -375.456513) (xy 77.956835 -375.389577) (xy 77.972868 -375.324089)
			(xy 77.99663 -375.260993) (xy 78.027778 -375.201198) (xy 78.065865 -375.145565) (xy 78.087728 -375.1199)
			(xy 78.093511 -375.112745) (xy 78.100033 -375.095562) (xy 78.100428 -375.086372) (xy 78.100428 -374.928638)
			(xy 78.100958 -374.918515) (xy 78.108671 -374.899797) (xy 78.122944 -374.88544) (xy 78.141616 -374.877618)
			(xy 78.151736 -374.877076) (xy 78.868016 -374.877076) (xy 78.878123 -374.877572) (xy 78.896797 -374.88531)
			(xy 78.91109 -374.899603) (xy 78.918828 -374.918277) (xy 78.919324 -374.928384) (xy 78.919324 -375.086372)
			(xy 78.919742 -375.095558) (xy 78.92625 -375.112743) (xy 78.932024 -375.1199) (xy 78.953919 -375.14554)
			(xy 78.992005 -375.201178) (xy 79.023153 -375.260978) (xy 79.046914 -375.324079) (xy 79.062947 -375.38957)
			(xy 79.07102 -375.456511) (xy 79.071017 -375.523937) (xy 79.062938 -375.590877) (xy 79.0469 -375.656367)
			(xy 79.023133 -375.719466) (xy 78.99198 -375.779263) (xy 78.953889 -375.834898) (xy 78.932024 -375.860564)
			(xy 78.926221 -375.867704) (xy 78.919709 -375.884898) (xy 78.919324 -375.894092) (xy 78.919324 -376.386344)
			(xy 78.919708 -376.395534) (xy 78.926239 -376.412718) (xy 78.932024 -376.419872) (xy 78.953891 -376.445534)
			(xy 78.991978 -376.50117) (xy 79.023127 -376.560967) (xy 79.04689 -376.624064) (xy 79.062925 -376.689553)
			(xy 79.071 -376.756491) (xy 79.071 -376.756551) (xy 82.349064 -376.756551) (xy 82.357108 -376.689729)
			(xy 82.373079 -376.624347) (xy 82.396751 -376.561343) (xy 82.427782 -376.501619) (xy 82.465729 -376.446032)
			(xy 82.487516 -376.42038) (xy 82.493305 -376.41323) (xy 82.499824 -376.396043) (xy 82.500216 -376.386852)
			(xy 82.500216 -375.893584) (xy 82.49981 -375.884396) (xy 82.493293 -375.867212) (xy 82.487516 -375.860056)
			(xy 82.46576 -375.834378) (xy 82.427812 -375.778795) (xy 82.396779 -375.719074) (xy 82.373105 -375.656073)
			(xy 82.357131 -375.590694) (xy 82.349084 -375.523875) (xy 82.349081 -375.456573) (xy 82.357122 -375.389753)
			(xy 82.373091 -375.324373) (xy 82.396759 -375.26137) (xy 82.427787 -375.201647) (xy 82.465731 -375.14606)
			(xy 82.487516 -375.120408) (xy 82.493294 -375.113249) (xy 82.499819 -375.096069) (xy 82.500216 -375.08688)
			(xy 82.500216 -374.928638) (xy 82.500694 -374.918472) (xy 82.508463 -374.899682) (xy 82.522832 -374.885297)
			(xy 82.541612 -374.877506) (xy 82.551778 -374.877076) (xy 83.268058 -374.877076) (xy 83.278232 -374.877499)
			(xy 83.297033 -374.885277) (xy 83.31142 -374.899664) (xy 83.3192 -374.918464) (xy 83.31962 -374.928638)
			(xy 83.31962 -375.08688) (xy 83.320035 -375.096067) (xy 83.326545 -375.113251) (xy 83.33232 -375.120408)
			(xy 83.35414 -375.146034) (xy 83.392091 -375.201623) (xy 83.423125 -375.26135) (xy 83.446798 -375.324358)
			(xy 83.46277 -375.389744) (xy 83.470812 -375.45657) (xy 83.470809 -375.523878) (xy 83.462761 -375.590704)
			(xy 83.446784 -375.656088) (xy 83.423105 -375.719094) (xy 83.392066 -375.778818) (xy 83.354111 -375.834404)
			(xy 83.33232 -375.860056) (xy 83.326519 -375.867199) (xy 83.320007 -375.884391) (xy 83.31962 -375.893584)
			(xy 83.31962 -376.386852) (xy 83.320049 -376.396037) (xy 83.326549 -376.413222) (xy 83.33232 -376.42038)
			(xy 83.354113 -376.446028) (xy 83.392064 -376.501614) (xy 83.4231 -376.561338) (xy 83.446774 -376.624343)
			(xy 83.462748 -376.689726) (xy 83.470792 -376.75655) (xy 83.470792 -376.823856) (xy 83.470785 -376.823915)
			(xy 86.748833 -376.823915) (xy 86.748833 -376.756491) (xy 86.756908 -376.689553) (xy 86.772944 -376.624064)
			(xy 86.796708 -376.560967) (xy 86.827859 -376.501171) (xy 86.865948 -376.445537) (xy 86.887812 -376.419872)
			(xy 86.893604 -376.412724) (xy 86.900121 -376.395536) (xy 86.900512 -376.386344) (xy 86.900512 -375.894092)
			(xy 86.900103 -375.884905) (xy 86.893588 -375.86772) (xy 86.887812 -375.860564) (xy 86.865979 -375.834873)
			(xy 86.827889 -375.779242) (xy 86.796736 -375.71945) (xy 86.772969 -375.656356) (xy 86.756931 -375.59087)
			(xy 86.748853 -375.523935) (xy 86.74885 -375.456513) (xy 86.756923 -375.389577) (xy 86.772955 -375.32409)
			(xy 86.796716 -375.260994) (xy 86.827864 -375.201199) (xy 86.86595 -375.145565) (xy 86.887812 -375.1199)
			(xy 86.893592 -375.112743) (xy 86.900116 -375.095562) (xy 86.900512 -375.086372) (xy 86.900512 -374.928638)
			(xy 86.901057 -374.918517) (xy 86.908767 -374.899802) (xy 86.923035 -374.885446) (xy 86.941702 -374.87762)
			(xy 86.95182 -374.877076) (xy 87.6681 -374.877076) (xy 87.678206 -374.877585) (xy 87.696879 -374.885318)
			(xy 87.711173 -374.899607) (xy 87.718912 -374.918278) (xy 87.719408 -374.928384) (xy 87.719408 -375.086372)
			(xy 87.71983 -375.095558) (xy 87.726335 -375.112743) (xy 87.732108 -375.1199) (xy 87.754003 -375.145539)
			(xy 87.79209 -375.201178) (xy 87.798441 -375.213371) (xy 104.681961 -375.213371) (xy 104.681961 -375.153429)
			(xy 104.689785 -375.094001) (xy 104.7053 -375.036103) (xy 104.72824 -374.980725) (xy 104.758212 -374.928815)
			(xy 104.794703 -374.881262) (xy 104.837089 -374.838879) (xy 104.884645 -374.802391) (xy 104.936557 -374.772424)
			(xy 104.991937 -374.749489) (xy 105.049837 -374.733978) (xy 105.109265 -374.726159) (xy 105.139236 -374.725692)
			(xy 106.002836 -374.725692) (xy 106.032802 -374.726184) (xy 106.092221 -374.734011) (xy 106.15011 -374.749527)
			(xy 106.205479 -374.772465) (xy 106.25738 -374.802434) (xy 106.304926 -374.838921) (xy 106.347303 -374.881301)
			(xy 106.383786 -374.92885) (xy 106.413751 -374.980753) (xy 106.436685 -375.036124) (xy 106.452196 -375.094014)
			(xy 106.460018 -375.153434) (xy 106.460018 -375.213366) (xy 106.452196 -375.272786) (xy 106.436685 -375.330676)
			(xy 106.413751 -375.386047) (xy 106.383786 -375.43795) (xy 106.347303 -375.485499) (xy 106.304926 -375.527879)
			(xy 106.25738 -375.564366) (xy 106.205479 -375.594335) (xy 106.15011 -375.617273) (xy 106.092221 -375.632789)
			(xy 106.032802 -375.640616) (xy 106.002836 -375.641108) (xy 105.139236 -375.641108) (xy 105.109265 -375.640641)
			(xy 105.049837 -375.632822) (xy 104.991937 -375.617311) (xy 104.936557 -375.594376) (xy 104.884645 -375.564409)
			(xy 104.837089 -375.527921) (xy 104.794703 -375.485538) (xy 104.758212 -375.437985) (xy 104.72824 -375.386075)
			(xy 104.7053 -375.330697) (xy 104.689785 -375.272799) (xy 104.681961 -375.213371) (xy 87.798441 -375.213371)
			(xy 87.823239 -375.260978) (xy 87.847001 -375.324078) (xy 87.863034 -375.38957) (xy 87.871107 -375.456511)
			(xy 87.871105 -375.523937) (xy 87.863026 -375.590877) (xy 87.846987 -375.656368) (xy 87.82322 -375.719466)
			(xy 87.792066 -375.779263) (xy 87.753974 -375.834899) (xy 87.732108 -375.860564) (xy 87.726303 -375.867703)
			(xy 87.719793 -375.884898) (xy 87.719408 -375.894092) (xy 87.719408 -376.386344) (xy 87.719795 -376.395534)
			(xy 87.726324 -376.412718) (xy 87.732108 -376.419872) (xy 87.753976 -376.445534) (xy 87.792064 -376.501169)
			(xy 87.823214 -376.560966) (xy 87.846977 -376.624063) (xy 87.863012 -376.689553) (xy 87.871088 -376.756491)
			(xy 87.871087 -376.823915) (xy 117.548863 -376.823915) (xy 117.548863 -376.756491) (xy 117.556939 -376.689552)
			(xy 117.572976 -376.624062) (xy 117.596742 -376.560965) (xy 117.627895 -376.50117) (xy 117.665986 -376.445536)
			(xy 117.687852 -376.419872) (xy 117.693649 -376.412728) (xy 117.700162 -376.395536) (xy 117.700552 -376.386344)
			(xy 117.700552 -375.894092) (xy 117.700134 -375.884906) (xy 117.693625 -375.867722) (xy 117.687852 -375.860564)
			(xy 117.666018 -375.834874) (xy 117.627925 -375.779244) (xy 117.59677 -375.719452) (xy 117.573001 -375.656358)
			(xy 117.556962 -375.590871) (xy 117.548883 -375.523935) (xy 117.54888 -375.456513) (xy 117.556953 -375.389576)
			(xy 117.572987 -375.324088) (xy 117.59675 -375.260992) (xy 117.6279 -375.201197) (xy 117.665988 -375.145564)
			(xy 117.687852 -375.1199) (xy 117.693638 -375.112747) (xy 117.700157 -375.095562) (xy 117.700552 -375.086372)
			(xy 117.700552 -374.928638) (xy 117.701058 -374.918512) (xy 117.708776 -374.89979) (xy 117.723056 -374.885432)
			(xy 117.741737 -374.877613) (xy 117.75186 -374.877076) (xy 118.46814 -374.877076) (xy 118.478294 -374.877488)
			(xy 118.497042 -374.885293) (xy 118.511363 -374.899691) (xy 118.519066 -374.918482) (xy 118.519448 -374.928638)
			(xy 118.519448 -375.086372) (xy 118.519883 -375.095556) (xy 118.526381 -375.11274) (xy 118.532148 -375.1199)
			(xy 118.554045 -375.145538) (xy 118.592136 -375.201176) (xy 118.623289 -375.260975) (xy 118.647053 -375.324075)
			(xy 118.663088 -375.389568) (xy 118.671162 -375.45651) (xy 118.671159 -375.523938) (xy 118.66308 -375.590879)
			(xy 118.647039 -375.656371) (xy 118.623269 -375.719469) (xy 118.592112 -375.779266) (xy 118.554016 -375.8349)
			(xy 118.532148 -375.860564) (xy 118.526335 -375.867698) (xy 118.519832 -375.884897) (xy 118.519448 -375.894092)
			(xy 118.519448 -376.386344) (xy 118.519849 -376.395532) (xy 118.52637 -376.412715) (xy 118.532148 -376.419872)
			(xy 118.554018 -376.445533) (xy 118.59211 -376.501167) (xy 118.623263 -376.560963) (xy 118.647029 -376.624061)
			(xy 118.663066 -376.689551) (xy 118.671143 -376.75649) (xy 118.671143 -376.756551) (xy 121.949182 -376.756551)
			(xy 121.957226 -376.689728) (xy 121.973199 -376.624346) (xy 121.996871 -376.561342) (xy 122.027904 -376.501618)
			(xy 122.065852 -376.446032) (xy 122.08764 -376.42038) (xy 122.093433 -376.413232) (xy 122.099949 -376.396044)
			(xy 122.10034 -376.386852) (xy 122.10034 -375.893584) (xy 122.099929 -375.884397) (xy 122.093415 -375.867213)
			(xy 122.08764 -375.860056) (xy 122.065884 -375.834378) (xy 122.027934 -375.778795) (xy 121.996899 -375.719075)
			(xy 121.973225 -375.656074) (xy 121.95725 -375.590695) (xy 121.949203 -375.523875) (xy 121.9492 -375.456573)
			(xy 121.957241 -375.389752) (xy 121.973211 -375.324372) (xy 121.99688 -375.261369) (xy 122.027909 -375.201646)
			(xy 122.065854 -375.14606) (xy 122.08764 -375.120408) (xy 122.093421 -375.113252) (xy 122.099944 -375.09607)
			(xy 122.10034 -375.08688) (xy 122.10034 -374.928638) (xy 122.100795 -374.918469) (xy 122.108568 -374.899674)
			(xy 122.122944 -374.885288) (xy 122.141733 -374.877502) (xy 122.151902 -374.877076) (xy 122.868182 -374.877076)
			(xy 122.878357 -374.877479) (xy 122.897159 -374.885265) (xy 122.911546 -374.899658) (xy 122.919325 -374.918463)
			(xy 122.919744 -374.928638) (xy 122.919744 -375.08688) (xy 122.920176 -375.096065) (xy 122.926676 -375.113249)
			(xy 122.932444 -375.120408) (xy 122.954264 -375.146034) (xy 122.992213 -375.201624) (xy 123.023246 -375.261351)
			(xy 123.046917 -375.324359) (xy 123.062889 -375.389744) (xy 123.070931 -375.45657) (xy 123.070928 -375.523878)
			(xy 123.06288 -375.590703) (xy 123.046903 -375.656087) (xy 123.023226 -375.719093) (xy 122.992188 -375.778818)
			(xy 122.954234 -375.834404) (xy 122.932444 -375.860056) (xy 122.926634 -375.867192) (xy 122.920129 -375.88439)
			(xy 122.919744 -375.893584) (xy 122.919744 -376.386852) (xy 122.92019 -376.396035) (xy 122.92668 -376.413219)
			(xy 122.932444 -376.42038) (xy 122.954236 -376.446029) (xy 122.992186 -376.501615) (xy 123.02322 -376.561339)
			(xy 123.046893 -376.624344) (xy 123.062866 -376.689727) (xy 123.07091 -376.75655) (xy 123.07091 -376.823856)
			(xy 123.070903 -376.823915) (xy 126.348951 -376.823915) (xy 126.348951 -376.756491) (xy 126.357027 -376.689552)
			(xy 126.373063 -376.624063) (xy 126.396828 -376.560966) (xy 126.42798 -376.50117) (xy 126.466071 -376.445537)
			(xy 126.487936 -376.419872) (xy 126.493732 -376.412726) (xy 126.500246 -376.395536) (xy 126.500636 -376.386344)
			(xy 126.500636 -375.894092) (xy 126.500222 -375.884905) (xy 126.49371 -375.867721) (xy 126.487936 -375.860564)
			(xy 126.466102 -375.834873) (xy 126.42801 -375.779243) (xy 126.396856 -375.719451) (xy 126.373088 -375.656357)
			(xy 126.35705 -375.590871) (xy 126.348971 -375.523935) (xy 126.348968 -375.456513) (xy 126.357041 -375.389576)
			(xy 126.373074 -375.324089) (xy 126.396836 -375.260993) (xy 126.427985 -375.201198) (xy 126.466073 -375.145565)
			(xy 126.487936 -375.1199) (xy 126.49372 -375.112746) (xy 126.500241 -375.095562) (xy 126.500636 -375.086372)
			(xy 126.500636 -374.928638) (xy 126.501158 -374.918514) (xy 126.508872 -374.899795) (xy 126.523148 -374.885437)
			(xy 126.541823 -374.877616) (xy 126.551944 -374.877076) (xy 127.268224 -374.877076) (xy 127.278377 -374.877501)
			(xy 127.297125 -374.8853) (xy 127.311447 -374.899695) (xy 127.31915 -374.918483) (xy 127.319532 -374.928638)
			(xy 127.319532 -375.086372) (xy 127.319971 -375.095556) (xy 127.326466 -375.11274) (xy 127.332232 -375.1199)
			(xy 127.354126 -375.14554) (xy 127.392212 -375.201179) (xy 127.423359 -375.260979) (xy 127.44712 -375.324079)
			(xy 127.463153 -375.389571) (xy 127.471226 -375.456511) (xy 127.471223 -375.523937) (xy 127.463144 -375.590877)
			(xy 127.447106 -375.656367) (xy 127.42334 -375.719465) (xy 127.392187 -375.779263) (xy 127.354097 -375.834898)
			(xy 127.332232 -375.860564) (xy 127.326417 -375.867696) (xy 127.319915 -375.884897) (xy 127.319532 -375.894092)
			(xy 127.319532 -376.386344) (xy 127.319936 -376.395532) (xy 127.326456 -376.412715) (xy 127.332232 -376.419872)
			(xy 127.354099 -376.445535) (xy 127.392185 -376.50117) (xy 127.423334 -376.560967) (xy 127.447097 -376.624064)
			(xy 127.463131 -376.689553) (xy 127.471206 -376.756491) (xy 127.471206 -376.756551) (xy 130.74927 -376.756551)
			(xy 130.757314 -376.689729) (xy 130.773286 -376.624347) (xy 130.796958 -376.561343) (xy 130.827989 -376.501619)
			(xy 130.865937 -376.446032) (xy 130.887724 -376.42038) (xy 130.893514 -376.413231) (xy 130.900032 -376.396043)
			(xy 130.900424 -376.386852) (xy 130.900424 -375.893584) (xy 130.900016 -375.884397) (xy 130.8935 -375.867213)
			(xy 130.887724 -375.860056) (xy 130.865968 -375.834378) (xy 130.82802 -375.778795) (xy 130.796986 -375.719074)
			(xy 130.773312 -375.656073) (xy 130.757337 -375.590695) (xy 130.749291 -375.523875) (xy 130.749288 -375.456573)
			(xy 130.757329 -375.389753) (xy 130.773298 -375.324373) (xy 130.796966 -375.26137) (xy 130.827995 -375.201647)
			(xy 130.865939 -375.146061) (xy 130.887724 -375.120408) (xy 130.893502 -375.11325) (xy 130.900027 -375.096069)
			(xy 130.900424 -375.08688) (xy 130.900424 -374.928638) (xy 130.900895 -374.918471) (xy 130.908665 -374.899679)
			(xy 130.923036 -374.885294) (xy 130.941819 -374.877505) (xy 130.951986 -374.877076) (xy 131.668266 -374.877076)
			(xy 131.67844 -374.877493) (xy 131.697241 -374.885274) (xy 131.711629 -374.899662) (xy 131.719408 -374.918464)
			(xy 131.719828 -374.928638) (xy 131.719828 -375.08688) (xy 131.720241 -375.096067) (xy 131.726752 -375.113252)
			(xy 131.732528 -375.120408) (xy 131.754348 -375.146034) (xy 131.792298 -375.201623) (xy 131.823332 -375.26135)
			(xy 131.847005 -375.324358) (xy 131.862976 -375.389744) (xy 131.871018 -375.45657) (xy 131.871016 -375.523878)
			(xy 131.862968 -375.590704) (xy 131.84699 -375.656088) (xy 131.823313 -375.719094) (xy 131.792274 -375.778818)
			(xy 131.754319 -375.834404) (xy 131.732528 -375.860056) (xy 131.726716 -375.86719) (xy 131.720213 -375.884389)
			(xy 131.719828 -375.893584) (xy 131.719828 -376.386852) (xy 131.720255 -376.396037) (xy 131.726756 -376.413222)
			(xy 131.732528 -376.42038) (xy 131.754321 -376.446029) (xy 131.792271 -376.501615) (xy 131.823306 -376.561338)
			(xy 131.84698 -376.624344) (xy 131.862954 -376.689727) (xy 131.870991 -376.756492) (xy 161.548796 -376.756492)
			(xy 161.556871 -376.689554) (xy 161.572905 -376.624066) (xy 161.596667 -376.560969) (xy 161.627816 -376.501173)
			(xy 161.665902 -376.445538) (xy 161.687764 -376.419872) (xy 161.693563 -376.412729) (xy 161.700074 -376.395536)
			(xy 161.700464 -376.386344) (xy 161.700464 -375.894092) (xy 161.700043 -375.884906) (xy 161.693535 -375.867723)
			(xy 161.687764 -375.860564) (xy 161.665933 -375.834872) (xy 161.627845 -375.779241) (xy 161.596695 -375.719448)
			(xy 161.572931 -375.656354) (xy 161.556894 -375.590869) (xy 161.548816 -375.523934) (xy 161.548814 -375.456514)
			(xy 161.556886 -375.389578) (xy 161.572917 -375.324092) (xy 161.596676 -375.260996) (xy 161.627821 -375.201201)
			(xy 161.665903 -375.145566) (xy 161.687764 -375.1199) (xy 161.693551 -375.112748) (xy 161.70007 -375.095562)
			(xy 161.700464 -375.086372) (xy 161.700464 -374.928638) (xy 161.700959 -374.918511) (xy 161.708678 -374.899786)
			(xy 161.722963 -374.885428) (xy 161.741647 -374.877611) (xy 161.751772 -374.877076) (xy 162.468052 -374.877076)
			(xy 162.478168 -374.877555) (xy 162.496866 -374.885283) (xy 162.511181 -374.89958) (xy 162.518933 -374.918268)
			(xy 162.51936 -374.928384) (xy 162.51936 -375.086372) (xy 162.519793 -375.095557) (xy 162.526292 -375.112741)
			(xy 162.53206 -375.1199) (xy 162.553957 -375.145539) (xy 162.592047 -375.201176) (xy 162.623199 -375.260976)
			(xy 162.646963 -375.324076) (xy 162.662997 -375.389569) (xy 162.671071 -375.456511) (xy 162.671068 -375.523938)
			(xy 162.662989 -375.590879) (xy 162.646949 -375.65637) (xy 162.623179 -375.719468) (xy 162.592022 -375.779265)
			(xy 162.553927 -375.834899) (xy 162.53206 -375.860564) (xy 162.526249 -375.867699) (xy 162.519744 -375.884897)
			(xy 162.51936 -375.894092) (xy 162.51936 -376.386344) (xy 162.519758 -376.395532) (xy 162.526281 -376.412716)
			(xy 162.53206 -376.419872) (xy 162.553929 -376.445533) (xy 162.592021 -376.501167) (xy 162.623173 -376.560964)
			(xy 162.646939 -376.624061) (xy 162.662975 -376.689551) (xy 162.671052 -376.756491) (xy 162.671051 -376.823855)
			(xy 165.949092 -376.823855) (xy 165.949092 -376.756551) (xy 165.957136 -376.689728) (xy 165.973109 -376.624346)
			(xy 165.996782 -376.561342) (xy 166.027815 -376.501618) (xy 166.065764 -376.446032) (xy 166.087552 -376.42038)
			(xy 166.093346 -376.413233) (xy 166.099861 -376.396044) (xy 166.100252 -376.386852) (xy 166.100252 -375.893584)
			(xy 166.099838 -375.884397) (xy 166.093326 -375.867214) (xy 166.087552 -375.860056) (xy 166.065795 -375.834378)
			(xy 166.027845 -375.778796) (xy 165.996809 -375.719076) (xy 165.973134 -375.656075) (xy 165.957159 -375.590695)
			(xy 165.949112 -375.523875) (xy 165.949109 -375.456573) (xy 165.95715 -375.389752) (xy 165.97312 -375.324371)
			(xy 165.99679 -375.261368) (xy 166.02782 -375.201646) (xy 166.065766 -375.14606) (xy 166.087552 -375.120408)
			(xy 166.093334 -375.113253) (xy 166.099856 -375.09607) (xy 166.100252 -375.08688) (xy 166.100252 -374.928638)
			(xy 166.100695 -374.918467) (xy 166.10847 -374.899671) (xy 166.12285 -374.885284) (xy 166.141643 -374.8775)
			(xy 166.151814 -374.877076) (xy 166.868094 -374.877076) (xy 166.87827 -374.87747) (xy 166.897072 -374.88526)
			(xy 166.911458 -374.899655) (xy 166.919237 -374.918462) (xy 166.919656 -374.928638) (xy 166.919656 -375.08688)
			(xy 166.920085 -375.096065) (xy 166.926587 -375.113249) (xy 166.932356 -375.120408) (xy 166.954175 -375.146034)
			(xy 166.992124 -375.201624) (xy 167.023156 -375.261351) (xy 167.046827 -375.324359) (xy 167.062798 -375.389745)
			(xy 167.07084 -375.45657) (xy 167.070837 -375.523878) (xy 167.062789 -375.590703) (xy 167.046813 -375.656087)
			(xy 167.023136 -375.719093) (xy 166.992099 -375.778817) (xy 166.954146 -375.834404) (xy 166.932356 -375.860056)
			(xy 166.926548 -375.867193) (xy 166.920041 -375.88439) (xy 166.919656 -375.893584) (xy 166.919656 -376.386852)
			(xy 166.920099 -376.396035) (xy 166.926591 -376.41322) (xy 166.932356 -376.42038) (xy 166.954148 -376.446029)
			(xy 166.992097 -376.501616) (xy 167.02313 -376.56134) (xy 167.046803 -376.624345) (xy 167.062776 -376.689727)
			(xy 167.07082 -376.75655) (xy 167.07082 -376.823856) (xy 167.070813 -376.823915) (xy 170.34886 -376.823915)
			(xy 170.34886 -376.756491) (xy 170.356936 -376.689552) (xy 170.372972 -376.624063) (xy 170.396738 -376.560966)
			(xy 170.427891 -376.50117) (xy 170.465983 -376.445536) (xy 170.487848 -376.419872) (xy 170.493645 -376.412727)
			(xy 170.500158 -376.395536) (xy 170.500548 -376.386344) (xy 170.500548 -375.894092) (xy 170.500131 -375.884906)
			(xy 170.493621 -375.867722) (xy 170.487848 -375.860564) (xy 170.466014 -375.834874) (xy 170.427921 -375.779244)
			(xy 170.396766 -375.719452) (xy 170.372998 -375.656358) (xy 170.356959 -375.590871) (xy 170.34888 -375.523935)
			(xy 170.348877 -375.456513) (xy 170.35695 -375.389576) (xy 170.372984 -375.324088) (xy 170.396747 -375.260992)
			(xy 170.427896 -375.201197) (xy 170.465984 -375.145564) (xy 170.487848 -375.1199) (xy 170.493633 -375.112747)
			(xy 170.500153 -375.095562) (xy 170.500548 -375.086372) (xy 170.500548 -374.928638) (xy 170.501058 -374.918513)
			(xy 170.508775 -374.899791) (xy 170.523054 -374.885433) (xy 170.541734 -374.877614) (xy 170.551856 -374.877076)
			(xy 171.268136 -374.877076) (xy 171.278289 -374.877492) (xy 171.297038 -374.885295) (xy 171.311359 -374.899692)
			(xy 171.319062 -374.918482) (xy 171.319444 -374.928638) (xy 171.319444 -375.086372) (xy 171.31988 -375.095556)
			(xy 171.326377 -375.11274) (xy 171.332144 -375.1199) (xy 171.354041 -375.145538) (xy 171.392133 -375.201175)
			(xy 171.423285 -375.260975) (xy 171.44705 -375.324075) (xy 171.463085 -375.389568) (xy 171.471159 -375.45651)
			(xy 171.471156 -375.523938) (xy 171.463076 -375.590879) (xy 171.447036 -375.656371) (xy 171.423266 -375.719469)
			(xy 171.392108 -375.779266) (xy 171.354012 -375.8349) (xy 171.332144 -375.860564) (xy 171.326331 -375.867697)
			(xy 171.319828 -375.884897) (xy 171.319444 -375.894092) (xy 171.319444 -376.386344) (xy 171.319845 -376.395532)
			(xy 171.326366 -376.412716) (xy 171.332144 -376.419872) (xy 171.354014 -376.445533) (xy 171.392106 -376.501167)
			(xy 171.42326 -376.560963) (xy 171.447026 -376.624061) (xy 171.463063 -376.689551) (xy 171.47114 -376.75649)
			(xy 171.47114 -376.756551) (xy 174.749179 -376.756551) (xy 174.757223 -376.689728) (xy 174.773195 -376.624346)
			(xy 174.796868 -376.561342) (xy 174.8279 -376.501619) (xy 174.865848 -376.446032) (xy 174.887636 -376.42038)
			(xy 174.893428 -376.413232) (xy 174.899945 -376.396043) (xy 174.900336 -376.386852) (xy 174.900336 -375.893584)
			(xy 174.899926 -375.884397) (xy 174.893411 -375.867213) (xy 174.887636 -375.860056) (xy 174.86588 -375.834378)
			(xy 174.82793 -375.778795) (xy 174.796896 -375.719075) (xy 174.773222 -375.656074) (xy 174.757246 -375.590695)
			(xy 174.7492 -375.523875) (xy 174.749197 -375.456573) (xy 174.757238 -375.389752) (xy 174.773207 -375.324372)
			(xy 174.796876 -375.261369) (xy 174.827906 -375.201646) (xy 174.865851 -375.14606) (xy 174.887636 -375.120408)
			(xy 174.893416 -375.113251) (xy 174.89994 -375.096069) (xy 174.900336 -375.08688) (xy 174.900336 -374.928638)
			(xy 174.900795 -374.918469) (xy 174.908567 -374.899676) (xy 174.922942 -374.88529) (xy 174.941729 -374.877503)
			(xy 174.951898 -374.877076) (xy 175.668178 -374.877076) (xy 175.678353 -374.877483) (xy 175.697154 -374.885268)
			(xy 175.711541 -374.899659) (xy 175.71932 -374.918463) (xy 175.71974 -374.928638) (xy 175.71974 -375.08688)
			(xy 175.720173 -375.096064) (xy 175.726672 -375.113248) (xy 175.73244 -375.120408) (xy 175.75426 -375.146034)
			(xy 175.792209 -375.201624) (xy 175.823242 -375.261351) (xy 175.846914 -375.324359) (xy 175.862886 -375.389744)
			(xy 175.870928 -375.45657) (xy 175.870925 -375.523878) (xy 175.862877 -375.590703) (xy 175.8469 -375.656087)
			(xy 175.823223 -375.719093) (xy 175.792185 -375.778818) (xy 175.754231 -375.834404) (xy 175.73244 -375.860056)
			(xy 175.72663 -375.867191) (xy 175.720125 -375.88439) (xy 175.71974 -375.893584) (xy 175.71974 -376.386852)
			(xy 175.720186 -376.396035) (xy 175.726676 -376.413219) (xy 175.73244 -376.42038) (xy 175.754232 -376.446029)
			(xy 175.792182 -376.501615) (xy 175.823216 -376.561339) (xy 175.84689 -376.624344) (xy 175.862863 -376.689727)
			(xy 175.870907 -376.75655) (xy 175.870907 -376.823856) (xy 175.862862 -376.890679) (xy 175.846888 -376.956062)
			(xy 175.823214 -377.019066) (xy 175.792179 -377.07879) (xy 175.754228 -377.134376) (xy 175.73244 -377.160028)
			(xy 175.726642 -377.167172) (xy 175.72013 -377.184364) (xy 175.71974 -377.193556) (xy 175.71974 -377.35129)
			(xy 175.719328 -377.361464) (xy 175.711542 -377.380262) (xy 175.697152 -377.394648) (xy 175.678352 -377.40243)
			(xy 175.668178 -377.402852) (xy 174.951898 -377.402852) (xy 174.941725 -377.402438) (xy 174.922928 -377.39465)
			(xy 174.908543 -377.380262) (xy 174.90076 -377.361463) (xy 174.900336 -377.35129) (xy 174.900336 -377.193556)
			(xy 174.899939 -377.184368) (xy 174.893415 -377.167184) (xy 174.887636 -377.160028) (xy 174.865852 -377.134373)
			(xy 174.827903 -377.078787) (xy 174.79687 -377.019063) (xy 174.773197 -376.956059) (xy 174.757224 -376.890678)
			(xy 174.74918 -376.823855) (xy 174.749179 -376.756551) (xy 171.47114 -376.756551) (xy 171.471139 -376.823916)
			(xy 171.463062 -376.890855) (xy 171.447024 -376.956345) (xy 171.423257 -377.019442) (xy 171.392103 -377.079238)
			(xy 171.35401 -377.134872) (xy 171.332144 -377.160536) (xy 171.326343 -377.167678) (xy 171.319832 -377.184871)
			(xy 171.319444 -377.194064) (xy 171.319444 -377.35129) (xy 171.318965 -377.361418) (xy 171.311237 -377.380142)
			(xy 171.296948 -377.394499) (xy 171.278262 -377.402316) (xy 171.268136 -377.402852) (xy 170.551856 -377.402852)
			(xy 170.541706 -377.402415) (xy 170.522962 -377.394615) (xy 170.508642 -377.380224) (xy 170.500935 -377.361442)
			(xy 170.500548 -377.35129) (xy 170.500548 -377.194064) (xy 170.500144 -377.184876) (xy 170.493625 -377.167693)
			(xy 170.487848 -377.160536) (xy 170.465986 -377.134868) (xy 170.427894 -377.079235) (xy 170.396741 -377.01944)
			(xy 170.372974 -376.956343) (xy 170.356937 -376.890854) (xy 170.34886 -376.823915) (xy 167.070813 -376.823915)
			(xy 167.062775 -376.890679) (xy 167.046801 -376.956061) (xy 167.023128 -377.019066) (xy 166.992094 -377.07879)
			(xy 166.954144 -377.134376) (xy 166.932356 -377.160028) (xy 166.92656 -377.167173) (xy 166.920046 -377.184364)
			(xy 166.919656 -377.193556) (xy 166.919656 -377.35129) (xy 166.919228 -377.361462) (xy 166.911445 -377.380257)
			(xy 166.897061 -377.394643) (xy 166.878266 -377.402427) (xy 166.868094 -377.402852) (xy 166.151814 -377.402852)
			(xy 166.141642 -377.402425) (xy 166.122846 -377.394642) (xy 166.10846 -377.380258) (xy 166.100676 -377.361462)
			(xy 166.100252 -377.35129) (xy 166.100252 -377.193556) (xy 166.099851 -377.184368) (xy 166.09333 -377.167185)
			(xy 166.087552 -377.160028) (xy 166.065768 -377.134373) (xy 166.027818 -377.078787) (xy 165.996784 -377.019064)
			(xy 165.97311 -376.95606) (xy 165.957137 -376.890678) (xy 165.949092 -376.823855) (xy 162.671051 -376.823855)
			(xy 162.671051 -376.823915) (xy 162.662974 -376.890855) (xy 162.646937 -376.956344) (xy 162.623171 -377.019442)
			(xy 162.592017 -377.079238) (xy 162.553926 -377.134871) (xy 162.53206 -377.160536) (xy 162.526261 -377.167679)
			(xy 162.519749 -377.184871) (xy 162.51936 -377.194064) (xy 162.51936 -377.35129) (xy 162.518865 -377.361416)
			(xy 162.511141 -377.380137) (xy 162.496857 -377.394494) (xy 162.478175 -377.402313) (xy 162.468052 -377.402852)
			(xy 161.751772 -377.402852) (xy 161.741668 -377.402339) (xy 161.722999 -377.394602) (xy 161.708707 -377.380314)
			(xy 161.700964 -377.361648) (xy 161.700464 -377.351544) (xy 161.700464 -377.194064) (xy 161.700057 -377.184877)
			(xy 161.69354 -377.167693) (xy 161.687764 -377.160536) (xy 161.665905 -377.134867) (xy 161.627819 -377.079232)
			(xy 161.59667 -377.019436) (xy 161.572907 -376.95634) (xy 161.556872 -376.890852) (xy 161.548797 -376.823914)
			(xy 161.548796 -376.756492) (xy 131.870991 -376.756492) (xy 131.870998 -376.75655) (xy 131.870998 -376.823856)
			(xy 131.862953 -376.890679) (xy 131.846979 -376.956062) (xy 131.823304 -377.019067) (xy 131.792268 -377.07879)
			(xy 131.754317 -377.134376) (xy 131.732528 -377.160028) (xy 131.726728 -377.167171) (xy 131.720218 -377.184363)
			(xy 131.719828 -377.193556) (xy 131.719828 -377.35129) (xy 131.719427 -377.361465) (xy 131.711639 -377.380266)
			(xy 131.697246 -377.394653) (xy 131.678441 -377.402432) (xy 131.668266 -377.402852) (xy 130.951986 -377.402852)
			(xy 130.941826 -377.402378) (xy 130.923055 -377.394597) (xy 130.90869 -377.380225) (xy 130.900918 -377.36145)
			(xy 130.900424 -377.35129) (xy 130.900424 -377.193556) (xy 130.90003 -377.184367) (xy 130.893504 -377.167183)
			(xy 130.887724 -377.160028) (xy 130.865941 -377.134372) (xy 130.827993 -377.078786) (xy 130.79696 -377.019063)
			(xy 130.773288 -376.956059) (xy 130.757315 -376.890677) (xy 130.749271 -376.823855) (xy 130.74927 -376.756551)
			(xy 127.471206 -376.756551) (xy 127.471205 -376.823915) (xy 127.46313 -376.890853) (xy 127.447095 -376.956342)
			(xy 127.423332 -377.019438) (xy 127.392182 -377.079235) (xy 127.354095 -377.13487) (xy 127.332232 -377.160536)
			(xy 127.326429 -377.167677) (xy 127.31992 -377.184871) (xy 127.319532 -377.194064) (xy 127.319532 -377.35129)
			(xy 127.319064 -377.36142) (xy 127.311335 -377.380146) (xy 127.297042 -377.394503) (xy 127.278351 -377.402318)
			(xy 127.268224 -377.402852) (xy 126.551944 -377.402852) (xy 126.541799 -377.402343) (xy 126.523058 -377.394572)
			(xy 126.508735 -377.380202) (xy 126.501024 -377.361436) (xy 126.500636 -377.35129) (xy 126.500636 -377.194064)
			(xy 126.500235 -377.184876) (xy 126.493714 -377.167692) (xy 126.487936 -377.160536) (xy 126.466075 -377.134868)
			(xy 126.427984 -377.079235) (xy 126.396831 -377.019439) (xy 126.373065 -376.956343) (xy 126.357028 -376.890854)
			(xy 126.348951 -376.823915) (xy 123.070903 -376.823915) (xy 123.062865 -376.890679) (xy 123.046891 -376.956062)
			(xy 123.023217 -377.019066) (xy 122.992183 -377.07879) (xy 122.954232 -377.134376) (xy 122.932444 -377.160028)
			(xy 122.926646 -377.167172) (xy 122.920134 -377.184364) (xy 122.919744 -377.193556) (xy 122.919744 -377.35129)
			(xy 122.919328 -377.361463) (xy 122.911543 -377.380261) (xy 122.897154 -377.394647) (xy 122.878355 -377.402429)
			(xy 122.868182 -377.402852) (xy 122.151902 -377.402852) (xy 122.141729 -377.402434) (xy 122.122933 -377.394648)
			(xy 122.108547 -377.380261) (xy 122.100764 -377.361463) (xy 122.10034 -377.35129) (xy 122.10034 -377.193556)
			(xy 122.099942 -377.184368) (xy 122.093419 -377.167184) (xy 122.08764 -377.160028) (xy 122.065856 -377.134373)
			(xy 122.027907 -377.078787) (xy 121.996873 -377.019064) (xy 121.9732 -376.95606) (xy 121.957227 -376.890678)
			(xy 121.949183 -376.823855) (xy 121.949182 -376.756551) (xy 118.671143 -376.756551) (xy 118.671142 -376.823916)
			(xy 118.663065 -376.890855) (xy 118.647028 -376.956345) (xy 118.623261 -377.019442) (xy 118.592107 -377.079238)
			(xy 118.554014 -377.134872) (xy 118.532148 -377.160536) (xy 118.526347 -377.167678) (xy 118.519836 -377.184871)
			(xy 118.519448 -377.194064) (xy 118.519448 -377.35129) (xy 118.518965 -377.361418) (xy 118.511238 -377.380141)
			(xy 118.496951 -377.394498) (xy 118.478265 -377.402315) (xy 118.46814 -377.402852) (xy 117.75186 -377.402852)
			(xy 117.74171 -377.402412) (xy 117.722967 -377.394613) (xy 117.708647 -377.380223) (xy 117.700939 -377.361442)
			(xy 117.700552 -377.35129) (xy 117.700552 -377.194064) (xy 117.700147 -377.184876) (xy 117.693628 -377.167693)
			(xy 117.687852 -377.160536) (xy 117.66599 -377.134868) (xy 117.627898 -377.079235) (xy 117.596744 -377.01944)
			(xy 117.572977 -376.956343) (xy 117.55694 -376.890854) (xy 117.548863 -376.823915) (xy 87.871087 -376.823915)
			(xy 87.863011 -376.890853) (xy 87.846976 -376.956342) (xy 87.823211 -377.019439) (xy 87.792061 -377.079236)
			(xy 87.753972 -377.134871) (xy 87.732108 -377.160536) (xy 87.726315 -377.167684) (xy 87.719798 -377.184872)
			(xy 87.719408 -377.194064) (xy 87.719408 -377.35129) (xy 87.718867 -377.36141) (xy 87.711151 -377.380122)
			(xy 87.696882 -377.394477) (xy 87.678217 -377.402305) (xy 87.6681 -377.402852) (xy 86.95182 -377.402852)
			(xy 86.941719 -377.4023) (xy 86.923051 -377.394578) (xy 86.908757 -377.380303) (xy 86.901013 -377.361644)
			(xy 86.900512 -377.351544) (xy 86.900512 -377.194064) (xy 86.900117 -377.184875) (xy 86.893592 -377.167691)
			(xy 86.887812 -377.160536) (xy 86.865952 -377.134868) (xy 86.827862 -377.079234) (xy 86.79671 -377.019438)
			(xy 86.772945 -376.956342) (xy 86.756909 -376.890853) (xy 86.748833 -376.823915) (xy 83.470785 -376.823915)
			(xy 83.462747 -376.89068) (xy 83.446772 -376.956063) (xy 83.423097 -377.019067) (xy 83.392061 -377.078791)
			(xy 83.354109 -377.134376) (xy 83.33232 -377.160028) (xy 83.326531 -377.167179) (xy 83.320011 -377.184365)
			(xy 83.31962 -377.193556) (xy 83.31962 -377.35129) (xy 83.319227 -377.361466) (xy 83.311438 -377.380269)
			(xy 83.297042 -377.394655) (xy 83.278234 -377.402433) (xy 83.268058 -377.402852) (xy 82.551778 -377.402852)
			(xy 82.541618 -377.402385) (xy 82.522846 -377.394601) (xy 82.508481 -377.380227) (xy 82.500709 -377.361451)
			(xy 82.500216 -377.35129) (xy 82.500216 -377.193556) (xy 82.499823 -377.184367) (xy 82.493297 -377.167183)
			(xy 82.487516 -377.160028) (xy 82.465733 -377.134372) (xy 82.427785 -377.078786) (xy 82.396753 -377.019063)
			(xy 82.373081 -376.956059) (xy 82.357109 -376.890677) (xy 82.349065 -376.823855) (xy 82.349064 -376.756551)
			(xy 79.071 -376.756551) (xy 79.070999 -376.823915) (xy 79.062924 -376.890853) (xy 79.046888 -376.956342)
			(xy 79.023125 -377.019439) (xy 78.991975 -377.079235) (xy 78.953887 -377.13487) (xy 78.932024 -377.160536)
			(xy 78.926232 -377.167685) (xy 78.919714 -377.184872) (xy 78.919324 -377.194064) (xy 78.919324 -377.35129)
			(xy 78.918864 -377.36142) (xy 78.911133 -377.380148) (xy 78.896838 -377.394506) (xy 78.878144 -377.402319)
			(xy 78.868016 -377.402852) (xy 78.151736 -377.402852) (xy 78.141636 -377.402286) (xy 78.122969 -377.39457)
			(xy 78.108674 -377.380299) (xy 78.100929 -377.361643) (xy 78.100428 -377.351544) (xy 78.100428 -377.194064)
			(xy 78.100029 -377.184876) (xy 78.093507 -377.167692) (xy 78.087728 -377.160536) (xy 78.065867 -377.134868)
			(xy 78.027776 -377.079235) (xy 77.996624 -377.019439) (xy 77.972858 -376.956342) (xy 77.956822 -376.890853)
			(xy 77.948745 -376.823915) (xy 74.670697 -376.823915) (xy 74.662659 -376.890679) (xy 74.646685 -376.956062)
			(xy 74.623011 -377.019067) (xy 74.591976 -377.07879) (xy 74.554025 -377.134376) (xy 74.532236 -377.160028)
			(xy 74.526437 -377.167171) (xy 74.519926 -377.184364) (xy 74.519536 -377.193556) (xy 74.519536 -377.35129)
			(xy 74.519127 -377.361464) (xy 74.511341 -377.380264) (xy 74.49695 -377.39465) (xy 74.478148 -377.402431)
			(xy 74.467974 -377.402852) (xy 73.751694 -377.402852) (xy 73.741521 -377.402441) (xy 73.722724 -377.394652)
			(xy 73.708339 -377.380263) (xy 73.700556 -377.361463) (xy 73.700132 -377.35129) (xy 73.700132 -377.193556)
			(xy 73.699736 -377.184367) (xy 73.693212 -377.167184) (xy 73.687432 -377.160028) (xy 73.665648 -377.134373)
			(xy 73.6277 -377.078786) (xy 73.596667 -377.019063) (xy 73.572994 -376.956059) (xy 73.557021 -376.890677)
			(xy 73.548977 -376.823855) (xy 73.548976 -376.756551) (xy 48.270947 -376.756551) (xy 48.270947 -376.823855)
			(xy 48.262903 -376.890678) (xy 48.24693 -376.95606) (xy 48.223258 -377.019064) (xy 48.192226 -377.078788)
			(xy 48.154279 -377.134375) (xy 48.132492 -377.160028) (xy 48.1267 -377.167176) (xy 48.120183 -377.184365)
			(xy 48.119792 -377.193556) (xy 48.119792 -377.351544) (xy 48.119414 -377.361702) (xy 48.111603 -377.380457)
			(xy 48.097193 -377.394779) (xy 48.07839 -377.402476) (xy 48.06823 -377.402852) (xy 47.35195 -377.402852)
			(xy 47.341825 -377.402332) (xy 47.323104 -377.394619) (xy 47.308746 -377.380343) (xy 47.300926 -377.361666)
			(xy 47.300388 -377.351544) (xy 47.300388 -377.193556) (xy 47.300002 -377.184366) (xy 47.293472 -377.167182)
			(xy 47.287688 -377.160028) (xy 47.265903 -377.134373) (xy 47.227951 -377.078788) (xy 47.196914 -377.019066)
			(xy 47.173239 -376.956061) (xy 47.157265 -376.890679) (xy 47.149219 -376.823856) (xy 43.871178 -376.823856)
			(xy 43.871178 -376.823915) (xy 43.863102 -376.890854) (xy 43.847066 -376.956343) (xy 43.823301 -377.01944)
			(xy 43.79215 -377.079236) (xy 43.75406 -377.134871) (xy 43.732196 -377.160536) (xy 43.726401 -377.167682)
			(xy 43.719886 -377.184872) (xy 43.719496 -377.194064) (xy 43.719496 -377.35129) (xy 43.718966 -377.361412)
			(xy 43.711248 -377.380126) (xy 43.696976 -377.394481) (xy 43.678307 -377.402307) (xy 43.668188 -377.402852)
			(xy 42.951908 -377.402852) (xy 42.941761 -377.402373) (xy 42.923019 -377.39459) (xy 42.908697 -377.380211)
			(xy 42.900988 -377.361439) (xy 42.9006 -377.35129) (xy 42.9006 -377.194064) (xy 42.900207 -377.184875)
			(xy 42.893682 -377.167691) (xy 42.8879 -377.160536) (xy 42.86604 -377.134868) (xy 42.827951 -377.079233)
			(xy 42.7968 -377.019438) (xy 42.773036 -376.956341) (xy 42.757 -376.890853) (xy 42.748924 -376.823915)
			(xy 39.470876 -376.823915) (xy 39.462838 -376.89068) (xy 39.446863 -376.956063) (xy 39.423187 -377.019068)
			(xy 39.39215 -377.078791) (xy 39.354198 -377.134377) (xy 39.332408 -377.160028) (xy 39.326618 -377.167178)
			(xy 39.320099 -377.184365) (xy 39.319708 -377.193556) (xy 39.319708 -377.35129) (xy 39.31916 -377.361441)
			(xy 39.311397 -377.380202) (xy 39.297049 -377.394566) (xy 39.278297 -377.402349) (xy 39.268146 -377.402852)
			(xy 38.551866 -377.402852) (xy 38.541705 -377.402394) (xy 38.522933 -377.394607) (xy 38.508569 -377.38023)
			(xy 38.500797 -377.361452) (xy 38.500304 -377.35129) (xy 38.500304 -377.193556) (xy 38.499914 -377.184367)
			(xy 38.493386 -377.167183) (xy 38.487604 -377.160028) (xy 38.465821 -377.134372) (xy 38.427875 -377.078785)
			(xy 38.396843 -377.019062) (xy 38.373172 -376.956058) (xy 38.357199 -376.890677) (xy 38.349156 -376.823855)
			(xy 38.349155 -376.756551) (xy 35.071091 -376.756551) (xy 35.07109 -376.823915) (xy 35.063014 -376.890853)
			(xy 35.046979 -376.956342) (xy 35.023215 -377.019439) (xy 34.992064 -377.079236) (xy 34.953976 -377.134871)
			(xy 34.932112 -377.160536) (xy 34.926319 -377.167684) (xy 34.919802 -377.184872) (xy 34.919412 -377.194064)
			(xy 34.919412 -377.35129) (xy 34.918867 -377.36141) (xy 34.911152 -377.380121) (xy 34.896884 -377.394476)
			(xy 34.878221 -377.402304) (xy 34.868104 -377.402852) (xy 34.151824 -377.402852) (xy 34.141678 -377.40236)
			(xy 34.122936 -377.394582) (xy 34.108614 -377.380208) (xy 34.100904 -377.361438) (xy 34.100516 -377.35129)
			(xy 34.100516 -377.194064) (xy 34.10012 -377.184875) (xy 34.093596 -377.167691) (xy 34.087816 -377.160536)
			(xy 34.065955 -377.134868) (xy 34.027866 -377.079234) (xy 33.996714 -377.019438) (xy 33.972949 -376.956342)
			(xy 33.956912 -376.890853) (xy 33.948836 -376.823915) (xy 30.670788 -376.823915) (xy 30.66275 -376.89068)
			(xy 30.646775 -376.956062) (xy 30.6231 -377.019067) (xy 30.592065 -377.078791) (xy 30.554113 -377.134376)
			(xy 30.532324 -377.160028) (xy 30.526536 -377.167179) (xy 30.520015 -377.184365) (xy 30.519624 -377.193556)
			(xy 30.519624 -377.35129) (xy 30.519227 -377.361466) (xy 30.511438 -377.380267) (xy 30.497044 -377.394654)
			(xy 30.478238 -377.402433) (xy 30.468062 -377.402852) (xy 29.751782 -377.402852) (xy 29.741622 -377.402381)
			(xy 29.72285 -377.394599) (xy 29.708485 -377.380226) (xy 29.700713 -377.36145) (xy 29.70022 -377.35129)
			(xy 29.70022 -377.193556) (xy 29.699827 -377.184367) (xy 29.693301 -377.167183) (xy 29.68752 -377.160028)
			(xy 29.665737 -377.134372) (xy 29.627789 -377.078786) (xy 29.596757 -377.019063) (xy 29.573084 -376.956059)
			(xy 29.557112 -376.890677) (xy 29.549068 -376.823855) (xy 29.549067 -376.756551) (xy 0.508 -376.756551)
			(xy 0.508 -378.323793) (xy 27.348888 -378.323793) (xy 27.34889 -378.256368) (xy 27.356968 -378.189428)
			(xy 27.373006 -378.123938) (xy 27.396772 -378.06084) (xy 27.427925 -378.001043) (xy 27.466015 -377.945408)
			(xy 27.48788 -377.919742) (xy 27.493681 -377.9126) (xy 27.500194 -377.895407) (xy 27.50058 -377.886214)
			(xy 27.50058 -377.728734) (xy 27.501056 -377.718605) (xy 27.50878 -377.699877) (xy 27.52307 -377.685518)
			(xy 27.541761 -377.677705) (xy 27.551888 -377.677172) (xy 28.268168 -377.677172) (xy 28.278285 -377.677641)
			(xy 28.296983 -377.685374) (xy 28.311297 -377.699674) (xy 28.319048 -377.718363) (xy 28.319476 -377.72848)
			(xy 28.319476 -377.886214) (xy 28.319885 -377.895401) (xy 28.3264 -377.912585) (xy 28.332176 -377.919742)
			(xy 28.354015 -377.945428) (xy 28.392106 -378.001059) (xy 28.42326 -378.060852) (xy 28.447026 -378.123946)
			(xy 28.463064 -378.189433) (xy 28.471143 -378.256369) (xy 28.471145 -378.323734) (xy 31.749183 -378.323734)
			(xy 31.749186 -378.256427) (xy 31.757233 -378.189602) (xy 31.773209 -378.124218) (xy 31.796886 -378.061212)
			(xy 31.827924 -378.001488) (xy 31.865878 -377.945902) (xy 31.887668 -377.92025) (xy 31.893477 -377.913114)
			(xy 31.899982 -377.895916) (xy 31.900368 -377.886722) (xy 31.900368 -377.728734) (xy 31.900793 -377.718561)
			(xy 31.908572 -377.699761) (xy 31.922958 -377.685374) (xy 31.941757 -377.677593) (xy 31.95193 -377.677172)
			(xy 32.66821 -377.677172) (xy 32.678386 -377.677557) (xy 32.697188 -377.685351) (xy 32.711574 -377.699749)
			(xy 32.719352 -377.718557) (xy 32.719772 -377.728734) (xy 32.719772 -377.886722) (xy 32.720178 -377.89591)
			(xy 32.726695 -377.913094) (xy 32.732472 -377.92025) (xy 32.754234 -377.945924) (xy 32.792182 -378.001507)
			(xy 32.823216 -378.061228) (xy 32.84689 -378.12423) (xy 32.862864 -378.189609) (xy 32.87091 -378.256429)
			(xy 32.870913 -378.323732) (xy 32.870906 -378.323793) (xy 36.148976 -378.323793) (xy 36.148978 -378.256368)
			(xy 36.157056 -378.189429) (xy 36.173093 -378.123939) (xy 36.196859 -378.060841) (xy 36.22801 -378.001044)
			(xy 36.2661 -377.945408) (xy 36.287964 -377.919742) (xy 36.293775 -377.912608) (xy 36.300279 -377.895409)
			(xy 36.300664 -377.886214) (xy 36.300664 -377.728734) (xy 36.301155 -377.718607) (xy 36.308876 -377.699882)
			(xy 36.323162 -377.685523) (xy 36.341847 -377.677707) (xy 36.351972 -377.677172) (xy 37.068252 -377.677172)
			(xy 37.0784 -377.67766) (xy 37.097145 -377.685435) (xy 37.11147 -377.699811) (xy 37.119176 -377.718585)
			(xy 37.11956 -377.728734) (xy 37.11956 -377.886214) (xy 37.119972 -377.895401) (xy 37.126485 -377.912585)
			(xy 37.13226 -377.919742) (xy 37.1541 -377.945428) (xy 37.192192 -378.001058) (xy 37.223346 -378.060851)
			(xy 37.247113 -378.123946) (xy 37.263152 -378.189433) (xy 37.27123 -378.256369) (xy 37.271233 -378.323792)
			(xy 37.271233 -378.323794) (xy 40.548742 -378.323794) (xy 40.548744 -378.256367) (xy 40.556824 -378.189426)
			(xy 40.572863 -378.123935) (xy 40.596633 -378.060837) (xy 40.627789 -378.00104) (xy 40.665885 -377.945406)
			(xy 40.687752 -377.919742) (xy 40.693562 -377.912607) (xy 40.700067 -377.895408) (xy 40.700452 -377.886214)
			(xy 40.700452 -377.728734) (xy 40.700955 -377.718608) (xy 40.708674 -377.699885) (xy 40.722955 -377.685528)
			(xy 40.741637 -377.677709) (xy 40.75176 -377.677172) (xy 41.46804 -377.677172) (xy 41.478193 -377.677588)
			(xy 41.496941 -377.685392) (xy 41.511262 -377.699789) (xy 41.518965 -377.718579) (xy 41.519348 -377.728734)
			(xy 41.519348 -377.886214) (xy 41.519763 -377.8954) (xy 41.526275 -377.912584) (xy 41.532048 -377.919742)
			(xy 41.553888 -377.945427) (xy 41.591981 -378.001058) (xy 41.623136 -378.060851) (xy 41.646904 -378.123945)
			(xy 41.662943 -378.189432) (xy 41.671021 -378.256369) (xy 41.671024 -378.323792) (xy 41.671024 -378.323793)
			(xy 71.348797 -378.323793) (xy 71.348799 -378.256368) (xy 71.356877 -378.189428) (xy 71.372915 -378.123937)
			(xy 71.396682 -378.060839) (xy 71.427835 -378.001042) (xy 71.465927 -377.945407) (xy 71.487792 -377.919742)
			(xy 71.493595 -377.912601) (xy 71.500106 -377.895407) (xy 71.500492 -377.886214) (xy 71.500492 -377.728734)
			(xy 71.501053 -377.718615) (xy 71.508761 -377.699904) (xy 71.523024 -377.685548) (xy 71.541685 -377.67772)
			(xy 71.5518 -377.677172) (xy 72.26808 -377.677172) (xy 72.278229 -377.677637) (xy 72.296976 -377.685421)
			(xy 72.311299 -377.699804) (xy 72.319005 -377.718583) (xy 72.319388 -377.728734) (xy 72.319388 -377.886214)
			(xy 72.319794 -377.895402) (xy 72.326311 -377.912586) (xy 72.332088 -377.919742) (xy 72.353927 -377.945428)
			(xy 72.392017 -378.001059) (xy 72.42317 -378.060853) (xy 72.446936 -378.123947) (xy 72.462973 -378.189433)
			(xy 72.471052 -378.25637) (xy 72.471054 -378.323734) (xy 75.749092 -378.323734) (xy 75.749095 -378.256427)
			(xy 75.757142 -378.189601) (xy 75.773119 -378.124217) (xy 75.796796 -378.061212) (xy 75.827835 -378.001488)
			(xy 75.86579 -377.945902) (xy 75.88758 -377.92025) (xy 75.893378 -377.913106) (xy 75.899892 -377.895915)
			(xy 75.90028 -377.886722) (xy 75.90028 -377.728734) (xy 75.900693 -377.718559) (xy 75.908474 -377.699757)
			(xy 75.922864 -377.68537) (xy 75.941667 -377.677591) (xy 75.951842 -377.677172) (xy 76.668122 -377.677172)
			(xy 76.678299 -377.677547) (xy 76.697101 -377.685345) (xy 76.711486 -377.699746) (xy 76.719264 -377.718556)
			(xy 76.719684 -377.728734) (xy 76.719684 -377.886722) (xy 76.720087 -377.89591) (xy 76.726606 -377.913094)
			(xy 76.732384 -377.92025) (xy 76.754146 -377.945923) (xy 76.792094 -378.001507) (xy 76.823127 -378.061228)
			(xy 76.8468 -378.12423) (xy 76.862774 -378.189609) (xy 76.87082 -378.256429) (xy 76.870822 -378.323732)
			(xy 76.870815 -378.323793) (xy 80.148885 -378.323793) (xy 80.148887 -378.256368) (xy 80.156965 -378.189428)
			(xy 80.173003 -378.123938) (xy 80.196769 -378.06084) (xy 80.227921 -378.001043) (xy 80.266011 -377.945408)
			(xy 80.287876 -377.919742) (xy 80.293677 -377.9126) (xy 80.30019 -377.895407) (xy 80.300576 -377.886214)
			(xy 80.300576 -377.728734) (xy 80.301056 -377.718605) (xy 80.308779 -377.699878) (xy 80.323068 -377.685519)
			(xy 80.341758 -377.677705) (xy 80.351884 -377.677172) (xy 81.068164 -377.677172) (xy 81.078281 -377.677645)
			(xy 81.096978 -377.685376) (xy 81.111293 -377.699675) (xy 81.119044 -377.718364) (xy 81.119472 -377.72848)
			(xy 81.119472 -377.886214) (xy 81.119882 -377.895401) (xy 81.126396 -377.912585) (xy 81.132172 -377.919742)
			(xy 81.154011 -377.945428) (xy 81.192103 -378.001059) (xy 81.223256 -378.060852) (xy 81.247023 -378.123946)
			(xy 81.263061 -378.189433) (xy 81.27114 -378.256369) (xy 81.271142 -378.323792) (xy 81.271142 -378.323793)
			(xy 84.548676 -378.323793) (xy 84.548678 -378.256368) (xy 84.556756 -378.189429) (xy 84.572793 -378.123939)
			(xy 84.596559 -378.060841) (xy 84.62771 -378.001044) (xy 84.6658 -377.945408) (xy 84.687664 -377.919742)
			(xy 84.693475 -377.912608) (xy 84.699979 -377.895409) (xy 84.700364 -377.886214) (xy 84.700364 -377.728734)
			(xy 84.700855 -377.718607) (xy 84.708576 -377.699882) (xy 84.722862 -377.685523) (xy 84.741547 -377.677707)
			(xy 84.751672 -377.677172) (xy 85.467952 -377.677172) (xy 85.478068 -377.677655) (xy 85.496765 -377.685382)
			(xy 85.51108 -377.699678) (xy 85.518832 -377.718365) (xy 85.51926 -377.72848) (xy 85.51926 -377.886214)
			(xy 85.519672 -377.895401) (xy 85.526185 -377.912585) (xy 85.53196 -377.919742) (xy 85.5538 -377.945428)
			(xy 85.591892 -378.001058) (xy 85.623046 -378.060851) (xy 85.646813 -378.123946) (xy 85.662852 -378.189433)
			(xy 85.67093 -378.256369) (xy 85.670933 -378.323734) (xy 115.349234 -378.323734) (xy 115.349237 -378.256427)
			(xy 115.357283 -378.189603) (xy 115.373258 -378.12422) (xy 115.396932 -378.061215) (xy 115.427966 -378.00149)
			(xy 115.465916 -377.945903) (xy 115.487704 -377.92025) (xy 115.493505 -377.913108) (xy 115.500017 -377.895915)
			(xy 115.500404 -377.886722) (xy 115.500404 -377.728734) (xy 115.500961 -377.718583) (xy 115.508717 -377.699821)
			(xy 115.523064 -377.685456) (xy 115.541815 -377.677674) (xy 115.551966 -377.677172) (xy 116.268246 -377.677172)
			(xy 116.278411 -377.677597) (xy 116.297188 -377.685393) (xy 116.311552 -377.69978) (xy 116.319319 -377.718568)
			(xy 116.319808 -377.728734) (xy 116.319808 -377.886722) (xy 116.320206 -377.895911) (xy 116.326728 -377.913095)
			(xy 116.332508 -377.92025) (xy 116.354272 -377.945922) (xy 116.392225 -378.001505) (xy 116.423262 -378.061225)
			(xy 116.446939 -378.124227) (xy 116.462915 -378.189607) (xy 116.470962 -378.256428) (xy 116.470964 -378.323732)
			(xy 116.470957 -378.323793) (xy 119.749003 -378.323793) (xy 119.749005 -378.256368) (xy 119.757084 -378.189428)
			(xy 119.773122 -378.123937) (xy 119.796889 -378.060839) (xy 119.828043 -378.001042) (xy 119.866134 -377.945407)
			(xy 119.888 -377.919742) (xy 119.893804 -377.912602) (xy 119.900314 -377.895407) (xy 119.9007 -377.886214)
			(xy 119.9007 -377.728734) (xy 119.901253 -377.718614) (xy 119.908963 -377.699902) (xy 119.923228 -377.685546)
			(xy 119.941892 -377.677718) (xy 119.952008 -377.677172) (xy 120.668288 -377.677172) (xy 120.678438 -377.677631)
			(xy 120.697185 -377.685417) (xy 120.711507 -377.699802) (xy 120.719213 -377.718582) (xy 120.719596 -377.728734)
			(xy 120.719596 -377.886214) (xy 120.72 -377.895402) (xy 120.726518 -377.912586) (xy 120.732296 -377.919742)
			(xy 120.754135 -377.945428) (xy 120.792224 -378.00106) (xy 120.823376 -378.060853) (xy 120.847142 -378.123947)
			(xy 120.86318 -378.189434) (xy 120.871258 -378.25637) (xy 120.87126 -378.323734) (xy 124.149298 -378.323734)
			(xy 124.149301 -378.256426) (xy 124.157348 -378.189601) (xy 124.173325 -378.124217) (xy 124.197003 -378.061211)
			(xy 124.228042 -378.001487) (xy 124.265997 -377.945902) (xy 124.287788 -377.92025) (xy 124.293587 -377.913106)
			(xy 124.300101 -377.895915) (xy 124.300488 -377.886722) (xy 124.300488 -377.728734) (xy 124.300893 -377.718558)
			(xy 124.308676 -377.699755) (xy 124.323068 -377.685367) (xy 124.341874 -377.67759) (xy 124.35205 -377.677172)
			(xy 125.06833 -377.677172) (xy 125.078508 -377.67754) (xy 125.09731 -377.685341) (xy 125.111695 -377.699744)
			(xy 125.119473 -377.718556) (xy 125.119892 -377.728734) (xy 125.119892 -377.886722) (xy 125.120293 -377.89591)
			(xy 125.126813 -377.913094) (xy 125.132592 -377.92025) (xy 125.154353 -377.945924) (xy 125.192301 -378.001508)
			(xy 125.223334 -378.061229) (xy 125.247006 -378.12423) (xy 125.26298 -378.189609) (xy 125.271026 -378.256429)
			(xy 125.271028 -378.323732) (xy 125.271028 -378.323734) (xy 128.549089 -378.323734) (xy 128.549092 -378.256427)
			(xy 128.557139 -378.189602) (xy 128.573116 -378.124218) (xy 128.596793 -378.061212) (xy 128.627831 -378.001488)
			(xy 128.665786 -377.945902) (xy 128.687576 -377.92025) (xy 128.693374 -377.913105) (xy 128.699888 -377.895915)
			(xy 128.700276 -377.886722) (xy 128.700276 -377.728734) (xy 128.700693 -377.71856) (xy 128.708474 -377.699759)
			(xy 128.722862 -377.685371) (xy 128.741664 -377.677592) (xy 128.751838 -377.677172) (xy 129.468118 -377.677172)
			(xy 129.478295 -377.67755) (xy 129.497097 -377.685347) (xy 129.511482 -377.699747) (xy 129.51926 -377.718557)
			(xy 129.51968 -377.728734) (xy 129.51968 -377.886722) (xy 129.520084 -377.89591) (xy 129.526602 -377.913094)
			(xy 129.53238 -377.92025) (xy 129.554142 -377.945923) (xy 129.59209 -378.001507) (xy 129.623123 -378.061228)
			(xy 129.646797 -378.12423) (xy 129.662771 -378.189609) (xy 129.670817 -378.256429) (xy 129.670819 -378.323732)
			(xy 129.670819 -378.323734) (xy 159.349143 -378.323734) (xy 159.349146 -378.256427) (xy 159.357192 -378.189603)
			(xy 159.373167 -378.12422) (xy 159.396842 -378.061214) (xy 159.427877 -378.00149) (xy 159.465827 -377.945902)
			(xy 159.487616 -377.92025) (xy 159.493418 -377.913109) (xy 159.499929 -377.895915) (xy 159.500316 -377.886722)
			(xy 159.500316 -377.728734) (xy 159.500791 -377.718567) (xy 159.508561 -377.699778) (xy 159.522931 -377.685392)
			(xy 159.541712 -377.677602) (xy 159.551878 -377.677172) (xy 160.268158 -377.677172) (xy 160.278331 -377.677599)
			(xy 160.297131 -377.685377) (xy 160.311519 -377.699762) (xy 160.319299 -377.718561) (xy 160.31972 -377.728734)
			(xy 160.31972 -377.886722) (xy 160.320115 -377.895911) (xy 160.326639 -377.913095) (xy 160.33242 -377.92025)
			(xy 160.354183 -377.945923) (xy 160.392136 -378.001505) (xy 160.423172 -378.061226) (xy 160.446848 -378.124227)
			(xy 160.462824 -378.189608) (xy 160.470871 -378.256429) (xy 160.470874 -378.323732) (xy 160.470867 -378.323793)
			(xy 163.748912 -378.323793) (xy 163.748914 -378.256367) (xy 163.756993 -378.189427) (xy 163.773031 -378.123937)
			(xy 163.796799 -378.060839) (xy 163.827953 -378.001042) (xy 163.866046 -377.945407) (xy 163.887912 -377.919742)
			(xy 163.893717 -377.912603) (xy 163.900226 -377.895408) (xy 163.900612 -377.886214) (xy 163.900612 -377.728734)
			(xy 163.901154 -377.718613) (xy 163.908865 -377.699898) (xy 163.923134 -377.685542) (xy 163.941802 -377.677716)
			(xy 163.95192 -377.677172) (xy 164.6682 -377.677172) (xy 164.678351 -377.677621) (xy 164.697098 -377.685411)
			(xy 164.71142 -377.699799) (xy 164.719125 -377.718582) (xy 164.719508 -377.728734) (xy 164.719508 -377.886214)
			(xy 164.71991 -377.895402) (xy 164.726429 -377.912586) (xy 164.732208 -377.919742) (xy 164.754046 -377.945428)
			(xy 164.792135 -378.00106) (xy 164.823286 -378.060853) (xy 164.847052 -378.123948) (xy 164.863089 -378.189434)
			(xy 164.871167 -378.25637) (xy 164.871169 -378.323734) (xy 168.149231 -378.323734) (xy 168.149234 -378.256427)
			(xy 168.15728 -378.189604) (xy 168.173254 -378.12422) (xy 168.196928 -378.061215) (xy 168.227963 -378.00149)
			(xy 168.265912 -377.945903) (xy 168.2877 -377.92025) (xy 168.2935 -377.913107) (xy 168.300013 -377.895915)
			(xy 168.3004 -377.886722) (xy 168.3004 -377.728734) (xy 168.30096 -377.718583) (xy 168.308717 -377.699822)
			(xy 168.323062 -377.685457) (xy 168.341812 -377.677675) (xy 168.351962 -377.677172) (xy 169.068242 -377.677172)
			(xy 169.078407 -377.6776) (xy 169.097183 -377.685394) (xy 169.111548 -377.699781) (xy 169.119315 -377.718569)
			(xy 169.119804 -377.728734) (xy 169.119804 -377.886722) (xy 169.120203 -377.89591) (xy 169.126724 -377.913095)
			(xy 169.132504 -377.92025) (xy 169.154265 -377.945924) (xy 169.192212 -378.001508) (xy 169.223244 -378.061229)
			(xy 169.246916 -378.124231) (xy 169.26289 -378.18961) (xy 169.270935 -378.256429) (xy 169.270937 -378.323732)
			(xy 169.270937 -378.323734) (xy 172.548998 -378.323734) (xy 172.549001 -378.256426) (xy 172.557048 -378.189601)
			(xy 172.573025 -378.124217) (xy 172.596703 -378.061211) (xy 172.627742 -378.001487) (xy 172.665697 -377.945902)
			(xy 172.687488 -377.92025) (xy 172.693287 -377.913106) (xy 172.699801 -377.895915) (xy 172.700188 -377.886722)
			(xy 172.700188 -377.728734) (xy 172.700593 -377.718558) (xy 172.708376 -377.699755) (xy 172.722768 -377.685367)
			(xy 172.741574 -377.67759) (xy 172.75175 -377.677172) (xy 173.46803 -377.677172) (xy 173.478208 -377.67754)
			(xy 173.49701 -377.685341) (xy 173.511395 -377.699744) (xy 173.519173 -377.718556) (xy 173.519592 -377.728734)
			(xy 173.519592 -377.886722) (xy 173.519993 -377.89591) (xy 173.526513 -377.913094) (xy 173.532292 -377.92025)
			(xy 173.554053 -377.945924) (xy 173.592001 -378.001508) (xy 173.623034 -378.061229) (xy 173.646706 -378.12423)
			(xy 173.66268 -378.189609) (xy 173.670726 -378.256429) (xy 173.670728 -378.323732) (xy 173.662687 -378.390552)
			(xy 173.646718 -378.455932) (xy 173.623049 -378.518936) (xy 173.592021 -378.578659) (xy 173.554077 -378.634245)
			(xy 173.532292 -378.659898) (xy 173.526513 -378.667056) (xy 173.519988 -378.684237) (xy 173.519592 -378.693426)
			(xy 173.519592 -378.766811) (xy 193.48983 -378.766811) (xy 193.48983 -378.633249) (xy 193.497894 -378.499931)
			(xy 193.513994 -378.367343) (xy 193.538069 -378.235969) (xy 193.570032 -378.106288) (xy 193.609767 -377.978774)
			(xy 193.657129 -377.853891) (xy 193.711944 -377.732096) (xy 193.774014 -377.613833) (xy 193.84311 -377.499534)
			(xy 193.918982 -377.389614) (xy 194.001352 -377.284477) (xy 194.08992 -377.184504) (xy 194.184362 -377.090062)
			(xy 194.284335 -377.001494) (xy 194.389472 -376.919124) (xy 194.499392 -376.843252) (xy 194.613691 -376.774156)
			(xy 194.731954 -376.712086) (xy 194.853749 -376.657271) (xy 194.978632 -376.609909) (xy 195.106146 -376.570174)
			(xy 195.235827 -376.538211) (xy 195.367201 -376.514136) (xy 195.499789 -376.498036) (xy 195.633107 -376.489972)
			(xy 195.766669 -376.489972) (xy 195.899987 -376.498036) (xy 196.032575 -376.514136) (xy 196.163949 -376.538211)
			(xy 196.29363 -376.570174) (xy 196.421144 -376.609909) (xy 196.546027 -376.657271) (xy 196.667822 -376.712086)
			(xy 196.786085 -376.774156) (xy 196.900384 -376.843252) (xy 197.010304 -376.919124) (xy 197.115441 -377.001494)
			(xy 197.215414 -377.090062) (xy 197.309856 -377.184504) (xy 197.398424 -377.284477) (xy 197.480794 -377.389614)
			(xy 197.556666 -377.499534) (xy 197.625762 -377.613833) (xy 197.687832 -377.732096) (xy 197.742647 -377.853891)
			(xy 197.790009 -377.978774) (xy 197.829744 -378.106288) (xy 197.861707 -378.235969) (xy 197.885782 -378.367343)
			(xy 197.901882 -378.499931) (xy 197.909946 -378.633249) (xy 197.91045 -378.70003) (xy 197.909946 -378.766811)
			(xy 197.901882 -378.900129) (xy 197.885782 -379.032717) (xy 197.861707 -379.164091) (xy 197.829744 -379.293772)
			(xy 197.790009 -379.421286) (xy 197.742647 -379.546169) (xy 197.687832 -379.667964) (xy 197.625762 -379.786227)
			(xy 197.556666 -379.900526) (xy 197.480794 -380.010446) (xy 197.398424 -380.115583) (xy 197.309856 -380.215556)
			(xy 197.215414 -380.309998) (xy 197.115441 -380.398566) (xy 197.010304 -380.480936) (xy 196.900384 -380.556808)
			(xy 196.786085 -380.625904) (xy 196.667822 -380.687974) (xy 196.546027 -380.742789) (xy 196.421144 -380.790151)
			(xy 196.29363 -380.829886) (xy 196.163949 -380.861849) (xy 196.032575 -380.885924) (xy 195.899987 -380.902024)
			(xy 195.766669 -380.910088) (xy 195.633107 -380.910088) (xy 195.499789 -380.902024) (xy 195.367201 -380.885924)
			(xy 195.235827 -380.861849) (xy 195.106146 -380.829886) (xy 194.978632 -380.790151) (xy 194.853749 -380.742789)
			(xy 194.731954 -380.687974) (xy 194.613691 -380.625904) (xy 194.499392 -380.556808) (xy 194.389472 -380.480936)
			(xy 194.284335 -380.398566) (xy 194.184362 -380.309998) (xy 194.08992 -380.215556) (xy 194.001352 -380.115583)
			(xy 193.918982 -380.010446) (xy 193.84311 -379.900526) (xy 193.774014 -379.786227) (xy 193.711944 -379.667964)
			(xy 193.657129 -379.546169) (xy 193.609767 -379.421286) (xy 193.570032 -379.293772) (xy 193.538069 -379.164091)
			(xy 193.513994 -379.032717) (xy 193.497894 -378.900129) (xy 193.48983 -378.766811) (xy 173.519592 -378.766811)
			(xy 173.519592 -379.186694) (xy 173.520007 -379.195881) (xy 173.526518 -379.213065) (xy 173.532292 -379.220222)
			(xy 173.554124 -379.245837) (xy 173.592069 -379.30143) (xy 173.623099 -379.361159) (xy 173.646768 -379.424168)
			(xy 173.662737 -379.489554) (xy 173.670777 -379.556381) (xy 173.670772 -379.623689) (xy 173.662724 -379.690514)
			(xy 173.646747 -379.755898) (xy 173.623071 -379.818905) (xy 173.592034 -379.87863) (xy 173.554082 -379.934217)
			(xy 173.532292 -379.95987) (xy 173.526482 -379.967006) (xy 173.519976 -379.984204) (xy 173.519592 -379.993398)
			(xy 173.519592 -380.151386) (xy 173.519056 -380.161539) (xy 173.511292 -380.180302) (xy 173.496939 -380.194667)
			(xy 173.478183 -380.202447) (xy 173.46803 -380.202948) (xy 172.75175 -380.202948) (xy 172.74158 -380.202495)
			(xy 172.722784 -380.194724) (xy 172.708396 -380.180347) (xy 172.700612 -380.161556) (xy 172.700188 -380.151386)
			(xy 172.700188 -379.993398) (xy 172.699781 -379.98421) (xy 172.693266 -379.967026) (xy 172.687488 -379.95987)
			(xy 172.665744 -379.934181) (xy 172.627791 -379.878601) (xy 172.596753 -379.818883) (xy 172.573075 -379.755883)
			(xy 172.557097 -379.690505) (xy 172.549049 -379.623686) (xy 172.549045 -379.556383) (xy 172.557085 -379.489563)
			(xy 172.573055 -379.424183) (xy 172.596724 -379.36118) (xy 172.627755 -379.301458) (xy 172.665702 -379.245873)
			(xy 172.687488 -379.220222) (xy 172.693299 -379.213087) (xy 172.699805 -379.195889) (xy 172.700188 -379.186694)
			(xy 172.700188 -378.693426) (xy 172.699768 -378.68424) (xy 172.693262 -378.667055) (xy 172.687488 -378.659898)
			(xy 172.665673 -378.634268) (xy 172.627722 -378.578679) (xy 172.596687 -378.518953) (xy 172.573014 -378.455946)
			(xy 172.557041 -378.39056) (xy 172.548998 -378.323734) (xy 169.270937 -378.323734) (xy 169.262897 -378.390552)
			(xy 169.246928 -378.455932) (xy 169.22326 -378.518935) (xy 169.192232 -378.578658) (xy 169.154289 -378.634245)
			(xy 169.132504 -378.659898) (xy 169.126726 -378.667057) (xy 169.1202 -378.684237) (xy 169.119804 -378.693426)
			(xy 169.119804 -379.186694) (xy 169.120216 -379.195881) (xy 169.126728 -379.213065) (xy 169.132504 -379.220222)
			(xy 169.154336 -379.245838) (xy 169.19228 -379.30143) (xy 169.223309 -379.361159) (xy 169.246977 -379.424169)
			(xy 169.262946 -379.489555) (xy 169.270986 -379.556381) (xy 169.270982 -379.623689) (xy 169.262933 -379.690513)
			(xy 169.246957 -379.755898) (xy 169.223281 -379.818904) (xy 169.192245 -379.878629) (xy 169.154293 -379.934217)
			(xy 169.132504 -379.95987) (xy 169.126696 -379.967007) (xy 169.120188 -379.984204) (xy 169.119804 -379.993398)
			(xy 169.119804 -380.151386) (xy 169.119256 -380.161538) (xy 169.111494 -380.180299) (xy 169.097146 -380.194663)
			(xy 169.078393 -380.202445) (xy 169.068242 -380.202948) (xy 168.351962 -380.202948) (xy 168.3418 -380.202497)
			(xy 168.323027 -380.194708) (xy 168.308663 -380.180329) (xy 168.300892 -380.161548) (xy 168.3004 -380.151386)
			(xy 168.3004 -379.993398) (xy 168.299991 -379.984211) (xy 168.293476 -379.967026) (xy 168.2877 -379.95987)
			(xy 168.265959 -379.93418) (xy 168.228011 -379.878598) (xy 168.196978 -379.818879) (xy 168.173304 -379.75588)
			(xy 168.157329 -379.690503) (xy 168.149282 -379.623685) (xy 168.149278 -379.556384) (xy 168.157317 -379.489565)
			(xy 168.173284 -379.424186) (xy 168.19695 -379.361184) (xy 168.227975 -379.301461) (xy 168.265916 -379.245875)
			(xy 168.2877 -379.220222) (xy 168.293512 -379.213088) (xy 168.300018 -379.195889) (xy 168.3004 -379.186694)
			(xy 168.3004 -378.693426) (xy 168.299977 -378.68424) (xy 168.293472 -378.667056) (xy 168.2877 -378.659898)
			(xy 168.265888 -378.634266) (xy 168.227942 -378.578676) (xy 168.196912 -378.518949) (xy 168.173243 -378.455942)
			(xy 168.157273 -378.390558) (xy 168.149231 -378.323734) (xy 164.871169 -378.323734) (xy 164.871169 -378.323791)
			(xy 164.863096 -378.390728) (xy 164.847063 -378.456215) (xy 164.823302 -378.519311) (xy 164.792155 -378.579106)
			(xy 164.75407 -378.634741) (xy 164.732208 -378.660406) (xy 164.726427 -378.667563) (xy 164.719903 -378.684744)
			(xy 164.719508 -378.693934) (xy 164.719508 -379.186186) (xy 164.719923 -379.195373) (xy 164.726433 -379.212557)
			(xy 164.732208 -379.219714) (xy 164.754117 -379.245342) (xy 164.792204 -379.300982) (xy 164.823352 -379.360784)
			(xy 164.847113 -379.423885) (xy 164.863145 -379.489379) (xy 164.871217 -379.556321) (xy 164.871213 -379.623748)
			(xy 164.863133 -379.690689) (xy 164.847093 -379.756181) (xy 164.823324 -379.81928) (xy 164.792168 -379.879077)
			(xy 164.754074 -379.934713) (xy 164.732208 -379.960378) (xy 164.726397 -379.967513) (xy 164.719891 -379.984711)
			(xy 164.719508 -379.993906) (xy 164.719508 -380.151386) (xy 164.718963 -380.161506) (xy 164.711249 -380.180218)
			(xy 164.696981 -380.194573) (xy 164.678317 -380.202401) (xy 164.6682 -380.202948) (xy 163.95192 -380.202948)
			(xy 163.941773 -380.202463) (xy 163.92303 -380.194683) (xy 163.908708 -380.180306) (xy 163.900999 -380.161534)
			(xy 163.900612 -380.151386) (xy 163.900612 -379.993906) (xy 163.900196 -379.98472) (xy 163.893686 -379.967535)
			(xy 163.887912 -379.960378) (xy 163.866093 -379.934676) (xy 163.828002 -379.879047) (xy 163.796849 -379.819256)
			(xy 163.773081 -379.756164) (xy 163.757042 -379.690679) (xy 163.748963 -379.623745) (xy 163.748958 -379.556324)
			(xy 163.75703 -379.489389) (xy 163.773061 -379.423902) (xy 163.79682 -379.360807) (xy 163.827966 -379.301013)
			(xy 163.86605 -379.245379) (xy 163.887912 -379.219714) (xy 163.893729 -379.212583) (xy 163.900231 -379.195382)
			(xy 163.900612 -379.186186) (xy 163.900612 -378.693934) (xy 163.900183 -378.684749) (xy 163.893682 -378.667565)
			(xy 163.887912 -378.660406) (xy 163.866022 -378.634762) (xy 163.827933 -378.579125) (xy 163.796783 -378.519326)
			(xy 163.77302 -378.456226) (xy 163.756986 -378.390734) (xy 163.748912 -378.323793) (xy 160.470867 -378.323793)
			(xy 160.462831 -378.390554) (xy 160.44686 -378.455935) (xy 160.423188 -378.518939) (xy 160.392156 -378.578661)
			(xy 160.354207 -378.634246) (xy 160.33242 -378.659898) (xy 160.326644 -378.667058) (xy 160.320116 -378.684237)
			(xy 160.31972 -378.693426) (xy 160.31972 -379.186694) (xy 160.320129 -379.195881) (xy 160.326643 -379.213066)
			(xy 160.33242 -379.220222) (xy 160.354254 -379.245836) (xy 160.392205 -379.301427) (xy 160.423238 -379.361156)
			(xy 160.44691 -379.424165) (xy 160.462881 -379.489552) (xy 160.470922 -379.55638) (xy 160.470918 -379.623689)
			(xy 160.462869 -379.690516) (xy 160.44689 -379.755901) (xy 160.42321 -379.818908) (xy 160.392169 -379.878632)
			(xy 160.354212 -379.934219) (xy 160.33242 -379.95987) (xy 160.326614 -379.967008) (xy 160.320104 -379.984204)
			(xy 160.31972 -379.993398) (xy 160.31972 -380.151386) (xy 160.319324 -380.161562) (xy 160.311536 -380.180364)
			(xy 160.297141 -380.194751) (xy 160.278334 -380.202529) (xy 160.268158 -380.202948) (xy 159.551878 -380.202948)
			(xy 159.541717 -380.202484) (xy 159.522945 -380.1947) (xy 159.50858 -380.180325) (xy 159.500808 -380.161547)
			(xy 159.500316 -380.151386) (xy 159.500316 -379.993398) (xy 159.499903 -379.984211) (xy 159.493391 -379.967027)
			(xy 159.487616 -379.95987) (xy 159.465874 -379.93418) (xy 159.427926 -379.878599) (xy 159.396892 -379.81888)
			(xy 159.373217 -379.75588) (xy 159.357242 -379.690503) (xy 159.349195 -379.623685) (xy 159.34919 -379.556384)
			(xy 159.35723 -379.489565) (xy 159.373197 -379.424186) (xy 159.396864 -379.361183) (xy 159.42789 -379.301461)
			(xy 159.465832 -379.245875) (xy 159.487616 -379.220222) (xy 159.49343 -379.213089) (xy 159.499934 -379.195889)
			(xy 159.500316 -379.186694) (xy 159.500316 -378.693426) (xy 159.49989 -378.684241) (xy 159.493387 -378.667056)
			(xy 159.487616 -378.659898) (xy 159.465803 -378.634267) (xy 159.427857 -378.578677) (xy 159.396826 -378.51895)
			(xy 159.373156 -378.455943) (xy 159.357185 -378.390558) (xy 159.349143 -378.323734) (xy 129.670819 -378.323734)
			(xy 129.662778 -378.390552) (xy 129.646808 -378.455933) (xy 129.623139 -378.518936) (xy 129.59211 -378.578659)
			(xy 129.554166 -378.634246) (xy 129.53238 -378.659898) (xy 129.526599 -378.667054) (xy 129.520076 -378.684236)
			(xy 129.51968 -378.693426) (xy 129.51968 -379.186694) (xy 129.520098 -379.19588) (xy 129.526607 -379.213064)
			(xy 129.53238 -379.220222) (xy 129.554212 -379.245837) (xy 129.592159 -379.301429) (xy 129.623189 -379.361158)
			(xy 129.646858 -379.424168) (xy 129.662827 -379.489554) (xy 129.670868 -379.55638) (xy 129.670863 -379.623689)
			(xy 129.662815 -379.690514) (xy 129.646838 -379.755899) (xy 129.623161 -379.818905) (xy 129.592123 -379.87863)
			(xy 129.55417 -379.934218) (xy 129.53238 -379.95987) (xy 129.526569 -379.967005) (xy 129.520064 -379.984203)
			(xy 129.51968 -379.993398) (xy 129.51968 -380.151386) (xy 129.519156 -380.161541) (xy 129.511389 -380.180306)
			(xy 129.497033 -380.194671) (xy 129.478272 -380.202449) (xy 129.468118 -380.202948) (xy 128.751838 -380.202948)
			(xy 128.741667 -380.202505) (xy 128.722871 -380.19473) (xy 128.708484 -380.18035) (xy 128.7007 -380.161557)
			(xy 128.700276 -380.151386) (xy 128.700276 -379.993398) (xy 128.699872 -379.98421) (xy 128.693355 -379.967025)
			(xy 128.687576 -379.95987) (xy 128.665832 -379.934181) (xy 128.62788 -379.878601) (xy 128.596842 -379.818883)
			(xy 128.573165 -379.755883) (xy 128.557188 -379.690505) (xy 128.54914 -379.623686) (xy 128.549136 -379.556384)
			(xy 128.557176 -379.489563) (xy 128.573145 -379.424183) (xy 128.596814 -379.361181) (xy 128.627844 -379.301459)
			(xy 128.66579 -379.245874) (xy 128.687576 -379.220222) (xy 128.693385 -379.213086) (xy 128.699893 -379.195889)
			(xy 128.700276 -379.186694) (xy 128.700276 -378.693426) (xy 128.699859 -378.684239) (xy 128.693351 -378.667055)
			(xy 128.687576 -378.659898) (xy 128.665762 -378.634267) (xy 128.627811 -378.578679) (xy 128.596777 -378.518952)
			(xy 128.573104 -378.455945) (xy 128.557132 -378.39056) (xy 128.549089 -378.323734) (xy 125.271028 -378.323734)
			(xy 125.262987 -378.390552) (xy 125.247018 -378.455932) (xy 125.223349 -378.518936) (xy 125.192321 -378.578659)
			(xy 125.154377 -378.634245) (xy 125.132592 -378.659898) (xy 125.126813 -378.667056) (xy 125.120288 -378.684237)
			(xy 125.119892 -378.693426) (xy 125.119892 -379.186694) (xy 125.120307 -379.195881) (xy 125.126818 -379.213065)
			(xy 125.132592 -379.220222) (xy 125.154424 -379.245837) (xy 125.192369 -379.30143) (xy 125.223399 -379.361159)
			(xy 125.247068 -379.424168) (xy 125.263037 -379.489554) (xy 125.271077 -379.556381) (xy 125.271072 -379.623689)
			(xy 125.263024 -379.690514) (xy 125.247047 -379.755898) (xy 125.223371 -379.818905) (xy 125.192334 -379.87863)
			(xy 125.154382 -379.934217) (xy 125.132592 -379.95987) (xy 125.126782 -379.967006) (xy 125.120276 -379.984204)
			(xy 125.119892 -379.993398) (xy 125.119892 -380.151386) (xy 125.119356 -380.161539) (xy 125.111592 -380.180302)
			(xy 125.097239 -380.194667) (xy 125.078483 -380.202447) (xy 125.06833 -380.202948) (xy 124.35205 -380.202948)
			(xy 124.34188 -380.202495) (xy 124.323084 -380.194724) (xy 124.308696 -380.180347) (xy 124.300912 -380.161556)
			(xy 124.300488 -380.151386) (xy 124.300488 -379.993398) (xy 124.300081 -379.98421) (xy 124.293566 -379.967026)
			(xy 124.287788 -379.95987) (xy 124.266044 -379.934181) (xy 124.228091 -379.878601) (xy 124.197053 -379.818883)
			(xy 124.173375 -379.755883) (xy 124.157397 -379.690505) (xy 124.149349 -379.623686) (xy 124.149345 -379.556383)
			(xy 124.157385 -379.489563) (xy 124.173355 -379.424183) (xy 124.197024 -379.36118) (xy 124.228055 -379.301458)
			(xy 124.266002 -379.245873) (xy 124.287788 -379.220222) (xy 124.293599 -379.213087) (xy 124.300105 -379.195889)
			(xy 124.300488 -379.186694) (xy 124.300488 -378.693426) (xy 124.300068 -378.68424) (xy 124.293562 -378.667055)
			(xy 124.287788 -378.659898) (xy 124.265973 -378.634268) (xy 124.228022 -378.578679) (xy 124.196987 -378.518953)
			(xy 124.173314 -378.455946) (xy 124.157341 -378.39056) (xy 124.149298 -378.323734) (xy 120.87126 -378.323734)
			(xy 120.87126 -378.323791) (xy 120.863187 -378.390728) (xy 120.847154 -378.456216) (xy 120.823392 -378.519311)
			(xy 120.792244 -378.579107) (xy 120.754159 -378.634741) (xy 120.732296 -378.660406) (xy 120.726514 -378.667561)
			(xy 120.719991 -378.684744) (xy 120.719596 -378.693934) (xy 120.719596 -379.186186) (xy 120.720014 -379.195372)
			(xy 120.726522 -379.212557) (xy 120.732296 -379.219714) (xy 120.754205 -379.245342) (xy 120.792293 -379.300982)
			(xy 120.823442 -379.360783) (xy 120.847204 -379.423885) (xy 120.863236 -379.489378) (xy 120.871308 -379.556321)
			(xy 120.871304 -379.623748) (xy 120.863224 -379.69069) (xy 120.847183 -379.756181) (xy 120.823414 -379.81928)
			(xy 120.792257 -379.879078) (xy 120.754163 -379.934713) (xy 120.732296 -379.960378) (xy 120.726483 -379.967512)
			(xy 120.719978 -379.984711) (xy 120.719596 -379.993906) (xy 120.719596 -380.151386) (xy 120.719063 -380.161507)
			(xy 120.711347 -380.180221) (xy 120.697075 -380.194577) (xy 120.678406 -380.202403) (xy 120.668288 -380.202948)
			(xy 119.952008 -380.202948) (xy 119.94186 -380.202473) (xy 119.923117 -380.194689) (xy 119.908795 -380.180309)
			(xy 119.901087 -380.161535) (xy 119.9007 -380.151386) (xy 119.9007 -379.993906) (xy 119.900287 -379.984719)
			(xy 119.893775 -379.967535) (xy 119.888 -379.960378) (xy 119.866181 -379.934675) (xy 119.828091 -379.879046)
			(xy 119.796938 -379.819255) (xy 119.773172 -379.756163) (xy 119.757133 -379.690679) (xy 119.749053 -379.623745)
			(xy 119.749049 -379.556325) (xy 119.757121 -379.489389) (xy 119.773151 -379.423903) (xy 119.79691 -379.360808)
			(xy 119.828056 -379.301013) (xy 119.866139 -379.245379) (xy 119.888 -379.219714) (xy 119.893816 -379.212582)
			(xy 119.900319 -379.195381) (xy 119.9007 -379.186186) (xy 119.9007 -378.693934) (xy 119.900273 -378.684749)
			(xy 119.893771 -378.667564) (xy 119.888 -378.660406) (xy 119.86611 -378.634762) (xy 119.828023 -378.579124)
			(xy 119.796873 -378.519325) (xy 119.77311 -378.456226) (xy 119.757077 -378.390734) (xy 119.749003 -378.323793)
			(xy 116.470957 -378.323793) (xy 116.462922 -378.390554) (xy 116.44695 -378.455936) (xy 116.423278 -378.518939)
			(xy 116.392245 -378.578662) (xy 116.354296 -378.634247) (xy 116.332508 -378.659898) (xy 116.326731 -378.667057)
			(xy 116.320204 -378.684237) (xy 116.319808 -378.693426) (xy 116.319808 -379.186694) (xy 116.320219 -379.195881)
			(xy 116.326732 -379.213066) (xy 116.332508 -379.220222) (xy 116.354343 -379.245836) (xy 116.392293 -379.301427)
			(xy 116.423328 -379.361155) (xy 116.447 -379.424165) (xy 116.462971 -379.489552) (xy 116.471013 -379.55638)
			(xy 116.471009 -379.623689) (xy 116.462959 -379.690516) (xy 116.44698 -379.755901) (xy 116.423299 -379.818908)
			(xy 116.392258 -379.878633) (xy 116.3543 -379.934219) (xy 116.332508 -379.95987) (xy 116.3267 -379.967007)
			(xy 116.320192 -379.984204) (xy 116.319808 -379.993398) (xy 116.319808 -380.151386) (xy 116.319256 -380.161537)
			(xy 116.311495 -380.180297) (xy 116.297148 -380.194661) (xy 116.278397 -380.202445) (xy 116.268246 -380.202948)
			(xy 115.551966 -380.202948) (xy 115.541804 -380.202494) (xy 115.523032 -380.194706) (xy 115.508667 -380.180328)
			(xy 115.500896 -380.161548) (xy 115.500404 -380.151386) (xy 115.500404 -379.993398) (xy 115.499994 -379.984211)
			(xy 115.49348 -379.967027) (xy 115.487704 -379.95987) (xy 115.465963 -379.93418) (xy 115.428015 -379.878598)
			(xy 115.396981 -379.81888) (xy 115.373307 -379.75588) (xy 115.357332 -379.690503) (xy 115.349285 -379.623685)
			(xy 115.349281 -379.556384) (xy 115.35732 -379.489565) (xy 115.373287 -379.424186) (xy 115.396953 -379.361184)
			(xy 115.427979 -379.301461) (xy 115.46592 -379.245875) (xy 115.487704 -379.220222) (xy 115.493517 -379.213088)
			(xy 115.500022 -379.195889) (xy 115.500404 -379.186694) (xy 115.500404 -378.693426) (xy 115.49998 -378.68424)
			(xy 115.493476 -378.667056) (xy 115.487704 -378.659898) (xy 115.465892 -378.634266) (xy 115.427946 -378.578676)
			(xy 115.396916 -378.518949) (xy 115.373246 -378.455942) (xy 115.357276 -378.390558) (xy 115.349234 -378.323734)
			(xy 85.670933 -378.323734) (xy 85.670933 -378.323792) (xy 85.662859 -378.390729) (xy 85.646825 -378.456217)
			(xy 85.623062 -378.519313) (xy 85.591912 -378.579108) (xy 85.553824 -378.634741) (xy 85.53196 -378.660406)
			(xy 85.526173 -378.667558) (xy 85.519654 -378.684743) (xy 85.51926 -378.693934) (xy 85.51926 -379.186186)
			(xy 85.519686 -379.195371) (xy 85.526189 -379.212555) (xy 85.53196 -379.219714) (xy 85.553871 -379.245341)
			(xy 85.591961 -379.30098) (xy 85.623111 -379.360781) (xy 85.646875 -379.423883) (xy 85.662908 -379.489377)
			(xy 85.670981 -379.55632) (xy 85.670977 -379.623749) (xy 85.662896 -379.690691) (xy 85.646854 -379.756183)
			(xy 85.623083 -379.819282) (xy 85.591925 -379.879079) (xy 85.553828 -379.934713) (xy 85.53196 -379.960378)
			(xy 85.526143 -379.967508) (xy 85.519641 -379.98471) (xy 85.51926 -379.993906) (xy 85.51926 -380.151386)
			(xy 85.518762 -380.161512) (xy 85.511039 -380.180233) (xy 85.496756 -380.194589) (xy 85.478075 -380.202409)
			(xy 85.467952 -380.202948) (xy 84.751672 -380.202948) (xy 84.741567 -380.202439) (xy 84.722898 -380.194701)
			(xy 84.708606 -380.180412) (xy 84.700863 -380.161744) (xy 84.700364 -380.15164) (xy 84.700364 -379.993906)
			(xy 84.699937 -379.984721) (xy 84.693433 -379.967537) (xy 84.687664 -379.960378) (xy 84.665846 -379.934675)
			(xy 84.627759 -379.879045) (xy 84.596608 -379.819254) (xy 84.572843 -379.756162) (xy 84.556805 -379.690678)
			(xy 84.548726 -379.623744) (xy 84.548722 -379.556325) (xy 84.556793 -379.48939) (xy 84.572822 -379.423904)
			(xy 84.59658 -379.36081) (xy 84.627723 -379.301014) (xy 84.665804 -379.24538) (xy 84.687664 -379.219714)
			(xy 84.693487 -379.212588) (xy 84.699984 -379.195383) (xy 84.700364 -379.186186) (xy 84.700364 -378.693934)
			(xy 84.699923 -378.68475) (xy 84.693429 -378.667566) (xy 84.687664 -378.660406) (xy 84.665776 -378.634761)
			(xy 84.62769 -378.579123) (xy 84.596543 -378.519324) (xy 84.572781 -378.456224) (xy 84.556749 -378.390733)
			(xy 84.548676 -378.323793) (xy 81.271142 -378.323793) (xy 81.263068 -378.390729) (xy 81.247035 -378.456217)
			(xy 81.223272 -378.519312) (xy 81.192123 -378.579108) (xy 81.154035 -378.634741) (xy 81.132172 -378.660406)
			(xy 81.126387 -378.667559) (xy 81.119866 -378.684744) (xy 81.119472 -378.693934) (xy 81.119472 -379.186186)
			(xy 81.119895 -379.195372) (xy 81.126401 -379.212556) (xy 81.132172 -379.219714) (xy 81.154082 -379.245341)
			(xy 81.192171 -379.300981) (xy 81.223322 -379.360782) (xy 81.247084 -379.423884) (xy 81.263118 -379.489378)
			(xy 81.27119 -379.556321) (xy 81.271186 -379.623748) (xy 81.263105 -379.69069) (xy 81.247064 -379.756182)
			(xy 81.223293 -379.819281) (xy 81.192136 -379.879079) (xy 81.15404 -379.934713) (xy 81.132172 -379.960378)
			(xy 81.126356 -379.967509) (xy 81.119854 -379.984711) (xy 81.119472 -379.993906) (xy 81.119472 -380.151386)
			(xy 81.118962 -380.16151) (xy 81.111241 -380.180229) (xy 81.096962 -380.194585) (xy 81.078286 -380.202407)
			(xy 81.068164 -380.202948) (xy 80.351884 -380.202948) (xy 80.34178 -380.202429) (xy 80.323111 -380.194695)
			(xy 80.308818 -380.180409) (xy 80.301076 -380.161744) (xy 80.300576 -380.15164) (xy 80.300576 -379.993906)
			(xy 80.300168 -379.984718) (xy 80.293654 -379.967534) (xy 80.287876 -379.960378) (xy 80.266058 -379.934675)
			(xy 80.22797 -379.879045) (xy 80.196818 -379.819254) (xy 80.173052 -379.756162) (xy 80.157015 -379.690678)
			(xy 80.148935 -379.623744) (xy 80.148931 -379.556325) (xy 80.157002 -379.48939) (xy 80.173032 -379.423904)
			(xy 80.19679 -379.360809) (xy 80.227934 -379.301014) (xy 80.266016 -379.24538) (xy 80.287876 -379.219714)
			(xy 80.293689 -379.21258) (xy 80.300195 -379.195381) (xy 80.300576 -379.186186) (xy 80.300576 -378.693934)
			(xy 80.300155 -378.684748) (xy 80.29365 -378.667563) (xy 80.287876 -378.660406) (xy 80.265987 -378.634761)
			(xy 80.227901 -378.579123) (xy 80.196753 -378.519324) (xy 80.172991 -378.456225) (xy 80.156958 -378.390733)
			(xy 80.148885 -378.323793) (xy 76.870815 -378.323793) (xy 76.862781 -378.390552) (xy 76.846812 -378.455933)
			(xy 76.823143 -378.518936) (xy 76.792114 -378.578659) (xy 76.75417 -378.634246) (xy 76.732384 -378.659898)
			(xy 76.726604 -378.667055) (xy 76.72008 -378.684236) (xy 76.719684 -378.693426) (xy 76.719684 -379.186694)
			(xy 76.720101 -379.19588) (xy 76.72661 -379.213065) (xy 76.732384 -379.220222) (xy 76.754216 -379.245837)
			(xy 76.792162 -379.30143) (xy 76.823192 -379.361158) (xy 76.846861 -379.424168) (xy 76.86283 -379.489554)
			(xy 76.870871 -379.55638) (xy 76.870866 -379.623689) (xy 76.862818 -379.690514) (xy 76.846841 -379.755899)
			(xy 76.823164 -379.818905) (xy 76.792127 -379.87863) (xy 76.754174 -379.934218) (xy 76.732384 -379.95987)
			(xy 76.726573 -379.967005) (xy 76.720068 -379.984203) (xy 76.719684 -379.993398) (xy 76.719684 -380.151386)
			(xy 76.719156 -380.16154) (xy 76.71139 -380.180305) (xy 76.697035 -380.19467) (xy 76.678276 -380.202449)
			(xy 76.668122 -380.202948) (xy 75.951842 -380.202948) (xy 75.941671 -380.202501) (xy 75.922875 -380.194728)
			(xy 75.908488 -380.180349) (xy 75.900704 -380.161556) (xy 75.90028 -380.151386) (xy 75.90028 -379.993398)
			(xy 75.899875 -379.98421) (xy 75.893358 -379.967026) (xy 75.88758 -379.95987) (xy 75.865836 -379.934181)
			(xy 75.827883 -379.878601) (xy 75.796846 -379.818883) (xy 75.773169 -379.755883) (xy 75.757191 -379.690505)
			(xy 75.749143 -379.623686) (xy 75.749139 -379.556383) (xy 75.757179 -379.489563) (xy 75.773148 -379.424183)
			(xy 75.796818 -379.36118) (xy 75.827848 -379.301458) (xy 75.865794 -379.245874) (xy 75.88758 -379.220222)
			(xy 75.89339 -379.213086) (xy 75.899897 -379.195889) (xy 75.90028 -379.186694) (xy 75.90028 -378.693426)
			(xy 75.899862 -378.68424) (xy 75.893354 -378.667055) (xy 75.88758 -378.659898) (xy 75.865766 -378.634267)
			(xy 75.827815 -378.578679) (xy 75.79678 -378.518953) (xy 75.773107 -378.455945) (xy 75.757135 -378.39056)
			(xy 75.749092 -378.323734) (xy 72.471054 -378.323734) (xy 72.471054 -378.323791) (xy 72.46298 -378.390728)
			(xy 72.446947 -378.456216) (xy 72.423186 -378.519312) (xy 72.392037 -378.579107) (xy 72.353951 -378.634741)
			(xy 72.332088 -378.660406) (xy 72.326305 -378.667561) (xy 72.319783 -378.684744) (xy 72.319388 -378.693934)
			(xy 72.319388 -379.186186) (xy 72.319808 -379.195372) (xy 72.326315 -379.212556) (xy 72.332088 -379.219714)
			(xy 72.353998 -379.245342) (xy 72.392086 -379.300981) (xy 72.423235 -379.360783) (xy 72.446997 -379.423884)
			(xy 72.46303 -379.489378) (xy 72.471102 -379.556321) (xy 72.471098 -379.623748) (xy 72.463017 -379.69069)
			(xy 72.446977 -379.756182) (xy 72.423207 -379.819281) (xy 72.39205 -379.879078) (xy 72.353955 -379.934713)
			(xy 72.332088 -379.960378) (xy 72.326274 -379.967511) (xy 72.31977 -379.984711) (xy 72.319388 -379.993906)
			(xy 72.319388 -380.151386) (xy 72.318863 -380.161508) (xy 72.311145 -380.180224) (xy 72.296871 -380.19458)
			(xy 72.278199 -380.202404) (xy 72.26808 -380.202948) (xy 71.5518 -380.202948) (xy 71.541652 -380.202479)
			(xy 71.522909 -380.194693) (xy 71.508587 -380.180311) (xy 71.500879 -380.161536) (xy 71.500492 -380.151386)
			(xy 71.500492 -379.993906) (xy 71.500081 -379.984719) (xy 71.493568 -379.967534) (xy 71.487792 -379.960378)
			(xy 71.465974 -379.934675) (xy 71.427884 -379.879046) (xy 71.396732 -379.819255) (xy 71.372965 -379.756163)
			(xy 71.356927 -379.690678) (xy 71.348847 -379.623744) (xy 71.348843 -379.556325) (xy 71.356914 -379.48939)
			(xy 71.372945 -379.423903) (xy 71.396703 -379.360808) (xy 71.427848 -379.301013) (xy 71.465931 -379.245379)
			(xy 71.487792 -379.219714) (xy 71.493607 -379.212582) (xy 71.500111 -379.195381) (xy 71.500492 -379.186186)
			(xy 71.500492 -378.693934) (xy 71.500067 -378.684748) (xy 71.493564 -378.667564) (xy 71.487792 -378.660406)
			(xy 71.465903 -378.634762) (xy 71.427815 -378.579124) (xy 71.396666 -378.519325) (xy 71.372904 -378.456225)
			(xy 71.35687 -378.390734) (xy 71.348797 -378.323793) (xy 41.671024 -378.323793) (xy 41.66295 -378.390729)
			(xy 41.646915 -378.456218) (xy 41.623152 -378.519314) (xy 41.592001 -378.579109) (xy 41.553912 -378.634742)
			(xy 41.532048 -378.660406) (xy 41.52626 -378.667557) (xy 41.519742 -378.684743) (xy 41.519348 -378.693934)
			(xy 41.519348 -379.186186) (xy 41.519776 -379.195371) (xy 41.526279 -379.212555) (xy 41.532048 -379.219714)
			(xy 41.553959 -379.245341) (xy 41.59205 -379.30098) (xy 41.623201 -379.360781) (xy 41.646965 -379.423883)
			(xy 41.662999 -379.489377) (xy 41.671072 -379.55632) (xy 41.671068 -379.623749) (xy 41.662987 -379.690691)
			(xy 41.646945 -379.756183) (xy 41.623173 -379.819282) (xy 41.592014 -379.879079) (xy 41.553917 -379.934714)
			(xy 41.532048 -379.960378) (xy 41.526229 -379.967507) (xy 41.519729 -379.98471) (xy 41.519348 -379.993906)
			(xy 41.519348 -380.151386) (xy 41.518862 -380.161513) (xy 41.511136 -380.180236) (xy 41.49685 -380.194594)
			(xy 41.478165 -380.202411) (xy 41.46804 -380.202948) (xy 40.75176 -380.202948) (xy 40.741609 -380.202512)
			(xy 40.722865 -380.194712) (xy 40.708545 -380.180321) (xy 40.700838 -380.161539) (xy 40.700452 -380.151386)
			(xy 40.700452 -379.993906) (xy 40.700027 -379.984721) (xy 40.693523 -379.967537) (xy 40.687752 -379.960378)
			(xy 40.665931 -379.934676) (xy 40.627838 -379.879048) (xy 40.596682 -379.819258) (xy 40.572913 -379.756165)
			(xy 40.556873 -379.69068) (xy 40.548793 -379.623745) (xy 40.548788 -379.556324) (xy 40.556861 -379.489388)
			(xy 40.572893 -379.423901) (xy 40.596654 -379.360806) (xy 40.627802 -379.301011) (xy 40.665889 -379.245378)
			(xy 40.687752 -379.219714) (xy 40.693574 -379.212587) (xy 40.700072 -379.195382) (xy 40.700452 -379.186186)
			(xy 40.700452 -378.693934) (xy 40.700014 -378.68475) (xy 40.693519 -378.667566) (xy 40.687752 -378.660406)
			(xy 40.665861 -378.634763) (xy 40.627769 -378.579126) (xy 40.596617 -378.519328) (xy 40.572852 -378.456228)
			(xy 40.556817 -378.390735) (xy 40.548742 -378.323794) (xy 37.271233 -378.323794) (xy 37.263159 -378.390729)
			(xy 37.247125 -378.456217) (xy 37.223362 -378.519313) (xy 37.192212 -378.579108) (xy 37.154124 -378.634741)
			(xy 37.13226 -378.660406) (xy 37.126473 -378.667558) (xy 37.119954 -378.684743) (xy 37.11956 -378.693934)
			(xy 37.11956 -379.186186) (xy 37.119986 -379.195371) (xy 37.126489 -379.212555) (xy 37.13226 -379.219714)
			(xy 37.154171 -379.245341) (xy 37.192261 -379.30098) (xy 37.223411 -379.360781) (xy 37.247175 -379.423883)
			(xy 37.263208 -379.489377) (xy 37.271281 -379.55632) (xy 37.271277 -379.623749) (xy 37.263196 -379.690691)
			(xy 37.247154 -379.756183) (xy 37.223383 -379.819282) (xy 37.192225 -379.879079) (xy 37.154128 -379.934713)
			(xy 37.13226 -379.960378) (xy 37.126443 -379.967508) (xy 37.119941 -379.98471) (xy 37.11956 -379.993906)
			(xy 37.11956 -380.151386) (xy 37.119062 -380.161512) (xy 37.111339 -380.180233) (xy 37.097056 -380.194589)
			(xy 37.078375 -380.202409) (xy 37.068252 -380.202948) (xy 36.351972 -380.202948) (xy 36.341822 -380.202502)
			(xy 36.323078 -380.194707) (xy 36.308758 -380.180318) (xy 36.30105 -380.161538) (xy 36.300664 -380.151386)
			(xy 36.300664 -379.993906) (xy 36.300237 -379.984721) (xy 36.293733 -379.967537) (xy 36.287964 -379.960378)
			(xy 36.266146 -379.934675) (xy 36.228059 -379.879045) (xy 36.196908 -379.819254) (xy 36.173143 -379.756162)
			(xy 36.157105 -379.690678) (xy 36.149026 -379.623744) (xy 36.149022 -379.556325) (xy 36.157093 -379.48939)
			(xy 36.173122 -379.423904) (xy 36.19688 -379.36081) (xy 36.228023 -379.301014) (xy 36.266104 -379.24538)
			(xy 36.287964 -379.219714) (xy 36.293787 -379.212588) (xy 36.300284 -379.195383) (xy 36.300664 -379.186186)
			(xy 36.300664 -378.693934) (xy 36.300223 -378.68475) (xy 36.293729 -378.667566) (xy 36.287964 -378.660406)
			(xy 36.266076 -378.634761) (xy 36.22799 -378.579123) (xy 36.196843 -378.519324) (xy 36.173081 -378.456224)
			(xy 36.157049 -378.390733) (xy 36.148976 -378.323793) (xy 32.870906 -378.323793) (xy 32.862871 -378.390552)
			(xy 32.846902 -378.455933) (xy 32.823232 -378.518936) (xy 32.792203 -378.578659) (xy 32.754258 -378.634246)
			(xy 32.732472 -378.659898) (xy 32.72669 -378.667053) (xy 32.720167 -378.684236) (xy 32.719772 -378.693426)
			(xy 32.719772 -379.186694) (xy 32.720191 -379.19588) (xy 32.726699 -379.213064) (xy 32.732472 -379.220222)
			(xy 32.754305 -379.245837) (xy 32.792251 -379.301429) (xy 32.823282 -379.361158) (xy 32.846952 -379.424167)
			(xy 32.862921 -379.489554) (xy 32.870962 -379.55638) (xy 32.870957 -379.623689) (xy 32.862909 -379.690514)
			(xy 32.846931 -379.755899) (xy 32.823254 -379.818905) (xy 32.792216 -379.87863) (xy 32.754262 -379.934218)
			(xy 32.732472 -379.95987) (xy 32.72666 -379.967004) (xy 32.720155 -379.984203) (xy 32.719772 -379.993398)
			(xy 32.719772 -380.151386) (xy 32.719325 -380.161556) (xy 32.711547 -380.180348) (xy 32.697168 -380.194733)
			(xy 32.678379 -380.20252) (xy 32.66821 -380.202948) (xy 31.95193 -380.202948) (xy 31.941759 -380.202511)
			(xy 31.922962 -380.194733) (xy 31.908576 -380.180351) (xy 31.900792 -380.161557) (xy 31.900368 -380.151386)
			(xy 31.900368 -379.993398) (xy 31.899944 -379.984213) (xy 31.893438 -379.967029) (xy 31.887668 -379.95987)
			(xy 31.865925 -379.934181) (xy 31.827973 -379.878601) (xy 31.796936 -379.818882) (xy 31.773259 -379.755883)
			(xy 31.757282 -379.690505) (xy 31.749234 -379.623686) (xy 31.74923 -379.556384) (xy 31.75727 -379.489564)
			(xy 31.773239 -379.424184) (xy 31.796908 -379.361181) (xy 31.827937 -379.301459) (xy 31.865882 -379.245874)
			(xy 31.887668 -379.220222) (xy 31.893488 -379.213094) (xy 31.899987 -379.19589) (xy 31.900368 -379.186694)
			(xy 31.900368 -378.693426) (xy 31.89993 -378.684242) (xy 31.893434 -378.667058) (xy 31.887668 -378.659898)
			(xy 31.865854 -378.634267) (xy 31.827904 -378.578678) (xy 31.79687 -378.518952) (xy 31.773198 -378.455945)
			(xy 31.757226 -378.39056) (xy 31.749183 -378.323734) (xy 28.471145 -378.323734) (xy 28.471145 -378.323792)
			(xy 28.463071 -378.390728) (xy 28.447038 -378.456216) (xy 28.423275 -378.519312) (xy 28.392126 -378.579108)
			(xy 28.354039 -378.634741) (xy 28.332176 -378.660406) (xy 28.326392 -378.66756) (xy 28.31987 -378.684744)
			(xy 28.319476 -378.693934) (xy 28.319476 -379.186186) (xy 28.319898 -379.195372) (xy 28.326404 -379.212556)
			(xy 28.332176 -379.219714) (xy 28.354036 -379.245382) (xy 28.392125 -379.301016) (xy 28.423276 -379.360812)
			(xy 28.447 -379.423801) (xy 29.549058 -379.423801) (xy 29.549059 -379.356496) (xy 29.557103 -379.289673)
			(xy 29.573076 -379.224291) (xy 29.596749 -379.161286) (xy 29.627783 -379.101562) (xy 29.665732 -379.045976)
			(xy 29.68752 -379.020324) (xy 29.693334 -379.013191) (xy 29.699837 -378.995991) (xy 29.70022 -378.986796)
			(xy 29.70022 -378.828554) (xy 29.700695 -378.818396) (xy 29.708482 -378.799629) (xy 29.722852 -378.785266)
			(xy 29.741623 -378.77749) (xy 29.751782 -378.776992) (xy 30.468062 -378.776992) (xy 30.478212 -378.777564)
			(xy 30.496971 -378.785317) (xy 30.511336 -378.799658) (xy 30.51912 -378.818405) (xy 30.519624 -378.828554)
			(xy 30.519624 -378.986796) (xy 30.520031 -378.995984) (xy 30.526546 -379.013168) (xy 30.532324 -379.020324)
			(xy 30.55411 -379.045978) (xy 30.592059 -379.101564) (xy 30.623093 -379.161287) (xy 30.646766 -379.224291)
			(xy 30.662739 -379.289673) (xy 30.670784 -379.356496) (xy 30.670784 -379.423801) (xy 30.66274 -379.490624)
			(xy 30.646767 -379.556006) (xy 30.623094 -379.61901) (xy 30.592061 -379.678734) (xy 30.554112 -379.73432)
			(xy 30.532324 -379.759972) (xy 30.526517 -379.76711) (xy 30.520008 -379.784306) (xy 30.519624 -379.7935)
			(xy 30.519624 -380.286768) (xy 30.520044 -380.295954) (xy 30.52655 -380.313139) (xy 30.532324 -380.320296)
			(xy 30.554132 -380.345932) (xy 30.592083 -380.40152) (xy 30.623117 -380.461245) (xy 30.646791 -380.524252)
			(xy 30.662763 -380.589636) (xy 30.6708 -380.656404) (xy 33.948845 -380.656404) (xy 33.95692 -380.589467)
			(xy 33.972953 -380.523978) (xy 33.996716 -380.460882) (xy 34.027865 -380.401087) (xy 34.065953 -380.345453)
			(xy 34.087816 -380.319788) (xy 34.093602 -380.312635) (xy 34.100122 -380.29545) (xy 34.100516 -380.28626)
			(xy 34.100516 -379.794008) (xy 34.100098 -379.784822) (xy 34.093589 -379.767638) (xy 34.087816 -379.76048)
			(xy 34.065999 -379.734776) (xy 34.027907 -379.679148) (xy 33.996754 -379.619357) (xy 33.972986 -379.556265)
			(xy 33.956947 -379.49078) (xy 33.948867 -379.423846) (xy 33.948863 -379.356426) (xy 33.956934 -379.289491)
			(xy 33.972965 -379.224004) (xy 33.996724 -379.160909) (xy 34.02787 -379.101114) (xy 34.065954 -379.045481)
			(xy 34.087816 -379.019816) (xy 34.093633 -379.012685) (xy 34.100135 -378.995484) (xy 34.100516 -378.986288)
			(xy 34.100516 -378.828554) (xy 34.100988 -378.818427) (xy 34.108727 -378.79971) (xy 34.123017 -378.785356)
			(xy 34.1417 -378.777534) (xy 34.151824 -378.776992) (xy 34.868104 -378.776992) (xy 34.878257 -378.777418)
			(xy 34.897008 -378.785214) (xy 34.911331 -378.799609) (xy 34.919032 -378.818399) (xy 34.919412 -378.828554)
			(xy 34.919412 -378.986288) (xy 34.919825 -378.995475) (xy 34.926336 -379.012659) (xy 34.932112 -379.019816)
			(xy 34.954023 -379.045443) (xy 34.992109 -379.101083) (xy 35.023257 -379.160885) (xy 35.047018 -379.223986)
			(xy 35.06305 -379.28948) (xy 35.071122 -379.356422) (xy 35.071117 -379.42385) (xy 35.063037 -379.490791)
			(xy 35.046997 -379.556283) (xy 35.023228 -379.619381) (xy 34.992072 -379.679179) (xy 34.953978 -379.734815)
			(xy 34.932112 -379.76048) (xy 34.9263 -379.767615) (xy 34.919794 -379.784813) (xy 34.919412 -379.794008)
			(xy 34.919412 -380.28626) (xy 34.919839 -380.295446) (xy 34.92634 -380.31263) (xy 34.932112 -380.319788)
			(xy 34.953995 -380.345437) (xy 34.992083 -380.401074) (xy 35.023232 -380.460873) (xy 35.046994 -380.523972)
			(xy 35.063028 -380.589463) (xy 35.071102 -380.656403) (xy 35.071102 -380.656464) (xy 38.349165 -380.656464)
			(xy 38.357207 -380.589643) (xy 38.373176 -380.524262) (xy 38.396845 -380.461259) (xy 38.427874 -380.401536)
			(xy 38.465819 -380.345949) (xy 38.487604 -380.320296) (xy 38.493385 -380.31314) (xy 38.499909 -380.295958)
			(xy 38.500304 -380.286768) (xy 38.500304 -379.7935) (xy 38.499893 -379.784313) (xy 38.49338 -379.767129)
			(xy 38.487604 -379.759972) (xy 38.465865 -379.73428) (xy 38.427917 -379.678699) (xy 38.396884 -379.61898)
			(xy 38.37321 -379.555981) (xy 38.357234 -379.490604) (xy 38.349187 -379.423786) (xy 38.349183 -379.356486)
			(xy 38.357221 -379.289667) (xy 38.373188 -379.224288) (xy 38.396854 -379.161286) (xy 38.42788 -379.101563)
			(xy 38.465821 -379.045977) (xy 38.487604 -379.020324) (xy 38.493416 -379.01319) (xy 38.499921 -378.995991)
			(xy 38.500304 -378.986796) (xy 38.500304 -378.828554) (xy 38.500795 -378.818397) (xy 38.508578 -378.799634)
			(xy 38.522944 -378.785271) (xy 38.541709 -378.777493) (xy 38.551866 -378.776992) (xy 39.268146 -378.776992)
			(xy 39.278301 -378.777495) (xy 39.297062 -378.785276) (xy 39.311424 -378.799638) (xy 39.319205 -378.818399)
			(xy 39.319708 -378.828554) (xy 39.319708 -378.986796) (xy 39.320118 -378.995983) (xy 39.326632 -379.013168)
			(xy 39.332408 -379.020324) (xy 39.354244 -379.045937) (xy 39.392195 -379.101528) (xy 39.423229 -379.161256)
			(xy 39.446902 -379.224266) (xy 39.462873 -379.289653) (xy 39.470914 -379.356481) (xy 39.47091 -379.423791)
			(xy 39.46286 -379.490618) (xy 39.44688 -379.556003) (xy 39.4232 -379.61901) (xy 39.392158 -379.678735)
			(xy 39.3542 -379.734321) (xy 39.332408 -379.759972) (xy 39.326599 -379.767109) (xy 39.320092 -379.784306)
			(xy 39.319708 -379.7935) (xy 39.319708 -380.286768) (xy 39.320132 -380.295954) (xy 39.326636 -380.313138)
			(xy 39.332408 -380.320296) (xy 39.354217 -380.345931) (xy 39.392169 -380.401519) (xy 39.423204 -380.461244)
			(xy 39.446878 -380.524251) (xy 39.462851 -380.589636) (xy 39.470887 -380.656404) (xy 42.748933 -380.656404)
			(xy 42.757007 -380.589467) (xy 42.773041 -380.523979) (xy 42.796803 -380.460883) (xy 42.827951 -380.401087)
			(xy 42.866037 -380.345453) (xy 42.8879 -380.319788) (xy 42.893684 -380.312634) (xy 42.900206 -380.29545)
			(xy 42.9006 -380.28626) (xy 42.9006 -379.794008) (xy 42.900186 -379.784821) (xy 42.893675 -379.767637)
			(xy 42.8879 -379.76048) (xy 42.866083 -379.734776) (xy 42.827993 -379.679147) (xy 42.79684 -379.619356)
			(xy 42.773073 -379.556264) (xy 42.757035 -379.49078) (xy 42.748955 -379.423846) (xy 42.748951 -379.356426)
			(xy 42.757022 -379.289491) (xy 42.773052 -379.224005) (xy 42.796811 -379.16091) (xy 42.827956 -379.101115)
			(xy 42.866039 -379.045481) (xy 42.8879 -379.019816) (xy 42.893715 -379.012684) (xy 42.900219 -378.995483)
			(xy 42.9006 -378.986288) (xy 42.9006 -378.828554) (xy 42.901088 -378.818429) (xy 42.908823 -378.799715)
			(xy 42.923108 -378.785361) (xy 42.941786 -378.777537) (xy 42.951908 -378.776992) (xy 43.668188 -378.776992)
			(xy 43.67834 -378.777431) (xy 43.697091 -378.785221) (xy 43.711414 -378.799613) (xy 43.719116 -378.8184)
			(xy 43.719496 -378.828554) (xy 43.719496 -378.986288) (xy 43.719913 -378.995474) (xy 43.726422 -379.012659)
			(xy 43.732196 -379.019816) (xy 43.754107 -379.045442) (xy 43.792195 -379.101082) (xy 43.823344 -379.160884)
			(xy 43.847105 -379.223986) (xy 43.863138 -379.28948) (xy 43.87121 -379.356422) (xy 43.871205 -379.42385)
			(xy 43.863125 -379.490791) (xy 43.847084 -379.556283) (xy 43.823314 -379.619382) (xy 43.792158 -379.67918)
			(xy 43.754063 -379.734815) (xy 43.732196 -379.76048) (xy 43.726382 -379.767613) (xy 43.719878 -379.784813)
			(xy 43.719496 -379.794008) (xy 43.719496 -380.28626) (xy 43.719926 -380.295445) (xy 43.726426 -380.31263)
			(xy 43.732196 -380.319788) (xy 43.75408 -380.345437) (xy 43.792168 -380.401074) (xy 43.823318 -380.460872)
			(xy 43.847081 -380.523971) (xy 43.863116 -380.589462) (xy 43.87119 -380.656402) (xy 43.87119 -380.656463)
			(xy 73.548987 -380.656463) (xy 73.557029 -380.589642) (xy 73.572999 -380.524261) (xy 73.596669 -380.461258)
			(xy 73.6277 -380.401535) (xy 73.665646 -380.345948) (xy 73.687432 -380.320296) (xy 73.693217 -380.313143)
			(xy 73.699738 -380.295958) (xy 73.700132 -380.286768) (xy 73.700132 -379.7935) (xy 73.699715 -379.784314)
			(xy 73.693205 -379.76713) (xy 73.687432 -379.759972) (xy 73.665692 -379.734281) (xy 73.627742 -379.6787)
			(xy 73.596707 -379.618982) (xy 73.573032 -379.555982) (xy 73.557056 -379.490605) (xy 73.549008 -379.423787)
			(xy 73.549004 -379.356486) (xy 73.557043 -379.289666) (xy 73.573011 -379.224287) (xy 73.596678 -379.161285)
			(xy 73.627705 -379.101562) (xy 73.665648 -379.045976) (xy 73.687432 -379.020324) (xy 73.693247 -379.013192)
			(xy 73.69975 -378.995991) (xy 73.700132 -378.986796) (xy 73.700132 -378.828554) (xy 73.700596 -378.818394)
			(xy 73.708384 -378.799625) (xy 73.722759 -378.785262) (xy 73.741534 -378.777488) (xy 73.751694 -378.776992)
			(xy 74.467974 -378.776992) (xy 74.478125 -378.777553) (xy 74.496884 -378.785311) (xy 74.511249 -378.799655)
			(xy 74.519032 -378.818404) (xy 74.519536 -378.828554) (xy 74.519536 -378.986796) (xy 74.519962 -378.995981)
			(xy 74.526466 -379.013165) (xy 74.532236 -379.020324) (xy 74.554072 -379.045937) (xy 74.592021 -379.101528)
			(xy 74.623053 -379.161257) (xy 74.646725 -379.224267) (xy 74.662695 -379.289654) (xy 74.670736 -379.356481)
			(xy 74.670731 -379.423791) (xy 74.662682 -379.490617) (xy 74.646703 -379.556002) (xy 74.623024 -379.619009)
			(xy 74.591984 -379.678734) (xy 74.554028 -379.73432) (xy 74.532236 -379.759972) (xy 74.526419 -379.767102)
			(xy 74.519918 -379.784304) (xy 74.519536 -379.7935) (xy 74.519536 -380.286768) (xy 74.519976 -380.295952)
			(xy 74.52647 -380.313136) (xy 74.532236 -380.320296) (xy 74.554044 -380.345932) (xy 74.591994 -380.40152)
			(xy 74.623028 -380.461246) (xy 74.6467 -380.524252) (xy 74.662673 -380.589637) (xy 74.670709 -380.656404)
			(xy 77.948754 -380.656404) (xy 77.956829 -380.589466) (xy 77.972863 -380.523978) (xy 77.996626 -380.460882)
			(xy 78.027776 -380.401086) (xy 78.065864 -380.345453) (xy 78.087728 -380.319788) (xy 78.093516 -380.312637)
			(xy 78.100035 -380.295451) (xy 78.100428 -380.28626) (xy 78.100428 -379.794008) (xy 78.100008 -379.784822)
			(xy 78.093501 -379.767638) (xy 78.087728 -379.76048) (xy 78.06591 -379.734776) (xy 78.027818 -379.679148)
			(xy 77.996664 -379.619357) (xy 77.972896 -379.556265) (xy 77.956856 -379.490781) (xy 77.948776 -379.423846)
			(xy 77.948772 -379.356426) (xy 77.956843 -379.28949) (xy 77.972874 -379.224004) (xy 77.996634 -379.160909)
			(xy 78.027781 -379.101114) (xy 78.065866 -379.045481) (xy 78.087728 -379.019816) (xy 78.093546 -379.012686)
			(xy 78.100047 -378.995484) (xy 78.100428 -378.986288) (xy 78.100428 -378.828554) (xy 78.100889 -378.818426)
			(xy 78.108629 -378.799706) (xy 78.122923 -378.785352) (xy 78.14161 -378.777532) (xy 78.151736 -378.776992)
			(xy 78.868016 -378.776992) (xy 78.878125 -378.777472) (xy 78.896802 -378.785213) (xy 78.911096 -378.799512)
			(xy 78.918831 -378.818191) (xy 78.919324 -378.8283) (xy 78.919324 -378.986288) (xy 78.919734 -378.995475)
			(xy 78.926247 -379.01266) (xy 78.932024 -379.019816) (xy 78.953934 -379.045443) (xy 78.99202 -379.101083)
			(xy 79.023167 -379.160885) (xy 79.046928 -379.223987) (xy 79.062959 -379.28948) (xy 79.071031 -379.356423)
			(xy 79.071026 -379.42385) (xy 79.062946 -379.490791) (xy 79.046906 -379.556282) (xy 79.023138 -379.619381)
			(xy 78.991983 -379.679179) (xy 78.95389 -379.734814) (xy 78.932024 -379.76048) (xy 78.926214 -379.767616)
			(xy 78.919706 -379.784813) (xy 78.919324 -379.794008) (xy 78.919324 -380.28626) (xy 78.919748 -380.295446)
			(xy 78.926251 -380.312631) (xy 78.932024 -380.319788) (xy 78.953907 -380.345437) (xy 78.991993 -380.401075)
			(xy 79.023142 -380.460873) (xy 79.046904 -380.523972) (xy 79.062937 -380.589463) (xy 79.071011 -380.656403)
			(xy 79.071011 -380.656464) (xy 82.349074 -380.656464) (xy 82.357116 -380.589643) (xy 82.373086 -380.524262)
			(xy 82.396755 -380.461258) (xy 82.427785 -380.401535) (xy 82.46573 -380.345948) (xy 82.487516 -380.320296)
			(xy 82.493299 -380.313141) (xy 82.499821 -380.295958) (xy 82.500216 -380.286768) (xy 82.500216 -379.7935)
			(xy 82.499803 -379.784313) (xy 82.493291 -379.767129) (xy 82.487516 -379.759972) (xy 82.465776 -379.734281)
			(xy 82.427828 -379.678699) (xy 82.396794 -379.618981) (xy 82.373119 -379.555982) (xy 82.357144 -379.490604)
			(xy 82.349096 -379.423786) (xy 82.349092 -379.356486) (xy 82.357131 -379.289667) (xy 82.373098 -379.224288)
			(xy 82.396764 -379.161285) (xy 82.427791 -379.101563) (xy 82.465732 -379.045977) (xy 82.487516 -379.020324)
			(xy 82.493329 -379.013191) (xy 82.499833 -378.995991) (xy 82.500216 -378.986796) (xy 82.500216 -378.828554)
			(xy 82.500695 -378.818396) (xy 82.508481 -378.79963) (xy 82.52285 -378.785267) (xy 82.54162 -378.777491)
			(xy 82.551778 -378.776992) (xy 83.268058 -378.776992) (xy 83.278207 -378.777567) (xy 83.296967 -378.785319)
			(xy 83.311332 -378.799659) (xy 83.319116 -378.818405) (xy 83.31962 -378.828554) (xy 83.31962 -378.986796)
			(xy 83.320028 -378.995984) (xy 83.326543 -379.013168) (xy 83.33232 -379.020324) (xy 83.354156 -379.045937)
			(xy 83.392107 -379.101528) (xy 83.42314 -379.161256) (xy 83.446812 -379.224266) (xy 83.462783 -379.289654)
			(xy 83.470824 -379.356481) (xy 83.470819 -379.423791) (xy 83.46277 -379.490618) (xy 83.446791 -379.556003)
			(xy 83.423111 -379.61901) (xy 83.392069 -379.678734) (xy 83.354112 -379.734321) (xy 83.33232 -379.759972)
			(xy 83.326513 -379.76711) (xy 83.320004 -379.784306) (xy 83.31962 -379.7935) (xy 83.31962 -380.286768)
			(xy 83.320041 -380.295954) (xy 83.326547 -380.313139) (xy 83.33232 -380.320296) (xy 83.354129 -380.345931)
			(xy 83.392079 -380.401519) (xy 83.423114 -380.461245) (xy 83.446788 -380.524252) (xy 83.46276 -380.589636)
			(xy 83.470797 -380.656404) (xy 86.748842 -380.656404) (xy 86.756916 -380.589467) (xy 86.77295 -380.523979)
			(xy 86.796713 -380.460883) (xy 86.827862 -380.401087) (xy 86.865949 -380.345453) (xy 86.887812 -380.319788)
			(xy 86.893598 -380.312635) (xy 86.900118 -380.29545) (xy 86.900512 -380.28626) (xy 86.900512 -379.794008)
			(xy 86.900095 -379.784822) (xy 86.893586 -379.767637) (xy 86.887812 -379.76048) (xy 86.865995 -379.734776)
			(xy 86.827904 -379.679147) (xy 86.79675 -379.619357) (xy 86.772983 -379.556265) (xy 86.756944 -379.49078)
			(xy 86.748864 -379.423846) (xy 86.74886 -379.356426) (xy 86.756931 -379.289491) (xy 86.772962 -379.224004)
			(xy 86.796721 -379.160909) (xy 86.827867 -379.101115) (xy 86.86595 -379.045481) (xy 86.887812 -379.019816)
			(xy 86.893628 -379.012685) (xy 86.900131 -378.995483) (xy 86.900512 -378.986288) (xy 86.900512 -378.828554)
			(xy 86.900988 -378.818428) (xy 86.908726 -378.799711) (xy 86.923015 -378.785357) (xy 86.941696 -378.777535)
			(xy 86.95182 -378.776992) (xy 87.6681 -378.776992) (xy 87.678208 -378.777485) (xy 87.696884 -378.785221)
			(xy 87.711179 -378.799516) (xy 87.718915 -378.818192) (xy 87.719408 -378.8283) (xy 87.719408 -378.986288)
			(xy 87.719822 -378.995475) (xy 87.726333 -379.012659) (xy 87.732108 -379.019816) (xy 87.754019 -379.045442)
			(xy 87.792106 -379.101083) (xy 87.823254 -379.160884) (xy 87.847015 -379.223986) (xy 87.863047 -379.28948)
			(xy 87.871119 -379.356422) (xy 87.871114 -379.42385) (xy 87.863034 -379.490791) (xy 87.846994 -379.556283)
			(xy 87.823224 -379.619382) (xy 87.792068 -379.679179) (xy 87.753975 -379.734815) (xy 87.732108 -379.76048)
			(xy 87.726296 -379.767614) (xy 87.71979 -379.784813) (xy 87.719408 -379.794008) (xy 87.719408 -380.28626)
			(xy 87.719836 -380.295445) (xy 87.726337 -380.31263) (xy 87.732108 -380.319788) (xy 87.753991 -380.345437)
			(xy 87.792079 -380.401074) (xy 87.823228 -380.460873) (xy 87.846991 -380.523972) (xy 87.863025 -380.589463)
			(xy 87.871099 -380.656402) (xy 87.871097 -380.723828) (xy 87.863019 -380.790767) (xy 87.846982 -380.856257)
			(xy 87.838954 -380.877572) (xy 105.0036 -380.877572) (xy 105.0036 -380.013972) (xy 105.00409 -379.983988)
			(xy 105.011918 -379.924532) (xy 105.027439 -379.866607) (xy 105.050388 -379.811203) (xy 105.080372 -379.759269)
			(xy 105.116878 -379.711693) (xy 105.159283 -379.669288) (xy 105.206859 -379.632782) (xy 105.258793 -379.602798)
			(xy 105.314197 -379.579849) (xy 105.372122 -379.564328) (xy 105.431578 -379.5565) (xy 105.491546 -379.5565)
			(xy 105.551002 -379.564328) (xy 105.608927 -379.579849) (xy 105.664331 -379.602798) (xy 105.716265 -379.632782)
			(xy 105.763841 -379.669288) (xy 105.806246 -379.711693) (xy 105.842752 -379.759269) (xy 105.872736 -379.811203)
			(xy 105.895685 -379.866607) (xy 105.911206 -379.924532) (xy 105.919034 -379.983988) (xy 105.919524 -380.013972)
			(xy 105.919524 -380.656403) (xy 117.548873 -380.656403) (xy 117.556947 -380.589466) (xy 117.572982 -380.523977)
			(xy 117.596746 -380.460881) (xy 117.627898 -380.401085) (xy 117.665987 -380.345452) (xy 117.687852 -380.319788)
			(xy 117.693643 -380.312639) (xy 117.700159 -380.295451) (xy 117.700552 -380.28626) (xy 117.700552 -379.794008)
			(xy 117.700126 -379.784823) (xy 117.693622 -379.767639) (xy 117.687852 -379.76048) (xy 117.666033 -379.734777)
			(xy 117.62794 -379.679149) (xy 117.596784 -379.619358) (xy 117.573015 -379.556266) (xy 117.556975 -379.490781)
			(xy 117.548894 -379.423846) (xy 117.54889 -379.356426) (xy 117.556962 -379.28949) (xy 117.572994 -379.224003)
			(xy 117.596755 -379.160908) (xy 117.627903 -379.101113) (xy 117.665989 -379.04548) (xy 117.687852 -379.019816)
			(xy 117.693673 -379.012688) (xy 117.700172 -378.995484) (xy 117.700552 -378.986288) (xy 117.700552 -378.828554)
			(xy 117.700989 -378.818423) (xy 117.708734 -378.799698) (xy 117.723036 -378.785343) (xy 117.741731 -378.777528)
			(xy 117.75186 -378.776992) (xy 118.46814 -378.776992) (xy 118.478296 -378.777389) (xy 118.497047 -378.785196)
			(xy 118.511369 -378.7996) (xy 118.519069 -378.818396) (xy 118.519448 -378.828554) (xy 118.519448 -378.986288)
			(xy 118.519875 -378.995473) (xy 118.526378 -379.012657) (xy 118.532148 -379.019816) (xy 118.554061 -379.045441)
			(xy 118.592152 -379.10108) (xy 118.623303 -379.160882) (xy 118.647067 -379.223984) (xy 118.663101 -379.289478)
			(xy 118.671174 -379.356422) (xy 118.671169 -379.42385) (xy 118.663088 -379.490793) (xy 118.647046 -379.556285)
			(xy 118.623274 -379.619384) (xy 118.592115 -379.679181) (xy 118.554017 -379.734816) (xy 118.532148 -379.76048)
			(xy 118.526329 -379.767609) (xy 118.519829 -379.784812) (xy 118.519448 -379.794008) (xy 118.519448 -380.28626)
			(xy 118.519889 -380.295444) (xy 118.526382 -380.312628) (xy 118.532148 -380.319788) (xy 118.554033 -380.345436)
			(xy 118.592125 -380.401072) (xy 118.623278 -380.46087) (xy 118.647043 -380.523969) (xy 118.663079 -380.589461)
			(xy 118.671154 -380.656402) (xy 118.671154 -380.656463) (xy 121.949193 -380.656463) (xy 121.957235 -380.589642)
			(xy 121.973206 -380.524261) (xy 121.996876 -380.461257) (xy 122.027907 -380.401534) (xy 122.065854 -380.345948)
			(xy 122.08764 -380.320296) (xy 122.093426 -380.313143) (xy 122.099946 -380.295958) (xy 122.10034 -380.286768)
			(xy 122.10034 -379.7935) (xy 122.099921 -379.784314) (xy 122.093413 -379.76713) (xy 122.08764 -379.759972)
			(xy 122.0659 -379.734281) (xy 122.027949 -379.6787) (xy 121.996914 -379.618982) (xy 121.973238 -379.555982)
			(xy 121.957262 -379.490605) (xy 121.949214 -379.423787) (xy 121.94921 -379.356485) (xy 121.957249 -379.289666)
			(xy 121.973217 -379.224287) (xy 121.996884 -379.161284) (xy 122.027912 -379.101562) (xy 122.065855 -379.045976)
			(xy 122.08764 -379.020324) (xy 122.093456 -379.013193) (xy 122.099958 -378.995991) (xy 122.10034 -378.986796)
			(xy 122.10034 -378.828554) (xy 122.100796 -378.818393) (xy 122.108586 -378.799623) (xy 122.122963 -378.785259)
			(xy 122.141741 -378.777486) (xy 122.151902 -378.776992) (xy 122.868182 -378.776992) (xy 122.878333 -378.777547)
			(xy 122.897093 -378.785307) (xy 122.911457 -378.799653) (xy 122.919241 -378.818404) (xy 122.919744 -378.828554)
			(xy 122.919744 -378.986796) (xy 122.920169 -378.995981) (xy 122.926674 -379.013165) (xy 122.932444 -379.020324)
			(xy 122.95428 -379.045937) (xy 122.992228 -379.101529) (xy 123.02326 -379.161257) (xy 123.046931 -379.224267)
			(xy 123.062901 -379.289654) (xy 123.070942 -379.356482) (xy 123.070937 -379.423791) (xy 123.062888 -379.490617)
			(xy 123.04691 -379.556002) (xy 123.023231 -379.619009) (xy 122.992191 -379.678733) (xy 122.954235 -379.73432)
			(xy 122.932444 -379.759972) (xy 122.926627 -379.767103) (xy 122.920126 -379.784305) (xy 122.919744 -379.7935)
			(xy 122.919744 -380.286768) (xy 122.920182 -380.295952) (xy 122.926678 -380.313136) (xy 122.932444 -380.320296)
			(xy 122.954252 -380.345932) (xy 122.992201 -380.40152) (xy 123.023235 -380.461246) (xy 123.046907 -380.524252)
			(xy 123.062879 -380.589637) (xy 123.070915 -380.656404) (xy 126.34896 -380.656404) (xy 126.357035 -380.589466)
			(xy 126.373069 -380.523978) (xy 126.396833 -380.460881) (xy 126.427983 -380.401086) (xy 126.466072 -380.345453)
			(xy 126.487936 -380.319788) (xy 126.493725 -380.312637) (xy 126.500243 -380.295451) (xy 126.500636 -380.28626)
			(xy 126.500636 -379.794008) (xy 126.500214 -379.784822) (xy 126.493708 -379.767638) (xy 126.487936 -379.76048)
			(xy 126.466118 -379.734776) (xy 126.428025 -379.679148) (xy 126.396871 -379.619358) (xy 126.373102 -379.556266)
			(xy 126.357062 -379.490781) (xy 126.348982 -379.423846) (xy 126.348978 -379.356426) (xy 126.357049 -379.28949)
			(xy 126.373081 -379.224003) (xy 126.396841 -379.160908) (xy 126.427988 -379.101114) (xy 126.466074 -379.045481)
			(xy 126.487936 -379.019816) (xy 126.493755 -379.012687) (xy 126.500256 -378.995484) (xy 126.500636 -378.986288)
			(xy 126.500636 -378.828554) (xy 126.501089 -378.818425) (xy 126.508831 -378.799703) (xy 126.523127 -378.785349)
			(xy 126.541817 -378.777531) (xy 126.551944 -378.776992) (xy 127.268224 -378.776992) (xy 127.278379 -378.777402)
			(xy 127.29713 -378.785204) (xy 127.311452 -378.799604) (xy 127.319153 -378.818397) (xy 127.319532 -378.828554)
			(xy 127.319532 -378.986288) (xy 127.319963 -378.995473) (xy 127.326464 -379.012656) (xy 127.332232 -379.019816)
			(xy 127.354142 -379.045443) (xy 127.392227 -379.101084) (xy 127.423374 -379.160885) (xy 127.447134 -379.223987)
			(xy 127.463165 -379.289481) (xy 127.471237 -379.356423) (xy 127.471232 -379.423849) (xy 127.463152 -379.49079)
			(xy 127.447113 -379.556282) (xy 127.423345 -379.61938) (xy 127.39219 -379.679178) (xy 127.354098 -379.734814)
			(xy 127.332232 -379.76048) (xy 127.326411 -379.767607) (xy 127.319913 -379.784812) (xy 127.319532 -379.794008)
			(xy 127.319532 -380.28626) (xy 127.319977 -380.295443) (xy 127.326468 -380.312627) (xy 127.332232 -380.319788)
			(xy 127.354114 -380.345438) (xy 127.392201 -380.401075) (xy 127.423349 -380.460874) (xy 127.44711 -380.523973)
			(xy 127.463143 -380.589463) (xy 127.471217 -380.656403) (xy 127.471217 -380.656463) (xy 130.74928 -380.656463)
			(xy 130.757322 -380.589642) (xy 130.773292 -380.524262) (xy 130.796962 -380.461258) (xy 130.827992 -380.401535)
			(xy 130.865938 -380.345948) (xy 130.887724 -380.320296) (xy 130.893508 -380.313142) (xy 130.900029 -380.295958)
			(xy 130.900424 -380.286768) (xy 130.900424 -379.7935) (xy 130.900009 -379.784313) (xy 130.893498 -379.767129)
			(xy 130.887724 -379.759972) (xy 130.865984 -379.734281) (xy 130.828035 -379.678699) (xy 130.797 -379.618981)
			(xy 130.773326 -379.555982) (xy 130.75735 -379.490605) (xy 130.749302 -379.423787) (xy 130.749298 -379.356486)
			(xy 130.757337 -379.289667) (xy 130.773304 -379.224287) (xy 130.796971 -379.161285) (xy 130.827998 -379.101563)
			(xy 130.86594 -379.045977) (xy 130.887724 -379.020324) (xy 130.893538 -379.013191) (xy 130.900042 -378.995991)
			(xy 130.900424 -378.986796) (xy 130.900424 -378.828554) (xy 130.900895 -378.818395) (xy 130.908682 -378.799628)
			(xy 130.923054 -378.785264) (xy 130.941827 -378.777489) (xy 130.951986 -378.776992) (xy 131.668266 -378.776992)
			(xy 131.678416 -378.77756) (xy 131.697175 -378.785315) (xy 131.71154 -378.799657) (xy 131.719324 -378.818405)
			(xy 131.719828 -378.828554) (xy 131.719828 -378.986796) (xy 131.720234 -378.995984) (xy 131.72675 -379.013168)
			(xy 131.732528 -379.020324) (xy 131.754364 -379.045937) (xy 131.792314 -379.101528) (xy 131.823347 -379.161257)
			(xy 131.847018 -379.224267) (xy 131.862989 -379.289654) (xy 131.87103 -379.356481) (xy 131.871025 -379.423791)
			(xy 131.862976 -379.490617) (xy 131.846997 -379.556003) (xy 131.823317 -379.619009) (xy 131.792277 -379.678734)
			(xy 131.75432 -379.73432) (xy 131.732528 -379.759972) (xy 131.72671 -379.767101) (xy 131.72021 -379.784304)
			(xy 131.719828 -379.7935) (xy 131.719828 -380.286768) (xy 131.720247 -380.295954) (xy 131.726754 -380.313139)
			(xy 131.732528 -380.320296) (xy 131.754336 -380.345932) (xy 131.792287 -380.40152) (xy 131.823321 -380.461245)
			(xy 131.846994 -380.524252) (xy 131.862967 -380.589636) (xy 131.871003 -380.656404) (xy 161.548806 -380.656404)
			(xy 161.55688 -380.589468) (xy 161.572912 -380.523981) (xy 161.596672 -380.460885) (xy 161.627819 -380.401089)
			(xy 161.665902 -380.345454) (xy 161.687764 -380.319788) (xy 161.693556 -380.31264) (xy 161.700072 -380.295451)
			(xy 161.700464 -380.28626) (xy 161.700464 -379.794008) (xy 161.700036 -379.784823) (xy 161.693533 -379.767639)
			(xy 161.687764 -379.76048) (xy 161.665948 -379.734775) (xy 161.627861 -379.679146) (xy 161.59671 -379.619354)
			(xy 161.572945 -379.556263) (xy 161.556907 -379.490779) (xy 161.548828 -379.423846) (xy 161.548823 -379.356426)
			(xy 161.556894 -379.289492) (xy 161.572923 -379.224006) (xy 161.59668 -379.160911) (xy 161.627824 -379.101116)
			(xy 161.665904 -379.045482) (xy 161.687764 -379.019816) (xy 161.693587 -379.01269) (xy 161.700084 -378.995484)
			(xy 161.700464 -378.986288) (xy 161.700464 -378.828554) (xy 161.70089 -378.818421) (xy 161.708637 -378.799695)
			(xy 161.722942 -378.785339) (xy 161.741641 -378.777526) (xy 161.751772 -378.776992) (xy 162.468052 -378.776992)
			(xy 162.47817 -378.777455) (xy 162.496871 -378.785186) (xy 162.511187 -378.799488) (xy 162.518935 -378.818182)
			(xy 162.51936 -378.8283) (xy 162.51936 -378.986288) (xy 162.519785 -378.995473) (xy 162.526289 -379.012658)
			(xy 162.53206 -379.019816) (xy 162.553973 -379.045442) (xy 162.592062 -379.101081) (xy 162.623213 -379.160882)
			(xy 162.646977 -379.223984) (xy 162.66301 -379.289479) (xy 162.671083 -379.356422) (xy 162.671078 -379.42385)
			(xy 162.662997 -379.490792) (xy 162.646955 -379.556285) (xy 162.623184 -379.619384) (xy 162.592025 -379.679181)
			(xy 162.553928 -379.734815) (xy 162.53206 -379.76048) (xy 162.526242 -379.76761) (xy 162.519741 -379.784812)
			(xy 162.51936 -379.794008) (xy 162.51936 -380.28626) (xy 162.519799 -380.295444) (xy 162.526294 -380.312628)
			(xy 162.53206 -380.319788) (xy 162.553945 -380.345436) (xy 162.592036 -380.401072) (xy 162.623188 -380.460871)
			(xy 162.646953 -380.52397) (xy 162.662988 -380.589461) (xy 162.671063 -380.656402) (xy 162.671063 -380.656463)
			(xy 165.949102 -380.656463) (xy 165.957144 -380.589642) (xy 165.973115 -380.524261) (xy 165.996786 -380.461257)
			(xy 166.027818 -380.401534) (xy 166.065765 -380.345948) (xy 166.087552 -380.320296) (xy 166.093339 -380.313144)
			(xy 166.099858 -380.295959) (xy 166.100252 -380.286768) (xy 166.100252 -379.7935) (xy 166.09983 -379.784314)
			(xy 166.093323 -379.76713) (xy 166.087552 -379.759972) (xy 166.065811 -379.734281) (xy 166.02786 -379.678701)
			(xy 165.996824 -379.618982) (xy 165.973148 -379.555983) (xy 165.957171 -379.490605) (xy 165.949123 -379.423787)
			(xy 165.949119 -379.356485) (xy 165.957158 -379.289666) (xy 165.973127 -379.224286) (xy 165.996795 -379.161284)
			(xy 166.027823 -379.101562) (xy 166.065767 -379.045976) (xy 166.087552 -379.020324) (xy 166.09337 -379.013194)
			(xy 166.09987 -378.995992) (xy 166.100252 -378.986796) (xy 166.100252 -378.828554) (xy 166.100696 -378.818392)
			(xy 166.108488 -378.799619) (xy 166.122869 -378.785255) (xy 166.141651 -378.777484) (xy 166.151814 -378.776992)
			(xy 166.868094 -378.776992) (xy 166.878246 -378.777537) (xy 166.897006 -378.785301) (xy 166.91137 -378.79965)
			(xy 166.919153 -378.818403) (xy 166.919656 -378.828554) (xy 166.919656 -378.986796) (xy 166.920078 -378.995982)
			(xy 166.926584 -379.013166) (xy 166.932356 -379.020324) (xy 166.954191 -379.045937) (xy 166.992139 -379.101529)
			(xy 167.02317 -379.161258) (xy 167.046841 -379.224268) (xy 167.06281 -379.289655) (xy 167.070851 -379.356482)
			(xy 167.070847 -379.423791) (xy 167.062798 -379.490617) (xy 167.046819 -379.556001) (xy 167.023141 -379.619008)
			(xy 166.992102 -379.678733) (xy 166.954147 -379.73432) (xy 166.932356 -379.759972) (xy 166.926541 -379.767104)
			(xy 166.920038 -379.784305) (xy 166.919656 -379.7935) (xy 166.919656 -380.286768) (xy 166.920091 -380.295952)
			(xy 166.926588 -380.313137) (xy 166.932356 -380.320296) (xy 166.954164 -380.345932) (xy 166.992112 -380.40152)
			(xy 167.023145 -380.461246) (xy 167.046817 -380.524253) (xy 167.062789 -380.589637) (xy 167.070824 -380.656403)
			(xy 170.34887 -380.656403) (xy 170.356944 -380.589466) (xy 170.372979 -380.523977) (xy 170.396743 -380.460881)
			(xy 170.427894 -380.401086) (xy 170.465984 -380.345452) (xy 170.487848 -380.319788) (xy 170.493638 -380.312638)
			(xy 170.500155 -380.295451) (xy 170.500548 -380.28626) (xy 170.500548 -379.794008) (xy 170.500123 -379.784823)
			(xy 170.493619 -379.767639) (xy 170.487848 -379.76048) (xy 170.46603 -379.734777) (xy 170.427936 -379.679149)
			(xy 170.396781 -379.619358) (xy 170.373012 -379.556266) (xy 170.356971 -379.490781) (xy 170.348891 -379.423846)
			(xy 170.348887 -379.356426) (xy 170.356959 -379.28949) (xy 170.37299 -379.224003) (xy 170.396751 -379.160908)
			(xy 170.427899 -379.101113) (xy 170.465985 -379.04548) (xy 170.487848 -379.019816) (xy 170.493669 -379.012688)
			(xy 170.500168 -378.995484) (xy 170.500548 -378.986288) (xy 170.500548 -378.828554) (xy 170.500989 -378.818423)
			(xy 170.508734 -378.7997) (xy 170.523034 -378.785345) (xy 170.541727 -378.777529) (xy 170.551856 -378.776992)
			(xy 171.268136 -378.776992) (xy 171.278291 -378.777392) (xy 171.297043 -378.785198) (xy 171.311365 -378.799601)
			(xy 171.319065 -378.818396) (xy 171.319444 -378.828554) (xy 171.319444 -378.986288) (xy 171.319872 -378.995473)
			(xy 171.326375 -379.012657) (xy 171.332144 -379.019816) (xy 171.354057 -379.045441) (xy 171.392148 -379.10108)
			(xy 171.4233 -379.160881) (xy 171.447064 -379.223984) (xy 171.463098 -379.289478) (xy 171.47117 -379.356422)
			(xy 171.471166 -379.42385) (xy 171.463085 -379.490793) (xy 171.447042 -379.556285) (xy 171.42327 -379.619384)
			(xy 171.392111 -379.679182) (xy 171.354013 -379.734816) (xy 171.332144 -379.76048) (xy 171.326324 -379.767608)
			(xy 171.319825 -379.784812) (xy 171.319444 -379.794008) (xy 171.319444 -380.28626) (xy 171.319886 -380.295444)
			(xy 171.326379 -380.312628) (xy 171.332144 -380.319788) (xy 171.35403 -380.345436) (xy 171.392121 -380.401072)
			(xy 171.423274 -380.46087) (xy 171.44704 -380.523969) (xy 171.463076 -380.589461) (xy 171.471151 -380.656402)
			(xy 171.471151 -380.656463) (xy 174.74919 -380.656463) (xy 174.757232 -380.589642) (xy 174.773202 -380.524261)
			(xy 174.796873 -380.461258) (xy 174.827904 -380.401535) (xy 174.86585 -380.345948) (xy 174.887636 -380.320296)
			(xy 174.893421 -380.313143) (xy 174.899942 -380.295958) (xy 174.900336 -380.286768) (xy 174.900336 -379.7935)
			(xy 174.899918 -379.784314) (xy 174.893409 -379.76713) (xy 174.887636 -379.759972) (xy 174.865896 -379.734281)
			(xy 174.827946 -379.6787) (xy 174.796911 -379.618982) (xy 174.773235 -379.555982) (xy 174.757259 -379.490605)
			(xy 174.749211 -379.423787) (xy 174.749207 -379.356486) (xy 174.757246 -379.289666) (xy 174.773214 -379.224287)
			(xy 174.796881 -379.161284) (xy 174.827909 -379.101562) (xy 174.865851 -379.045976) (xy 174.887636 -379.020324)
			(xy 174.893452 -379.013193) (xy 174.899954 -378.995991) (xy 174.900336 -378.986796) (xy 174.900336 -378.828554)
			(xy 174.900796 -378.818394) (xy 174.908585 -378.799624) (xy 174.922961 -378.78526) (xy 174.941737 -378.777487)
			(xy 174.951898 -378.776992) (xy 175.668178 -378.776992) (xy 175.678329 -378.77755) (xy 175.697089 -378.785309)
			(xy 175.711453 -378.799654) (xy 175.719237 -378.818404) (xy 175.71974 -378.828554) (xy 175.71974 -378.986796)
			(xy 175.720166 -378.995981) (xy 175.72667 -379.013165) (xy 175.73244 -379.020324) (xy 175.754276 -379.045937)
			(xy 175.792225 -379.101529) (xy 175.823257 -379.161257) (xy 175.846928 -379.224267) (xy 175.862898 -379.289654)
			(xy 175.870939 -379.356481) (xy 175.870934 -379.423791) (xy 175.862885 -379.490617) (xy 175.846907 -379.556002)
			(xy 175.823227 -379.619009) (xy 175.792187 -379.678734) (xy 175.754231 -379.73432) (xy 175.73244 -379.759972)
			(xy 175.726623 -379.767102) (xy 175.720122 -379.784305) (xy 175.71974 -379.7935) (xy 175.71974 -380.286768)
			(xy 175.720179 -380.295952) (xy 175.726674 -380.313136) (xy 175.73244 -380.320296) (xy 175.754248 -380.345932)
			(xy 175.792198 -380.40152) (xy 175.823231 -380.461246) (xy 175.846904 -380.524252) (xy 175.862876 -380.589637)
			(xy 175.870919 -380.656462) (xy 175.870917 -380.723769) (xy 175.862871 -380.790593) (xy 175.846895 -380.855977)
			(xy 175.823219 -380.918982) (xy 175.792182 -380.978706) (xy 175.75423 -381.034292) (xy 175.73244 -381.059944)
			(xy 175.726635 -381.067083) (xy 175.720127 -381.084278) (xy 175.71974 -381.093472) (xy 175.71974 -381.251206)
			(xy 175.71934 -381.261381) (xy 175.711549 -381.28018) (xy 175.697156 -381.294565) (xy 175.678353 -381.302346)
			(xy 175.668178 -381.302768) (xy 174.951898 -381.302768) (xy 174.941741 -381.302268) (xy 174.922973 -381.294494)
			(xy 174.908608 -381.280131) (xy 174.900832 -381.261363) (xy 174.900336 -381.251206) (xy 174.900336 -381.093472)
			(xy 174.899931 -381.084284) (xy 174.893413 -381.067101) (xy 174.887636 -381.059944) (xy 174.865868 -381.034275)
			(xy 174.827919 -380.978691) (xy 174.796885 -380.91897) (xy 174.773211 -380.855968) (xy 174.757237 -380.790587)
			(xy 174.749191 -380.723767) (xy 174.74919 -380.656463) (xy 171.471151 -380.656463) (xy 171.471149 -380.723828)
			(xy 171.46307 -380.790769) (xy 171.447031 -380.85626) (xy 171.423262 -380.919358) (xy 171.392106 -380.979154)
			(xy 171.354011 -381.034788) (xy 171.332144 -381.060452) (xy 171.326336 -381.067589) (xy 171.31983 -381.084786)
			(xy 171.319444 -381.09398) (xy 171.319444 -381.251206) (xy 171.318978 -381.261335) (xy 171.311245 -381.280059)
			(xy 171.296952 -381.294416) (xy 171.278263 -381.302232) (xy 171.268136 -381.302768) (xy 170.551856 -381.302768)
			(xy 170.541695 -381.302414) (xy 170.522936 -381.294598) (xy 170.508613 -381.28018) (xy 170.50092 -381.26137)
			(xy 170.500548 -381.251206) (xy 170.500548 -381.09398) (xy 170.500137 -381.084793) (xy 170.493623 -381.067609)
			(xy 170.487848 -381.060452) (xy 170.466002 -381.034771) (xy 170.42791 -380.97914) (xy 170.396755 -380.919347)
			(xy 170.372988 -380.856252) (xy 170.35695 -380.790764) (xy 170.348871 -380.723827) (xy 170.34887 -380.656403)
			(xy 167.070824 -380.656403) (xy 167.070831 -380.656462) (xy 167.070829 -380.723768) (xy 167.062783 -380.790592)
			(xy 167.046808 -380.855976) (xy 167.023133 -380.918981) (xy 166.992097 -380.978705) (xy 166.954145 -381.034292)
			(xy 166.932356 -381.059944) (xy 166.926553 -381.067084) (xy 166.920043 -381.084279) (xy 166.919656 -381.093472)
			(xy 166.919656 -381.251206) (xy 166.919171 -381.261365) (xy 166.911394 -381.280135) (xy 166.897025 -381.2945)
			(xy 166.878253 -381.302274) (xy 166.868094 -381.302768) (xy 166.151814 -381.302768) (xy 166.141644 -381.302325)
			(xy 166.122851 -381.294546) (xy 166.108466 -381.280166) (xy 166.100679 -381.261376) (xy 166.100252 -381.251206)
			(xy 166.100252 -381.093472) (xy 166.099844 -381.084285) (xy 166.093327 -381.067101) (xy 166.087552 -381.059944)
			(xy 166.065784 -381.034276) (xy 166.027833 -380.978692) (xy 165.996799 -380.918971) (xy 165.973124 -380.855968)
			(xy 165.957149 -380.790588) (xy 165.949103 -380.723767) (xy 165.949102 -380.656463) (xy 162.671063 -380.656463)
			(xy 162.671061 -380.723828) (xy 162.662983 -380.790768) (xy 162.646944 -380.856259) (xy 162.623176 -380.919357)
			(xy 162.59202 -380.979153) (xy 162.553927 -381.034787) (xy 162.53206 -381.060452) (xy 162.526254 -381.06759)
			(xy 162.519746 -381.084786) (xy 162.51936 -381.09398) (xy 162.51936 -381.251206) (xy 162.518878 -381.261333)
			(xy 162.511148 -381.280054) (xy 162.496861 -381.29441) (xy 162.478177 -381.302229) (xy 162.468052 -381.302768)
			(xy 161.751772 -381.302768) (xy 161.741644 -381.302406) (xy 161.722933 -381.294643) (xy 161.708619 -381.28031)
			(xy 161.70088 -381.261589) (xy 161.700464 -381.25146) (xy 161.700464 -381.09398) (xy 161.700049 -381.084794)
			(xy 161.693537 -381.06761) (xy 161.687764 -381.060452) (xy 161.665921 -381.03477) (xy 161.627834 -380.979137)
			(xy 161.596684 -380.919343) (xy 161.572921 -380.856248) (xy 161.556885 -380.790762) (xy 161.548808 -380.723826)
			(xy 161.548806 -380.656404) (xy 131.871003 -380.656404) (xy 131.87101 -380.656461) (xy 131.871008 -380.723769)
			(xy 131.862961 -380.790593) (xy 131.846985 -380.855977) (xy 131.823309 -380.918982) (xy 131.792271 -380.978706)
			(xy 131.754318 -381.034292) (xy 131.732528 -381.059944) (xy 131.726722 -381.067082) (xy 131.720215 -381.084278)
			(xy 131.719828 -381.093472) (xy 131.719828 -381.251206) (xy 131.71944 -381.261382) (xy 131.711647 -381.280184)
			(xy 131.69725 -381.294569) (xy 131.678443 -381.302348) (xy 131.668266 -381.302768) (xy 130.951986 -381.302768)
			(xy 130.941828 -381.302278) (xy 130.92306 -381.2945) (xy 130.908695 -381.280133) (xy 130.90092 -381.261364)
			(xy 130.900424 -381.251206) (xy 130.900424 -381.093472) (xy 130.900022 -381.084284) (xy 130.893502 -381.0671)
			(xy 130.887724 -381.059944) (xy 130.865956 -381.034276) (xy 130.828008 -380.978691) (xy 130.796975 -380.91897)
			(xy 130.773301 -380.855967) (xy 130.757327 -380.790587) (xy 130.749282 -380.723767) (xy 130.74928 -380.656463)
			(xy 127.471217 -380.656463) (xy 127.471215 -380.723827) (xy 127.463138 -380.790766) (xy 127.447101 -380.856256)
			(xy 127.423336 -380.919354) (xy 127.392185 -380.979151) (xy 127.354096 -381.034786) (xy 127.332232 -381.060452)
			(xy 127.326423 -381.067588) (xy 127.319918 -381.084786) (xy 127.319532 -381.09398) (xy 127.319532 -381.251206)
			(xy 127.319077 -381.261337) (xy 127.311342 -381.280063) (xy 127.297046 -381.29442) (xy 127.278352 -381.302234)
			(xy 127.268224 -381.302768) (xy 126.551944 -381.302768) (xy 126.541789 -381.302342) (xy 126.523031 -381.294555)
			(xy 126.508705 -381.280159) (xy 126.50101 -381.261363) (xy 126.500636 -381.251206) (xy 126.500636 -381.09398)
			(xy 126.500227 -381.084793) (xy 126.493712 -381.067609) (xy 126.487936 -381.060452) (xy 126.46609 -381.034771)
			(xy 126.427999 -380.97914) (xy 126.396845 -380.919346) (xy 126.373078 -380.856251) (xy 126.35704 -380.790764)
			(xy 126.348962 -380.723826) (xy 126.34896 -380.656404) (xy 123.070915 -380.656404) (xy 123.070922 -380.656462)
			(xy 123.07092 -380.723769) (xy 123.062874 -380.790593) (xy 123.046898 -380.855976) (xy 123.023223 -380.918982)
			(xy 122.992186 -380.978706) (xy 122.954234 -381.034292) (xy 122.932444 -381.059944) (xy 122.926639 -381.067083)
			(xy 122.920131 -381.084279) (xy 122.919744 -381.093472) (xy 122.919744 -381.251206) (xy 122.919341 -381.26138)
			(xy 122.91155 -381.280178) (xy 122.897158 -381.294564) (xy 122.878356 -381.302345) (xy 122.868182 -381.302768)
			(xy 122.151902 -381.302768) (xy 122.141745 -381.302265) (xy 122.122977 -381.294492) (xy 122.108612 -381.28013)
			(xy 122.100836 -381.261363) (xy 122.10034 -381.251206) (xy 122.10034 -381.093472) (xy 122.099934 -381.084285)
			(xy 122.093417 -381.067101) (xy 122.08764 -381.059944) (xy 122.065872 -381.034276) (xy 122.027923 -380.978691)
			(xy 121.996888 -380.91897) (xy 121.973215 -380.855968) (xy 121.95724 -380.790588) (xy 121.949194 -380.723767)
			(xy 121.949193 -380.656463) (xy 118.671154 -380.656463) (xy 118.671152 -380.723828) (xy 118.663073 -380.790769)
			(xy 118.647034 -380.85626) (xy 118.623265 -380.919357) (xy 118.592109 -380.979154) (xy 118.554015 -381.034788)
			(xy 118.532148 -381.060452) (xy 118.52634 -381.067589) (xy 118.519834 -381.084786) (xy 118.519448 -381.09398)
			(xy 118.519448 -381.251206) (xy 118.518978 -381.261335) (xy 118.511246 -381.280058) (xy 118.496954 -381.294415)
			(xy 118.478266 -381.302231) (xy 118.46814 -381.302768) (xy 117.75186 -381.302768) (xy 117.741699 -381.30241)
			(xy 117.72294 -381.294596) (xy 117.708617 -381.280179) (xy 117.700924 -381.261369) (xy 117.700552 -381.251206)
			(xy 117.700552 -381.09398) (xy 117.70014 -381.084793) (xy 117.693626 -381.06761) (xy 117.687852 -381.060452)
			(xy 117.666006 -381.034771) (xy 117.627913 -380.97914) (xy 117.596759 -380.919347) (xy 117.572991 -380.856252)
			(xy 117.556953 -380.790764) (xy 117.548874 -380.723827) (xy 117.548873 -380.656403) (xy 105.919524 -380.656403)
			(xy 105.919524 -380.877572) (xy 105.919034 -380.907556) (xy 105.911206 -380.967012) (xy 105.895685 -381.024937)
			(xy 105.872736 -381.080341) (xy 105.842752 -381.132275) (xy 105.806246 -381.179851) (xy 105.763841 -381.222256)
			(xy 105.716265 -381.258762) (xy 105.664331 -381.288746) (xy 105.608927 -381.311695) (xy 105.551002 -381.327216)
			(xy 105.491546 -381.335044) (xy 105.431578 -381.335044) (xy 105.372122 -381.327216) (xy 105.314197 -381.311695)
			(xy 105.258793 -381.288746) (xy 105.206859 -381.258762) (xy 105.159283 -381.222256) (xy 105.116878 -381.179851)
			(xy 105.080372 -381.132275) (xy 105.050388 -381.080341) (xy 105.027439 -381.024937) (xy 105.011918 -380.967012)
			(xy 105.00409 -380.907556) (xy 105.0036 -380.877572) (xy 87.838954 -380.877572) (xy 87.823216 -380.919355)
			(xy 87.792063 -380.979152) (xy 87.753973 -381.034787) (xy 87.732108 -381.060452) (xy 87.726308 -381.067595)
			(xy 87.719795 -381.084787) (xy 87.719408 -381.09398) (xy 87.719408 -381.251206) (xy 87.71888 -381.261327)
			(xy 87.711159 -381.280039) (xy 87.696886 -381.294394) (xy 87.678218 -381.302221) (xy 87.6681 -381.302768)
			(xy 86.95182 -381.302768) (xy 86.941695 -381.302367) (xy 86.922985 -381.294619) (xy 86.908669 -381.280298)
			(xy 86.900929 -381.261585) (xy 86.900512 -381.25146) (xy 86.900512 -381.09398) (xy 86.900109 -381.084792)
			(xy 86.89359 -381.067608) (xy 86.887812 -381.060452) (xy 86.865967 -381.034771) (xy 86.827877 -380.979139)
			(xy 86.796725 -380.919345) (xy 86.772959 -380.85625) (xy 86.756922 -380.790763) (xy 86.748844 -380.723826)
			(xy 86.748842 -380.656404) (xy 83.470797 -380.656404) (xy 83.470804 -380.656461) (xy 83.470802 -380.723769)
			(xy 83.462755 -380.790593) (xy 83.446779 -380.855977) (xy 83.423102 -380.918983) (xy 83.392064 -380.978706)
			(xy 83.35411 -381.034292) (xy 83.33232 -381.059944) (xy 83.326525 -381.06709) (xy 83.320009 -381.08428)
			(xy 83.31962 -381.093472) (xy 83.31962 -381.251206) (xy 83.31924 -381.261383) (xy 83.311445 -381.280186)
			(xy 83.297046 -381.294572) (xy 83.278236 -381.302349) (xy 83.268058 -381.302768) (xy 82.551778 -381.302768)
			(xy 82.54162 -381.302285) (xy 82.522851 -381.294504) (xy 82.508487 -381.280136) (xy 82.500712 -381.261365)
			(xy 82.500216 -381.251206) (xy 82.500216 -381.093472) (xy 82.499816 -381.084284) (xy 82.493295 -381.0671)
			(xy 82.487516 -381.059944) (xy 82.465749 -381.034275) (xy 82.427801 -380.978691) (xy 82.396768 -380.918969)
			(xy 82.373095 -380.855967) (xy 82.357121 -380.790587) (xy 82.349076 -380.723767) (xy 82.349074 -380.656464)
			(xy 79.071011 -380.656464) (xy 79.071009 -380.723827) (xy 79.062932 -380.790767) (xy 79.046895 -380.856256)
			(xy 79.02313 -380.919354) (xy 78.991978 -380.979151) (xy 78.953888 -381.034786) (xy 78.932024 -381.060452)
			(xy 78.926226 -381.067596) (xy 78.919711 -381.084787) (xy 78.919324 -381.09398) (xy 78.919324 -381.251206)
			(xy 78.918877 -381.261337) (xy 78.911141 -381.280066) (xy 78.896842 -381.294423) (xy 78.878145 -381.302235)
			(xy 78.868016 -381.302768) (xy 78.151736 -381.302768) (xy 78.141612 -381.302354) (xy 78.122903 -381.294611)
			(xy 78.108586 -381.280294) (xy 78.100846 -381.261584) (xy 78.100428 -381.25146) (xy 78.100428 -381.09398)
			(xy 78.100021 -381.084793) (xy 78.093505 -381.067609) (xy 78.087728 -381.060452) (xy 78.065883 -381.034771)
			(xy 78.027792 -380.979139) (xy 77.996638 -380.919346) (xy 77.972872 -380.856251) (xy 77.956834 -380.790763)
			(xy 77.948756 -380.723826) (xy 77.948754 -380.656404) (xy 74.670709 -380.656404) (xy 74.670716 -380.656462)
			(xy 74.670714 -380.723769) (xy 74.662667 -380.790593) (xy 74.646691 -380.855977) (xy 74.623015 -380.918982)
			(xy 74.591978 -380.978706) (xy 74.554026 -381.034292) (xy 74.532236 -381.059944) (xy 74.52643 -381.067082)
			(xy 74.519923 -381.084278) (xy 74.519536 -381.093472) (xy 74.519536 -381.251206) (xy 74.51914 -381.261381)
			(xy 74.511349 -381.280181) (xy 74.496954 -381.294567) (xy 74.478149 -381.302347) (xy 74.467974 -381.302768)
			(xy 73.751694 -381.302768) (xy 73.741537 -381.302272) (xy 73.722769 -381.294496) (xy 73.708404 -381.280131)
			(xy 73.700628 -381.261363) (xy 73.700132 -381.251206) (xy 73.700132 -381.093472) (xy 73.699728 -381.084284)
			(xy 73.693209 -381.0671) (xy 73.687432 -381.059944) (xy 73.665664 -381.034275) (xy 73.627715 -380.978691)
			(xy 73.596682 -380.91897) (xy 73.573008 -380.855967) (xy 73.557034 -380.790587) (xy 73.548988 -380.723767)
			(xy 73.548987 -380.656463) (xy 43.87119 -380.656463) (xy 43.871188 -380.723828) (xy 43.86311 -380.790767)
			(xy 43.847073 -380.856258) (xy 43.823306 -380.919355) (xy 43.792153 -380.979152) (xy 43.754061 -381.034787)
			(xy 43.732196 -381.060452) (xy 43.726394 -381.067594) (xy 43.719883 -381.084787) (xy 43.719496 -381.09398)
			(xy 43.719496 -381.251206) (xy 43.718979 -381.261329) (xy 43.711256 -381.280043) (xy 43.69698 -381.294398)
			(xy 43.678308 -381.302223) (xy 43.668188 -381.302768) (xy 42.951908 -381.302768) (xy 42.94175 -381.302371)
			(xy 42.922992 -381.294572) (xy 42.908667 -381.280167) (xy 42.900973 -381.261366) (xy 42.9006 -381.251206)
			(xy 42.9006 -381.09398) (xy 42.9002 -381.084792) (xy 42.893679 -381.067607) (xy 42.8879 -381.060452)
			(xy 42.866056 -381.034771) (xy 42.827966 -380.979138) (xy 42.796815 -380.919344) (xy 42.773049 -380.85625)
			(xy 42.757013 -380.790763) (xy 42.748935 -380.723826) (xy 42.748933 -380.656404) (xy 39.470887 -380.656404)
			(xy 39.470894 -380.656461) (xy 39.470893 -380.723769) (xy 39.462846 -380.790594) (xy 39.446869 -380.855978)
			(xy 39.423192 -380.918983) (xy 39.392153 -380.978707) (xy 39.354199 -381.034293) (xy 39.332408 -381.059944)
			(xy 39.326611 -381.067089) (xy 39.320096 -381.08428) (xy 39.319708 -381.093472) (xy 39.319708 -381.251206)
			(xy 39.319173 -381.261358) (xy 39.311405 -381.280119) (xy 39.297052 -381.294482) (xy 39.278298 -381.302265)
			(xy 39.268146 -381.302768) (xy 38.551866 -381.302768) (xy 38.541707 -381.302295) (xy 38.522938 -381.29451)
			(xy 38.508574 -381.280138) (xy 38.5008 -381.261365) (xy 38.500304 -381.251206) (xy 38.500304 -381.093472)
			(xy 38.499907 -381.084283) (xy 38.493384 -381.067099) (xy 38.487604 -381.059944) (xy 38.465837 -381.034275)
			(xy 38.42789 -380.97869) (xy 38.396858 -380.918969) (xy 38.373185 -380.855966) (xy 38.357212 -380.790587)
			(xy 38.349167 -380.723766) (xy 38.349165 -380.656464) (xy 35.071102 -380.656464) (xy 35.0711 -380.723828)
			(xy 35.063023 -380.790767) (xy 35.046985 -380.856257) (xy 35.023219 -380.919355) (xy 34.992067 -380.979151)
			(xy 34.953977 -381.034787) (xy 34.932112 -381.060452) (xy 34.926312 -381.067595) (xy 34.919799 -381.084787)
			(xy 34.919412 -381.09398) (xy 34.919412 -381.251206) (xy 34.91888 -381.261327) (xy 34.91116 -381.280038)
			(xy 34.896888 -381.294392) (xy 34.878222 -381.30222) (xy 34.868104 -381.302768) (xy 34.151824 -381.302768)
			(xy 34.141667 -381.302358) (xy 34.122909 -381.294565) (xy 34.108584 -381.280164) (xy 34.100889 -381.261365)
			(xy 34.100516 -381.251206) (xy 34.100516 -381.09398) (xy 34.100112 -381.084792) (xy 34.093594 -381.067608)
			(xy 34.087816 -381.060452) (xy 34.065971 -381.034771) (xy 34.027881 -380.979139) (xy 33.996728 -380.919345)
			(xy 33.972962 -380.85625) (xy 33.956925 -380.790763) (xy 33.948847 -380.723826) (xy 33.948845 -380.656404)
			(xy 30.6708 -380.656404) (xy 30.670807 -380.656461) (xy 30.670805 -380.723769) (xy 30.662758 -380.790593)
			(xy 30.646782 -380.855977) (xy 30.623105 -380.918982) (xy 30.592068 -380.978706) (xy 30.554114 -381.034292)
			(xy 30.532324 -381.059944) (xy 30.526529 -381.067091) (xy 30.520013 -381.08428) (xy 30.519624 -381.093472)
			(xy 30.519624 -381.251206) (xy 30.51924 -381.261383) (xy 30.511446 -381.280185) (xy 30.497048 -381.294571)
			(xy 30.478239 -381.302349) (xy 30.468062 -381.302768) (xy 29.751782 -381.302768) (xy 29.741624 -381.302282)
			(xy 29.722855 -381.294502) (xy 29.708491 -381.280135) (xy 29.700716 -381.261364) (xy 29.70022 -381.251206)
			(xy 29.70022 -381.093472) (xy 29.699819 -381.084284) (xy 29.693298 -381.0671) (xy 29.68752 -381.059944)
			(xy 29.665752 -381.034276) (xy 29.627804 -380.978691) (xy 29.596771 -380.918969) (xy 29.573098 -380.855967)
			(xy 29.557124 -380.790587) (xy 29.549079 -380.723767) (xy 29.549077 -380.656463) (xy 29.557119 -380.589643)
			(xy 29.573089 -380.524262) (xy 29.596759 -380.461258) (xy 29.627789 -380.401535) (xy 29.665734 -380.345948)
			(xy 29.68752 -380.320296) (xy 29.693303 -380.313141) (xy 29.699825 -380.295958) (xy 29.70022 -380.286768)
			(xy 29.70022 -379.7935) (xy 29.699806 -379.784313) (xy 29.693295 -379.767129) (xy 29.68752 -379.759972)
			(xy 29.66573 -379.734322) (xy 29.627781 -379.678735) (xy 29.596748 -379.619011) (xy 29.573075 -379.556006)
			(xy 29.557102 -379.490624) (xy 29.549058 -379.423801) (xy 28.447 -379.423801) (xy 28.447041 -379.423909)
			(xy 28.463077 -379.489397) (xy 28.471153 -379.556335) (xy 28.471153 -379.623759) (xy 28.463078 -379.690697)
			(xy 28.447043 -379.756186) (xy 28.423279 -379.819282) (xy 28.392128 -379.879078) (xy 28.35404 -379.934713)
			(xy 28.332176 -379.960378) (xy 28.326361 -379.96751) (xy 28.319858 -379.984711) (xy 28.319476 -379.993906)
			(xy 28.319476 -380.151386) (xy 28.318962 -380.16151) (xy 28.311242 -380.180228) (xy 28.296964 -380.194584)
			(xy 28.278289 -380.202406) (xy 28.268168 -380.202948) (xy 27.551888 -380.202948) (xy 27.541784 -380.202426)
			(xy 27.523115 -380.194693) (xy 27.508823 -380.180408) (xy 27.50108 -380.161743) (xy 27.50058 -380.15164)
			(xy 27.50058 -379.993906) (xy 27.500171 -379.984719) (xy 27.493657 -379.967534) (xy 27.48788 -379.960378)
			(xy 27.466012 -379.934716) (xy 27.427923 -379.879081) (xy 27.396771 -379.819285) (xy 27.373007 -379.756187)
			(xy 27.356972 -379.690698) (xy 27.348896 -379.623759) (xy 27.348896 -379.556335) (xy 27.356973 -379.489396)
			(xy 27.373009 -379.423907) (xy 27.396774 -379.36081) (xy 27.427926 -379.301013) (xy 27.466015 -379.245379)
			(xy 27.48788 -379.219714) (xy 27.493693 -379.21258) (xy 27.500199 -379.195381) (xy 27.50058 -379.186186)
			(xy 27.50058 -378.693934) (xy 27.500158 -378.684748) (xy 27.493653 -378.667563) (xy 27.48788 -378.660406)
			(xy 27.465991 -378.634761) (xy 27.427905 -378.579124) (xy 27.396756 -378.519324) (xy 27.372994 -378.456225)
			(xy 27.356961 -378.390733) (xy 27.348888 -378.323793) (xy 0.508 -378.323793) (xy 0.508 -382.223705)
			(xy 27.348899 -382.223705) (xy 27.3489 -382.15628) (xy 27.356976 -382.089342) (xy 27.373012 -382.023853)
			(xy 27.396777 -381.960755) (xy 27.427928 -381.900959) (xy 27.466016 -381.845324) (xy 27.48788 -381.819658)
			(xy 27.493675 -381.812511) (xy 27.500191 -381.795322) (xy 27.50058 -381.78613) (xy 27.50058 -381.628904)
			(xy 27.501088 -381.618798) (xy 27.508821 -381.600124) (xy 27.52311 -381.58583) (xy 27.541782 -381.578091)
			(xy 27.551888 -381.577596) (xy 28.268168 -381.577596) (xy 28.278288 -381.578042) (xy 28.29699 -381.585779)
			(xy 28.311306 -381.600086) (xy 28.319053 -381.618784) (xy 28.319476 -381.628904) (xy 28.319476 -381.78613)
			(xy 28.319877 -381.795318) (xy 28.326398 -381.812502) (xy 28.332176 -381.819658) (xy 28.354031 -381.845331)
			(xy 28.392122 -381.900964) (xy 28.423274 -381.960759) (xy 28.44704 -382.023855) (xy 28.463077 -382.089343)
			(xy 28.471154 -382.156281) (xy 28.471155 -382.223646) (xy 31.749194 -382.223646) (xy 31.749195 -382.156339)
			(xy 31.757241 -382.089516) (xy 31.773216 -382.024132) (xy 31.796891 -381.961127) (xy 31.827927 -381.901404)
			(xy 31.865879 -381.845818) (xy 31.887668 -381.820166) (xy 31.89347 -381.813025) (xy 31.899979 -381.795831)
			(xy 31.900368 -381.786638) (xy 31.900368 -381.628904) (xy 31.900824 -381.618754) (xy 31.908613 -381.600008)
			(xy 31.922998 -381.585686) (xy 31.941778 -381.57798) (xy 31.95193 -381.577596) (xy 32.66821 -381.577596)
			(xy 32.678332 -381.578117) (xy 32.697045 -381.58584) (xy 32.711399 -381.600115) (xy 32.719226 -381.618785)
			(xy 32.719772 -381.628904) (xy 32.719772 -381.786638) (xy 32.72017 -381.795826) (xy 32.726693 -381.81301)
			(xy 32.732472 -381.820166) (xy 32.75425 -381.845826) (xy 32.792198 -381.901412) (xy 32.823231 -381.961134)
			(xy 32.846904 -382.024138) (xy 32.862877 -382.089519) (xy 32.870922 -382.15634) (xy 32.870923 -382.223645)
			(xy 32.870916 -382.223704) (xy 36.148987 -382.223704) (xy 36.148988 -382.156281) (xy 36.157064 -382.089342)
			(xy 36.1731 -382.023853) (xy 36.196863 -381.960756) (xy 36.228013 -381.900959) (xy 36.266101 -381.845324)
			(xy 36.287964 -381.819658) (xy 36.293769 -381.812519) (xy 36.300277 -381.795323) (xy 36.300664 -381.78613)
			(xy 36.300664 -381.628904) (xy 36.301188 -381.6188) (xy 36.308917 -381.600129) (xy 36.323202 -381.585835)
			(xy 36.341868 -381.578094) (xy 36.351972 -381.577596) (xy 37.068252 -381.577596) (xy 37.078371 -381.578055)
			(xy 37.097073 -381.585787) (xy 37.111388 -381.60009) (xy 37.119136 -381.618786) (xy 37.11956 -381.628904)
			(xy 37.11956 -381.78613) (xy 37.119965 -381.795318) (xy 37.126483 -381.812501) (xy 37.13226 -381.819658)
			(xy 37.154116 -381.845331) (xy 37.192207 -381.900963) (xy 37.223361 -381.960758) (xy 37.247127 -382.023854)
			(xy 37.263164 -382.089343) (xy 37.271242 -382.156281) (xy 37.271243 -382.223704) (xy 37.271243 -382.223705)
			(xy 40.548753 -382.223705) (xy 40.548754 -382.15628) (xy 40.556832 -382.08934) (xy 40.57287 -382.02385)
			(xy 40.596638 -381.960752) (xy 40.627792 -381.900956) (xy 40.665886 -381.845322) (xy 40.687752 -381.819658)
			(xy 40.693555 -381.812518) (xy 40.700065 -381.795323) (xy 40.700452 -381.78613) (xy 40.700452 -381.628904)
			(xy 40.700987 -381.618801) (xy 40.708715 -381.600133) (xy 40.722996 -381.585839) (xy 40.741658 -381.578096)
			(xy 40.75176 -381.577596) (xy 41.46804 -381.577596) (xy 41.478151 -381.578052) (xy 41.496829 -381.585802)
			(xy 41.511122 -381.600108) (xy 41.518856 -381.618793) (xy 41.519348 -381.628904) (xy 41.519348 -381.78613)
			(xy 41.519755 -381.795317) (xy 41.526272 -381.812501) (xy 41.532048 -381.819658) (xy 41.553904 -381.84533)
			(xy 41.591996 -381.900963) (xy 41.62315 -381.960757) (xy 41.646917 -382.023853) (xy 41.662955 -382.089342)
			(xy 41.671033 -382.156281) (xy 41.671034 -382.223645) (xy 44.949073 -382.223645) (xy 44.949074 -382.15634)
			(xy 44.957119 -382.089516) (xy 44.973093 -382.024133) (xy 44.996767 -381.961128) (xy 45.027801 -381.901405)
			(xy 45.065751 -381.845818) (xy 45.08754 -381.820166) (xy 45.093339 -381.813022) (xy 45.099851 -381.795831)
			(xy 45.10024 -381.786638) (xy 45.10024 -381.628904) (xy 45.100626 -381.618745) (xy 45.108427 -381.599985)
			(xy 45.122836 -381.58566) (xy 45.141641 -381.577968) (xy 45.151802 -381.577596) (xy 45.868082 -381.577596)
			(xy 45.878202 -381.57814) (xy 45.896915 -381.585854) (xy 45.91127 -381.600122) (xy 45.919098 -381.618787)
			(xy 45.919644 -381.628904) (xy 45.919644 -381.786638) (xy 45.920049 -381.795826) (xy 45.926568 -381.813009)
			(xy 45.932344 -381.820166) (xy 45.954122 -381.845826) (xy 45.992072 -381.901411) (xy 46.023107 -381.961133)
			(xy 46.046781 -382.024137) (xy 46.062755 -382.089518) (xy 46.070801 -382.15634) (xy 46.070801 -382.223645)
			(xy 46.070794 -382.223705) (xy 71.348808 -382.223705) (xy 71.348809 -382.15628) (xy 71.356886 -382.089342)
			(xy 71.372922 -382.023852) (xy 71.396687 -381.960755) (xy 71.427838 -381.900958) (xy 71.465928 -381.845323)
			(xy 71.487792 -381.819658) (xy 71.493588 -381.812512) (xy 71.500103 -381.795322) (xy 71.500492 -381.78613)
			(xy 71.500492 -381.628904) (xy 71.500919 -381.618783) (xy 71.508664 -381.600081) (xy 71.522977 -381.585767)
			(xy 71.541679 -381.57802) (xy 71.5518 -381.577596) (xy 72.26808 -381.577596) (xy 72.278201 -381.578032)
			(xy 72.296903 -381.585773) (xy 72.311218 -381.600083) (xy 72.318965 -381.618783) (xy 72.319388 -381.628904)
			(xy 72.319388 -381.78613) (xy 72.319786 -381.795318) (xy 72.326308 -381.812503) (xy 72.332088 -381.819658)
			(xy 72.353943 -381.845331) (xy 72.392032 -381.900964) (xy 72.423184 -381.960759) (xy 72.446949 -382.023855)
			(xy 72.462986 -382.089343) (xy 72.471063 -382.156281) (xy 72.471064 -382.223646) (xy 75.749104 -382.223646)
			(xy 75.749104 -382.156339) (xy 75.75715 -382.089515) (xy 75.773125 -382.024132) (xy 75.796801 -381.961127)
			(xy 75.827838 -381.901403) (xy 75.86579 -381.845818) (xy 75.88758 -381.820166) (xy 75.893371 -381.813017)
			(xy 75.89989 -381.795829) (xy 75.90028 -381.786638) (xy 75.90028 -381.628904) (xy 75.900725 -381.618753)
			(xy 75.908515 -381.600004) (xy 75.922904 -381.585681) (xy 75.941689 -381.577978) (xy 75.951842 -381.577596)
			(xy 76.668122 -381.577596) (xy 76.678245 -381.578107) (xy 76.696958 -381.585834) (xy 76.711312 -381.600112)
			(xy 76.719138 -381.618784) (xy 76.719684 -381.628904) (xy 76.719684 -381.786638) (xy 76.720079 -381.795827)
			(xy 76.726604 -381.813011) (xy 76.732384 -381.820166) (xy 76.754161 -381.845826) (xy 76.792109 -381.901412)
			(xy 76.823141 -381.961135) (xy 76.846814 -382.024138) (xy 76.862787 -382.089519) (xy 76.870831 -382.156341)
			(xy 76.870832 -382.223644) (xy 76.870825 -382.223704) (xy 80.148896 -382.223704) (xy 80.148897 -382.15628)
			(xy 80.156973 -382.089342) (xy 80.173009 -382.023853) (xy 80.196773 -381.960755) (xy 80.227924 -381.900959)
			(xy 80.266012 -381.845324) (xy 80.287876 -381.819658) (xy 80.29367 -381.812511) (xy 80.300187 -381.795322)
			(xy 80.300576 -381.78613) (xy 80.300576 -381.628904) (xy 80.301088 -381.618798) (xy 80.30882 -381.600125)
			(xy 80.323108 -381.585831) (xy 80.341779 -381.578092) (xy 80.351884 -381.577596) (xy 81.068164 -381.577596)
			(xy 81.078284 -381.578046) (xy 81.096986 -381.585781) (xy 81.111301 -381.600087) (xy 81.119048 -381.618785)
			(xy 81.119472 -381.628904) (xy 81.119472 -381.78613) (xy 81.119874 -381.795318) (xy 81.126394 -381.812502)
			(xy 81.132172 -381.819658) (xy 81.154027 -381.845331) (xy 81.192118 -381.900964) (xy 81.223271 -381.960759)
			(xy 81.247037 -382.023854) (xy 81.263074 -382.089343) (xy 81.271151 -382.156281) (xy 81.271152 -382.223704)
			(xy 84.548687 -382.223704) (xy 84.548688 -382.156281) (xy 84.556764 -382.089342) (xy 84.5728 -382.023853)
			(xy 84.596563 -381.960756) (xy 84.627713 -381.900959) (xy 84.665801 -381.845324) (xy 84.687664 -381.819658)
			(xy 84.693469 -381.812519) (xy 84.699977 -381.795323) (xy 84.700364 -381.78613) (xy 84.700364 -381.628904)
			(xy 84.700888 -381.6188) (xy 84.708617 -381.600129) (xy 84.722902 -381.585835) (xy 84.741568 -381.578094)
			(xy 84.751672 -381.577596) (xy 85.467952 -381.577596) (xy 85.478071 -381.578055) (xy 85.496773 -381.585787)
			(xy 85.511088 -381.60009) (xy 85.518836 -381.618786) (xy 85.51926 -381.628904) (xy 85.51926 -381.78613)
			(xy 85.519665 -381.795318) (xy 85.526183 -381.812501) (xy 85.53196 -381.819658) (xy 85.553816 -381.845331)
			(xy 85.591907 -381.900963) (xy 85.623061 -381.960758) (xy 85.646827 -382.023854) (xy 85.662864 -382.089343)
			(xy 85.670942 -382.156281) (xy 85.670943 -382.223646) (xy 88.948982 -382.223646) (xy 88.948983 -382.156339)
			(xy 88.957028 -382.089516) (xy 88.973003 -382.024133) (xy 88.996677 -381.961128) (xy 89.027712 -381.901404)
			(xy 89.065663 -381.845818) (xy 89.087452 -381.820166) (xy 89.093252 -381.813023) (xy 89.099763 -381.795831)
			(xy 89.100152 -381.786638) (xy 89.100152 -381.628904) (xy 89.100624 -381.618756) (xy 89.108409 -381.600013)
			(xy 89.12279 -381.585691) (xy 89.141564 -381.577983) (xy 89.151714 -381.577596) (xy 89.867994 -381.577596)
			(xy 89.878115 -381.57813) (xy 89.896828 -381.585848) (xy 89.911183 -381.600119) (xy 89.91901 -381.618786)
			(xy 89.919556 -381.628904) (xy 89.919556 -381.786638) (xy 89.919958 -381.795826) (xy 89.926478 -381.81301)
			(xy 89.932256 -381.820166) (xy 89.954034 -381.845826) (xy 89.991983 -381.901411) (xy 90.023017 -381.961134)
			(xy 90.046691 -382.024137) (xy 90.062665 -382.089519) (xy 90.07071 -382.15634) (xy 90.070711 -382.223645)
			(xy 115.349246 -382.223645) (xy 115.349247 -382.15634) (xy 115.357291 -382.089517) (xy 115.373264 -382.024135)
			(xy 115.396937 -381.96113) (xy 115.427969 -381.901406) (xy 115.465917 -381.845819) (xy 115.487704 -381.820166)
			(xy 115.493498 -381.813019) (xy 115.500014 -381.79583) (xy 115.500404 -381.786638) (xy 115.500404 -381.628904)
			(xy 115.500825 -381.61875) (xy 115.50862 -381.599997) (xy 115.523017 -381.585673) (xy 115.54181 -381.577974)
			(xy 115.551966 -381.577596) (xy 116.268246 -381.577596) (xy 116.27837 -381.578088) (xy 116.297084 -381.585822)
			(xy 116.311437 -381.600106) (xy 116.319262 -381.618782) (xy 116.319808 -381.628904) (xy 116.319808 -381.786638)
			(xy 116.320198 -381.795827) (xy 116.326725 -381.813012) (xy 116.332508 -381.820166) (xy 116.354288 -381.845826)
			(xy 116.39224 -381.90141) (xy 116.423277 -381.961132) (xy 116.446952 -382.024135) (xy 116.462928 -382.089517)
			(xy 116.470973 -382.15634) (xy 116.470974 -382.223645) (xy 116.470967 -382.223705) (xy 119.749014 -382.223705)
			(xy 119.749015 -382.15628) (xy 119.757092 -382.089341) (xy 119.773128 -382.023852) (xy 119.796894 -381.960754)
			(xy 119.828046 -381.900958) (xy 119.866135 -381.845323) (xy 119.888 -381.819658) (xy 119.893797 -381.812513)
			(xy 119.900311 -381.795322) (xy 119.9007 -381.78613) (xy 119.9007 -381.628904) (xy 119.901119 -381.618782)
			(xy 119.908866 -381.600078) (xy 119.923182 -381.585764) (xy 119.941886 -381.578019) (xy 119.952008 -381.577596)
			(xy 120.668288 -381.577596) (xy 120.678409 -381.578026) (xy 120.697112 -381.585769) (xy 120.711426 -381.600081)
			(xy 120.719173 -381.618783) (xy 120.719596 -381.628904) (xy 120.719596 -381.78613) (xy 120.719992 -381.795319)
			(xy 120.726516 -381.812503) (xy 120.732296 -381.819658) (xy 120.75415 -381.845331) (xy 120.79224 -381.900965)
			(xy 120.823391 -381.96076) (xy 120.847156 -382.023855) (xy 120.863192 -382.089344) (xy 120.871269 -382.156281)
			(xy 120.87127 -382.223646) (xy 124.14931 -382.223646) (xy 124.14931 -382.156339) (xy 124.157356 -382.089515)
			(xy 124.173332 -382.024132) (xy 124.197008 -381.961127) (xy 124.228045 -381.901403) (xy 124.265998 -381.845818)
			(xy 124.287788 -381.820166) (xy 124.29358 -381.813018) (xy 124.300098 -381.79583) (xy 124.300488 -381.786638)
			(xy 124.300488 -381.628904) (xy 124.300925 -381.618752) (xy 124.308717 -381.600002) (xy 124.323109 -381.585679)
			(xy 124.341896 -381.577977) (xy 124.35205 -381.577596) (xy 125.06833 -381.577596) (xy 125.078453 -381.578101)
			(xy 125.097167 -381.58583) (xy 125.11152 -381.60011) (xy 125.119346 -381.618783) (xy 125.119892 -381.628904)
			(xy 125.119892 -381.786638) (xy 125.120286 -381.795827) (xy 125.126811 -381.813011) (xy 125.132592 -381.820166)
			(xy 125.154369 -381.845827) (xy 125.192316 -381.901413) (xy 125.223348 -381.961135) (xy 125.24702 -382.024139)
			(xy 125.262993 -382.089519) (xy 125.271037 -382.156341) (xy 125.271038 -382.223644) (xy 125.271038 -382.223646)
			(xy 128.5491 -382.223646) (xy 128.549101 -382.156339) (xy 128.557147 -382.089515) (xy 128.573122 -382.024132)
			(xy 128.596798 -381.961127) (xy 128.627834 -381.901404) (xy 128.665787 -381.845818) (xy 128.687576 -381.820166)
			(xy 128.693367 -381.813016) (xy 128.699886 -381.795829) (xy 128.700276 -381.786638) (xy 128.700276 -381.628904)
			(xy 128.700724 -381.618753) (xy 128.708514 -381.600005) (xy 128.722902 -381.585683) (xy 128.741685 -381.577979)
			(xy 128.751838 -381.577596) (xy 129.468118 -381.577596) (xy 129.47824 -381.57811) (xy 129.496954 -381.585836)
			(xy 129.511308 -381.600113) (xy 129.519134 -381.618784) (xy 129.51968 -381.628904) (xy 129.51968 -381.786638)
			(xy 129.520076 -381.795827) (xy 129.5266 -381.813011) (xy 129.53238 -381.820166) (xy 129.554157 -381.845826)
			(xy 129.592105 -381.901412) (xy 129.623138 -381.961135) (xy 129.64681 -382.024138) (xy 129.662784 -382.089519)
			(xy 129.670828 -382.156341) (xy 129.670829 -382.223644) (xy 129.670829 -382.223645) (xy 159.349155 -382.223645)
			(xy 159.349156 -382.15634) (xy 159.3572 -382.089517) (xy 159.373174 -382.024134) (xy 159.396847 -381.96113)
			(xy 159.42788 -381.901406) (xy 159.465828 -381.845818) (xy 159.487616 -381.820166) (xy 159.493411 -381.81302)
			(xy 159.499926 -381.79583) (xy 159.500316 -381.786638) (xy 159.500316 -381.628904) (xy 159.50072 -381.61878)
			(xy 159.508469 -381.600073) (xy 159.52279 -381.585758) (xy 159.5415 -381.578016) (xy 159.551624 -381.577596)
			(xy 160.268158 -381.577596) (xy 160.278277 -381.57816) (xy 160.296988 -381.585866) (xy 160.311345 -381.600128)
			(xy 160.319173 -381.618789) (xy 160.31972 -381.628904) (xy 160.31972 -381.786638) (xy 160.320108 -381.795828)
			(xy 160.326637 -381.813012) (xy 160.33242 -381.820166) (xy 160.354199 -381.845826) (xy 160.392151 -381.90141)
			(xy 160.423187 -381.961132) (xy 160.446862 -382.024136) (xy 160.462837 -382.089518) (xy 160.470882 -382.15634)
			(xy 160.470883 -382.223645) (xy 160.470876 -382.223705) (xy 163.748923 -382.223705) (xy 163.748924 -382.15628)
			(xy 163.757001 -382.089341) (xy 163.773038 -382.023851) (xy 163.796804 -381.960754) (xy 163.827956 -381.900957)
			(xy 163.866047 -381.845323) (xy 163.887912 -381.819658) (xy 163.89371 -381.812514) (xy 163.900224 -381.795323)
			(xy 163.900612 -381.78613) (xy 163.900612 -381.628904) (xy 163.90102 -381.61878) (xy 163.908769 -381.600074)
			(xy 163.923088 -381.58576) (xy 163.941796 -381.578016) (xy 163.95192 -381.577596) (xy 164.6682 -381.577596)
			(xy 164.678322 -381.578016) (xy 164.697025 -381.585763) (xy 164.711339 -381.600079) (xy 164.719085 -381.618782)
			(xy 164.719508 -381.628904) (xy 164.719508 -381.78613) (xy 164.719902 -381.795319) (xy 164.726426 -381.812503)
			(xy 164.732208 -381.819658) (xy 164.754062 -381.845331) (xy 164.79215 -381.900965) (xy 164.823301 -381.96076)
			(xy 164.847065 -382.023856) (xy 164.863101 -382.089344) (xy 164.871178 -382.156281) (xy 164.871179 -382.223645)
			(xy 168.149243 -382.223645) (xy 168.149244 -382.15634) (xy 168.157288 -382.089517) (xy 168.173261 -382.024135)
			(xy 168.196933 -381.96113) (xy 168.227965 -381.901406) (xy 168.265913 -381.845819) (xy 168.2877 -381.820166)
			(xy 168.293494 -381.813019) (xy 168.30001 -381.79583) (xy 168.3004 -381.786638) (xy 168.3004 -381.628904)
			(xy 168.300825 -381.61875) (xy 168.308619 -381.599998) (xy 168.323015 -381.585674) (xy 168.341806 -381.577975)
			(xy 168.351962 -381.577596) (xy 169.068242 -381.577596) (xy 169.078366 -381.578091) (xy 169.09708 -381.585824)
			(xy 169.111433 -381.600107) (xy 169.119258 -381.618783) (xy 169.119804 -381.628904) (xy 169.119804 -381.786638)
			(xy 169.120195 -381.795827) (xy 169.126722 -381.813012) (xy 169.132504 -381.820166) (xy 169.154281 -381.845827)
			(xy 169.192227 -381.901413) (xy 169.223258 -381.961136) (xy 169.24693 -382.024139) (xy 169.262902 -382.08952)
			(xy 169.270946 -382.156341) (xy 169.270947 -382.223644) (xy 169.270947 -382.223646) (xy 172.54901 -382.223646)
			(xy 172.54901 -382.156339) (xy 172.557056 -382.089515) (xy 172.573032 -382.024132) (xy 172.596708 -381.961127)
			(xy 172.627745 -381.901403) (xy 172.665698 -381.845818) (xy 172.687488 -381.820166) (xy 172.69328 -381.813018)
			(xy 172.699798 -381.79583) (xy 172.700188 -381.786638) (xy 172.700188 -381.628904) (xy 172.700625 -381.618752)
			(xy 172.708417 -381.600002) (xy 172.722809 -381.585679) (xy 172.741596 -381.577977) (xy 172.75175 -381.577596)
			(xy 173.46803 -381.577596) (xy 173.478153 -381.578101) (xy 173.496867 -381.58583) (xy 173.51122 -381.60011)
			(xy 173.519046 -381.618783) (xy 173.519592 -381.628904) (xy 173.519592 -381.786638) (xy 173.519986 -381.795827)
			(xy 173.526511 -381.813011) (xy 173.532292 -381.820166) (xy 173.554069 -381.845827) (xy 173.592016 -381.901413)
			(xy 173.623048 -381.961135) (xy 173.64672 -382.024139) (xy 173.662693 -382.089519) (xy 173.670737 -382.156341)
			(xy 173.670738 -382.223644) (xy 173.662695 -382.290466) (xy 173.646725 -382.355847) (xy 173.623054 -382.418851)
			(xy 173.592024 -382.478574) (xy 173.554078 -382.534161) (xy 173.532292 -382.559814) (xy 173.526506 -382.566967)
			(xy 173.519985 -382.584151) (xy 173.519592 -382.593342) (xy 173.519592 -383.086864) (xy 173.520021 -383.096049)
			(xy 173.526522 -383.113234) (xy 173.532292 -383.120392) (xy 173.554094 -383.146032) (xy 173.592041 -383.201621)
			(xy 173.623072 -383.261346) (xy 173.646507 -383.323727) (xy 174.749152 -383.323727) (xy 174.749155 -383.256419)
			(xy 174.757202 -383.189594) (xy 174.773179 -383.12421) (xy 174.796856 -383.061204) (xy 174.827893 -383.001479)
			(xy 174.865846 -382.945892) (xy 174.887636 -382.92024) (xy 174.893445 -382.913104) (xy 174.899951 -382.895906)
			(xy 174.900336 -382.886712) (xy 174.900336 -382.728724) (xy 174.900742 -382.718567) (xy 174.908536 -382.699808)
			(xy 174.922939 -382.685482) (xy 174.941739 -382.677788) (xy 174.951898 -382.677416) (xy 175.668178 -382.677416)
			(xy 175.6783 -382.677944) (xy 175.697017 -382.68566) (xy 175.711373 -382.699933) (xy 175.719197 -382.718605)
			(xy 175.71974 -382.728724) (xy 175.71974 -382.886712) (xy 175.720158 -382.895898) (xy 175.726668 -382.913082)
			(xy 175.73244 -382.92024) (xy 175.754193 -382.945921) (xy 175.792144 -383.001503) (xy 175.82318 -383.061222)
			(xy 175.846856 -383.124223) (xy 175.862832 -383.189602) (xy 175.870879 -383.256422) (xy 175.870883 -383.323724)
			(xy 175.862842 -383.390545) (xy 175.846872 -383.455925) (xy 175.823202 -383.518928) (xy 175.792172 -383.578651)
			(xy 175.754226 -383.634236) (xy 175.73244 -383.659888) (xy 175.726616 -383.667014) (xy 175.720119 -383.684219)
			(xy 175.71974 -383.693416) (xy 175.71974 -384.186684) (xy 175.720171 -384.195869) (xy 175.726672 -384.213053)
			(xy 175.73244 -384.220212) (xy 175.754264 -384.245835) (xy 175.792213 -384.301425) (xy 175.823246 -384.361152)
			(xy 175.846918 -384.424161) (xy 175.862889 -384.489547) (xy 175.87093 -384.556373) (xy 175.870927 -384.623681)
			(xy 175.862879 -384.690507) (xy 175.846902 -384.755891) (xy 175.823224 -384.818897) (xy 175.792185 -384.878622)
			(xy 175.754231 -384.934208) (xy 175.73244 -384.95986) (xy 175.726628 -384.966994) (xy 175.720124 -384.984193)
			(xy 175.71974 -384.993388) (xy 175.71974 -385.151376) (xy 175.71926 -385.161524) (xy 175.71148 -385.180268)
			(xy 175.697101 -385.194591) (xy 175.678327 -385.202298) (xy 175.668178 -385.202684) (xy 174.951898 -385.202684)
			(xy 174.941774 -385.202176) (xy 174.923058 -385.194452) (xy 174.908702 -385.180172) (xy 174.900879 -385.161497)
			(xy 174.900336 -385.151376) (xy 174.900336 -384.993388) (xy 174.899924 -384.984201) (xy 174.893411 -384.967017)
			(xy 174.887636 -384.95986) (xy 174.865884 -384.934179) (xy 174.827934 -384.878596) (xy 174.7969 -384.818877)
			(xy 174.773225 -384.755876) (xy 174.75725 -384.690497) (xy 174.749203 -384.623678) (xy 174.749199 -384.556376)
			(xy 174.75724 -384.489556) (xy 174.773209 -384.424176) (xy 174.796878 -384.361173) (xy 174.827906 -384.30145)
			(xy 174.865851 -384.245864) (xy 174.887636 -384.220212) (xy 174.893457 -384.213084) (xy 174.899956 -384.19588)
			(xy 174.900336 -384.186684) (xy 174.900336 -383.693416) (xy 174.89991 -383.684231) (xy 174.893407 -383.667046)
			(xy 174.887636 -383.659888) (xy 174.865813 -383.634265) (xy 174.827865 -383.578674) (xy 174.796834 -383.518947)
			(xy 174.773163 -383.455938) (xy 174.757193 -383.390553) (xy 174.749152 -383.323727) (xy 173.646507 -383.323727)
			(xy 173.646742 -383.324352) (xy 173.662713 -383.389736) (xy 173.670756 -383.456559) (xy 173.670754 -383.523865)
			(xy 173.662709 -383.590688) (xy 173.646735 -383.656071) (xy 173.623062 -383.719076) (xy 173.592028 -383.7788)
			(xy 173.55408 -383.834387) (xy 173.532292 -383.86004) (xy 173.526495 -383.867185) (xy 173.519981 -383.884376)
			(xy 173.519592 -383.893568) (xy 173.519592 -384.051556) (xy 173.519142 -384.061708) (xy 173.51136 -384.080461)
			(xy 173.496971 -384.094786) (xy 173.478184 -384.102486) (xy 173.46803 -384.102864) (xy 172.75175 -384.102864)
			(xy 172.741627 -384.102333) (xy 172.722908 -384.094622) (xy 172.70855 -384.080349) (xy 172.700728 -384.061676)
			(xy 172.700188 -384.051556) (xy 172.700188 -383.893568) (xy 172.699796 -383.884379) (xy 172.69327 -383.867194)
			(xy 172.687488 -383.86004) (xy 172.665715 -383.834376) (xy 172.627762 -383.778792) (xy 172.596725 -383.719071)
			(xy 172.57305 -383.656068) (xy 172.557074 -383.590686) (xy 172.549028 -383.523864) (xy 172.549026 -383.45656)
			(xy 172.55707 -383.389737) (xy 172.573042 -383.324355) (xy 172.596716 -383.261351) (xy 172.62775 -383.201629)
			(xy 172.6657 -383.146043) (xy 172.687488 -383.120392) (xy 172.693269 -383.113236) (xy 172.699793 -383.096054)
			(xy 172.700188 -383.086864) (xy 172.700188 -382.593342) (xy 172.69976 -382.584157) (xy 172.693259 -382.566972)
			(xy 172.687488 -382.559814) (xy 172.665689 -382.534171) (xy 172.627737 -382.478584) (xy 172.596702 -382.41886)
			(xy 172.573027 -382.355854) (xy 172.557054 -382.29047) (xy 172.54901 -382.223646) (xy 169.270947 -382.223646)
			(xy 169.262905 -382.290465) (xy 169.246934 -382.355847) (xy 169.223264 -382.41885) (xy 169.192235 -382.478574)
			(xy 169.15429 -382.534161) (xy 169.132504 -382.559814) (xy 169.126719 -382.566968) (xy 169.120197 -382.584152)
			(xy 169.119804 -382.593342) (xy 169.119804 -383.086864) (xy 169.120231 -383.096049) (xy 169.126733 -383.113234)
			(xy 169.132504 -383.120392) (xy 169.154306 -383.146032) (xy 169.192252 -383.201621) (xy 169.223282 -383.261347)
			(xy 169.246739 -383.323787) (xy 170.348832 -383.323787) (xy 170.348835 -383.256359) (xy 170.356915 -383.189418)
			(xy 170.372956 -383.123926) (xy 170.396726 -383.060827) (xy 170.427884 -383.001031) (xy 170.46598 -382.945396)
			(xy 170.487848 -382.919732) (xy 170.493662 -382.912599) (xy 170.500165 -382.895399) (xy 170.500548 -382.886204)
			(xy 170.500548 -382.728724) (xy 170.501103 -382.718623) (xy 170.508823 -382.699955) (xy 170.523098 -382.685662)
			(xy 170.541756 -382.677917) (xy 170.551856 -382.677416) (xy 171.268136 -382.677416) (xy 171.278249 -382.677856)
			(xy 171.296931 -382.685608) (xy 171.311225 -382.699919) (xy 171.318956 -382.71861) (xy 171.319444 -382.728724)
			(xy 171.319444 -382.886204) (xy 171.319865 -382.89539) (xy 171.326372 -382.912574) (xy 171.332144 -382.919732)
			(xy 171.353975 -382.945425) (xy 171.392068 -383.001055) (xy 171.423223 -383.060846) (xy 171.446992 -383.12394)
			(xy 171.463032 -383.189426) (xy 171.471111 -383.256362) (xy 171.471115 -383.323784) (xy 171.463041 -383.390721)
			(xy 171.447008 -383.456209) (xy 171.423246 -383.519304) (xy 171.392096 -383.579099) (xy 171.354008 -383.634732)
			(xy 171.332144 -383.660396) (xy 171.32636 -383.66755) (xy 171.319839 -383.684734) (xy 171.319444 -383.693924)
			(xy 171.319444 -384.186176) (xy 171.319878 -384.19536) (xy 171.326376 -384.212544) (xy 171.332144 -384.219704)
			(xy 171.354045 -384.245339) (xy 171.392137 -384.300977) (xy 171.423289 -384.360776) (xy 171.447054 -384.423877)
			(xy 171.463088 -384.489371) (xy 171.471162 -384.556313) (xy 171.471159 -384.623741) (xy 171.463078 -384.690683)
			(xy 171.447037 -384.756174) (xy 171.423267 -384.819273) (xy 171.392109 -384.87907) (xy 171.354012 -384.934704)
			(xy 171.332144 -384.960368) (xy 171.326329 -384.9675) (xy 171.319827 -384.984701) (xy 171.319444 -384.993896)
			(xy 171.319444 -385.151376) (xy 171.318896 -385.161478) (xy 171.311175 -385.180147) (xy 171.296897 -385.194441)
			(xy 171.278237 -385.202185) (xy 171.268136 -385.202684) (xy 170.551856 -385.202684) (xy 170.541742 -385.20225)
			(xy 170.52306 -385.194495) (xy 170.508766 -385.180183) (xy 170.501036 -385.16149) (xy 170.500548 -385.151376)
			(xy 170.500548 -384.993896) (xy 170.500129 -384.98471) (xy 170.49362 -384.967526) (xy 170.487848 -384.960368)
			(xy 170.466018 -384.934674) (xy 170.427925 -384.879045) (xy 170.39677 -384.819253) (xy 170.373001 -384.75616)
			(xy 170.356962 -384.690674) (xy 170.348883 -384.623738) (xy 170.348879 -384.556316) (xy 170.356952 -384.489379)
			(xy 170.372985 -384.423892) (xy 170.396748 -384.360796) (xy 170.427897 -384.301001) (xy 170.465984 -384.245368)
			(xy 170.487848 -384.219704) (xy 170.493631 -384.21255) (xy 170.500153 -384.195366) (xy 170.500548 -384.186176)
			(xy 170.500548 -383.693924) (xy 170.500116 -383.684739) (xy 170.493616 -383.667555) (xy 170.487848 -383.660396)
			(xy 170.465947 -383.634761) (xy 170.427856 -383.579123) (xy 170.396704 -383.519323) (xy 170.37294 -383.456222)
			(xy 170.356906 -383.390729) (xy 170.348832 -383.323787) (xy 169.246739 -383.323787) (xy 169.246952 -383.324353)
			(xy 169.262922 -383.389736) (xy 169.270965 -383.456559) (xy 169.270963 -383.523865) (xy 169.262918 -383.590688)
			(xy 169.246945 -383.65607) (xy 169.223272 -383.719075) (xy 169.192239 -383.7788) (xy 169.154291 -383.834387)
			(xy 169.132504 -383.86004) (xy 169.126708 -383.867186) (xy 169.120193 -383.884376) (xy 169.119804 -383.893568)
			(xy 169.119804 -384.051556) (xy 169.119342 -384.061707) (xy 169.111562 -384.080457) (xy 169.097177 -384.094782)
			(xy 169.078394 -384.102484) (xy 169.068242 -384.102864) (xy 168.351962 -384.102864) (xy 168.341833 -384.102405)
			(xy 168.323112 -384.094665) (xy 168.308757 -384.080371) (xy 168.300939 -384.061682) (xy 168.3004 -384.051556)
			(xy 168.3004 -383.893568) (xy 168.300005 -383.884379) (xy 168.293481 -383.867195) (xy 168.2877 -383.86004)
			(xy 168.265929 -383.834374) (xy 168.227982 -383.778789) (xy 168.196951 -383.719067) (xy 168.173279 -383.656064)
			(xy 168.157306 -383.590684) (xy 168.149261 -383.523864) (xy 168.149259 -383.456561) (xy 168.157301 -383.38974)
			(xy 168.173272 -383.324359) (xy 168.196941 -383.261355) (xy 168.22797 -383.201632) (xy 168.265914 -383.146045)
			(xy 168.2877 -383.120392) (xy 168.293482 -383.113237) (xy 168.300006 -383.096054) (xy 168.3004 -383.086864)
			(xy 168.3004 -382.593342) (xy 168.29997 -382.584157) (xy 168.29347 -382.566972) (xy 168.2877 -382.559814)
			(xy 168.265904 -382.534169) (xy 168.227958 -382.478581) (xy 168.196927 -382.418856) (xy 168.173256 -382.355851)
			(xy 168.157285 -382.290468) (xy 168.149243 -382.223645) (xy 164.871179 -382.223645) (xy 164.871179 -382.223704)
			(xy 164.863104 -382.290641) (xy 164.84707 -382.35613) (xy 164.823307 -382.419226) (xy 164.792158 -382.479022)
			(xy 164.754071 -382.534657) (xy 164.732208 -382.560322) (xy 164.726421 -382.567474) (xy 164.7199 -382.584659)
			(xy 164.719508 -382.59385) (xy 164.719508 -383.086356) (xy 164.719937 -383.095541) (xy 164.726437 -383.112726)
			(xy 164.732208 -383.119884) (xy 164.754087 -383.145536) (xy 164.792175 -383.201173) (xy 164.823325 -383.260971)
			(xy 164.846959 -383.323727) (xy 165.949064 -383.323727) (xy 165.949067 -383.256419) (xy 165.957115 -383.189594)
			(xy 165.973092 -383.124209) (xy 165.996769 -383.061203) (xy 166.027808 -383.001479) (xy 166.065762 -382.945892)
			(xy 166.087552 -382.92024) (xy 166.093363 -382.913105) (xy 166.099868 -382.895907) (xy 166.100252 -382.886712)
			(xy 166.100252 -382.728724) (xy 166.10074 -382.718577) (xy 166.108519 -382.699835) (xy 166.122895 -382.685512)
			(xy 166.141666 -382.677803) (xy 166.151814 -382.677416) (xy 166.868094 -382.677416) (xy 166.878217 -382.677931)
			(xy 166.896934 -382.685652) (xy 166.911289 -382.699929) (xy 166.919113 -382.718603) (xy 166.919656 -382.728724)
			(xy 166.919656 -382.886712) (xy 166.92007 -382.895899) (xy 166.926582 -382.913082) (xy 166.932356 -382.92024)
			(xy 166.954108 -382.945921) (xy 166.992059 -383.001503) (xy 167.023094 -383.061223) (xy 167.046769 -383.124224)
			(xy 167.062744 -383.189602) (xy 167.070791 -383.256422) (xy 167.070795 -383.323724) (xy 167.062754 -383.390544)
			(xy 167.046785 -383.455925) (xy 167.023116 -383.518928) (xy 166.992086 -383.57865) (xy 166.954142 -383.634236)
			(xy 166.932356 -383.659888) (xy 166.926534 -383.667015) (xy 166.920036 -383.68422) (xy 166.919656 -383.693416)
			(xy 166.919656 -384.186684) (xy 166.920084 -384.195869) (xy 166.926586 -384.213053) (xy 166.932356 -384.220212)
			(xy 166.954179 -384.245835) (xy 166.992127 -384.301425) (xy 167.023159 -384.361153) (xy 167.04683 -384.424161)
			(xy 167.062801 -384.489547) (xy 167.070842 -384.556373) (xy 167.070839 -384.623681) (xy 167.062791 -384.690506)
			(xy 167.046814 -384.75589) (xy 167.023137 -384.818897) (xy 166.9921 -384.878621) (xy 166.954146 -384.934208)
			(xy 166.932356 -384.95986) (xy 166.926546 -384.966995) (xy 166.92004 -384.984194) (xy 166.919656 -384.993388)
			(xy 166.919656 -385.151376) (xy 166.91916 -385.161522) (xy 166.911383 -385.180263) (xy 166.89701 -385.194585)
			(xy 166.878241 -385.202296) (xy 166.868094 -385.202684) (xy 166.151814 -385.202684) (xy 166.141691 -385.202163)
			(xy 166.122975 -385.194444) (xy 166.108619 -385.180169) (xy 166.100795 -385.161496) (xy 166.100252 -385.151376)
			(xy 166.100252 -384.993388) (xy 166.099836 -384.984202) (xy 166.093325 -384.967018) (xy 166.087552 -384.95986)
			(xy 166.065799 -384.934179) (xy 166.027849 -384.878597) (xy 165.996813 -384.818877) (xy 165.973138 -384.755877)
			(xy 165.957162 -384.690498) (xy 165.949115 -384.623678) (xy 165.949111 -384.556376) (xy 165.957152 -384.489555)
			(xy 165.973122 -384.424175) (xy 165.996791 -384.361172) (xy 166.027821 -384.30145) (xy 166.065766 -384.245864)
			(xy 166.087552 -384.220212) (xy 166.093375 -384.213086) (xy 166.099872 -384.19588) (xy 166.100252 -384.186684)
			(xy 166.100252 -383.693416) (xy 166.099823 -383.684231) (xy 166.093321 -383.667047) (xy 166.087552 -383.659888)
			(xy 166.065728 -383.634265) (xy 166.02778 -383.578675) (xy 165.996747 -383.518947) (xy 165.973076 -383.455939)
			(xy 165.957105 -383.390553) (xy 165.949064 -383.323727) (xy 164.846959 -383.323727) (xy 164.847088 -383.32407)
			(xy 164.863122 -383.38956) (xy 164.871196 -383.4565) (xy 164.871195 -383.523924) (xy 164.863117 -383.590864)
			(xy 164.84708 -383.656353) (xy 164.823315 -383.719451) (xy 164.792163 -383.779248) (xy 164.754073 -383.834883)
			(xy 164.732208 -383.860548) (xy 164.726409 -383.867692) (xy 164.719896 -383.884883) (xy 164.719508 -383.894076)
			(xy 164.719508 -384.051556) (xy 164.719048 -384.061675) (xy 164.711316 -384.080376) (xy 164.697013 -384.094691)
			(xy 164.678318 -384.102439) (xy 164.6682 -384.102864) (xy 163.95192 -384.102864) (xy 163.941794 -384.102467)
			(xy 163.923084 -384.094719) (xy 163.908768 -384.080396) (xy 163.901028 -384.061682) (xy 163.900612 -384.051556)
			(xy 163.900612 -383.894076) (xy 163.900211 -383.884888) (xy 163.893691 -383.867704) (xy 163.887912 -383.860548)
			(xy 163.866063 -383.83487) (xy 163.827973 -383.779238) (xy 163.796821 -383.719443) (xy 163.773056 -383.656348)
			(xy 163.757019 -383.59086) (xy 163.748941 -383.523923) (xy 163.74894 -383.456501) (xy 163.757014 -383.389563)
			(xy 163.773049 -383.324075) (xy 163.796811 -383.260979) (xy 163.827961 -383.201183) (xy 163.866049 -383.145549)
			(xy 163.887912 -383.119884) (xy 163.893699 -383.112732) (xy 163.900219 -383.095547) (xy 163.900612 -383.086356)
			(xy 163.900612 -382.59385) (xy 163.900175 -382.584666) (xy 163.89368 -382.567481) (xy 163.887912 -382.560322)
			(xy 163.866038 -382.534665) (xy 163.827949 -382.47903) (xy 163.796798 -382.419232) (xy 163.773034 -382.356134)
			(xy 163.756998 -382.290644) (xy 163.748923 -382.223705) (xy 160.470876 -382.223705) (xy 160.46284 -382.290468)
			(xy 160.446866 -382.35585) (xy 160.423193 -382.418854) (xy 160.392159 -382.478577) (xy 160.354208 -382.534162)
			(xy 160.33242 -382.559814) (xy 160.326637 -382.566969) (xy 160.320114 -382.584152) (xy 160.31972 -382.593342)
			(xy 160.31972 -383.086864) (xy 160.320143 -383.09605) (xy 160.326647 -383.113235) (xy 160.33242 -383.120392)
			(xy 160.354225 -383.146031) (xy 160.392176 -383.201618) (xy 160.42321 -383.261343) (xy 160.446672 -383.323786)
			(xy 161.548769 -383.323786) (xy 161.548772 -383.25636) (xy 161.556851 -383.18942) (xy 161.572889 -383.123929)
			(xy 161.596656 -383.060831) (xy 161.627809 -383.001034) (xy 161.665899 -382.945398) (xy 161.687764 -382.919732)
			(xy 161.69358 -382.912601) (xy 161.700081 -382.895399) (xy 161.700464 -382.886204) (xy 161.700464 -382.728724)
			(xy 161.701004 -382.718621) (xy 161.708727 -382.69995) (xy 161.723007 -382.685656) (xy 161.74167 -382.677914)
			(xy 161.751772 -382.677416) (xy 162.468052 -382.677416) (xy 162.478173 -382.677856) (xy 162.496879 -382.685591)
			(xy 162.511195 -382.699901) (xy 162.51894 -382.718603) (xy 162.51936 -382.728724) (xy 162.51936 -382.886204)
			(xy 162.519777 -382.89539) (xy 162.526287 -382.912574) (xy 162.53206 -382.919732) (xy 162.55389 -382.945426)
			(xy 162.591982 -383.001055) (xy 162.623137 -383.060847) (xy 162.646905 -383.12394) (xy 162.662944 -383.189426)
			(xy 162.671023 -383.256362) (xy 162.671027 -383.323784) (xy 162.662954 -383.39072) (xy 162.646921 -383.456208)
			(xy 162.623159 -383.519303) (xy 162.59201 -383.579098) (xy 162.553923 -383.634731) (xy 162.53206 -383.660396)
			(xy 162.526278 -383.667551) (xy 162.519755 -383.684734) (xy 162.51936 -383.693924) (xy 162.51936 -384.186176)
			(xy 162.51979 -384.195361) (xy 162.526291 -384.212545) (xy 162.53206 -384.219704) (xy 162.553961 -384.245339)
			(xy 162.592051 -384.300977) (xy 162.623202 -384.360777) (xy 162.646966 -384.423878) (xy 162.663 -384.489371)
			(xy 162.671074 -384.556313) (xy 162.671071 -384.623741) (xy 162.662991 -384.690682) (xy 162.64695 -384.756174)
			(xy 162.62318 -384.819272) (xy 162.592023 -384.879069) (xy 162.553928 -384.934703) (xy 162.53206 -384.960368)
			(xy 162.526247 -384.967501) (xy 162.519743 -384.984701) (xy 162.51936 -384.993896) (xy 162.51936 -385.151376)
			(xy 162.518964 -385.161502) (xy 162.511216 -385.180213) (xy 162.496893 -385.194529) (xy 162.478178 -385.202268)
			(xy 162.468052 -385.202684) (xy 161.751772 -385.202684) (xy 161.741659 -385.202238) (xy 161.722978 -385.194488)
			(xy 161.708683 -385.180179) (xy 161.700952 -385.161489) (xy 161.700464 -385.151376) (xy 161.700464 -384.993896)
			(xy 161.700041 -384.98471) (xy 161.693535 -384.967527) (xy 161.687764 -384.960368) (xy 161.665937 -384.934673)
			(xy 161.627849 -384.879042) (xy 161.596699 -384.819249) (xy 161.572934 -384.756157) (xy 161.556897 -384.690671)
			(xy 161.548819 -384.623737) (xy 161.548816 -384.556317) (xy 161.556888 -384.489382) (xy 161.572918 -384.423895)
			(xy 161.596677 -384.3608) (xy 161.627821 -384.301005) (xy 161.665903 -384.24537) (xy 161.687764 -384.219704)
			(xy 161.693549 -384.212551) (xy 161.700069 -384.195366) (xy 161.700464 -384.186176) (xy 161.700464 -383.693924)
			(xy 161.700028 -383.68474) (xy 161.693531 -383.667556) (xy 161.687764 -383.660396) (xy 161.665866 -383.634759)
			(xy 161.627781 -383.57912) (xy 161.596634 -383.519319) (xy 161.572873 -383.456219) (xy 161.556841 -383.390727)
			(xy 161.548769 -383.323786) (xy 160.446672 -383.323786) (xy 160.446884 -383.32435) (xy 160.462857 -383.389734)
			(xy 160.470901 -383.456558) (xy 160.470899 -383.523866) (xy 160.462853 -383.59069) (xy 160.446877 -383.656074)
			(xy 160.423201 -383.719079) (xy 160.392163 -383.778803) (xy 160.35421 -383.834388) (xy 160.33242 -383.86004)
			(xy 160.326626 -383.867187) (xy 160.320109 -383.884376) (xy 160.31972 -383.893568) (xy 160.31972 -384.051556)
			(xy 160.319248 -384.061673) (xy 160.311518 -384.080372) (xy 160.297219 -384.094687) (xy 160.278529 -384.102437)
			(xy 160.268412 -384.102864) (xy 159.551878 -384.102864) (xy 159.54175 -384.102392) (xy 159.523029 -384.094657)
			(xy 159.508674 -384.080367) (xy 159.500855 -384.061681) (xy 159.500316 -384.051556) (xy 159.500316 -383.893568)
			(xy 159.499918 -383.88438) (xy 159.493395 -383.867196) (xy 159.487616 -383.86004) (xy 159.465845 -383.834375)
			(xy 159.427897 -383.77879) (xy 159.396864 -383.719068) (xy 159.373191 -383.656065) (xy 159.357218 -383.590684)
			(xy 159.349173 -383.523864) (xy 159.349172 -383.45656) (xy 159.357214 -383.389739) (xy 159.373184 -383.324358)
			(xy 159.396854 -383.261354) (xy 159.427884 -383.201631) (xy 159.46583 -383.146044) (xy 159.487616 -383.120392)
			(xy 159.4934 -383.113238) (xy 159.499922 -383.096054) (xy 159.500316 -383.086864) (xy 159.500316 -382.593342)
			(xy 159.499882 -382.584157) (xy 159.493384 -382.566973) (xy 159.487616 -382.559814) (xy 159.465819 -382.53417)
			(xy 159.427872 -382.478582) (xy 159.396841 -382.418857) (xy 159.373169 -382.355851) (xy 159.357198 -382.290468)
			(xy 159.349155 -382.223645) (xy 129.670829 -382.223645) (xy 129.662786 -382.290466) (xy 129.646815 -382.355847)
			(xy 129.623144 -382.418851) (xy 129.592113 -382.478575) (xy 129.554167 -382.534162) (xy 129.53238 -382.559814)
			(xy 129.526593 -382.566966) (xy 129.520073 -382.584151) (xy 129.51968 -382.593342) (xy 129.51968 -383.086864)
			(xy 129.520112 -383.096049) (xy 129.526611 -383.113233) (xy 129.53238 -383.120392) (xy 129.554183 -383.146031)
			(xy 129.59213 -383.20162) (xy 129.623162 -383.261346) (xy 129.646598 -383.323727) (xy 130.749242 -383.323727)
			(xy 130.749246 -383.256419) (xy 130.757293 -383.189594) (xy 130.77327 -383.12421) (xy 130.796946 -383.061204)
			(xy 130.827982 -383.00148) (xy 130.865935 -382.945892) (xy 130.887724 -382.92024) (xy 130.893531 -382.913103)
			(xy 130.900039 -382.895906) (xy 130.900424 -382.886712) (xy 130.900424 -382.728724) (xy 130.900842 -382.718568)
			(xy 130.908634 -382.699812) (xy 130.923032 -382.685487) (xy 130.941828 -382.67779) (xy 130.951986 -382.677416)
			(xy 131.668266 -382.677416) (xy 131.678388 -382.677954) (xy 131.697103 -382.685666) (xy 131.71146 -382.699937)
			(xy 131.719284 -382.718606) (xy 131.719828 -382.728724) (xy 131.719828 -382.886712) (xy 131.720226 -382.895901)
			(xy 131.726747 -382.913085) (xy 131.732528 -382.92024) (xy 131.754281 -382.945921) (xy 131.792233 -383.001502)
			(xy 131.82327 -383.061222) (xy 131.846946 -383.124223) (xy 131.862923 -383.189602) (xy 131.87097 -383.256422)
			(xy 131.870973 -383.323724) (xy 131.862932 -383.390545) (xy 131.846962 -383.455926) (xy 131.823292 -383.518929)
			(xy 131.792261 -383.578651) (xy 131.754314 -383.634236) (xy 131.732528 -383.659888) (xy 131.726703 -383.667013)
			(xy 131.720207 -383.684219) (xy 131.719828 -383.693416) (xy 131.719828 -384.186684) (xy 131.720239 -384.195871)
			(xy 131.726751 -384.213056) (xy 131.732528 -384.220212) (xy 131.754352 -384.245834) (xy 131.792302 -384.301424)
			(xy 131.823336 -384.361152) (xy 131.847008 -384.42416) (xy 131.86298 -384.489546) (xy 131.871021 -384.556373)
			(xy 131.871018 -384.623681) (xy 131.86297 -384.690507) (xy 131.846992 -384.755892) (xy 131.823314 -384.818898)
			(xy 131.792274 -384.878622) (xy 131.754319 -384.934208) (xy 131.732528 -384.95986) (xy 131.726715 -384.966993)
			(xy 131.720212 -384.984193) (xy 131.719828 -384.993388) (xy 131.719828 -385.151376) (xy 131.719359 -385.161525)
			(xy 131.711577 -385.180272) (xy 131.697195 -385.194595) (xy 131.678417 -385.202301) (xy 131.668266 -385.202684)
			(xy 130.951986 -385.202684) (xy 130.941861 -385.202185) (xy 130.923145 -385.194457) (xy 130.90879 -385.180175)
			(xy 130.900967 -385.161498) (xy 130.900424 -385.151376) (xy 130.900424 -384.993388) (xy 130.900014 -384.984201)
			(xy 130.8935 -384.967017) (xy 130.887724 -384.95986) (xy 130.865972 -384.934178) (xy 130.828023 -384.878596)
			(xy 130.796989 -384.818876) (xy 130.773315 -384.755876) (xy 130.75734 -384.690497) (xy 130.749294 -384.623678)
			(xy 130.74929 -384.556376) (xy 130.757331 -384.489556) (xy 130.773299 -384.424176) (xy 130.796967 -384.361173)
			(xy 130.827996 -384.301451) (xy 130.865939 -384.245865) (xy 130.887724 -384.220212) (xy 130.893543 -384.213083)
			(xy 130.900044 -384.19588) (xy 130.900424 -384.186684) (xy 130.900424 -383.693416) (xy 130.900001 -383.68423)
			(xy 130.893495 -383.667046) (xy 130.887724 -383.659888) (xy 130.865901 -383.634265) (xy 130.827955 -383.578674)
			(xy 130.796924 -383.518946) (xy 130.773254 -383.455938) (xy 130.757284 -383.390552) (xy 130.749242 -383.323727)
			(xy 129.646598 -383.323727) (xy 129.646833 -383.324352) (xy 129.662804 -383.389735) (xy 129.670846 -383.456559)
			(xy 129.670845 -383.523865) (xy 129.6628 -383.590688) (xy 129.646826 -383.656071) (xy 129.623152 -383.719076)
			(xy 129.592118 -383.778801) (xy 129.554168 -383.834388) (xy 129.53238 -383.86004) (xy 129.526582 -383.867184)
			(xy 129.520069 -383.884375) (xy 129.51968 -383.893568) (xy 129.51968 -384.051556) (xy 129.519242 -384.06171)
			(xy 129.511457 -384.080465) (xy 129.497065 -384.094791) (xy 129.478274 -384.102488) (xy 129.468118 -384.102864)
			(xy 128.751838 -384.102864) (xy 128.741714 -384.102342) (xy 128.722995 -384.094628) (xy 128.708637 -384.080352)
			(xy 128.700816 -384.061677) (xy 128.700276 -384.051556) (xy 128.700276 -383.893568) (xy 128.699886 -383.884379)
			(xy 128.693359 -383.867194) (xy 128.687576 -383.86004) (xy 128.665803 -383.834375) (xy 128.627851 -383.778792)
			(xy 128.596815 -383.71907) (xy 128.57314 -383.656067) (xy 128.557165 -383.590686) (xy 128.549119 -383.523864)
			(xy 128.549117 -383.45656) (xy 128.55716 -383.389738) (xy 128.573133 -383.324356) (xy 128.596805 -383.261352)
			(xy 128.627839 -383.201629) (xy 128.665788 -383.146044) (xy 128.687576 -383.120392) (xy 128.693356 -383.113235)
			(xy 128.699881 -383.096054) (xy 128.700276 -383.086864) (xy 128.700276 -382.593342) (xy 128.699851 -382.584156)
			(xy 128.693348 -382.566971) (xy 128.687576 -382.559814) (xy 128.665777 -382.53417) (xy 128.627826 -382.478584)
			(xy 128.596792 -382.418859) (xy 128.573118 -382.355853) (xy 128.557144 -382.29047) (xy 128.5491 -382.223646)
			(xy 125.271038 -382.223646) (xy 125.262995 -382.290466) (xy 125.247025 -382.355847) (xy 125.223354 -382.418851)
			(xy 125.192324 -382.478574) (xy 125.154378 -382.534161) (xy 125.132592 -382.559814) (xy 125.126806 -382.566967)
			(xy 125.120285 -382.584151) (xy 125.119892 -382.593342) (xy 125.119892 -383.086864) (xy 125.120321 -383.096049)
			(xy 125.126822 -383.113234) (xy 125.132592 -383.120392) (xy 125.154394 -383.146032) (xy 125.192341 -383.201621)
			(xy 125.223372 -383.261346) (xy 125.24683 -383.323787) (xy 126.348923 -383.323787) (xy 126.348926 -383.256359)
			(xy 126.357006 -383.189418) (xy 126.373047 -383.123926) (xy 126.396816 -383.060828) (xy 126.427973 -383.001031)
			(xy 126.466069 -382.945397) (xy 126.487936 -382.919732) (xy 126.493749 -382.912598) (xy 126.500253 -382.895399)
			(xy 126.500636 -382.886204) (xy 126.500636 -382.728724) (xy 126.501036 -382.718599) (xy 126.508783 -382.699889)
			(xy 126.523105 -382.685572) (xy 126.541818 -382.677832) (xy 126.551944 -382.677416) (xy 127.268224 -382.677416)
			(xy 127.278336 -382.677866) (xy 127.297018 -382.685614) (xy 127.311313 -382.699922) (xy 127.319044 -382.718611)
			(xy 127.319532 -382.728724) (xy 127.319532 -382.886204) (xy 127.319956 -382.895389) (xy 127.326462 -382.912573)
			(xy 127.332232 -382.919732) (xy 127.354059 -382.945427) (xy 127.392147 -383.001058) (xy 127.423298 -383.06085)
			(xy 127.447062 -383.123943) (xy 127.463099 -383.189428) (xy 127.471178 -383.256363) (xy 127.471181 -383.323783)
			(xy 127.463109 -383.390718) (xy 127.447078 -383.456205) (xy 127.42332 -383.5193) (xy 127.392175 -383.579096)
			(xy 127.354093 -383.63473) (xy 127.332232 -383.660396) (xy 127.326446 -383.667549) (xy 127.319927 -383.684734)
			(xy 127.319532 -383.693924) (xy 127.319532 -384.186176) (xy 127.319969 -384.19536) (xy 127.326466 -384.212544)
			(xy 127.332232 -384.219704) (xy 127.35413 -384.245341) (xy 127.392216 -384.30098) (xy 127.423363 -384.36078)
			(xy 127.447124 -384.423881) (xy 127.463156 -384.489373) (xy 127.471228 -384.556314) (xy 127.471225 -384.62374)
			(xy 127.463146 -384.69068) (xy 127.447108 -384.756171) (xy 127.423341 -384.819269) (xy 127.392188 -384.879066)
			(xy 127.354097 -384.934702) (xy 127.332232 -384.960368) (xy 127.326416 -384.967499) (xy 127.319915 -384.984701)
			(xy 127.319532 -384.993896) (xy 127.319532 -385.151376) (xy 127.318996 -385.161479) (xy 127.311272 -385.180151)
			(xy 127.296991 -385.194445) (xy 127.278327 -385.202187) (xy 127.268224 -385.202684) (xy 126.551944 -385.202684)
			(xy 126.541822 -385.202247) (xy 126.523117 -385.194511) (xy 126.5088 -385.1802) (xy 126.501056 -385.161497)
			(xy 126.500636 -385.151376) (xy 126.500636 -384.993896) (xy 126.50022 -384.98471) (xy 126.49371 -384.967526)
			(xy 126.487936 -384.960368) (xy 126.466106 -384.934674) (xy 126.428014 -384.879045) (xy 126.39686 -384.819253)
			(xy 126.373092 -384.756159) (xy 126.357053 -384.690673) (xy 126.348974 -384.623738) (xy 126.34897 -384.556316)
			(xy 126.357043 -384.48938) (xy 126.373076 -384.423892) (xy 126.396838 -384.360797) (xy 126.427986 -384.301002)
			(xy 126.466073 -384.245369) (xy 126.487936 -384.219704) (xy 126.493718 -384.212549) (xy 126.50024 -384.195366)
			(xy 126.500636 -384.186176) (xy 126.500636 -383.693924) (xy 126.500206 -383.684739) (xy 126.493705 -383.667555)
			(xy 126.487936 -383.660396) (xy 126.466035 -383.634761) (xy 126.427945 -383.579123) (xy 126.396794 -383.519323)
			(xy 126.373031 -383.456222) (xy 126.356996 -383.390729) (xy 126.348923 -383.323787) (xy 125.24683 -383.323787)
			(xy 125.247042 -383.324352) (xy 125.263013 -383.389736) (xy 125.271056 -383.456559) (xy 125.271054 -383.523865)
			(xy 125.263009 -383.590688) (xy 125.247035 -383.656071) (xy 125.223362 -383.719076) (xy 125.192328 -383.7788)
			(xy 125.15438 -383.834387) (xy 125.132592 -383.86004) (xy 125.126795 -383.867185) (xy 125.120281 -383.884376)
			(xy 125.119892 -383.893568) (xy 125.119892 -384.051556) (xy 125.119442 -384.061708) (xy 125.11166 -384.080461)
			(xy 125.097271 -384.094786) (xy 125.078484 -384.102486) (xy 125.06833 -384.102864) (xy 124.35205 -384.102864)
			(xy 124.341927 -384.102333) (xy 124.323208 -384.094622) (xy 124.30885 -384.080349) (xy 124.301028 -384.061676)
			(xy 124.300488 -384.051556) (xy 124.300488 -383.893568) (xy 124.300096 -383.884379) (xy 124.29357 -383.867194)
			(xy 124.287788 -383.86004) (xy 124.266015 -383.834376) (xy 124.228062 -383.778792) (xy 124.197025 -383.719071)
			(xy 124.17335 -383.656068) (xy 124.157374 -383.590686) (xy 124.149328 -383.523864) (xy 124.149326 -383.45656)
			(xy 124.15737 -383.389737) (xy 124.173342 -383.324355) (xy 124.197016 -383.261351) (xy 124.22805 -383.201629)
			(xy 124.266 -383.146043) (xy 124.287788 -383.120392) (xy 124.293569 -383.113236) (xy 124.300093 -383.096054)
			(xy 124.300488 -383.086864) (xy 124.300488 -382.593342) (xy 124.30006 -382.584157) (xy 124.293559 -382.566972)
			(xy 124.287788 -382.559814) (xy 124.265989 -382.534171) (xy 124.228037 -382.478584) (xy 124.197002 -382.41886)
			(xy 124.173327 -382.355854) (xy 124.157354 -382.29047) (xy 124.14931 -382.223646) (xy 120.87127 -382.223646)
			(xy 120.87127 -382.223704) (xy 120.863195 -382.290642) (xy 120.84716 -382.35613) (xy 120.823397 -382.419227)
			(xy 120.792247 -382.479023) (xy 120.75416 -382.534657) (xy 120.732296 -382.560322) (xy 120.726507 -382.567473)
			(xy 120.719988 -382.584659) (xy 120.719596 -382.59385) (xy 120.719596 -383.086356) (xy 120.720028 -383.095541)
			(xy 120.726527 -383.112725) (xy 120.732296 -383.119884) (xy 120.754176 -383.145536) (xy 120.792264 -383.201173)
			(xy 120.823415 -383.26097) (xy 120.847049 -383.323727) (xy 121.949155 -383.323727) (xy 121.949158 -383.256419)
			(xy 121.957206 -383.189594) (xy 121.973182 -383.12421) (xy 121.996859 -383.061204) (xy 122.027897 -383.001479)
			(xy 122.06585 -382.945892) (xy 122.08764 -382.92024) (xy 122.09345 -382.913104) (xy 122.099955 -382.895906)
			(xy 122.10034 -382.886712) (xy 122.10034 -382.728724) (xy 122.100742 -382.718566) (xy 122.108537 -382.699807)
			(xy 122.122941 -382.685481) (xy 122.141742 -382.677788) (xy 122.151902 -382.677416) (xy 122.868182 -382.677416)
			(xy 122.878305 -382.677941) (xy 122.897021 -382.685658) (xy 122.911377 -382.699932) (xy 122.919201 -382.718604)
			(xy 122.919744 -382.728724) (xy 122.919744 -382.886712) (xy 122.920161 -382.895898) (xy 122.926671 -382.913082)
			(xy 122.932444 -382.92024) (xy 122.954197 -382.945921) (xy 122.992148 -383.001503) (xy 123.023183 -383.061222)
			(xy 123.046859 -383.124223) (xy 123.062835 -383.189602) (xy 123.070882 -383.256422) (xy 123.070886 -383.323724)
			(xy 123.062845 -383.390545) (xy 123.046875 -383.455925) (xy 123.023206 -383.518928) (xy 122.992176 -383.57865)
			(xy 122.95423 -383.634236) (xy 122.932444 -383.659888) (xy 122.926621 -383.667014) (xy 122.920124 -383.684219)
			(xy 122.919744 -383.693416) (xy 122.919744 -384.186684) (xy 122.920174 -384.195869) (xy 122.926675 -384.213053)
			(xy 122.932444 -384.220212) (xy 122.954268 -384.245835) (xy 122.992217 -384.301425) (xy 123.023249 -384.361152)
			(xy 123.046921 -384.424161) (xy 123.062892 -384.489547) (xy 123.070933 -384.556373) (xy 123.07093 -384.623681)
			(xy 123.062882 -384.690507) (xy 123.046905 -384.755891) (xy 123.023227 -384.818897) (xy 122.992189 -384.878622)
			(xy 122.954235 -384.934208) (xy 122.932444 -384.95986) (xy 122.926633 -384.966994) (xy 122.920128 -384.984193)
			(xy 122.919744 -384.993388) (xy 122.919744 -385.151376) (xy 122.91926 -385.161523) (xy 122.91148 -385.180267)
			(xy 122.897103 -385.194589) (xy 122.878331 -385.202298) (xy 122.868182 -385.202684) (xy 122.151902 -385.202684)
			(xy 122.141778 -385.202172) (xy 122.123062 -385.19445) (xy 122.108706 -385.180171) (xy 122.100883 -385.161497)
			(xy 122.10034 -385.151376) (xy 122.10034 -384.993388) (xy 122.099927 -384.984201) (xy 122.093414 -384.967017)
			(xy 122.08764 -384.95986) (xy 122.065888 -384.934179) (xy 122.027938 -384.878596) (xy 121.996903 -384.818877)
			(xy 121.973228 -384.755876) (xy 121.957253 -384.690498) (xy 121.949206 -384.623678) (xy 121.949202 -384.556376)
			(xy 121.957243 -384.489556) (xy 121.973212 -384.424176) (xy 121.996881 -384.361173) (xy 122.02791 -384.30145)
			(xy 122.065855 -384.245864) (xy 122.08764 -384.220212) (xy 122.093461 -384.213085) (xy 122.09996 -384.19588)
			(xy 122.10034 -384.186684) (xy 122.10034 -383.693416) (xy 122.099913 -383.684231) (xy 122.09341 -383.667047)
			(xy 122.08764 -383.659888) (xy 122.065817 -383.634265) (xy 122.027869 -383.578674) (xy 121.996837 -383.518947)
			(xy 121.973166 -383.455939) (xy 121.957196 -383.390553) (xy 121.949155 -383.323727) (xy 120.847049 -383.323727)
			(xy 120.847178 -383.324069) (xy 120.863212 -383.38956) (xy 120.871287 -383.4565) (xy 120.871286 -383.523925)
			(xy 120.863208 -383.590864) (xy 120.847171 -383.656354) (xy 120.823405 -383.719452) (xy 120.792252 -383.779248)
			(xy 120.754161 -383.834883) (xy 120.732296 -383.860548) (xy 120.726496 -383.867691) (xy 120.719984 -383.884883)
			(xy 120.719596 -383.894076) (xy 120.719596 -384.051556) (xy 120.719148 -384.061676) (xy 120.711413 -384.080379)
			(xy 120.697106 -384.094695) (xy 120.678408 -384.102441) (xy 120.668288 -384.102864) (xy 119.952008 -384.102864)
			(xy 119.941882 -384.102477) (xy 119.923171 -384.094724) (xy 119.908855 -384.080399) (xy 119.901116 -384.061683)
			(xy 119.9007 -384.051556) (xy 119.9007 -383.894076) (xy 119.900302 -383.884888) (xy 119.89378 -383.867703)
			(xy 119.888 -383.860548) (xy 119.866152 -383.83487) (xy 119.828063 -383.779237) (xy 119.796911 -383.719443)
			(xy 119.773146 -383.656348) (xy 119.75711 -383.59086) (xy 119.749032 -383.523923) (xy 119.749031 -383.456501)
			(xy 119.757105 -383.389564) (xy 119.773139 -383.324075) (xy 119.796901 -383.260979) (xy 119.82805 -383.201184)
			(xy 119.866137 -383.145549) (xy 119.888 -383.119884) (xy 119.893786 -383.112731) (xy 119.900307 -383.095547)
			(xy 119.9007 -383.086356) (xy 119.9007 -382.59385) (xy 119.900266 -382.584665) (xy 119.893769 -382.567481)
			(xy 119.888 -382.560322) (xy 119.866126 -382.534665) (xy 119.828038 -382.479029) (xy 119.796888 -382.419232)
			(xy 119.773124 -382.356134) (xy 119.757089 -382.290644) (xy 119.749014 -382.223705) (xy 116.470967 -382.223705)
			(xy 116.46293 -382.290468) (xy 116.446957 -382.35585) (xy 116.423283 -382.418855) (xy 116.392248 -382.478577)
			(xy 116.354297 -382.534163) (xy 116.332508 -382.559814) (xy 116.326724 -382.566968) (xy 116.320202 -382.584152)
			(xy 116.319808 -382.593342) (xy 116.319808 -383.086864) (xy 116.320234 -383.09605) (xy 116.326736 -383.113234)
			(xy 116.332508 -383.120392) (xy 116.354313 -383.146031) (xy 116.392265 -383.201618) (xy 116.4233 -383.261343)
			(xy 116.446764 -383.323787) (xy 117.548835 -383.323787) (xy 117.548838 -383.256359) (xy 117.556918 -383.189418)
			(xy 117.572959 -383.123926) (xy 117.59673 -383.060827) (xy 117.627888 -383.00103) (xy 117.665984 -382.945396)
			(xy 117.687852 -382.919732) (xy 117.693666 -382.9126) (xy 117.700169 -382.895399) (xy 117.700552 -382.886204)
			(xy 117.700552 -382.728724) (xy 117.701103 -382.718623) (xy 117.708824 -382.699954) (xy 117.7231 -382.68566)
			(xy 117.741759 -382.677916) (xy 117.75186 -382.677416) (xy 118.46814 -382.677416) (xy 118.478253 -382.677853)
			(xy 118.496935 -382.685607) (xy 118.511229 -382.699918) (xy 118.51896 -382.71861) (xy 118.519448 -382.728724)
			(xy 118.519448 -382.886204) (xy 118.519868 -382.89539) (xy 118.526376 -382.912574) (xy 118.532148 -382.919732)
			(xy 118.553978 -382.945426) (xy 118.592072 -383.001055) (xy 118.623227 -383.060847) (xy 118.646995 -383.12394)
			(xy 118.663035 -383.189426) (xy 118.671114 -383.256362) (xy 118.671118 -383.323784) (xy 118.663045 -383.390721)
			(xy 118.647011 -383.456208) (xy 118.623249 -383.519304) (xy 118.592099 -383.579099) (xy 118.554012 -383.634732)
			(xy 118.532148 -383.660396) (xy 118.526364 -383.66755) (xy 118.519843 -383.684734) (xy 118.519448 -383.693924)
			(xy 118.519448 -384.186176) (xy 118.519881 -384.195361) (xy 118.52638 -384.212545) (xy 118.532148 -384.219704)
			(xy 118.554049 -384.245339) (xy 118.59214 -384.300977) (xy 118.623292 -384.360777) (xy 118.647057 -384.423878)
			(xy 118.663091 -384.489371) (xy 118.671165 -384.556313) (xy 118.671162 -384.623741) (xy 118.663082 -384.690682)
			(xy 118.647041 -384.756174) (xy 118.62327 -384.819273) (xy 118.592112 -384.87907) (xy 118.554016 -384.934704)
			(xy 118.532148 -384.960368) (xy 118.526334 -384.9675) (xy 118.519831 -384.984701) (xy 118.519448 -384.993896)
			(xy 118.519448 -385.151376) (xy 118.518897 -385.161477) (xy 118.511176 -385.180146) (xy 118.4969 -385.19444)
			(xy 118.478241 -385.202184) (xy 118.46814 -385.202684) (xy 117.75186 -385.202684) (xy 117.741747 -385.202247)
			(xy 117.723065 -385.194493) (xy 117.708771 -385.180182) (xy 117.70104 -385.16149) (xy 117.700552 -385.151376)
			(xy 117.700552 -384.993896) (xy 117.700132 -384.98471) (xy 117.693624 -384.967526) (xy 117.687852 -384.960368)
			(xy 117.666022 -384.934674) (xy 117.627928 -384.879045) (xy 117.596773 -384.819253) (xy 117.573005 -384.75616)
			(xy 117.556965 -384.690674) (xy 117.548886 -384.623738) (xy 117.548882 -384.556316) (xy 117.556955 -384.489379)
			(xy 117.572989 -384.423892) (xy 117.596751 -384.360796) (xy 117.627901 -384.301001) (xy 117.665988 -384.245368)
			(xy 117.687852 -384.219704) (xy 117.693636 -384.21255) (xy 117.700157 -384.195366) (xy 117.700552 -384.186176)
			(xy 117.700552 -383.693924) (xy 117.700119 -383.684739) (xy 117.69362 -383.667555) (xy 117.687852 -383.660396)
			(xy 117.665951 -383.634761) (xy 117.62786 -383.579123) (xy 117.596708 -383.519323) (xy 117.572943 -383.456222)
			(xy 117.556909 -383.390729) (xy 117.548835 -383.323787) (xy 116.446764 -383.323787) (xy 116.446975 -383.324349)
			(xy 116.462948 -383.389733) (xy 116.470992 -383.456558) (xy 116.47099 -383.523866) (xy 116.462944 -383.59069)
			(xy 116.446967 -383.656074) (xy 116.423291 -383.719079) (xy 116.392252 -383.778803) (xy 116.354298 -383.834389)
			(xy 116.332508 -383.86004) (xy 116.326713 -383.867186) (xy 116.320197 -383.884376) (xy 116.319808 -383.893568)
			(xy 116.319808 -384.051556) (xy 116.319342 -384.061706) (xy 116.311563 -384.080456) (xy 116.297179 -384.094781)
			(xy 116.278398 -384.102483) (xy 116.268246 -384.102864) (xy 115.551966 -384.102864) (xy 115.541838 -384.102401)
			(xy 115.523116 -384.094663) (xy 115.508761 -384.08037) (xy 115.500943 -384.061682) (xy 115.500404 -384.051556)
			(xy 115.500404 -383.893568) (xy 115.500009 -383.884379) (xy 115.493485 -383.867195) (xy 115.487704 -383.86004)
			(xy 115.465933 -383.834374) (xy 115.427986 -383.778789) (xy 115.396954 -383.719067) (xy 115.373282 -383.656064)
			(xy 115.357309 -383.590684) (xy 115.349264 -383.523864) (xy 115.349262 -383.45656) (xy 115.357305 -383.38974)
			(xy 115.373275 -383.324359) (xy 115.396944 -383.261355) (xy 115.427974 -383.201632) (xy 115.465918 -383.146045)
			(xy 115.487704 -383.120392) (xy 115.493487 -383.113237) (xy 115.50001 -383.096054) (xy 115.500404 -383.086864)
			(xy 115.500404 -382.593342) (xy 115.499973 -382.584157) (xy 115.493474 -382.566973) (xy 115.487704 -382.559814)
			(xy 115.465908 -382.534169) (xy 115.427961 -382.478581) (xy 115.39693 -382.418856) (xy 115.37326 -382.355851)
			(xy 115.357288 -382.290468) (xy 115.349246 -382.223645) (xy 90.070711 -382.223645) (xy 90.062667 -382.290467)
			(xy 90.046695 -382.355848) (xy 90.023023 -382.418852) (xy 89.991991 -382.478576) (xy 89.954043 -382.534162)
			(xy 89.932256 -382.559814) (xy 89.926465 -382.566963) (xy 89.919948 -382.584151) (xy 89.919556 -382.593342)
			(xy 89.919556 -383.086864) (xy 89.919994 -383.096048) (xy 89.926489 -383.113232) (xy 89.932256 -383.120392)
			(xy 89.95406 -383.146031) (xy 89.992008 -383.201619) (xy 90.023041 -383.261345) (xy 90.046478 -383.323726)
			(xy 91.149124 -383.323726) (xy 91.149128 -383.256419) (xy 91.157175 -383.189595) (xy 91.17315 -383.124211)
			(xy 91.196825 -383.061205) (xy 91.227861 -383.001481) (xy 91.265811 -382.945893) (xy 91.2876 -382.92024)
			(xy 91.293405 -382.9131) (xy 91.299914 -382.895906) (xy 91.3003 -382.886712) (xy 91.3003 -382.728724)
			(xy 91.300741 -382.718571) (xy 91.308529 -382.699819) (xy 91.32292 -382.685495) (xy 91.341708 -382.677795)
			(xy 91.351862 -382.677416) (xy 92.068142 -382.677416) (xy 92.078268 -382.677891) (xy 92.096986 -382.685629)
			(xy 92.11134 -382.699918) (xy 92.119162 -382.7186) (xy 92.119704 -382.728724) (xy 92.119704 -382.886712)
			(xy 92.120108 -382.8959) (xy 92.126626 -382.913084) (xy 92.132404 -382.92024) (xy 92.154155 -382.945922)
			(xy 92.192102 -383.001505) (xy 92.223135 -383.061225) (xy 92.246808 -383.124225) (xy 92.262782 -383.189604)
			(xy 92.270828 -383.256422) (xy 92.270831 -383.323724) (xy 92.262791 -383.390543) (xy 92.246824 -383.455923)
			(xy 92.223157 -383.518926) (xy 92.19213 -383.578648) (xy 92.154188 -383.634235) (xy 92.132404 -383.659888)
			(xy 92.126588 -383.66702) (xy 92.120085 -383.68422) (xy 92.119704 -383.693416) (xy 92.119704 -384.186684)
			(xy 92.120121 -384.19587) (xy 92.12663 -384.213055) (xy 92.132404 -384.220212) (xy 92.154226 -384.245836)
			(xy 92.192171 -384.301427) (xy 92.2232 -384.361155) (xy 92.246869 -384.424163) (xy 92.262838 -384.489548)
			(xy 92.270879 -384.556374) (xy 92.270875 -384.623681) (xy 92.262828 -384.690505) (xy 92.246853 -384.755889)
			(xy 92.223178 -384.818894) (xy 92.192143 -384.878619) (xy 92.154193 -384.934207) (xy 92.132404 -384.95986)
			(xy 92.1266 -384.967) (xy 92.12009 -384.984194) (xy 92.119704 -384.993388) (xy 92.119704 -385.151376)
			(xy 92.119259 -385.161528) (xy 92.111472 -385.180279) (xy 92.097082 -385.194603) (xy 92.078296 -385.202305)
			(xy 92.068142 -385.202684) (xy 91.351862 -385.202684) (xy 91.341736 -385.202205) (xy 91.323018 -385.194469)
			(xy 91.308664 -385.180181) (xy 91.300842 -385.1615) (xy 91.3003 -385.151376) (xy 91.3003 -384.993388)
			(xy 91.299895 -384.9842) (xy 91.293378 -384.967016) (xy 91.2876 -384.95986) (xy 91.265849 -384.934178)
			(xy 91.227901 -384.878595) (xy 91.196869 -384.818875) (xy 91.173196 -384.755875) (xy 91.157221 -384.690497)
			(xy 91.149175 -384.623678) (xy 91.149172 -384.556376) (xy 91.157212 -384.489557) (xy 91.17318 -384.424177)
			(xy 91.196847 -384.361174) (xy 91.227874 -384.301451) (xy 91.265816 -384.245865) (xy 91.2876 -384.220212)
			(xy 91.293416 -384.213081) (xy 91.299919 -384.19588) (xy 91.3003 -384.186684) (xy 91.3003 -383.693416)
			(xy 91.299882 -383.68423) (xy 91.293374 -383.667045) (xy 91.2876 -383.659888) (xy 91.265778 -383.634264)
			(xy 91.227833 -383.578673) (xy 91.196803 -383.518945) (xy 91.173134 -383.455937) (xy 91.157165 -383.390552)
			(xy 91.149124 -383.323726) (xy 90.046478 -383.323726) (xy 90.046713 -383.324351) (xy 90.062685 -383.389735)
			(xy 90.070728 -383.456559) (xy 90.070727 -383.523865) (xy 90.062681 -383.590689) (xy 90.046706 -383.656072)
			(xy 90.023031 -383.719077) (xy 89.991996 -383.778801) (xy 89.954045 -383.834388) (xy 89.932256 -383.86004)
			(xy 89.926454 -383.867181) (xy 89.919944 -383.884375) (xy 89.919556 -383.893568) (xy 89.919556 -384.051556)
			(xy 89.919043 -384.0617) (xy 89.911273 -384.080441) (xy 89.896905 -384.094764) (xy 89.87814 -384.102475)
			(xy 89.867994 -384.102864) (xy 89.151714 -384.102864) (xy 89.141589 -384.102362) (xy 89.122869 -384.09464)
			(xy 89.108512 -384.080358) (xy 89.100692 -384.061679) (xy 89.100152 -384.051556) (xy 89.100152 -383.893568)
			(xy 89.099745 -383.884381) (xy 89.093228 -383.867197) (xy 89.087452 -383.86004) (xy 89.06568 -383.834375)
			(xy 89.02773 -383.778791) (xy 88.996695 -383.719069) (xy 88.973021 -383.656066) (xy 88.957046 -383.590685)
			(xy 88.949001 -383.523864) (xy 88.948999 -383.45656) (xy 88.957042 -383.389738) (xy 88.973014 -383.324357)
			(xy 88.996685 -383.261353) (xy 89.027717 -383.20163) (xy 89.065665 -383.146044) (xy 89.087452 -383.120392)
			(xy 89.093241 -383.113242) (xy 89.099759 -383.096055) (xy 89.100152 -383.086864) (xy 89.100152 -382.593342)
			(xy 89.09971 -382.584158) (xy 89.093217 -382.566975) (xy 89.087452 -382.559814) (xy 89.065654 -382.53417)
			(xy 89.027704 -382.478583) (xy 88.996671 -382.418858) (xy 88.972998 -382.355853) (xy 88.957025 -382.290469)
			(xy 88.948982 -382.223646) (xy 85.670943 -382.223646) (xy 85.670943 -382.223704) (xy 85.662867 -382.290643)
			(xy 85.646832 -382.356132) (xy 85.623067 -382.419228) (xy 85.591915 -382.479024) (xy 85.553825 -382.534657)
			(xy 85.53196 -382.560322) (xy 85.526167 -382.567469) (xy 85.519651 -382.584658) (xy 85.51926 -382.59385)
			(xy 85.51926 -383.086356) (xy 85.5197 -383.09554) (xy 85.526194 -383.112724) (xy 85.53196 -383.119884)
			(xy 85.553841 -383.145536) (xy 85.591932 -383.201171) (xy 85.623084 -383.260969) (xy 85.646743 -383.323786)
			(xy 86.748805 -383.323786) (xy 86.748808 -383.25636) (xy 86.756888 -383.189419) (xy 86.772927 -383.123927)
			(xy 86.796696 -383.060829) (xy 86.827852 -383.001032) (xy 86.865945 -382.945397) (xy 86.887812 -382.919732)
			(xy 86.893621 -382.912596) (xy 86.900128 -382.895398) (xy 86.900512 -382.886204) (xy 86.900512 -382.728724)
			(xy 86.900936 -382.718602) (xy 86.908678 -382.699896) (xy 86.922993 -382.685581) (xy 86.941698 -382.677837)
			(xy 86.95182 -382.677416) (xy 87.6681 -382.677416) (xy 87.678224 -382.677816) (xy 87.696931 -382.685568)
			(xy 87.711246 -382.699889) (xy 87.718988 -382.718599) (xy 87.719408 -382.728724) (xy 87.719408 -382.886204)
			(xy 87.719815 -382.895392) (xy 87.726331 -382.912576) (xy 87.732108 -382.919732) (xy 87.753936 -382.945427)
			(xy 87.792026 -383.001057) (xy 87.823177 -383.060849) (xy 87.846943 -383.123942) (xy 87.862981 -383.189428)
			(xy 87.87106 -383.256363) (xy 87.871063 -383.323783) (xy 87.862991 -383.390719) (xy 87.846959 -383.456206)
			(xy 87.8232 -383.519301) (xy 87.792053 -383.579096) (xy 87.75397 -383.634731) (xy 87.732108 -383.660396)
			(xy 87.726332 -383.667556) (xy 87.719805 -383.684735) (xy 87.719408 -383.693924) (xy 87.719408 -384.186176)
			(xy 87.719828 -384.195362) (xy 87.726335 -384.212547) (xy 87.732108 -384.219704) (xy 87.754007 -384.24534)
			(xy 87.792094 -384.300979) (xy 87.823243 -384.360779) (xy 87.847005 -384.42388) (xy 87.863037 -384.489373)
			(xy 87.87111 -384.556314) (xy 87.871107 -384.62374) (xy 87.863028 -384.690681) (xy 87.846989 -384.756172)
			(xy 87.823221 -384.81927) (xy 87.792066 -384.879067) (xy 87.753974 -384.934703) (xy 87.732108 -384.960368)
			(xy 87.726301 -384.967506) (xy 87.719792 -384.984702) (xy 87.719408 -384.993896) (xy 87.719408 -385.151376)
			(xy 87.718965 -385.161496) (xy 87.711226 -385.180198) (xy 87.696918 -385.194512) (xy 87.67822 -385.20226)
			(xy 87.6681 -385.202684) (xy 86.95182 -385.202684) (xy 86.941697 -385.202267) (xy 86.922991 -385.194523)
			(xy 86.908675 -385.180206) (xy 86.900932 -385.161499) (xy 86.900512 -385.151376) (xy 86.900512 -384.993896)
			(xy 86.900101 -384.984709) (xy 86.893587 -384.967525) (xy 86.887812 -384.960368) (xy 86.865983 -384.934674)
			(xy 86.827892 -384.879044) (xy 86.796739 -384.819252) (xy 86.772973 -384.756158) (xy 86.756934 -384.690673)
			(xy 86.748855 -384.623738) (xy 86.748852 -384.556316) (xy 86.756925 -384.48938) (xy 86.772957 -384.423893)
			(xy 86.796717 -384.360798) (xy 86.827865 -384.301003) (xy 86.86595 -384.245369) (xy 86.887812 -384.219704)
			(xy 86.893591 -384.212546) (xy 86.900116 -384.195365) (xy 86.900512 -384.186176) (xy 86.900512 -383.693924)
			(xy 86.900088 -383.684738) (xy 86.893583 -383.667554) (xy 86.887812 -383.660396) (xy 86.865912 -383.63476)
			(xy 86.827824 -383.579122) (xy 86.796674 -383.519322) (xy 86.772911 -383.456221) (xy 86.756878 -383.390728)
			(xy 86.748805 -383.323786) (xy 85.646743 -383.323786) (xy 85.646849 -383.324068) (xy 85.662885 -383.389559)
			(xy 85.67096 -383.456499) (xy 85.670959 -383.523925) (xy 85.662881 -383.590865) (xy 85.646842 -383.656355)
			(xy 85.623074 -383.719453) (xy 85.59192 -383.77925) (xy 85.553826 -383.834883) (xy 85.53196 -383.860548)
			(xy 85.526156 -383.867687) (xy 85.519647 -383.884883) (xy 85.51926 -383.894076) (xy 85.51926 -384.051556)
			(xy 85.518847 -384.061681) (xy 85.511106 -384.080391) (xy 85.496787 -384.094708) (xy 85.478077 -384.102448)
			(xy 85.467952 -384.102864) (xy 84.751672 -384.102864) (xy 84.741543 -384.102506) (xy 84.722832 -384.094742)
			(xy 84.708517 -384.080407) (xy 84.70078 -384.061685) (xy 84.700364 -384.051556) (xy 84.700364 -383.894076)
			(xy 84.699951 -383.884889) (xy 84.693438 -383.867706) (xy 84.687664 -383.860548) (xy 84.665817 -383.834869)
			(xy 84.62773 -383.779236) (xy 84.596581 -383.719441) (xy 84.572817 -383.656346) (xy 84.556782 -383.590859)
			(xy 84.548705 -383.523923) (xy 84.548704 -383.456501) (xy 84.556778 -383.389565) (xy 84.57281 -383.324077)
			(xy 84.596571 -383.260981) (xy 84.627718 -383.201185) (xy 84.665802 -383.14555) (xy 84.687664 -383.119884)
			(xy 84.693458 -383.112737) (xy 84.699972 -383.095548) (xy 84.700364 -383.086356) (xy 84.700364 -382.59385)
			(xy 84.699916 -382.584667) (xy 84.693427 -382.567483) (xy 84.687664 -382.560322) (xy 84.665791 -382.534664)
			(xy 84.627705 -382.479028) (xy 84.596557 -382.41923) (xy 84.572795 -382.356132) (xy 84.556761 -382.290643)
			(xy 84.548687 -382.223704) (xy 81.271152 -382.223704) (xy 81.263076 -382.290642) (xy 81.247041 -382.356131)
			(xy 81.223277 -382.419228) (xy 81.192126 -382.479023) (xy 81.154036 -382.534657) (xy 81.132172 -382.560322)
			(xy 81.12638 -382.56747) (xy 81.119863 -382.584659) (xy 81.119472 -382.59385) (xy 81.119472 -383.086356)
			(xy 81.11991 -383.09554) (xy 81.126405 -383.112724) (xy 81.132172 -383.119884) (xy 81.154053 -383.145536)
			(xy 81.192143 -383.201172) (xy 81.223294 -383.260969) (xy 81.246931 -383.323727) (xy 82.349036 -383.323727)
			(xy 82.34904 -383.256419) (xy 82.357087 -383.189595) (xy 82.373063 -383.124211) (xy 82.396739 -383.061205)
			(xy 82.427775 -383.00148) (xy 82.465727 -382.945892) (xy 82.487516 -382.92024) (xy 82.493322 -382.913102)
			(xy 82.499831 -382.895906) (xy 82.500216 -382.886712) (xy 82.500216 -382.728724) (xy 82.500636 -382.718601)
			(xy 82.508379 -382.699895) (xy 82.522695 -382.685579) (xy 82.541401 -382.677836) (xy 82.551524 -382.677416)
			(xy 83.268058 -382.677416) (xy 83.278179 -382.67796) (xy 83.296895 -382.68567) (xy 83.311252 -382.699938)
			(xy 83.319076 -382.718606) (xy 83.31962 -382.728724) (xy 83.31962 -382.886712) (xy 83.32002 -382.8959)
			(xy 83.32654 -382.913085) (xy 83.33232 -382.92024) (xy 83.354074 -382.945921) (xy 83.392026 -383.001502)
			(xy 83.423063 -383.061221) (xy 83.44674 -383.124222) (xy 83.462717 -383.189601) (xy 83.470764 -383.256421)
			(xy 83.470767 -383.323724) (xy 83.462726 -383.390545) (xy 83.446756 -383.455926) (xy 83.423085 -383.518929)
			(xy 83.392054 -383.578651) (xy 83.354107 -383.634236) (xy 83.33232 -383.659888) (xy 83.326506 -383.667021)
			(xy 83.320001 -383.684221) (xy 83.31962 -383.693416) (xy 83.31962 -384.186684) (xy 83.320033 -384.195871)
			(xy 83.326544 -384.213056) (xy 83.33232 -384.220212) (xy 83.354144 -384.245835) (xy 83.392095 -384.301424)
			(xy 83.423129 -384.361152) (xy 83.446801 -384.42416) (xy 83.462773 -384.489546) (xy 83.470815 -384.556373)
			(xy 83.470812 -384.623681) (xy 83.462763 -384.690507) (xy 83.446785 -384.755892) (xy 83.423107 -384.818898)
			(xy 83.392067 -384.878622) (xy 83.354111 -384.934208) (xy 83.33232 -384.95986) (xy 83.326518 -384.967001)
			(xy 83.320006 -384.984195) (xy 83.31962 -384.993388) (xy 83.31962 -385.151376) (xy 83.319165 -385.161494)
			(xy 83.311428 -385.180194) (xy 83.297124 -385.194508) (xy 83.27843 -385.202258) (xy 83.268312 -385.202684)
			(xy 82.551778 -385.202684) (xy 82.541653 -385.202192) (xy 82.522936 -385.194462) (xy 82.508581 -385.180178)
			(xy 82.500758 -385.161499) (xy 82.500216 -385.151376) (xy 82.500216 -384.993388) (xy 82.499808 -384.984201)
			(xy 82.493293 -384.967016) (xy 82.487516 -384.95986) (xy 82.465765 -384.934178) (xy 82.427816 -384.878595)
			(xy 82.396783 -384.818876) (xy 82.373109 -384.755875) (xy 82.357134 -384.690497) (xy 82.349088 -384.623678)
			(xy 82.349084 -384.556376) (xy 82.357125 -384.489556) (xy 82.373093 -384.424177) (xy 82.396761 -384.361174)
			(xy 82.427788 -384.301451) (xy 82.465731 -384.245865) (xy 82.487516 -384.220212) (xy 82.493334 -384.213082)
			(xy 82.499835 -384.19588) (xy 82.500216 -384.186684) (xy 82.500216 -383.693416) (xy 82.499794 -383.68423)
			(xy 82.493288 -383.667046) (xy 82.487516 -383.659888) (xy 82.465694 -383.634265) (xy 82.427747 -383.578674)
			(xy 82.396717 -383.518946) (xy 82.373047 -383.455938) (xy 82.357077 -383.390552) (xy 82.349036 -383.323727)
			(xy 81.246931 -383.323727) (xy 81.247059 -383.324068) (xy 81.263094 -383.389559) (xy 81.271169 -383.456499)
			(xy 81.271168 -383.523925) (xy 81.26309 -383.590865) (xy 81.247052 -383.656355) (xy 81.223285 -383.719453)
			(xy 81.19213 -383.779249) (xy 81.154038 -383.834883) (xy 81.132172 -383.860548) (xy 81.126369 -383.867688)
			(xy 81.119859 -383.884883) (xy 81.119472 -383.894076) (xy 81.119472 -384.051556) (xy 81.119047 -384.061679)
			(xy 81.111308 -384.080387) (xy 81.096994 -384.094704) (xy 81.078287 -384.102446) (xy 81.068164 -384.102864)
			(xy 80.351884 -384.102864) (xy 80.341756 -384.102496) (xy 80.323045 -384.094736) (xy 80.30873 -384.080405)
			(xy 80.300992 -384.061685) (xy 80.300576 -384.051556) (xy 80.300576 -383.894076) (xy 80.300183 -383.884887)
			(xy 80.293658 -383.867703) (xy 80.287876 -383.860548) (xy 80.266029 -383.834869) (xy 80.227941 -383.779236)
			(xy 80.196791 -383.719442) (xy 80.173027 -383.656347) (xy 80.156991 -383.590859) (xy 80.148914 -383.523923)
			(xy 80.148913 -383.456501) (xy 80.156987 -383.389564) (xy 80.17302 -383.324076) (xy 80.196781 -383.26098)
			(xy 80.227929 -383.201184) (xy 80.266014 -383.14555) (xy 80.287876 -383.119884) (xy 80.293659 -383.112729)
			(xy 80.300183 -383.095546) (xy 80.300576 -383.086356) (xy 80.300576 -382.59385) (xy 80.300147 -382.584665)
			(xy 80.293647 -382.56748) (xy 80.287876 -382.560322) (xy 80.266003 -382.534664) (xy 80.227916 -382.479028)
			(xy 80.196767 -382.419231) (xy 80.173005 -382.356133) (xy 80.156971 -382.290643) (xy 80.148896 -382.223704)
			(xy 76.870825 -382.223704) (xy 76.862789 -382.290466) (xy 76.846818 -382.355847) (xy 76.823147 -382.418851)
			(xy 76.792117 -382.478575) (xy 76.75417 -382.534162) (xy 76.732384 -382.559814) (xy 76.726597 -382.566966)
			(xy 76.720077 -382.584151) (xy 76.719684 -382.593342) (xy 76.719684 -383.086864) (xy 76.720115 -383.096049)
			(xy 76.726615 -383.113233) (xy 76.732384 -383.120392) (xy 76.754187 -383.146031) (xy 76.792134 -383.20162)
			(xy 76.823165 -383.261346) (xy 76.846624 -383.323787) (xy 77.948717 -383.323787) (xy 77.94872 -383.256359)
			(xy 77.9568 -383.189418) (xy 77.97284 -383.123927) (xy 77.99661 -383.060828) (xy 78.027766 -383.001031)
			(xy 78.065861 -382.945397) (xy 78.087728 -382.919732) (xy 78.09354 -382.912598) (xy 78.100045 -382.895399)
			(xy 78.100428 -382.886204) (xy 78.100428 -382.728724) (xy 78.100836 -382.7186) (xy 78.108582 -382.699891)
			(xy 78.122901 -382.685575) (xy 78.141611 -382.677834) (xy 78.151736 -382.677416) (xy 78.868016 -382.677416)
			(xy 78.878142 -382.677803) (xy 78.896849 -382.685559) (xy 78.911163 -382.699885) (xy 78.918905 -382.718598)
			(xy 78.919324 -382.728724) (xy 78.919324 -382.886204) (xy 78.919727 -382.895392) (xy 78.926245 -382.912577)
			(xy 78.932024 -382.919732) (xy 78.953852 -382.945427) (xy 78.99194 -383.001058) (xy 79.023091 -383.06085)
			(xy 79.046856 -383.123943) (xy 79.062893 -383.189428) (xy 79.070972 -383.256363) (xy 79.070975 -383.323783)
			(xy 79.062903 -383.390719) (xy 79.046872 -383.456205) (xy 79.023113 -383.519301) (xy 78.991968 -383.579096)
			(xy 78.953885 -383.63473) (xy 78.932024 -383.660396) (xy 78.926249 -383.667557) (xy 78.919721 -383.684735)
			(xy 78.919324 -383.693924) (xy 78.919324 -384.186176) (xy 78.91974 -384.195363) (xy 78.926249 -384.212547)
			(xy 78.932024 -384.219704) (xy 78.953922 -384.24534) (xy 78.992009 -384.30098) (xy 79.023156 -384.36078)
			(xy 79.046917 -384.423881) (xy 79.06295 -384.489373) (xy 79.071022 -384.556314) (xy 79.071019 -384.62374)
			(xy 79.06294 -384.69068) (xy 79.046901 -384.756171) (xy 79.023134 -384.819269) (xy 78.991981 -384.879067)
			(xy 78.953889 -384.934702) (xy 78.932024 -384.960368) (xy 78.926219 -384.967507) (xy 78.919709 -384.984702)
			(xy 78.919324 -384.993896) (xy 78.919324 -385.151376) (xy 78.918865 -385.161494) (xy 78.911129 -385.180193)
			(xy 78.896826 -385.194507) (xy 78.878134 -385.202257) (xy 78.868016 -385.202684) (xy 78.151736 -385.202684)
			(xy 78.141614 -385.202254) (xy 78.122908 -385.194515) (xy 78.108592 -385.180202) (xy 78.100848 -385.161498)
			(xy 78.100428 -385.151376) (xy 78.100428 -384.993896) (xy 78.100014 -384.984709) (xy 78.093502 -384.967525)
			(xy 78.087728 -384.960368) (xy 78.065898 -384.934674) (xy 78.027807 -384.879044) (xy 77.996653 -384.819252)
			(xy 77.972886 -384.756159) (xy 77.956847 -384.690673) (xy 77.948768 -384.623738) (xy 77.948764 -384.556316)
			(xy 77.956837 -384.48938) (xy 77.972869 -384.423893) (xy 77.996631 -384.360797) (xy 78.027779 -384.301002)
			(xy 78.065865 -384.245369) (xy 78.087728 -384.219704) (xy 78.093509 -384.212548) (xy 78.100032 -384.195366)
			(xy 78.100428 -384.186176) (xy 78.100428 -383.693924) (xy 78.1 -383.684739) (xy 78.093498 -383.667555)
			(xy 78.087728 -383.660396) (xy 78.065828 -383.63476) (xy 78.027738 -383.579122) (xy 77.996587 -383.519322)
			(xy 77.972824 -383.456221) (xy 77.95679 -383.390728) (xy 77.948717 -383.323787) (xy 76.846624 -383.323787)
			(xy 76.846836 -383.324352) (xy 76.862807 -383.389735) (xy 76.870849 -383.456559) (xy 76.870848 -383.523865)
			(xy 76.862803 -383.590688) (xy 76.846829 -383.656071) (xy 76.823155 -383.719076) (xy 76.792121 -383.7788)
			(xy 76.754172 -383.834388) (xy 76.732384 -383.86004) (xy 76.726586 -383.867184) (xy 76.720073 -383.884376)
			(xy 76.719684 -383.893568) (xy 76.719684 -384.051556) (xy 76.719242 -384.061709) (xy 76.711458 -384.080464)
			(xy 76.697067 -384.094789) (xy 76.678277 -384.102488) (xy 76.668122 -384.102864) (xy 75.951842 -384.102864)
			(xy 75.941718 -384.102339) (xy 75.922999 -384.094626) (xy 75.908642 -384.080351) (xy 75.90082 -384.061677)
			(xy 75.90028 -384.051556) (xy 75.90028 -383.893568) (xy 75.89989 -383.884379) (xy 75.893363 -383.867194)
			(xy 75.88758 -383.86004) (xy 75.865807 -383.834375) (xy 75.827855 -383.778792) (xy 75.796819 -383.71907)
			(xy 75.773143 -383.656067) (xy 75.757168 -383.590686) (xy 75.749122 -383.523864) (xy 75.74912 -383.45656)
			(xy 75.757164 -383.389738) (xy 75.773136 -383.324356) (xy 75.796809 -383.261352) (xy 75.827842 -383.201629)
			(xy 75.865792 -383.146044) (xy 75.88758 -383.120392) (xy 75.89336 -383.113235) (xy 75.899885 -383.096054)
			(xy 75.90028 -383.086864) (xy 75.90028 -382.593342) (xy 75.899854 -382.584156) (xy 75.893352 -382.566972)
			(xy 75.88758 -382.559814) (xy 75.865781 -382.53417) (xy 75.82783 -382.478584) (xy 75.796795 -382.418859)
			(xy 75.773121 -382.355854) (xy 75.757147 -382.29047) (xy 75.749104 -382.223646) (xy 72.471064 -382.223646)
			(xy 72.471064 -382.223704) (xy 72.462989 -382.290642) (xy 72.446954 -382.356131) (xy 72.42319 -382.419227)
			(xy 72.39204 -382.479023) (xy 72.353952 -382.534657) (xy 72.332088 -382.560322) (xy 72.326298 -382.567472)
			(xy 72.31978 -382.584659) (xy 72.319388 -382.59385) (xy 72.319388 -383.086356) (xy 72.319822 -383.095541)
			(xy 72.326319 -383.112725) (xy 72.332088 -383.119884) (xy 72.353968 -383.145536) (xy 72.392057 -383.201172)
			(xy 72.423208 -383.26097) (xy 72.446843 -383.323727) (xy 73.548949 -383.323727) (xy 73.548952 -383.256419)
			(xy 73.556999 -383.189594) (xy 73.572976 -383.12421) (xy 73.596652 -383.061204) (xy 73.62769 -383.001479)
			(xy 73.665642 -382.945892) (xy 73.687432 -382.92024) (xy 73.693241 -382.913103) (xy 73.699747 -382.895906)
			(xy 73.700132 -382.886712) (xy 73.700132 -382.728724) (xy 73.700542 -382.718567) (xy 73.708335 -382.699809)
			(xy 73.722736 -382.685484) (xy 73.741535 -382.677789) (xy 73.751694 -382.677416) (xy 74.467974 -382.677416)
			(xy 74.478096 -382.677947) (xy 74.496812 -382.685662) (xy 74.511169 -382.699934) (xy 74.518993 -382.718605)
			(xy 74.519536 -382.728724) (xy 74.519536 -382.886712) (xy 74.519955 -382.895898) (xy 74.526464 -382.913082)
			(xy 74.532236 -382.92024) (xy 74.553989 -382.945921) (xy 74.591941 -383.001503) (xy 74.622977 -383.061222)
			(xy 74.646653 -383.124223) (xy 74.662629 -383.189602) (xy 74.670676 -383.256422) (xy 74.670679 -383.323724)
			(xy 74.662639 -383.390545) (xy 74.646669 -383.455925) (xy 74.622999 -383.518928) (xy 74.591968 -383.578651)
			(xy 74.554022 -383.634236) (xy 74.532236 -383.659888) (xy 74.526412 -383.667013) (xy 74.519915 -383.684219)
			(xy 74.519536 -383.693416) (xy 74.519536 -384.186684) (xy 74.519968 -384.195869) (xy 74.526468 -384.213052)
			(xy 74.532236 -384.220212) (xy 74.55406 -384.245835) (xy 74.592009 -384.301425) (xy 74.623043 -384.361152)
			(xy 74.646714 -384.424161) (xy 74.662686 -384.489547) (xy 74.670727 -384.556373) (xy 74.670724 -384.623681)
			(xy 74.662676 -384.690507) (xy 74.646698 -384.755891) (xy 74.623021 -384.818897) (xy 74.591982 -384.878622)
			(xy 74.554027 -384.934208) (xy 74.532236 -384.95986) (xy 74.526424 -384.966994) (xy 74.51992 -384.984193)
			(xy 74.519536 -384.993388) (xy 74.519536 -385.151376) (xy 74.51906 -385.161524) (xy 74.511279 -385.180269)
			(xy 74.496899 -385.194592) (xy 74.478124 -385.202299) (xy 74.467974 -385.202684) (xy 73.751694 -385.202684)
			(xy 73.74157 -385.202179) (xy 73.722853 -385.194454) (xy 73.708498 -385.180173) (xy 73.700675 -385.161497)
			(xy 73.700132 -385.151376) (xy 73.700132 -384.993388) (xy 73.699721 -384.984201) (xy 73.693207 -384.967017)
			(xy 73.687432 -384.95986) (xy 73.66568 -384.934178) (xy 73.627731 -384.878596) (xy 73.596696 -384.818877)
			(xy 73.573022 -384.755876) (xy 73.557047 -384.690497) (xy 73.549 -384.623678) (xy 73.548996 -384.556376)
			(xy 73.557037 -384.489556) (xy 73.573006 -384.424176) (xy 73.596674 -384.361173) (xy 73.627703 -384.30145)
			(xy 73.665647 -384.245864) (xy 73.687432 -384.220212) (xy 73.693253 -384.213084) (xy 73.699752 -384.19588)
			(xy 73.700132 -384.186684) (xy 73.700132 -383.693416) (xy 73.699707 -383.684231) (xy 73.693203 -383.667046)
			(xy 73.687432 -383.659888) (xy 73.665609 -383.634265) (xy 73.627662 -383.578674) (xy 73.59663 -383.518946)
			(xy 73.57296 -383.455938) (xy 73.55699 -383.390553) (xy 73.548949 -383.323727) (xy 72.446843 -383.323727)
			(xy 72.446972 -383.324069) (xy 72.463006 -383.38956) (xy 72.471081 -383.456499) (xy 72.47108 -383.523925)
			(xy 72.463002 -383.590864) (xy 72.446964 -383.656354) (xy 72.423198 -383.719452) (xy 72.392045 -383.779248)
			(xy 72.353953 -383.834883) (xy 72.332088 -383.860548) (xy 72.326287 -383.86769) (xy 72.319775 -383.884883)
			(xy 72.319388 -383.894076) (xy 72.319388 -384.051556) (xy 72.318948 -384.061677) (xy 72.311212 -384.080382)
			(xy 72.296902 -384.094698) (xy 72.278201 -384.102443) (xy 72.26808 -384.102864) (xy 71.5518 -384.102864)
			(xy 71.541673 -384.102483) (xy 71.522963 -384.094728) (xy 71.508647 -384.0804) (xy 71.500908 -384.061683)
			(xy 71.500492 -384.051556) (xy 71.500492 -383.894076) (xy 71.500095 -383.884887) (xy 71.493572 -383.867703)
			(xy 71.487792 -383.860548) (xy 71.465944 -383.83487) (xy 71.427855 -383.779237) (xy 71.396704 -383.719442)
			(xy 71.37294 -383.656347) (xy 71.356903 -383.59086) (xy 71.348826 -383.523923) (xy 71.348825 -383.456501)
			(xy 71.356899 -383.389564) (xy 71.372933 -383.324076) (xy 71.396695 -383.26098) (xy 71.427843 -383.201184)
			(xy 71.465929 -383.145549) (xy 71.487792 -383.119884) (xy 71.493577 -383.11273) (xy 71.500099 -383.095546)
			(xy 71.500492 -383.086356) (xy 71.500492 -382.59385) (xy 71.50006 -382.584665) (xy 71.493562 -382.56748)
			(xy 71.487792 -382.560322) (xy 71.465918 -382.534665) (xy 71.427831 -382.479029) (xy 71.396681 -382.419231)
			(xy 71.372918 -382.356134) (xy 71.356883 -382.290644) (xy 71.348808 -382.223705) (xy 46.070794 -382.223705)
			(xy 46.062758 -382.290467) (xy 46.046786 -382.355849) (xy 46.023113 -382.418853) (xy 45.99208 -382.478576)
			(xy 45.954131 -382.534162) (xy 45.932344 -382.559814) (xy 45.926552 -382.566962) (xy 45.920036 -382.584151)
			(xy 45.919644 -382.593342) (xy 45.919644 -383.086864) (xy 45.920084 -383.096048) (xy 45.926578 -383.113232)
			(xy 45.932344 -383.120392) (xy 45.954148 -383.146031) (xy 45.992098 -383.201619) (xy 46.023131 -383.261344)
			(xy 46.04657 -383.323727) (xy 47.149191 -383.323727) (xy 47.149195 -383.256419) (xy 47.157243 -383.189593)
			(xy 47.173221 -383.124208) (xy 47.1969 -383.061202) (xy 47.22794 -383.001477) (xy 47.265897 -382.945892)
			(xy 47.287688 -382.92024) (xy 47.293491 -382.913099) (xy 47.300002 -382.895905) (xy 47.300388 -382.886712)
			(xy 47.300388 -382.728724) (xy 47.300841 -382.718573) (xy 47.308626 -382.699823) (xy 47.323013 -382.685499)
			(xy 47.341797 -382.677797) (xy 47.35195 -382.677416) (xy 48.06823 -382.677416) (xy 48.078356 -382.677901)
			(xy 48.097073 -382.685634) (xy 48.111427 -382.699921) (xy 48.11925 -382.718601) (xy 48.119792 -382.728724)
			(xy 48.119792 -382.886712) (xy 48.120198 -382.8959) (xy 48.126715 -382.913084) (xy 48.132492 -382.92024)
			(xy 48.154243 -382.945922) (xy 48.192191 -383.001505) (xy 48.223224 -383.061224) (xy 48.246898 -383.124225)
			(xy 48.262872 -383.189603) (xy 48.270919 -383.256422) (xy 48.270922 -383.323724) (xy 48.262882 -383.390543)
			(xy 48.246914 -383.455923) (xy 48.223247 -383.518926) (xy 48.192219 -383.578649) (xy 48.154277 -383.634236)
			(xy 48.132492 -383.659888) (xy 48.126675 -383.667018) (xy 48.120173 -383.68422) (xy 48.119792 -383.693416)
			(xy 48.119792 -384.186684) (xy 48.120212 -384.19587) (xy 48.126719 -384.213054) (xy 48.132492 -384.220212)
			(xy 48.154314 -384.245835) (xy 48.19226 -384.301427) (xy 48.22329 -384.361155) (xy 48.246959 -384.424163)
			(xy 48.262929 -384.489548) (xy 48.27097 -384.556373) (xy 48.270966 -384.623681) (xy 48.262919 -384.690505)
			(xy 48.246943 -384.755889) (xy 48.223268 -384.818895) (xy 48.192232 -384.87862) (xy 48.154281 -384.934207)
			(xy 48.132492 -384.95986) (xy 48.126687 -384.966999) (xy 48.120177 -384.984194) (xy 48.119792 -384.993388)
			(xy 48.119792 -385.151376) (xy 48.119359 -385.16153) (xy 48.11157 -385.180283) (xy 48.097176 -385.194608)
			(xy 48.078386 -385.202307) (xy 48.06823 -385.202684) (xy 47.35195 -385.202684) (xy 47.341829 -385.202133)
			(xy 47.323114 -385.194426) (xy 47.308757 -385.18016) (xy 47.300932 -385.161493) (xy 47.300388 -385.151376)
			(xy 47.300388 -384.993388) (xy 47.299986 -384.9842) (xy 47.293467 -384.967016) (xy 47.287688 -384.95986)
			(xy 47.265934 -384.934179) (xy 47.227981 -384.878598) (xy 47.196944 -384.818879) (xy 47.173267 -384.755878)
			(xy 47.15729 -384.690499) (xy 47.149242 -384.623679) (xy 47.149239 -384.556376) (xy 47.15728 -384.489554)
			(xy 47.173251 -384.424174) (xy 47.196921 -384.361171) (xy 47.227953 -384.301448) (xy 47.265901 -384.245863)
			(xy 47.287688 -384.220212) (xy 47.293503 -384.21308) (xy 47.300007 -384.195879) (xy 47.300388 -384.186684)
			(xy 47.300388 -383.693416) (xy 47.299973 -383.684229) (xy 47.293463 -383.667045) (xy 47.287688 -383.659888)
			(xy 47.265863 -383.634266) (xy 47.227913 -383.578676) (xy 47.196878 -383.518949) (xy 47.173205 -383.45594)
			(xy 47.157233 -383.390554) (xy 47.149191 -383.323727) (xy 46.04657 -383.323727) (xy 46.046804 -383.32435)
			(xy 46.062776 -383.389734) (xy 46.070819 -383.456559) (xy 46.070818 -383.523865) (xy 46.062772 -383.590689)
			(xy 46.046797 -383.656073) (xy 46.023121 -383.719078) (xy 45.992085 -383.778802) (xy 45.954133 -383.834388)
			(xy 45.932344 -383.86004) (xy 45.926541 -383.86718) (xy 45.920032 -383.884375) (xy 45.919644 -383.893568)
			(xy 45.919644 -384.051556) (xy 45.919143 -384.061702) (xy 45.91137 -384.080445) (xy 45.896998 -384.094768)
			(xy 45.878229 -384.102477) (xy 45.868082 -384.102864) (xy 45.151802 -384.102864) (xy 45.141676 -384.102372)
			(xy 45.122956 -384.094645) (xy 45.108599 -384.080361) (xy 45.100779 -384.06168) (xy 45.10024 -384.051556)
			(xy 45.10024 -383.893568) (xy 45.099836 -383.88438) (xy 45.093317 -383.867197) (xy 45.08754 -383.86004)
			(xy 45.065768 -383.834375) (xy 45.027819 -383.77879) (xy 44.996785 -383.719068) (xy 44.973111 -383.656066)
			(xy 44.957137 -383.590685) (xy 44.949092 -383.523864) (xy 44.94909 -383.45656) (xy 44.957133 -383.389739)
			(xy 44.973104 -383.324357) (xy 44.996775 -383.261354) (xy 45.027806 -383.20163) (xy 45.065753 -383.146044)
			(xy 45.08754 -383.120392) (xy 45.093328 -383.113241) (xy 45.099847 -383.096055) (xy 45.10024 -383.086864)
			(xy 45.10024 -382.593342) (xy 45.0998 -382.584158) (xy 45.093306 -382.566974) (xy 45.08754 -382.559814)
			(xy 45.065742 -382.53417) (xy 45.027794 -382.478582) (xy 44.996761 -382.418858) (xy 44.973088 -382.355852)
			(xy 44.957116 -382.290469) (xy 44.949073 -382.223645) (xy 41.671034 -382.223645) (xy 41.671034 -382.223704)
			(xy 41.662958 -382.290643) (xy 41.646922 -382.356132) (xy 41.623157 -382.419229) (xy 41.592004 -382.479024)
			(xy 41.553913 -382.534658) (xy 41.532048 -382.560322) (xy 41.526253 -382.567468) (xy 41.519739 -382.584658)
			(xy 41.519348 -382.59385) (xy 41.519348 -383.086356) (xy 41.519791 -383.095539) (xy 41.526283 -383.112723)
			(xy 41.532048 -383.119884) (xy 41.55393 -383.145535) (xy 41.592021 -383.201171) (xy 41.623174 -383.260968)
			(xy 41.646834 -383.323786) (xy 42.748896 -383.323786) (xy 42.748899 -383.25636) (xy 42.756978 -383.189419)
			(xy 42.773018 -383.123928) (xy 42.796786 -383.06083) (xy 42.827941 -383.001032) (xy 42.866034 -382.945397)
			(xy 42.8879 -382.919732) (xy 42.893708 -382.912595) (xy 42.900216 -382.895398) (xy 42.9006 -382.886204)
			(xy 42.9006 -382.728724) (xy 42.901035 -382.718603) (xy 42.908776 -382.6999) (xy 42.923086 -382.685585)
			(xy 42.941787 -382.677839) (xy 42.951908 -382.677416) (xy 43.668188 -382.677416) (xy 43.678312 -382.677826)
			(xy 43.697018 -382.685573) (xy 43.711333 -382.699892) (xy 43.719076 -382.7186) (xy 43.719496 -382.728724)
			(xy 43.719496 -382.886204) (xy 43.719905 -382.895391) (xy 43.72642 -382.912575) (xy 43.732196 -382.919732)
			(xy 43.754025 -382.945426) (xy 43.792115 -383.001057) (xy 43.823267 -383.060849) (xy 43.847034 -383.123942)
			(xy 43.863072 -383.189427) (xy 43.871151 -383.256363) (xy 43.871154 -383.323783) (xy 43.863081 -383.390719)
			(xy 43.84705 -383.456206) (xy 43.823289 -383.519302) (xy 43.792143 -383.579097) (xy 43.754058 -383.634731)
			(xy 43.732196 -383.660396) (xy 43.726418 -383.667554) (xy 43.719892 -383.684735) (xy 43.719496 -383.693924)
			(xy 43.719496 -384.186176) (xy 43.719919 -384.195362) (xy 43.726424 -384.212546) (xy 43.732196 -384.219704)
			(xy 43.754095 -384.24534) (xy 43.792183 -384.300979) (xy 43.823333 -384.360779) (xy 43.847095 -384.42388)
			(xy 43.863128 -384.489372) (xy 43.871201 -384.556314) (xy 43.871198 -384.62374) (xy 43.863118 -384.690681)
			(xy 43.847079 -384.756172) (xy 43.823311 -384.819271) (xy 43.792156 -384.879068) (xy 43.754062 -384.934703)
			(xy 43.732196 -384.960368) (xy 43.726388 -384.967505) (xy 43.71988 -384.984702) (xy 43.719496 -384.993896)
			(xy 43.719496 -385.151376) (xy 43.719064 -385.161497) (xy 43.711323 -385.180201) (xy 43.697011 -385.194517)
			(xy 43.678309 -385.202262) (xy 43.668188 -385.202684) (xy 42.951908 -385.202684) (xy 42.941784 -385.202277)
			(xy 42.923078 -385.194529) (xy 42.908762 -385.180209) (xy 42.90102 -385.1615) (xy 42.9006 -385.151376)
			(xy 42.9006 -384.993896) (xy 42.900192 -384.984709) (xy 42.893677 -384.967524) (xy 42.8879 -384.960368)
			(xy 42.866071 -384.934674) (xy 42.827982 -384.879043) (xy 42.796829 -384.819251) (xy 42.773063 -384.756158)
			(xy 42.757025 -384.690672) (xy 42.748946 -384.623737) (xy 42.748943 -384.556317) (xy 42.757015 -384.489381)
			(xy 42.773047 -384.423894) (xy 42.796807 -384.360798) (xy 42.827954 -384.301003) (xy 42.866038 -384.245369)
			(xy 42.8879 -384.219704) (xy 42.893677 -384.212545) (xy 42.900204 -384.195365) (xy 42.9006 -384.186176)
			(xy 42.9006 -383.693924) (xy 42.900178 -383.684738) (xy 42.893673 -383.667554) (xy 42.8879 -383.660396)
			(xy 42.866001 -383.63476) (xy 42.827913 -383.579121) (xy 42.796764 -383.519321) (xy 42.773002 -383.45622)
			(xy 42.756969 -383.390728) (xy 42.748896 -383.323786) (xy 41.646834 -383.323786) (xy 41.64694 -383.324067)
			(xy 41.662976 -383.389558) (xy 41.671051 -383.456499) (xy 41.67105 -383.523925) (xy 41.662971 -383.590865)
			(xy 41.646933 -383.656356) (xy 41.623164 -383.719454) (xy 41.592009 -383.77925) (xy 41.553915 -383.834884)
			(xy 41.532048 -383.860548) (xy 41.526242 -383.867686) (xy 41.519734 -383.884882) (xy 41.519348 -383.894076)
			(xy 41.519348 -384.051556) (xy 41.518849 -384.06167) (xy 41.511124 -384.080363) (xy 41.496834 -384.094677)
			(xy 41.478153 -384.102432) (xy 41.46804 -384.102864) (xy 40.75176 -384.102864) (xy 40.74163 -384.102516)
			(xy 40.722919 -384.094748) (xy 40.708605 -384.08041) (xy 40.700868 -384.061686) (xy 40.700452 -384.051556)
			(xy 40.700452 -383.894076) (xy 40.700042 -383.884889) (xy 40.693527 -383.867705) (xy 40.687752 -383.860548)
			(xy 40.665902 -383.834871) (xy 40.627809 -383.779239) (xy 40.596655 -383.719445) (xy 40.572888 -383.65635)
			(xy 40.556849 -383.590862) (xy 40.548772 -383.523924) (xy 40.54877 -383.4565) (xy 40.556845 -383.389562)
			(xy 40.572881 -383.324073) (xy 40.596645 -383.260977) (xy 40.627797 -383.201182) (xy 40.665887 -383.145548)
			(xy 40.687752 -383.119884) (xy 40.693544 -383.112736) (xy 40.70006 -383.095547) (xy 40.700452 -383.086356)
			(xy 40.700452 -382.59385) (xy 40.700006 -382.584667) (xy 40.693516 -382.567483) (xy 40.687752 -382.560322)
			(xy 40.665876 -382.534666) (xy 40.627785 -382.479031) (xy 40.596631 -382.419234) (xy 40.572865 -382.356136)
			(xy 40.556829 -382.290645) (xy 40.548753 -382.223705) (xy 37.271243 -382.223705) (xy 37.263167 -382.290643)
			(xy 37.247132 -382.356132) (xy 37.223367 -382.419228) (xy 37.192215 -382.479024) (xy 37.154125 -382.534657)
			(xy 37.13226 -382.560322) (xy 37.126467 -382.567469) (xy 37.119951 -382.584658) (xy 37.11956 -382.59385)
			(xy 37.11956 -383.086356) (xy 37.12 -383.09554) (xy 37.126494 -383.112724) (xy 37.13226 -383.119884)
			(xy 37.154141 -383.145536) (xy 37.192232 -383.201171) (xy 37.223384 -383.260969) (xy 37.247021 -383.323727)
			(xy 38.349127 -383.323727) (xy 38.349131 -383.256419) (xy 38.357178 -383.189595) (xy 38.373154 -383.124211)
			(xy 38.396829 -383.061205) (xy 38.427864 -383.00148) (xy 38.465815 -382.945893) (xy 38.487604 -382.92024)
			(xy 38.493409 -382.913101) (xy 38.499919 -382.895906) (xy 38.500304 -382.886712) (xy 38.500304 -382.728724)
			(xy 38.500741 -382.718571) (xy 38.50853 -382.699818) (xy 38.522922 -382.685494) (xy 38.541711 -382.677794)
			(xy 38.551866 -382.677416) (xy 39.268146 -382.677416) (xy 39.278273 -382.677888) (xy 39.29699 -382.685627)
			(xy 39.311344 -382.699917) (xy 39.319166 -382.7186) (xy 39.319708 -382.728724) (xy 39.319708 -382.886712)
			(xy 39.320111 -382.8959) (xy 39.326629 -382.913084) (xy 39.332408 -382.92024) (xy 39.354162 -382.945921)
			(xy 39.392115 -383.001502) (xy 39.423153 -383.061221) (xy 39.44683 -383.124222) (xy 39.462807 -383.189601)
			(xy 39.470855 -383.256421) (xy 39.470858 -383.323725) (xy 39.462817 -383.390546) (xy 39.446846 -383.455926)
			(xy 39.423175 -383.51893) (xy 39.392143 -383.578652) (xy 39.354195 -383.634237) (xy 39.332408 -383.659888)
			(xy 39.326592 -383.66702) (xy 39.320089 -383.684221) (xy 39.319708 -383.693416) (xy 39.319708 -384.186684)
			(xy 39.320124 -384.195871) (xy 39.326633 -384.213055) (xy 39.332408 -384.220212) (xy 39.354233 -384.245834)
			(xy 39.392184 -384.301424) (xy 39.423219 -384.361151) (xy 39.446892 -384.42416) (xy 39.462864 -384.489546)
			(xy 39.470906 -384.556373) (xy 39.470902 -384.623682) (xy 39.462854 -384.690507) (xy 39.446876 -384.755892)
			(xy 39.423196 -384.818898) (xy 39.392156 -384.878623) (xy 39.354199 -384.934209) (xy 39.332408 -384.95986)
			(xy 39.326604 -384.967) (xy 39.320094 -384.984195) (xy 39.319708 -384.993388) (xy 39.319708 -385.151376)
			(xy 39.319259 -385.161528) (xy 39.311473 -385.180278) (xy 39.297085 -385.194602) (xy 39.278299 -385.202304)
			(xy 39.268146 -385.202684) (xy 38.551866 -385.202684) (xy 38.54174 -385.202202) (xy 38.523023 -385.194468)
			(xy 38.508668 -385.18018) (xy 38.500846 -385.1615) (xy 38.500304 -385.151376) (xy 38.500304 -384.993388)
			(xy 38.499899 -384.9842) (xy 38.493381 -384.967016) (xy 38.487604 -384.95986) (xy 38.465853 -384.934178)
			(xy 38.427905 -384.878595) (xy 38.396872 -384.818875) (xy 38.373199 -384.755875) (xy 38.357224 -384.690497)
			(xy 38.349178 -384.623678) (xy 38.349175 -384.556376) (xy 38.357215 -384.489557) (xy 38.373183 -384.424177)
			(xy 38.39685 -384.361174) (xy 38.427877 -384.301451) (xy 38.465819 -384.245865) (xy 38.487604 -384.220212)
			(xy 38.493421 -384.213081) (xy 38.499923 -384.19588) (xy 38.500304 -384.186684) (xy 38.500304 -383.693416)
			(xy 38.499885 -383.68423) (xy 38.493377 -383.667045) (xy 38.487604 -383.659888) (xy 38.465782 -383.634264)
			(xy 38.427837 -383.578673) (xy 38.396807 -383.518945) (xy 38.373138 -383.455937) (xy 38.357168 -383.390552)
			(xy 38.349127 -383.323727) (xy 37.247021 -383.323727) (xy 37.247149 -383.324068) (xy 37.263185 -383.389559)
			(xy 37.27126 -383.456499) (xy 37.271259 -383.523925) (xy 37.263181 -383.590865) (xy 37.247142 -383.656355)
			(xy 37.223374 -383.719453) (xy 37.19222 -383.77925) (xy 37.154126 -383.834883) (xy 37.13226 -383.860548)
			(xy 37.126456 -383.867687) (xy 37.119947 -383.884883) (xy 37.11956 -383.894076) (xy 37.11956 -384.051556)
			(xy 37.119147 -384.061681) (xy 37.111406 -384.080391) (xy 37.097087 -384.094708) (xy 37.078377 -384.102448)
			(xy 37.068252 -384.102864) (xy 36.351972 -384.102864) (xy 36.341843 -384.102506) (xy 36.323132 -384.094742)
			(xy 36.308817 -384.080407) (xy 36.30108 -384.061685) (xy 36.300664 -384.051556) (xy 36.300664 -383.894076)
			(xy 36.300251 -383.884889) (xy 36.293738 -383.867706) (xy 36.287964 -383.860548) (xy 36.266117 -383.834869)
			(xy 36.22803 -383.779236) (xy 36.196881 -383.719441) (xy 36.173117 -383.656346) (xy 36.157082 -383.590859)
			(xy 36.149005 -383.523923) (xy 36.149004 -383.456501) (xy 36.157078 -383.389565) (xy 36.17311 -383.324077)
			(xy 36.196871 -383.260981) (xy 36.228018 -383.201185) (xy 36.266102 -383.14555) (xy 36.287964 -383.119884)
			(xy 36.293758 -383.112737) (xy 36.300272 -383.095548) (xy 36.300664 -383.086356) (xy 36.300664 -382.59385)
			(xy 36.300216 -382.584667) (xy 36.293727 -382.567483) (xy 36.287964 -382.560322) (xy 36.266091 -382.534664)
			(xy 36.228005 -382.479028) (xy 36.196857 -382.41923) (xy 36.173095 -382.356132) (xy 36.157061 -382.290643)
			(xy 36.148987 -382.223704) (xy 32.870916 -382.223704) (xy 32.86288 -382.290466) (xy 32.846909 -382.355848)
			(xy 32.823237 -382.418852) (xy 32.792206 -382.478575) (xy 32.754259 -382.534162) (xy 32.732472 -382.559814)
			(xy 32.726683 -382.566965) (xy 32.720165 -382.584151) (xy 32.719772 -382.593342) (xy 32.719772 -383.086864)
			(xy 32.720206 -383.096049) (xy 32.726704 -383.113233) (xy 32.732472 -383.120392) (xy 32.754275 -383.146031)
			(xy 32.792223 -383.20162) (xy 32.823255 -383.261345) (xy 32.846714 -383.323786) (xy 33.948808 -383.323786)
			(xy 33.948811 -383.25636) (xy 33.956891 -383.189419) (xy 33.972931 -383.123927) (xy 33.996699 -383.060829)
			(xy 34.027855 -383.001032) (xy 34.065949 -382.945397) (xy 34.087816 -382.919732) (xy 34.093626 -382.912596)
			(xy 34.100132 -382.895398) (xy 34.100516 -382.886204) (xy 34.100516 -382.728724) (xy 34.100936 -382.718601)
			(xy 34.108679 -382.699895) (xy 34.122995 -382.685579) (xy 34.141701 -382.677836) (xy 34.151824 -382.677416)
			(xy 34.868104 -382.677416) (xy 34.878229 -382.677813) (xy 34.896935 -382.685566) (xy 34.91125 -382.699888)
			(xy 34.918992 -382.718599) (xy 34.919412 -382.728724) (xy 34.919412 -382.886204) (xy 34.919818 -382.895392)
			(xy 34.926334 -382.912576) (xy 34.932112 -382.919732) (xy 34.95394 -382.945427) (xy 34.992029 -383.001057)
			(xy 35.023181 -383.060849) (xy 35.046946 -383.123942) (xy 35.062984 -383.189428) (xy 35.071063 -383.256363)
			(xy 35.071066 -383.323783) (xy 35.062994 -383.390719) (xy 35.046962 -383.456206) (xy 35.023203 -383.519301)
			(xy 34.992057 -383.579096) (xy 34.953973 -383.634731) (xy 34.932112 -383.660396) (xy 34.926336 -383.667556)
			(xy 34.919809 -383.684735) (xy 34.919412 -383.693924) (xy 34.919412 -384.186176) (xy 34.919831 -384.195362)
			(xy 34.926338 -384.212547) (xy 34.932112 -384.219704) (xy 34.954011 -384.24534) (xy 34.992098 -384.300979)
			(xy 35.023246 -384.36078) (xy 35.047008 -384.42388) (xy 35.06304 -384.489373) (xy 35.071113 -384.556314)
			(xy 35.07111 -384.62374) (xy 35.063031 -384.690681) (xy 35.046992 -384.756172) (xy 35.023224 -384.81927)
			(xy 34.99207 -384.879067) (xy 34.953978 -384.934703) (xy 34.932112 -384.960368) (xy 34.926305 -384.967506)
			(xy 34.919796 -384.984702) (xy 34.919412 -384.993896) (xy 34.919412 -385.151376) (xy 34.918965 -385.161495)
			(xy 34.911227 -385.180196) (xy 34.89692 -385.194511) (xy 34.878223 -385.202259) (xy 34.868104 -385.202684)
			(xy 34.151824 -385.202684) (xy 34.141701 -385.202264) (xy 34.122995 -385.194521) (xy 34.108679 -385.180205)
			(xy 34.100936 -385.161499) (xy 34.100516 -385.151376) (xy 34.100516 -384.993896) (xy 34.100104 -384.984709)
			(xy 34.093591 -384.967525) (xy 34.087816 -384.960368) (xy 34.065987 -384.934674) (xy 34.027896 -384.879044)
			(xy 33.996743 -384.819252) (xy 33.972976 -384.756159) (xy 33.956937 -384.690673) (xy 33.948858 -384.623738)
			(xy 33.948855 -384.556316) (xy 33.956928 -384.48938) (xy 33.97296 -384.423893) (xy 33.996721 -384.360798)
			(xy 34.027868 -384.301003) (xy 34.065954 -384.245369) (xy 34.087816 -384.219704) (xy 34.093595 -384.212547)
			(xy 34.10012 -384.195365) (xy 34.100516 -384.186176) (xy 34.100516 -383.693924) (xy 34.100091 -383.684739)
			(xy 34.093587 -383.667554) (xy 34.087816 -383.660396) (xy 34.065916 -383.63476) (xy 34.027827 -383.579122)
			(xy 33.996677 -383.519322) (xy 33.972915 -383.456221) (xy 33.956881 -383.390728) (xy 33.948808 -383.323786)
			(xy 32.846714 -383.323786) (xy 32.846926 -383.324351) (xy 32.862898 -383.389735) (xy 32.87094 -383.456559)
			(xy 32.870939 -383.523865) (xy 32.862893 -383.590689) (xy 32.846919 -383.656072) (xy 32.823245 -383.719077)
			(xy 32.79221 -383.778801) (xy 32.75426 -383.834388) (xy 32.732472 -383.86004) (xy 32.726672 -383.867183)
			(xy 32.72016 -383.884375) (xy 32.719772 -383.893568) (xy 32.719772 -384.051556) (xy 32.719342 -384.061711)
			(xy 32.711555 -384.080468) (xy 32.697161 -384.094793) (xy 32.678367 -384.10249) (xy 32.66821 -384.102864)
			(xy 31.95193 -384.102864) (xy 31.941806 -384.102349) (xy 31.923086 -384.094632) (xy 31.908729 -384.080354)
			(xy 31.900908 -384.061678) (xy 31.900368 -384.051556) (xy 31.900368 -383.893568) (xy 31.899958 -383.884381)
			(xy 31.893443 -383.867197) (xy 31.887668 -383.86004) (xy 31.865895 -383.834375) (xy 31.827944 -383.778791)
			(xy 31.796908 -383.71907) (xy 31.773234 -383.656067) (xy 31.757259 -383.590686) (xy 31.749213 -383.523864)
			(xy 31.749211 -383.45656) (xy 31.757254 -383.389738) (xy 31.773226 -383.324356) (xy 31.796899 -383.261352)
			(xy 31.827932 -383.201629) (xy 31.86588 -383.146044) (xy 31.887668 -383.120392) (xy 31.893459 -383.113243)
			(xy 31.899975 -383.096055) (xy 31.900368 -383.086864) (xy 31.900368 -382.593342) (xy 31.899923 -382.584159)
			(xy 31.893432 -382.566975) (xy 31.887668 -382.559814) (xy 31.86587 -382.53417) (xy 31.827919 -382.478583)
			(xy 31.796885 -382.418859) (xy 31.773211 -382.355853) (xy 31.757238 -382.29047) (xy 31.749194 -382.223646)
			(xy 28.471155 -382.223646) (xy 28.471155 -382.223704) (xy 28.463079 -382.290642) (xy 28.447044 -382.356131)
			(xy 28.42328 -382.419228) (xy 28.392129 -382.479023) (xy 28.35404 -382.534657) (xy 28.332176 -382.560322)
			(xy 28.326385 -382.567471) (xy 28.319868 -382.584659) (xy 28.319476 -382.59385) (xy 28.319476 -383.086356)
			(xy 28.319913 -383.09554) (xy 28.326409 -383.112725) (xy 28.332176 -383.119884) (xy 28.354057 -383.145536)
			(xy 28.392146 -383.201172) (xy 28.423298 -383.26097) (xy 28.446934 -383.323727) (xy 29.549039 -383.323727)
			(xy 29.549043 -383.256419) (xy 29.55709 -383.189594) (xy 29.573066 -383.12421) (xy 29.596742 -383.061205)
			(xy 29.627779 -383.00148) (xy 29.665731 -382.945892) (xy 29.68752 -382.92024) (xy 29.693327 -382.913102)
			(xy 29.699835 -382.895906) (xy 29.70022 -382.886712) (xy 29.70022 -382.728724) (xy 29.700636 -382.718601)
			(xy 29.70838 -382.699894) (xy 29.722697 -382.685578) (xy 29.741405 -382.677835) (xy 29.751528 -382.677416)
			(xy 30.468062 -382.677416) (xy 30.478183 -382.677957) (xy 30.496899 -382.685668) (xy 30.511256 -382.699938)
			(xy 30.51908 -382.718606) (xy 30.519624 -382.728724) (xy 30.519624 -382.886712) (xy 30.520023 -382.8959)
			(xy 30.526544 -382.913085) (xy 30.532324 -382.92024) (xy 30.554077 -382.945921) (xy 30.59203 -383.001502)
			(xy 30.623067 -383.061222) (xy 30.646743 -383.124222) (xy 30.66272 -383.189601) (xy 30.670767 -383.256421)
			(xy 30.67077 -383.323724) (xy 30.662729 -383.390545) (xy 30.646759 -383.455926) (xy 30.623089 -383.518929)
			(xy 30.592058 -383.578651) (xy 30.554111 -383.634236) (xy 30.532324 -383.659888) (xy 30.52651 -383.667021)
			(xy 30.520005 -383.684221) (xy 30.519624 -383.693416) (xy 30.519624 -384.186684) (xy 30.520036 -384.195871)
			(xy 30.526548 -384.213056) (xy 30.532324 -384.220212) (xy 30.554149 -384.245834) (xy 30.592099 -384.301424)
			(xy 30.623132 -384.361152) (xy 30.646805 -384.42416) (xy 30.662776 -384.489546) (xy 30.670818 -384.556373)
			(xy 30.670815 -384.623681) (xy 30.662767 -384.690507) (xy 30.646789 -384.755892) (xy 30.62311 -384.818898)
			(xy 30.592071 -384.878622) (xy 30.554115 -384.934209) (xy 30.532324 -384.95986) (xy 30.526522 -384.967002)
			(xy 30.52001 -384.984195) (xy 30.519624 -384.993388) (xy 30.519624 -385.151376) (xy 30.519165 -385.161494)
			(xy 30.511429 -385.180193) (xy 30.497126 -385.194507) (xy 30.478434 -385.202257) (xy 30.468316 -385.202684)
			(xy 29.751782 -385.202684) (xy 29.741657 -385.202189) (xy 29.72294 -385.19446) (xy 29.708585 -385.180177)
			(xy 29.700762 -385.161498) (xy 29.70022 -385.151376) (xy 29.70022 -384.993388) (xy 29.699811 -384.984201)
			(xy 29.693296 -384.967017) (xy 29.68752 -384.95986) (xy 29.665769 -384.934178) (xy 29.62782 -384.878596)
			(xy 29.596786 -384.818876) (xy 29.573112 -384.755875) (xy 29.557137 -384.690497) (xy 29.549091 -384.623678)
			(xy 29.549087 -384.556376) (xy 29.557128 -384.489556) (xy 29.573096 -384.424176) (xy 29.596764 -384.361174)
			(xy 29.627792 -384.301451) (xy 29.665735 -384.245865) (xy 29.68752 -384.220212) (xy 29.693339 -384.213083)
			(xy 29.69984 -384.19588) (xy 29.70022 -384.186684) (xy 29.70022 -383.693416) (xy 29.699797 -383.68423)
			(xy 29.693292 -383.667046) (xy 29.68752 -383.659888) (xy 29.665697 -383.634265) (xy 29.627751 -383.578674)
			(xy 29.59672 -383.518946) (xy 29.57305 -383.455938) (xy 29.55708 -383.390552) (xy 29.549039 -383.323727)
			(xy 28.446934 -383.323727) (xy 28.447062 -383.324068) (xy 28.463097 -383.389559) (xy 28.471172 -383.456499)
			(xy 28.471171 -383.523925) (xy 28.463093 -383.590865) (xy 28.447055 -383.656355) (xy 28.423288 -383.719452)
			(xy 28.392134 -383.779249) (xy 28.354042 -383.834883) (xy 28.332176 -383.860548) (xy 28.326374 -383.867689)
			(xy 28.319863 -383.884883) (xy 28.319476 -383.894076) (xy 28.319476 -384.051556) (xy 28.319047 -384.061679)
			(xy 28.311309 -384.080386) (xy 28.296996 -384.094702) (xy 28.27829 -384.102445) (xy 28.268168 -384.102864)
			(xy 27.551888 -384.102864) (xy 27.54176 -384.102493) (xy 27.523049 -384.094734) (xy 27.508734 -384.080404)
			(xy 27.500996 -384.061684) (xy 27.50058 -384.051556) (xy 27.50058 -383.894076) (xy 27.500186 -383.884887)
			(xy 27.493661 -383.867703) (xy 27.48788 -383.860548) (xy 27.466032 -383.834869) (xy 27.427945 -383.779236)
			(xy 27.396794 -383.719442) (xy 27.37303 -383.656347) (xy 27.356994 -383.59086) (xy 27.348917 -383.523923)
			(xy 27.348916 -383.456501) (xy 27.35699 -383.389564) (xy 27.373023 -383.324076) (xy 27.396784 -383.26098)
			(xy 27.427932 -383.201184) (xy 27.466018 -383.14555) (xy 27.48788 -383.119884) (xy 27.493664 -383.112729)
			(xy 27.500187 -383.095546) (xy 27.50058 -383.086356) (xy 27.50058 -382.59385) (xy 27.50015 -382.584665)
			(xy 27.49365 -382.56748) (xy 27.48788 -382.560322) (xy 27.466007 -382.534665) (xy 27.42792 -382.479028)
			(xy 27.396771 -382.419231) (xy 27.373008 -382.356133) (xy 27.356974 -382.290643) (xy 27.348899 -382.223705)
			(xy 0.508 -382.223705) (xy 0.508 -385.583938) (xy 100.447856 -385.583938) (xy 100.447856 -384.720338)
			(xy 100.448346 -384.690354) (xy 100.456174 -384.630898) (xy 100.471695 -384.572973) (xy 100.494644 -384.517569)
			(xy 100.524628 -384.465635) (xy 100.561134 -384.418059) (xy 100.603539 -384.375654) (xy 100.651115 -384.339148)
			(xy 100.703049 -384.309164) (xy 100.758453 -384.286215) (xy 100.816378 -384.270694) (xy 100.875834 -384.262866)
			(xy 100.935802 -384.262866) (xy 100.995258 -384.270694) (xy 101.053183 -384.286215) (xy 101.108587 -384.309164)
			(xy 101.160521 -384.339148) (xy 101.208097 -384.375654) (xy 101.250502 -384.418059) (xy 101.287008 -384.465635)
			(xy 101.316992 -384.517569) (xy 101.339941 -384.572973) (xy 101.355462 -384.630898) (xy 101.36329 -384.690354)
			(xy 101.36378 -384.720338) (xy 101.36378 -385.319283) (xy 104.635826 -385.319283) (xy 104.635826 -385.259317)
			(xy 104.643653 -385.199864) (xy 104.659172 -385.141942) (xy 104.682119 -385.08654) (xy 104.7121 -385.034608)
			(xy 104.748603 -384.987032) (xy 104.791004 -384.944628) (xy 104.838576 -384.908121) (xy 104.890506 -384.878136)
			(xy 104.945906 -384.855184) (xy 105.003827 -384.83966) (xy 105.063279 -384.831828) (xy 105.093262 -384.831336)
			(xy 105.956862 -384.831336) (xy 105.986849 -384.831807) (xy 106.046311 -384.83963) (xy 106.104243 -384.855149)
			(xy 106.159653 -384.878097) (xy 106.211594 -384.908081) (xy 106.259176 -384.944589) (xy 106.301586 -384.986995)
			(xy 106.338098 -385.034574) (xy 106.368087 -385.086513) (xy 106.391039 -385.141921) (xy 106.406562 -385.199852)
			(xy 106.414391 -385.259313) (xy 106.414391 -385.319287) (xy 106.406562 -385.378748) (xy 106.391039 -385.436679)
			(xy 106.368087 -385.492087) (xy 106.338098 -385.544026) (xy 106.301586 -385.591605) (xy 106.259176 -385.634011)
			(xy 106.211594 -385.670519) (xy 106.159653 -385.700503) (xy 106.104243 -385.723451) (xy 106.046311 -385.73897)
			(xy 105.986849 -385.746793) (xy 105.956862 -385.74726) (xy 105.093262 -385.74726) (xy 105.063279 -385.746772)
			(xy 105.003827 -385.73894) (xy 104.945906 -385.723416) (xy 104.890506 -385.700464) (xy 104.838576 -385.670479)
			(xy 104.791004 -385.633972) (xy 104.748603 -385.591568) (xy 104.7121 -385.543992) (xy 104.682119 -385.49206)
			(xy 104.659172 -385.436658) (xy 104.643653 -385.378736) (xy 104.635826 -385.319283) (xy 101.36378 -385.319283)
			(xy 101.36378 -385.583938) (xy 101.36329 -385.613922) (xy 101.355462 -385.673378) (xy 101.339941 -385.731303)
			(xy 101.316992 -385.786707) (xy 101.287008 -385.838641) (xy 101.250502 -385.886217) (xy 101.208097 -385.928622)
			(xy 101.160521 -385.965128) (xy 101.108587 -385.995112) (xy 101.053183 -386.018061) (xy 100.995258 -386.033582)
			(xy 100.935802 -386.04141) (xy 100.875834 -386.04141) (xy 100.816378 -386.033582) (xy 100.758453 -386.018061)
			(xy 100.703049 -385.995112) (xy 100.651115 -385.965128) (xy 100.603539 -385.928622) (xy 100.561134 -385.886217)
			(xy 100.524628 -385.838641) (xy 100.494644 -385.786707) (xy 100.471695 -385.731303) (xy 100.456174 -385.673378)
			(xy 100.448346 -385.613922) (xy 100.447856 -385.583938) (xy 0.508 -385.583938) (xy 0.508 -388.37489)
			(xy 1.56972 -388.37489) (xy 1.56972 -387.51129) (xy 1.57021 -387.481322) (xy 1.578033 -387.4219)
			(xy 1.593546 -387.364007) (xy 1.616482 -387.308634) (xy 1.646449 -387.256728) (xy 1.682936 -387.209178)
			(xy 1.725316 -387.166798) (xy 1.772866 -387.130311) (xy 1.824772 -387.100344) (xy 1.880145 -387.077408)
			(xy 1.938038 -387.061895) (xy 1.99746 -387.054072) (xy 2.057396 -387.054072) (xy 2.116818 -387.061895)
			(xy 2.174711 -387.077408) (xy 2.230084 -387.100344) (xy 2.28199 -387.130311) (xy 2.32954 -387.166798)
			(xy 2.37192 -387.209178) (xy 2.408407 -387.256728) (xy 2.438374 -387.308634) (xy 2.46131 -387.364007)
			(xy 2.476823 -387.4219) (xy 2.484646 -387.481322) (xy 2.485136 -387.51129) (xy 2.485136 -388.37489)
			(xy 2.484646 -388.404858) (xy 2.476823 -388.46428) (xy 2.46131 -388.522173) (xy 2.438374 -388.577546)
			(xy 2.408407 -388.629452) (xy 2.37192 -388.677002) (xy 2.32954 -388.719382) (xy 2.28199 -388.755869)
			(xy 2.230084 -388.785836) (xy 2.174711 -388.808772) (xy 2.116818 -388.824285) (xy 2.057396 -388.832108)
			(xy 1.99746 -388.832108) (xy 1.938038 -388.824285) (xy 1.880145 -388.808772) (xy 1.824772 -388.785836)
			(xy 1.772866 -388.755869) (xy 1.725316 -388.719382) (xy 1.682936 -388.677002) (xy 1.646449 -388.629452)
			(xy 1.616482 -388.577546) (xy 1.593546 -388.522173) (xy 1.578033 -388.46428) (xy 1.57021 -388.404858)
			(xy 1.56972 -388.37489) (xy 0.508 -388.37489) (xy 0.508 -398.164722) (xy 3.141726 -398.164722) (xy 3.141726 -398.035362)
			(xy 3.149849 -397.906256) (xy 3.166062 -397.777916) (xy 3.190302 -397.650846) (xy 3.222472 -397.52555)
			(xy 3.262447 -397.40252) (xy 3.310068 -397.282244) (xy 3.365147 -397.165195) (xy 3.427467 -397.051835)
			(xy 3.496782 -396.942612) (xy 3.572818 -396.837957) (xy 3.655276 -396.738283) (xy 3.743829 -396.643983)
			(xy 3.838129 -396.55543) (xy 3.937803 -396.472972) (xy 4.042458 -396.396936) (xy 4.151681 -396.327621)
			(xy 4.265041 -396.265301) (xy 4.38209 -396.210222) (xy 4.502366 -396.162601) (xy 4.625396 -396.122626)
			(xy 4.750692 -396.090456) (xy 4.877762 -396.066216) (xy 5.006102 -396.050003) (xy 5.135208 -396.04188)
			(xy 5.199888 -396.041372) (xy 6.800088 -396.041372) (xy 6.864769 -396.041866) (xy 6.993875 -396.049988)
			(xy 7.122217 -396.066201) (xy 7.249287 -396.090441) (xy 7.374584 -396.122612) (xy 7.497614 -396.162587)
			(xy 7.617892 -396.210208) (xy 7.734942 -396.265287) (xy 7.848302 -396.327608) (xy 7.957526 -396.396923)
			(xy 8.062181 -396.47296) (xy 8.161856 -396.555418) (xy 8.256157 -396.643972) (xy 8.344711 -396.738272)
			(xy 8.427169 -396.837947) (xy 8.503206 -396.942603) (xy 8.572521 -397.051826) (xy 8.634842 -397.165187)
			(xy 8.689921 -397.282236) (xy 8.737543 -397.402514) (xy 8.777518 -397.525544) (xy 8.809688 -397.650841)
			(xy 8.833928 -397.777911) (xy 8.839736 -397.823885) (xy 27.348879 -397.823885) (xy 27.348883 -397.756458)
			(xy 27.356962 -397.689518) (xy 27.373001 -397.624027) (xy 27.396769 -397.560929) (xy 27.427923 -397.501131)
			(xy 27.466014 -397.445496) (xy 27.48788 -397.41983) (xy 27.493686 -397.412692) (xy 27.500196 -397.395496)
			(xy 27.50058 -397.386302) (xy 27.50058 -396.89405) (xy 27.50015 -396.884865) (xy 27.49365 -396.86768)
			(xy 27.48788 -396.860522) (xy 27.466007 -396.834865) (xy 27.42792 -396.779228) (xy 27.396771 -396.719431)
			(xy 27.373008 -396.656333) (xy 27.356974 -396.590843) (xy 27.348899 -396.523905) (xy 27.3489 -396.45648)
			(xy 27.356976 -396.389542) (xy 27.373012 -396.324053) (xy 27.396777 -396.260955) (xy 27.427928 -396.201159)
			(xy 27.466016 -396.145524) (xy 27.48788 -396.119858) (xy 27.493675 -396.112711) (xy 27.500191 -396.095522)
			(xy 27.50058 -396.08633) (xy 27.50058 -395.92885) (xy 27.501069 -395.918722) (xy 27.508787 -395.899994)
			(xy 27.523074 -395.885635) (xy 27.541762 -395.877821) (xy 27.551888 -395.877288) (xy 28.268168 -395.877288)
			(xy 28.278319 -395.877747) (xy 28.297068 -395.88553) (xy 28.311392 -395.899915) (xy 28.319095 -395.918698)
			(xy 28.319476 -395.92885) (xy 28.319476 -396.08633) (xy 28.319877 -396.095518) (xy 28.326398 -396.112702)
			(xy 28.332176 -396.119858) (xy 28.354031 -396.145531) (xy 28.392122 -396.201164) (xy 28.423274 -396.260959)
			(xy 28.44704 -396.324055) (xy 28.463077 -396.389543) (xy 28.471154 -396.456481) (xy 28.471155 -396.523904)
			(xy 28.463079 -396.590842) (xy 28.447044 -396.656331) (xy 28.42328 -396.719428) (xy 28.392129 -396.779223)
			(xy 28.35404 -396.834857) (xy 28.332176 -396.860522) (xy 28.326385 -396.867671) (xy 28.319868 -396.884859)
			(xy 28.319476 -396.89405) (xy 28.319476 -397.386302) (xy 28.31989 -397.395489) (xy 28.326402 -397.412673)
			(xy 28.332176 -397.41983) (xy 28.354003 -397.445526) (xy 28.392095 -397.501155) (xy 28.420857 -397.556356)
			(xy 29.549071 -397.556356) (xy 29.557114 -397.489534) (xy 29.573085 -397.424153) (xy 29.596756 -397.361149)
			(xy 29.627787 -397.301425) (xy 29.665733 -397.245838) (xy 29.68752 -397.220186) (xy 29.693307 -397.213034)
			(xy 29.699827 -397.195849) (xy 29.70022 -397.186658) (xy 29.70022 -397.028924) (xy 29.700641 -397.018769)
			(xy 29.708433 -397.000013) (xy 29.72283 -396.985688) (xy 29.741625 -396.977991) (xy 29.751782 -396.977616)
			(xy 30.468062 -396.977616) (xy 30.478183 -396.978157) (xy 30.496899 -396.985868) (xy 30.511256 -397.000138)
			(xy 30.51908 -397.018806) (xy 30.519624 -397.028924) (xy 30.519624 -397.186658) (xy 30.520049 -397.195844)
			(xy 30.526552 -397.213029) (xy 30.532324 -397.220186) (xy 30.554123 -397.24583) (xy 30.592074 -397.301416)
			(xy 30.623108 -397.361141) (xy 30.646782 -397.424147) (xy 30.662756 -397.48953) (xy 30.6708 -397.556354)
			(xy 30.670799 -397.623661) (xy 30.662753 -397.690485) (xy 30.646778 -397.755868) (xy 30.623102 -397.818873)
			(xy 30.620528 -397.823826) (xy 31.749174 -397.823826) (xy 31.749178 -397.756517) (xy 31.757226 -397.689691)
			(xy 31.773204 -397.624307) (xy 31.796882 -397.5613) (xy 31.827922 -397.501576) (xy 31.865877 -397.44599)
			(xy 31.887668 -397.420338) (xy 31.893482 -397.413205) (xy 31.899984 -397.396005) (xy 31.900368 -397.38681)
			(xy 31.900368 -396.893542) (xy 31.899923 -396.884359) (xy 31.893432 -396.867175) (xy 31.887668 -396.860014)
			(xy 31.86587 -396.83437) (xy 31.827919 -396.778783) (xy 31.796885 -396.719059) (xy 31.773211 -396.656053)
			(xy 31.757238 -396.59067) (xy 31.749194 -396.523846) (xy 31.749195 -396.456539) (xy 31.757241 -396.389716)
			(xy 31.773216 -396.324332) (xy 31.796891 -396.261327) (xy 31.827927 -396.201604) (xy 31.865879 -396.146018)
			(xy 31.887668 -396.120366) (xy 31.89347 -396.113225) (xy 31.899979 -396.096031) (xy 31.900368 -396.086838)
			(xy 31.900368 -395.92885) (xy 31.900805 -395.918678) (xy 31.90858 -395.899879) (xy 31.922962 -395.885491)
			(xy 31.941758 -395.877709) (xy 31.95193 -395.877288) (xy 32.66821 -395.877288) (xy 32.678388 -395.877657)
			(xy 32.697193 -395.885455) (xy 32.711579 -395.899858) (xy 32.719355 -395.918671) (xy 32.719772 -395.92885)
			(xy 32.719772 -396.086838) (xy 32.72017 -396.096026) (xy 32.726693 -396.11321) (xy 32.732472 -396.120366)
			(xy 32.75425 -396.146026) (xy 32.792198 -396.201612) (xy 32.823231 -396.261334) (xy 32.846904 -396.324338)
			(xy 32.862877 -396.389719) (xy 32.870922 -396.45654) (xy 32.870923 -396.523845) (xy 32.86288 -396.590666)
			(xy 32.846909 -396.656048) (xy 32.823237 -396.719052) (xy 32.792206 -396.778775) (xy 32.754259 -396.834362)
			(xy 32.732472 -396.860014) (xy 32.726683 -396.867165) (xy 32.720165 -396.884351) (xy 32.719772 -396.893542)
			(xy 32.719772 -397.38681) (xy 32.720183 -397.395997) (xy 32.726697 -397.413181) (xy 32.732472 -397.420338)
			(xy 32.754222 -397.446021) (xy 32.792171 -397.501603) (xy 32.820593 -397.556296) (xy 33.948839 -397.556296)
			(xy 33.956914 -397.489358) (xy 33.972949 -397.423869) (xy 33.996713 -397.360773) (xy 34.027863 -397.300977)
			(xy 34.065952 -397.245343) (xy 34.087816 -397.219678) (xy 34.093606 -397.212528) (xy 34.100124 -397.195341)
			(xy 34.100516 -397.18615) (xy 34.100516 -397.028924) (xy 34.100936 -397.018801) (xy 34.108679 -397.000095)
			(xy 34.122995 -396.985779) (xy 34.141701 -396.978036) (xy 34.151824 -396.977616) (xy 34.868104 -396.977616)
			(xy 34.878229 -396.978013) (xy 34.896935 -396.985766) (xy 34.91125 -397.000088) (xy 34.918992 -397.018799)
			(xy 34.919412 -397.028924) (xy 34.919412 -397.18615) (xy 34.919843 -397.195335) (xy 34.926342 -397.21252)
			(xy 34.932112 -397.219678) (xy 34.953985 -397.245335) (xy 34.992073 -397.300971) (xy 35.023223 -397.360769)
			(xy 35.046986 -397.423867) (xy 35.06302 -397.489356) (xy 35.071095 -397.556295) (xy 35.071094 -397.62372)
			(xy 35.063017 -397.690658) (xy 35.046981 -397.756148) (xy 35.023216 -397.819245) (xy 35.020799 -397.823884)
			(xy 36.148967 -397.823884) (xy 36.148971 -397.756458) (xy 36.15705 -397.689518) (xy 36.173088 -397.624028)
			(xy 36.196855 -397.560929) (xy 36.228008 -397.501132) (xy 36.266099 -397.445496) (xy 36.287964 -397.41983)
			(xy 36.293781 -397.412699) (xy 36.300282 -397.395497) (xy 36.300664 -397.386302) (xy 36.300664 -396.89405)
			(xy 36.300216 -396.884867) (xy 36.293727 -396.867683) (xy 36.287964 -396.860522) (xy 36.266091 -396.834864)
			(xy 36.228005 -396.779228) (xy 36.196857 -396.71943) (xy 36.173095 -396.656332) (xy 36.157061 -396.590843)
			(xy 36.148987 -396.523904) (xy 36.148988 -396.456481) (xy 36.157064 -396.389542) (xy 36.1731 -396.324053)
			(xy 36.196863 -396.260956) (xy 36.228013 -396.201159) (xy 36.266101 -396.145524) (xy 36.287964 -396.119858)
			(xy 36.293769 -396.112719) (xy 36.300277 -396.095523) (xy 36.300664 -396.08633) (xy 36.300664 -395.92885)
			(xy 36.301168 -395.918724) (xy 36.308884 -395.899999) (xy 36.323166 -395.88564) (xy 36.341848 -395.877823)
			(xy 36.351972 -395.877288) (xy 37.068252 -395.877288) (xy 37.078402 -395.877761) (xy 37.097151 -395.885538)
			(xy 37.111475 -395.899919) (xy 37.119179 -395.918699) (xy 37.11956 -395.92885) (xy 37.11956 -396.08633)
			(xy 37.119965 -396.095518) (xy 37.126483 -396.112701) (xy 37.13226 -396.119858) (xy 37.154116 -396.145531)
			(xy 37.192207 -396.201163) (xy 37.223361 -396.260958) (xy 37.247127 -396.324054) (xy 37.263164 -396.389543)
			(xy 37.271242 -396.456481) (xy 37.271243 -396.523904) (xy 37.263167 -396.590843) (xy 37.247132 -396.656332)
			(xy 37.223367 -396.719428) (xy 37.192215 -396.779224) (xy 37.154125 -396.834857) (xy 37.13226 -396.860522)
			(xy 37.126467 -396.867669) (xy 37.119951 -396.884858) (xy 37.11956 -396.89405) (xy 37.11956 -397.386302)
			(xy 37.119978 -397.395488) (xy 37.126487 -397.412672) (xy 37.13226 -397.41983) (xy 37.154088 -397.445525)
			(xy 37.192181 -397.501155) (xy 37.220943 -397.556356) (xy 38.349159 -397.556356) (xy 38.357201 -397.489534)
			(xy 38.373172 -397.424153) (xy 38.396842 -397.361149) (xy 38.427873 -397.301426) (xy 38.465818 -397.245839)
			(xy 38.487604 -397.220186) (xy 38.493389 -397.213033) (xy 38.499911 -397.195848) (xy 38.500304 -397.186658)
			(xy 38.500304 -397.028924) (xy 38.500741 -397.018771) (xy 38.50853 -397.000018) (xy 38.522922 -396.985694)
			(xy 38.541711 -396.977994) (xy 38.551866 -396.977616) (xy 39.268146 -396.977616) (xy 39.278273 -396.978088)
			(xy 39.29699 -396.985827) (xy 39.311344 -397.000117) (xy 39.319166 -397.0188) (xy 39.319708 -397.028924)
			(xy 39.319708 -397.186658) (xy 39.320136 -397.195843) (xy 39.326637 -397.213028) (xy 39.332408 -397.220186)
			(xy 39.354207 -397.245829) (xy 39.392159 -397.301416) (xy 39.423195 -397.36114) (xy 39.446869 -397.424146)
			(xy 39.462843 -397.48953) (xy 39.470887 -397.556354) (xy 39.470887 -397.623661) (xy 39.462841 -397.690485)
			(xy 39.446865 -397.755869) (xy 39.423189 -397.818874) (xy 39.420585 -397.823885) (xy 40.548734 -397.823885)
			(xy 40.548737 -397.756458) (xy 40.556817 -397.689516) (xy 40.572859 -397.624024) (xy 40.596629 -397.560925)
			(xy 40.627787 -397.501128) (xy 40.665884 -397.445494) (xy 40.687752 -397.41983) (xy 40.693567 -397.412698)
			(xy 40.700069 -397.395497) (xy 40.700452 -397.386302) (xy 40.700452 -396.89405) (xy 40.700006 -396.884867)
			(xy 40.693516 -396.867683) (xy 40.687752 -396.860522) (xy 40.665876 -396.834866) (xy 40.627785 -396.779231)
			(xy 40.596631 -396.719434) (xy 40.572865 -396.656336) (xy 40.556829 -396.590845) (xy 40.548753 -396.523905)
			(xy 40.548754 -396.45648) (xy 40.556832 -396.38954) (xy 40.57287 -396.32405) (xy 40.596638 -396.260952)
			(xy 40.627792 -396.201156) (xy 40.665886 -396.145522) (xy 40.687752 -396.119858) (xy 40.693555 -396.112718)
			(xy 40.700065 -396.095523) (xy 40.700452 -396.08633) (xy 40.700452 -395.92885) (xy 40.700968 -395.918725)
			(xy 40.708682 -395.900003) (xy 40.722959 -395.885644) (xy 40.741638 -395.877825) (xy 40.75176 -395.877288)
			(xy 41.46804 -395.877288) (xy 41.478195 -395.877689) (xy 41.496946 -395.885495) (xy 41.511268 -395.899898)
			(xy 41.518968 -395.918693) (xy 41.519348 -395.92885) (xy 41.519348 -396.08633) (xy 41.519755 -396.095517)
			(xy 41.526272 -396.112701) (xy 41.532048 -396.119858) (xy 41.553904 -396.14553) (xy 41.591996 -396.201163)
			(xy 41.62315 -396.260957) (xy 41.646917 -396.324053) (xy 41.662955 -396.389542) (xy 41.671033 -396.456481)
			(xy 41.671034 -396.523904) (xy 41.662958 -396.590843) (xy 41.646922 -396.656332) (xy 41.623157 -396.719429)
			(xy 41.592004 -396.779224) (xy 41.553913 -396.834858) (xy 41.532048 -396.860522) (xy 41.526253 -396.867668)
			(xy 41.519739 -396.884858) (xy 41.519348 -396.89405) (xy 41.519348 -397.386302) (xy 41.519769 -397.395488)
			(xy 41.526276 -397.412672) (xy 41.532048 -397.41983) (xy 41.553876 -397.445525) (xy 41.59197 -397.501154)
			(xy 41.620702 -397.556296) (xy 42.748927 -397.556296) (xy 42.757002 -397.489358) (xy 42.773037 -397.42387)
			(xy 42.7968 -397.360774) (xy 42.827949 -397.300978) (xy 42.866037 -397.245343) (xy 42.8879 -397.219678)
			(xy 42.893688 -397.212527) (xy 42.900208 -397.195341) (xy 42.9006 -397.18615) (xy 42.9006 -397.028924)
			(xy 42.901035 -397.018803) (xy 42.908776 -397.0001) (xy 42.923086 -396.985785) (xy 42.941787 -396.978039)
			(xy 42.951908 -396.977616) (xy 43.668188 -396.977616) (xy 43.678312 -396.978026) (xy 43.697018 -396.985773)
			(xy 43.711333 -397.000092) (xy 43.719076 -397.0188) (xy 43.719496 -397.028924) (xy 43.719496 -397.18615)
			(xy 43.719931 -397.195335) (xy 43.726427 -397.212519) (xy 43.732196 -397.219678) (xy 43.75407 -397.245335)
			(xy 43.792159 -397.300971) (xy 43.823309 -397.360768) (xy 43.847073 -397.423866) (xy 43.863108 -397.489356)
			(xy 43.871183 -397.556295) (xy 43.871182 -397.62372) (xy 43.863105 -397.690659) (xy 43.847068 -397.756148)
			(xy 43.823303 -397.819246) (xy 43.820917 -397.823825) (xy 44.949053 -397.823825) (xy 44.949057 -397.756517)
			(xy 44.957105 -397.689692) (xy 44.973082 -397.624308) (xy 44.996759 -397.561302) (xy 45.027796 -397.501577)
			(xy 45.06575 -397.44599) (xy 45.08754 -397.420338) (xy 45.09335 -397.413203) (xy 45.099856 -397.396004)
			(xy 45.10024 -397.38681) (xy 45.10024 -396.893542) (xy 45.0998 -396.884358) (xy 45.093306 -396.867174)
			(xy 45.08754 -396.860014) (xy 45.065742 -396.83437) (xy 45.027794 -396.778782) (xy 44.996761 -396.719058)
			(xy 44.973088 -396.656052) (xy 44.957116 -396.590669) (xy 44.949073 -396.523845) (xy 44.949074 -396.45654)
			(xy 44.957119 -396.389716) (xy 44.973093 -396.324333) (xy 44.996767 -396.261328) (xy 45.027801 -396.201605)
			(xy 45.065751 -396.146018) (xy 45.08754 -396.120366) (xy 45.093339 -396.113222) (xy 45.099851 -396.096031)
			(xy 45.10024 -396.086838) (xy 45.10024 -395.92885) (xy 45.100705 -395.918681) (xy 45.108474 -395.899887)
			(xy 45.122847 -395.885501) (xy 45.141634 -395.877714) (xy 45.151802 -395.877288) (xy 45.868082 -395.877288)
			(xy 45.878259 -395.87768) (xy 45.897063 -395.885468) (xy 45.91145 -395.899864) (xy 45.919227 -395.918673)
			(xy 45.919644 -395.92885) (xy 45.919644 -396.086838) (xy 45.920049 -396.096026) (xy 45.926568 -396.113209)
			(xy 45.932344 -396.120366) (xy 45.954122 -396.146026) (xy 45.992072 -396.201611) (xy 46.023107 -396.261333)
			(xy 46.046781 -396.324337) (xy 46.062755 -396.389718) (xy 46.070801 -396.45654) (xy 46.070801 -396.523845)
			(xy 46.062758 -396.590667) (xy 46.046786 -396.656049) (xy 46.023113 -396.719053) (xy 45.99208 -396.778776)
			(xy 45.954131 -396.834362) (xy 45.932344 -396.860014) (xy 45.926552 -396.867162) (xy 45.920036 -396.884351)
			(xy 45.919644 -396.893542) (xy 45.919644 -397.38681) (xy 45.920062 -397.395996) (xy 45.926572 -397.41318)
			(xy 45.932344 -397.420338) (xy 45.954095 -397.446021) (xy 45.992046 -397.501602) (xy 46.020501 -397.556355)
			(xy 47.149223 -397.556355) (xy 47.157267 -397.489532) (xy 47.17324 -397.42415) (xy 47.196914 -397.361146)
			(xy 47.227949 -397.301423) (xy 47.265899 -397.245837) (xy 47.287688 -397.220186) (xy 47.293472 -397.213032)
			(xy 47.299994 -397.195848) (xy 47.300388 -397.186658) (xy 47.300388 -397.028924) (xy 47.300841 -397.018773)
			(xy 47.308626 -397.000023) (xy 47.323013 -396.985699) (xy 47.341797 -396.977997) (xy 47.35195 -396.977616)
			(xy 48.06823 -396.977616) (xy 48.078356 -396.978101) (xy 48.097073 -396.985834) (xy 48.111427 -397.000121)
			(xy 48.11925 -397.018801) (xy 48.119792 -397.028924) (xy 48.119792 -397.186658) (xy 48.120224 -397.195843)
			(xy 48.126723 -397.213027) (xy 48.132492 -397.220186) (xy 48.154289 -397.24583) (xy 48.192235 -397.301419)
			(xy 48.223266 -397.361144) (xy 48.246937 -397.424149) (xy 48.262908 -397.489532) (xy 48.270951 -397.556355)
			(xy 48.27095 -397.62366) (xy 48.262906 -397.690483) (xy 48.246933 -397.755865) (xy 48.22326 -397.81887)
			(xy 48.192227 -397.878594) (xy 48.154279 -397.934181) (xy 48.132492 -397.959834) (xy 48.126698 -397.966981)
			(xy 48.120182 -397.98417) (xy 48.119792 -397.993362) (xy 48.119792 -398.486884) (xy 48.120212 -398.49607)
			(xy 48.126719 -398.513254) (xy 48.132492 -398.520412) (xy 48.154314 -398.546035) (xy 48.19226 -398.601627)
			(xy 48.22329 -398.661355) (xy 48.246959 -398.724363) (xy 48.262929 -398.789748) (xy 48.27097 -398.856573)
			(xy 48.270966 -398.923881) (xy 48.262919 -398.990705) (xy 48.246943 -399.056089) (xy 48.223268 -399.119095)
			(xy 48.192232 -399.17882) (xy 48.154281 -399.234407) (xy 48.132492 -399.26006) (xy 48.126687 -399.267199)
			(xy 48.120177 -399.284394) (xy 48.119792 -399.293588) (xy 48.119792 -399.451576) (xy 48.119359 -399.46173)
			(xy 48.11157 -399.480483) (xy 48.097176 -399.494808) (xy 48.078386 -399.502507) (xy 48.06823 -399.502884)
			(xy 47.35195 -399.502884) (xy 47.341829 -399.502333) (xy 47.323114 -399.494626) (xy 47.308757 -399.48036)
			(xy 47.300932 -399.461693) (xy 47.300388 -399.451576) (xy 47.300388 -399.293588) (xy 47.299986 -399.2844)
			(xy 47.293467 -399.267216) (xy 47.287688 -399.26006) (xy 47.265934 -399.234379) (xy 47.227981 -399.178798)
			(xy 47.196944 -399.119079) (xy 47.173267 -399.056078) (xy 47.15729 -398.990699) (xy 47.149242 -398.923879)
			(xy 47.149239 -398.856576) (xy 47.15728 -398.789754) (xy 47.173251 -398.724374) (xy 47.196921 -398.661371)
			(xy 47.227953 -398.601648) (xy 47.265901 -398.546063) (xy 47.287688 -398.520412) (xy 47.293503 -398.51328)
			(xy 47.300007 -398.496079) (xy 47.300388 -398.486884) (xy 47.300388 -397.993362) (xy 47.299999 -397.984172)
			(xy 47.293471 -397.966988) (xy 47.287688 -397.959834) (xy 47.265909 -397.934174) (xy 47.227956 -397.87859)
			(xy 47.19692 -397.818868) (xy 47.173244 -397.755864) (xy 47.157269 -397.690483) (xy 47.149224 -397.62366)
			(xy 47.149223 -397.556355) (xy 46.020501 -397.556355) (xy 46.023082 -397.561322) (xy 46.046757 -397.624322)
			(xy 46.062733 -397.689701) (xy 46.070781 -397.75652) (xy 46.070784 -397.823823) (xy 46.062744 -397.890643)
			(xy 46.046774 -397.956023) (xy 46.023105 -398.019026) (xy 45.992075 -398.078748) (xy 45.95413 -398.134334)
			(xy 45.932344 -398.159986) (xy 45.926522 -398.167113) (xy 45.920024 -398.184318) (xy 45.919644 -398.193514)
			(xy 45.919644 -398.351502) (xy 45.919237 -398.361676) (xy 45.911448 -398.380474) (xy 45.897057 -398.39486)
			(xy 45.878256 -398.402641) (xy 45.868082 -398.403064) (xy 45.151802 -398.403064) (xy 45.141645 -398.402565)
			(xy 45.122876 -398.394792) (xy 45.108511 -398.380427) (xy 45.100736 -398.361659) (xy 45.10024 -398.351502)
			(xy 45.10024 -398.193514) (xy 45.099814 -398.184329) (xy 45.093311 -398.167145) (xy 45.08754 -398.159986)
			(xy 45.065715 -398.134365) (xy 45.027767 -398.078774) (xy 44.996735 -398.019046) (xy 44.973065 -397.956037)
			(xy 44.957094 -397.890651) (xy 44.949053 -397.823825) (xy 43.820917 -397.823825) (xy 43.792151 -397.879042)
			(xy 43.754061 -397.934677) (xy 43.732196 -397.960342) (xy 43.726399 -397.967487) (xy 43.719885 -397.984678)
			(xy 43.719496 -397.99387) (xy 43.719496 -398.486376) (xy 43.719919 -398.495562) (xy 43.726424 -398.512746)
			(xy 43.732196 -398.519904) (xy 43.754095 -398.54554) (xy 43.792183 -398.601179) (xy 43.823333 -398.660979)
			(xy 43.847095 -398.72408) (xy 43.863128 -398.789572) (xy 43.871201 -398.856514) (xy 43.871198 -398.92394)
			(xy 43.863118 -398.990881) (xy 43.847079 -399.056372) (xy 43.823311 -399.119471) (xy 43.792156 -399.179268)
			(xy 43.754062 -399.234903) (xy 43.732196 -399.260568) (xy 43.726388 -399.267705) (xy 43.71988 -399.284902)
			(xy 43.719496 -399.294096) (xy 43.719496 -399.451576) (xy 43.719064 -399.461697) (xy 43.711323 -399.480401)
			(xy 43.697011 -399.494717) (xy 43.678309 -399.502462) (xy 43.668188 -399.502884) (xy 42.951908 -399.502884)
			(xy 42.941784 -399.502477) (xy 42.923078 -399.494729) (xy 42.908762 -399.480409) (xy 42.90102 -399.4617)
			(xy 42.9006 -399.451576) (xy 42.9006 -399.294096) (xy 42.900192 -399.284909) (xy 42.893677 -399.267724)
			(xy 42.8879 -399.260568) (xy 42.866071 -399.234874) (xy 42.827982 -399.179243) (xy 42.796829 -399.119451)
			(xy 42.773063 -399.056358) (xy 42.757025 -398.990872) (xy 42.748946 -398.923937) (xy 42.748943 -398.856517)
			(xy 42.757015 -398.789581) (xy 42.773047 -398.724094) (xy 42.796807 -398.660998) (xy 42.827954 -398.601203)
			(xy 42.866038 -398.545569) (xy 42.8879 -398.519904) (xy 42.893677 -398.512745) (xy 42.900204 -398.495565)
			(xy 42.9006 -398.486376) (xy 42.9006 -397.99387) (xy 42.900204 -397.984681) (xy 42.893681 -397.967497)
			(xy 42.8879 -397.960342) (xy 42.866046 -397.934669) (xy 42.827957 -397.879035) (xy 42.796806 -397.81924)
			(xy 42.773041 -397.756144) (xy 42.757005 -397.690656) (xy 42.748928 -397.623719) (xy 42.748927 -397.556296)
			(xy 41.620702 -397.556296) (xy 41.623125 -397.560946) (xy 41.646894 -397.624039) (xy 41.662933 -397.689525)
			(xy 41.671013 -397.756461) (xy 41.671016 -397.823882) (xy 41.662944 -397.890819) (xy 41.646911 -397.956307)
			(xy 41.623148 -398.019402) (xy 41.591999 -398.079197) (xy 41.553912 -398.13483) (xy 41.532048 -398.160494)
			(xy 41.526265 -398.167649) (xy 41.519744 -398.184832) (xy 41.519348 -398.194022) (xy 41.519348 -398.351502)
			(xy 41.518875 -398.36163) (xy 41.511144 -398.380354) (xy 41.496853 -398.39471) (xy 41.478166 -398.402527)
			(xy 41.46804 -398.403064) (xy 40.75176 -398.403064) (xy 40.741599 -398.40271) (xy 40.722839 -398.394895)
			(xy 40.708515 -398.380477) (xy 40.700824 -398.361666) (xy 40.700452 -398.351502) (xy 40.700452 -398.194022)
			(xy 40.70002 -398.184837) (xy 40.69352 -398.167653) (xy 40.687752 -398.160494) (xy 40.665849 -398.13486)
			(xy 40.627758 -398.079223) (xy 40.596606 -398.019423) (xy 40.572842 -397.956321) (xy 40.556807 -397.890828)
			(xy 40.548734 -397.823885) (xy 39.420585 -397.823885) (xy 39.392151 -397.878597) (xy 39.354198 -397.934183)
			(xy 39.332408 -397.959834) (xy 39.326615 -397.966982) (xy 39.320098 -397.98417) (xy 39.319708 -397.993362)
			(xy 39.319708 -398.486884) (xy 39.320124 -398.496071) (xy 39.326633 -398.513255) (xy 39.332408 -398.520412)
			(xy 39.354233 -398.546034) (xy 39.392184 -398.601624) (xy 39.423219 -398.661351) (xy 39.446892 -398.72436)
			(xy 39.462864 -398.789746) (xy 39.470906 -398.856573) (xy 39.470902 -398.923882) (xy 39.462854 -398.990707)
			(xy 39.446876 -399.056092) (xy 39.423196 -399.119098) (xy 39.392156 -399.178823) (xy 39.354199 -399.234409)
			(xy 39.332408 -399.26006) (xy 39.326604 -399.2672) (xy 39.320094 -399.284395) (xy 39.319708 -399.293588)
			(xy 39.319708 -399.451576) (xy 39.319259 -399.461728) (xy 39.311473 -399.480478) (xy 39.297085 -399.494802)
			(xy 39.278299 -399.502504) (xy 39.268146 -399.502884) (xy 38.551866 -399.502884) (xy 38.54174 -399.502402)
			(xy 38.523023 -399.494668) (xy 38.508668 -399.48038) (xy 38.500846 -399.4617) (xy 38.500304 -399.451576)
			(xy 38.500304 -399.293588) (xy 38.499899 -399.2844) (xy 38.493381 -399.267216) (xy 38.487604 -399.26006)
			(xy 38.465853 -399.234378) (xy 38.427905 -399.178795) (xy 38.396872 -399.119075) (xy 38.373199 -399.056075)
			(xy 38.357224 -398.990697) (xy 38.349178 -398.923878) (xy 38.349175 -398.856576) (xy 38.357215 -398.789757)
			(xy 38.373183 -398.724377) (xy 38.39685 -398.661374) (xy 38.427877 -398.601651) (xy 38.465819 -398.546065)
			(xy 38.487604 -398.520412) (xy 38.493421 -398.513281) (xy 38.499923 -398.49608) (xy 38.500304 -398.486884)
			(xy 38.500304 -397.993362) (xy 38.499911 -397.984173) (xy 38.493385 -397.966989) (xy 38.487604 -397.959834)
			(xy 38.465827 -397.934173) (xy 38.42788 -397.878587) (xy 38.396849 -397.818865) (xy 38.373177 -397.755861)
			(xy 38.357204 -397.69048) (xy 38.34916 -397.623659) (xy 38.349159 -397.556356) (xy 37.220943 -397.556356)
			(xy 37.223335 -397.560946) (xy 37.247103 -397.624039) (xy 37.263142 -397.689525) (xy 37.271222 -397.756461)
			(xy 37.271225 -397.823882) (xy 37.263153 -397.890819) (xy 37.24712 -397.956306) (xy 37.223358 -398.019402)
			(xy 37.19221 -398.079196) (xy 37.154123 -398.134829) (xy 37.13226 -398.160494) (xy 37.126478 -398.16765)
			(xy 37.119956 -398.184832) (xy 37.11956 -398.194022) (xy 37.11956 -398.351502) (xy 37.119075 -398.361629)
			(xy 37.111347 -398.38035) (xy 37.09706 -398.394706) (xy 37.078376 -398.402525) (xy 37.068252 -398.403064)
			(xy 36.351972 -398.403064) (xy 36.341812 -398.402701) (xy 36.323052 -398.394889) (xy 36.308728 -398.380474)
			(xy 36.301036 -398.361665) (xy 36.300664 -398.351502) (xy 36.300664 -398.194022) (xy 36.300229 -398.184838)
			(xy 36.293731 -398.167654) (xy 36.287964 -398.160494) (xy 36.266064 -398.134859) (xy 36.227979 -398.079219)
			(xy 36.196832 -398.019419) (xy 36.173071 -397.956318) (xy 36.15704 -397.890825) (xy 36.148967 -397.823884)
			(xy 35.020799 -397.823884) (xy 34.992065 -397.879042) (xy 34.953976 -397.934677) (xy 34.932112 -397.960342)
			(xy 34.926316 -397.967488) (xy 34.919801 -397.984678) (xy 34.919412 -397.99387) (xy 34.919412 -398.486376)
			(xy 34.919831 -398.495562) (xy 34.926338 -398.512747) (xy 34.932112 -398.519904) (xy 34.954011 -398.54554)
			(xy 34.992098 -398.601179) (xy 35.023246 -398.66098) (xy 35.047008 -398.72408) (xy 35.06304 -398.789573)
			(xy 35.071113 -398.856514) (xy 35.07111 -398.92394) (xy 35.063031 -398.990881) (xy 35.046992 -399.056372)
			(xy 35.023224 -399.11947) (xy 34.99207 -399.179267) (xy 34.953978 -399.234903) (xy 34.932112 -399.260568)
			(xy 34.926305 -399.267706) (xy 34.919796 -399.284902) (xy 34.919412 -399.294096) (xy 34.919412 -399.451576)
			(xy 34.918965 -399.461695) (xy 34.911227 -399.480396) (xy 34.89692 -399.494711) (xy 34.878223 -399.502459)
			(xy 34.868104 -399.502884) (xy 34.151824 -399.502884) (xy 34.141701 -399.502464) (xy 34.122995 -399.494721)
			(xy 34.108679 -399.480405) (xy 34.100936 -399.461699) (xy 34.100516 -399.451576) (xy 34.100516 -399.294096)
			(xy 34.100104 -399.284909) (xy 34.093591 -399.267725) (xy 34.087816 -399.260568) (xy 34.065987 -399.234874)
			(xy 34.027896 -399.179244) (xy 33.996743 -399.119452) (xy 33.972976 -399.056359) (xy 33.956937 -398.990873)
			(xy 33.948858 -398.923938) (xy 33.948855 -398.856516) (xy 33.956928 -398.78958) (xy 33.97296 -398.724093)
			(xy 33.996721 -398.660998) (xy 34.027868 -398.601203) (xy 34.065954 -398.545569) (xy 34.087816 -398.519904)
			(xy 34.093595 -398.512747) (xy 34.10012 -398.495565) (xy 34.100516 -398.486376) (xy 34.100516 -397.99387)
			(xy 34.100117 -397.984682) (xy 34.093595 -397.967498) (xy 34.087816 -397.960342) (xy 34.065961 -397.934669)
			(xy 34.027871 -397.879036) (xy 33.996719 -397.819241) (xy 33.972954 -397.756145) (xy 33.956917 -397.690657)
			(xy 33.94884 -397.623719) (xy 33.948839 -397.556296) (xy 32.820593 -397.556296) (xy 32.823205 -397.561323)
			(xy 32.84688 -397.624323) (xy 32.862855 -397.689702) (xy 32.870902 -397.756521) (xy 32.870905 -397.823822)
			(xy 32.862865 -397.890642) (xy 32.846897 -397.956022) (xy 32.823229 -398.019025) (xy 32.7922 -398.078747)
			(xy 32.754257 -398.134334) (xy 32.732472 -398.159986) (xy 32.726653 -398.167115) (xy 32.720152 -398.184318)
			(xy 32.719772 -398.193514) (xy 32.719772 -398.351502) (xy 32.719268 -398.361659) (xy 32.711495 -398.380426)
			(xy 32.697133 -398.394791) (xy 32.678367 -398.402567) (xy 32.66821 -398.403064) (xy 31.95193 -398.403064)
			(xy 31.941761 -398.402611) (xy 31.922967 -398.394837) (xy 31.908581 -398.38046) (xy 31.900795 -398.361671)
			(xy 31.900368 -398.351502) (xy 31.900368 -398.193514) (xy 31.899936 -398.184329) (xy 31.893436 -398.167146)
			(xy 31.887668 -398.159986) (xy 31.865842 -398.134365) (xy 31.827892 -398.078775) (xy 31.796859 -398.019047)
			(xy 31.773187 -397.956039) (xy 31.757216 -397.890652) (xy 31.749174 -397.823826) (xy 30.620528 -397.823826)
			(xy 30.592066 -397.878596) (xy 30.554113 -397.934182) (xy 30.532324 -397.959834) (xy 30.526533 -397.966984)
			(xy 30.520014 -397.984171) (xy 30.519624 -397.993362) (xy 30.519624 -398.486884) (xy 30.520036 -398.496071)
			(xy 30.526548 -398.513256) (xy 30.532324 -398.520412) (xy 30.554149 -398.546034) (xy 30.592099 -398.601624)
			(xy 30.623132 -398.661352) (xy 30.646805 -398.72436) (xy 30.662776 -398.789746) (xy 30.670818 -398.856573)
			(xy 30.670815 -398.923881) (xy 30.662767 -398.990707) (xy 30.646789 -399.056092) (xy 30.62311 -399.119098)
			(xy 30.592071 -399.178822) (xy 30.554115 -399.234409) (xy 30.532324 -399.26006) (xy 30.526522 -399.267202)
			(xy 30.52001 -399.284395) (xy 30.519624 -399.293588) (xy 30.519624 -399.451576) (xy 30.519159 -399.461726)
			(xy 30.511376 -399.480473) (xy 30.496993 -399.494796) (xy 30.478213 -399.502501) (xy 30.468062 -399.502884)
			(xy 29.751782 -399.502884) (xy 29.741657 -399.502389) (xy 29.72294 -399.49466) (xy 29.708585 -399.480377)
			(xy 29.700762 -399.461698) (xy 29.70022 -399.451576) (xy 29.70022 -399.293588) (xy 29.699811 -399.284401)
			(xy 29.693296 -399.267217) (xy 29.68752 -399.26006) (xy 29.665769 -399.234378) (xy 29.62782 -399.178796)
			(xy 29.596786 -399.119076) (xy 29.573112 -399.056075) (xy 29.557137 -398.990697) (xy 29.549091 -398.923878)
			(xy 29.549087 -398.856576) (xy 29.557128 -398.789756) (xy 29.573096 -398.724376) (xy 29.596764 -398.661374)
			(xy 29.627792 -398.601651) (xy 29.665735 -398.546065) (xy 29.68752 -398.520412) (xy 29.693339 -398.513283)
			(xy 29.69984 -398.49608) (xy 29.70022 -398.486884) (xy 29.70022 -397.993362) (xy 29.699824 -397.984173)
			(xy 29.6933 -397.966989) (xy 29.68752 -397.959834) (xy 29.665743 -397.934174) (xy 29.627795 -397.878588)
			(xy 29.596762 -397.818865) (xy 29.57309 -397.755862) (xy 29.557116 -397.690481) (xy 29.549072 -397.623659)
			(xy 29.549071 -397.556356) (xy 28.420857 -397.556356) (xy 28.423249 -397.560947) (xy 28.447016 -397.62404)
			(xy 28.463055 -397.689526) (xy 28.471134 -397.756461) (xy 28.471138 -397.823882) (xy 28.463065 -397.890818)
			(xy 28.447033 -397.956305) (xy 28.423272 -398.019401) (xy 28.392124 -398.079196) (xy 28.354039 -398.134829)
			(xy 28.332176 -398.160494) (xy 28.326397 -398.167651) (xy 28.319873 -398.184833) (xy 28.319476 -398.194022)
			(xy 28.319476 -398.351502) (xy 28.318975 -398.361627) (xy 28.31125 -398.380345) (xy 28.296968 -398.394701)
			(xy 28.27829 -398.402523) (xy 28.268168 -398.403064) (xy 27.551888 -398.403064) (xy 27.541729 -398.402688)
			(xy 27.522969 -398.394881) (xy 27.508645 -398.38047) (xy 27.500952 -398.361664) (xy 27.50058 -398.351502)
			(xy 27.50058 -398.194022) (xy 27.500164 -398.184835) (xy 27.493655 -398.167651) (xy 27.48788 -398.160494)
			(xy 27.465979 -398.134859) (xy 27.427893 -398.07922) (xy 27.396745 -398.019419) (xy 27.372984 -397.956318)
			(xy 27.356952 -397.890826) (xy 27.348879 -397.823885) (xy 8.839736 -397.823885) (xy 8.850142 -397.906253)
			(xy 8.858264 -398.035359) (xy 8.858264 -398.164721) (xy 8.850142 -398.293827) (xy 8.833928 -398.422169)
			(xy 8.809688 -398.549239) (xy 8.777518 -398.674536) (xy 8.737543 -398.797566) (xy 8.689921 -398.917844)
			(xy 8.634842 -399.034893) (xy 8.572521 -399.148254) (xy 8.503206 -399.257477) (xy 8.427169 -399.362133)
			(xy 8.344711 -399.461808) (xy 8.256157 -399.556108) (xy 8.161856 -399.644662) (xy 8.062181 -399.72712)
			(xy 7.957526 -399.803157) (xy 7.848302 -399.872472) (xy 7.734942 -399.934793) (xy 7.617892 -399.989872)
			(xy 7.497614 -400.037493) (xy 7.374584 -400.077468) (xy 7.249287 -400.109639) (xy 7.122217 -400.133879)
			(xy 6.993875 -400.150092) (xy 6.864769 -400.158214) (xy 6.800088 -400.158712) (xy 5.199888 -400.158712)
			(xy 5.135208 -400.158204) (xy 5.006102 -400.150081) (xy 4.877762 -400.133868) (xy 4.750692 -400.109628)
			(xy 4.625396 -400.077458) (xy 4.502366 -400.037483) (xy 4.38209 -399.989862) (xy 4.265041 -399.934783)
			(xy 4.151681 -399.872463) (xy 4.042458 -399.803148) (xy 3.937803 -399.727112) (xy 3.838129 -399.644654)
			(xy 3.743829 -399.556101) (xy 3.655276 -399.461801) (xy 3.572818 -399.362127) (xy 3.496782 -399.257472)
			(xy 3.427467 -399.148249) (xy 3.365147 -399.034889) (xy 3.310068 -398.91784) (xy 3.262447 -398.797564)
			(xy 3.222472 -398.674534) (xy 3.190302 -398.549238) (xy 3.166062 -398.422168) (xy 3.149849 -398.293828)
			(xy 3.141726 -398.164722) (xy 0.508 -398.164722) (xy 0.508 -401.723796) (xy 27.348891 -401.723796)
			(xy 27.348893 -401.656371) (xy 27.35697 -401.589432) (xy 27.373007 -401.523942) (xy 27.396773 -401.460844)
			(xy 27.427925 -401.401047) (xy 27.466015 -401.345412) (xy 27.48788 -401.319746) (xy 27.49368 -401.312603)
			(xy 27.500193 -401.295411) (xy 27.50058 -401.286218) (xy 27.50058 -400.793966) (xy 27.500191 -400.784777)
			(xy 27.493663 -400.767592) (xy 27.48788 -400.760438) (xy 27.466023 -400.734768) (xy 27.427935 -400.679133)
			(xy 27.396785 -400.619338) (xy 27.373022 -400.556241) (xy 27.356986 -400.490753) (xy 27.34891 -400.423816)
			(xy 27.34891 -400.356393) (xy 27.356985 -400.289456) (xy 27.373019 -400.223967) (xy 27.396782 -400.160871)
			(xy 27.42793 -400.101074) (xy 27.466017 -400.04544) (xy 27.48788 -400.019774) (xy 27.493668 -400.012622)
			(xy 27.500188 -399.995437) (xy 27.50058 -399.986246) (xy 27.50058 -399.828766) (xy 27.501 -399.818632)
			(xy 27.508746 -399.799903) (xy 27.523053 -399.785546) (xy 27.541756 -399.777735) (xy 27.551888 -399.777204)
			(xy 28.268168 -399.777204) (xy 28.278321 -399.777648) (xy 28.297073 -399.785433) (xy 28.311398 -399.799824)
			(xy 28.319098 -399.818612) (xy 28.319476 -399.828766) (xy 28.319476 -399.986246) (xy 28.319918 -399.99543)
			(xy 28.32641 -400.012614) (xy 28.332176 -400.019774) (xy 28.354047 -400.045434) (xy 28.392137 -400.101069)
			(xy 28.423289 -400.160865) (xy 28.447053 -400.223963) (xy 28.463089 -400.289453) (xy 28.471165 -400.356392)
			(xy 28.471165 -400.423817) (xy 28.463088 -400.490756) (xy 28.447051 -400.556246) (xy 28.423285 -400.619343)
			(xy 28.392132 -400.679139) (xy 28.354041 -400.734773) (xy 28.332176 -400.760438) (xy 28.326378 -400.767582)
			(xy 28.319865 -400.784774) (xy 28.319476 -400.793966) (xy 28.319476 -401.286218) (xy 28.319883 -401.295405)
			(xy 28.326399 -401.31259) (xy 28.332176 -401.319746) (xy 28.354019 -401.345429) (xy 28.39211 -401.40106)
			(xy 28.423263 -401.460854) (xy 28.446989 -401.523838) (xy 29.549051 -401.523838) (xy 29.549053 -401.456532)
			(xy 29.557098 -401.389708) (xy 29.573073 -401.324325) (xy 29.596747 -401.26132) (xy 29.627782 -401.201596)
			(xy 29.665732 -401.146008) (xy 29.68752 -401.120356) (xy 29.69332 -401.113213) (xy 29.699832 -401.096021)
			(xy 29.70022 -401.086828) (xy 29.70022 -400.92884) (xy 29.700655 -400.918686) (xy 29.708441 -400.899931)
			(xy 29.722834 -400.885605) (xy 29.741626 -400.877908) (xy 29.751782 -400.877532) (xy 30.468062 -400.877532)
			(xy 30.478185 -400.878058) (xy 30.496904 -400.885771) (xy 30.511261 -400.900046) (xy 30.519083 -400.91872)
			(xy 30.519624 -400.92884) (xy 30.519624 -401.086828) (xy 30.520015 -401.096017) (xy 30.526542 -401.113202)
			(xy 30.532324 -401.120356) (xy 30.554093 -401.146024) (xy 30.592045 -401.201607) (xy 30.623081 -401.261328)
			(xy 30.646757 -401.324331) (xy 30.662732 -401.389711) (xy 30.670778 -401.456533) (xy 30.67078 -401.523837)
			(xy 30.662738 -401.590659) (xy 30.646766 -401.65604) (xy 30.623093 -401.719044) (xy 30.620654 -401.723737)
			(xy 31.749186 -401.723737) (xy 31.749188 -401.65643) (xy 31.757235 -401.589605) (xy 31.773211 -401.524221)
			(xy 31.796887 -401.461216) (xy 31.827925 -401.401492) (xy 31.865878 -401.345906) (xy 31.887668 -401.320254)
			(xy 31.893475 -401.313116) (xy 31.899981 -401.29592) (xy 31.900368 -401.286726) (xy 31.900368 -400.793458)
			(xy 31.899963 -400.784271) (xy 31.893444 -400.767087) (xy 31.887668 -400.75993) (xy 31.865885 -400.734273)
			(xy 31.827935 -400.678688) (xy 31.796899 -400.618966) (xy 31.773225 -400.555962) (xy 31.757251 -400.49058)
			(xy 31.749206 -400.423757) (xy 31.749205 -400.356452) (xy 31.757249 -400.289629) (xy 31.773222 -400.224247)
			(xy 31.796896 -400.161243) (xy 31.82793 -400.10152) (xy 31.86588 -400.045934) (xy 31.887668 -400.020282)
			(xy 31.893463 -400.013136) (xy 31.899977 -399.995946) (xy 31.900368 -399.986754) (xy 31.900368 -399.828766)
			(xy 31.900806 -399.818602) (xy 31.908597 -399.799827) (xy 31.92298 -399.785462) (xy 31.941766 -399.777694)
			(xy 31.95193 -399.777204) (xy 32.66821 -399.777204) (xy 32.678364 -399.777725) (xy 32.697127 -399.785496)
			(xy 32.711491 -399.799853) (xy 32.719271 -399.818612) (xy 32.719772 -399.828766) (xy 32.719772 -399.986754)
			(xy 32.720211 -399.995938) (xy 32.726705 -400.013122) (xy 32.732472 -400.020282) (xy 32.754265 -400.045929)
			(xy 32.792213 -400.101517) (xy 32.823246 -400.161241) (xy 32.846918 -400.224246) (xy 32.86289 -400.289629)
			(xy 32.870933 -400.356452) (xy 32.870933 -400.423757) (xy 32.862888 -400.49058) (xy 32.846915 -400.555962)
			(xy 32.823242 -400.618967) (xy 32.792209 -400.678691) (xy 32.75426 -400.734278) (xy 32.732472 -400.75993)
			(xy 32.726677 -400.767076) (xy 32.720162 -400.784266) (xy 32.719772 -400.793458) (xy 32.719772 -401.286726)
			(xy 32.720176 -401.295914) (xy 32.726695 -401.313098) (xy 32.732472 -401.320254) (xy 32.754237 -401.345924)
			(xy 32.792186 -401.401508) (xy 32.82322 -401.46123) (xy 32.846893 -401.524232) (xy 32.862868 -401.589612)
			(xy 32.870913 -401.656432) (xy 32.870915 -401.723735) (xy 32.862873 -401.790556) (xy 32.846903 -401.855937)
			(xy 32.823233 -401.91894) (xy 32.792203 -401.978663) (xy 32.754258 -402.03425) (xy 32.732472 -402.059902)
			(xy 32.726688 -402.067056) (xy 32.720167 -402.08424) (xy 32.719772 -402.09343) (xy 32.719772 -402.251418)
			(xy 32.719282 -402.261576) (xy 32.711503 -402.280343) (xy 32.697137 -402.294708) (xy 32.678368 -402.302483)
			(xy 32.66821 -402.30298) (xy 31.95193 -402.30298) (xy 31.941763 -402.302512) (xy 31.922972 -402.29474)
			(xy 31.908587 -402.280368) (xy 31.900798 -402.261585) (xy 31.900368 -402.251418) (xy 31.900368 -402.09343)
			(xy 31.899928 -402.084246) (xy 31.893434 -402.067062) (xy 31.887668 -402.059902) (xy 31.865858 -402.034268)
			(xy 31.827908 -401.97868) (xy 31.796874 -401.918954) (xy 31.773201 -401.855947) (xy 31.757229 -401.790562)
			(xy 31.749186 -401.723737) (xy 30.620654 -401.723737) (xy 30.59206 -401.778767) (xy 30.554112 -401.834352)
			(xy 30.532324 -401.860004) (xy 30.526546 -401.867163) (xy 30.520019 -401.884343) (xy 30.519624 -401.893532)
			(xy 30.519624 -402.3868) (xy 30.520029 -402.395988) (xy 30.526546 -402.413172) (xy 30.532324 -402.420328)
			(xy 30.554114 -402.445978) (xy 30.592063 -402.501565) (xy 30.623097 -402.561289) (xy 30.64677 -402.624293)
			(xy 30.662743 -402.689676) (xy 30.670787 -402.756499) (xy 30.670787 -402.823804) (xy 30.670778 -402.823878)
			(xy 33.948799 -402.823878) (xy 33.948804 -402.75645) (xy 33.956885 -402.689508) (xy 33.972926 -402.624016)
			(xy 33.996696 -402.560917) (xy 34.027853 -402.50112) (xy 34.065949 -402.445485) (xy 34.087816 -402.41982)
			(xy 34.093631 -402.412688) (xy 34.100134 -402.395487) (xy 34.100516 -402.386292) (xy 34.100516 -401.89404)
			(xy 34.100083 -401.884855) (xy 34.093585 -401.867671) (xy 34.087816 -401.860512) (xy 34.065932 -401.834863)
			(xy 34.027843 -401.779227) (xy 33.996692 -401.719428) (xy 33.972928 -401.656329) (xy 33.956894 -401.590838)
			(xy 33.948819 -401.523898) (xy 33.948821 -401.456472) (xy 33.956899 -401.389532) (xy 33.972937 -401.324042)
			(xy 33.996704 -401.260944) (xy 34.027858 -401.201147) (xy 34.06595 -401.145513) (xy 34.087816 -401.119848)
			(xy 34.093619 -401.112707) (xy 34.100129 -401.095513) (xy 34.100516 -401.08632) (xy 34.100516 -400.92884)
			(xy 34.100949 -400.918718) (xy 34.108687 -400.900012) (xy 34.122999 -400.885696) (xy 34.141702 -400.877952)
			(xy 34.151824 -400.877532) (xy 34.868104 -400.877532) (xy 34.878231 -400.877914) (xy 34.89694 -400.885669)
			(xy 34.911256 -400.899997) (xy 34.918995 -400.918713) (xy 34.919412 -400.92884) (xy 34.919412 -401.08632)
			(xy 34.91981 -401.095509) (xy 34.926332 -401.112693) (xy 34.932112 -401.119848) (xy 34.953956 -401.14553)
			(xy 34.992044 -401.201162) (xy 35.023195 -401.260956) (xy 35.04696 -401.324051) (xy 35.062997 -401.389538)
			(xy 35.071074 -401.456474) (xy 35.071076 -401.523896) (xy 35.063002 -401.590833) (xy 35.046969 -401.65632)
			(xy 35.023208 -401.719416) (xy 35.020926 -401.723796) (xy 36.148978 -401.723796) (xy 36.14898 -401.656371)
			(xy 36.157058 -401.589432) (xy 36.173095 -401.523942) (xy 36.19686 -401.460845) (xy 36.228011 -401.401047)
			(xy 36.2661 -401.345412) (xy 36.287964 -401.319746) (xy 36.293774 -401.312611) (xy 36.300279 -401.295412)
			(xy 36.300664 -401.286218) (xy 36.300664 -400.793966) (xy 36.300256 -400.784779) (xy 36.293739 -400.767595)
			(xy 36.287964 -400.760438) (xy 36.266107 -400.734767) (xy 36.228021 -400.679133) (xy 36.196872 -400.619337)
			(xy 36.173109 -400.556241) (xy 36.157074 -400.490753) (xy 36.148998 -400.423816) (xy 36.148998 -400.356393)
			(xy 36.157072 -400.289456) (xy 36.173106 -400.223968) (xy 36.196868 -400.160871) (xy 36.228016 -400.101075)
			(xy 36.266102 -400.04544) (xy 36.287964 -400.019774) (xy 36.293762 -400.01263) (xy 36.300274 -399.995438)
			(xy 36.300664 -399.986246) (xy 36.300664 -399.828766) (xy 36.301099 -399.818634) (xy 36.308843 -399.799908)
			(xy 36.323145 -399.785552) (xy 36.341842 -399.777738) (xy 36.351972 -399.777204) (xy 37.068252 -399.777204)
			(xy 37.078404 -399.777661) (xy 37.097156 -399.785442) (xy 37.111481 -399.799828) (xy 37.119181 -399.818613)
			(xy 37.11956 -399.828766) (xy 37.11956 -399.986246) (xy 37.120005 -399.995429) (xy 37.126496 -400.012613)
			(xy 37.13226 -400.019774) (xy 37.154131 -400.045434) (xy 37.192222 -400.101068) (xy 37.223375 -400.160865)
			(xy 37.247141 -400.223962) (xy 37.263177 -400.289453) (xy 37.271253 -400.356392) (xy 37.271252 -400.423817)
			(xy 37.263175 -400.490756) (xy 37.247138 -400.556246) (xy 37.223371 -400.619344) (xy 37.192218 -400.67914)
			(xy 37.154126 -400.734773) (xy 37.13226 -400.760438) (xy 37.12646 -400.76758) (xy 37.119948 -400.784773)
			(xy 37.11956 -400.793966) (xy 37.11956 -401.286218) (xy 37.11997 -401.295405) (xy 37.126485 -401.312589)
			(xy 37.13226 -401.319746) (xy 37.154104 -401.345428) (xy 37.192196 -401.40106) (xy 37.22335 -401.460853)
			(xy 37.247117 -401.523948) (xy 37.263155 -401.589435) (xy 37.271233 -401.656372) (xy 37.271235 -401.723795)
			(xy 37.263161 -401.790732) (xy 37.247127 -401.856221) (xy 37.223363 -401.919317) (xy 37.192213 -401.979112)
			(xy 37.154124 -402.034745) (xy 37.13226 -402.06041) (xy 37.126472 -402.067561) (xy 37.119953 -402.084747)
			(xy 37.11956 -402.093938) (xy 37.11956 -402.251418) (xy 37.119088 -402.261546) (xy 37.111355 -402.280268)
			(xy 37.097064 -402.294623) (xy 37.078378 -402.302442) (xy 37.068252 -402.30298) (xy 36.351972 -402.30298)
			(xy 36.341814 -402.302601) (xy 36.323057 -402.294792) (xy 36.308734 -402.280383) (xy 36.301038 -402.261579)
			(xy 36.300664 -402.251418) (xy 36.300664 -402.093938) (xy 36.300221 -402.084755) (xy 36.293729 -402.067571)
			(xy 36.287964 -402.06041) (xy 36.26608 -402.034762) (xy 36.227994 -401.979124) (xy 36.196846 -401.919325)
			(xy 36.173085 -401.856226) (xy 36.157052 -401.790735) (xy 36.148978 -401.723796) (xy 35.020926 -401.723796)
			(xy 34.99206 -401.779212) (xy 34.953974 -401.834847) (xy 34.932112 -401.860512) (xy 34.926329 -401.867667)
			(xy 34.919806 -401.88485) (xy 34.919412 -401.89404) (xy 34.919412 -402.386292) (xy 34.919823 -402.395479)
			(xy 34.926336 -402.412664) (xy 34.932112 -402.41982) (xy 34.953928 -402.445524) (xy 34.992018 -402.501154)
			(xy 35.02317 -402.560944) (xy 35.046936 -402.624036) (xy 35.062975 -402.68952) (xy 35.071054 -402.756454)
			(xy 35.071059 -402.823818) (xy 38.349119 -402.823818) (xy 38.349123 -402.75651) (xy 38.357172 -402.689685)
			(xy 38.373149 -402.6243) (xy 38.396825 -402.561294) (xy 38.427862 -402.501569) (xy 38.465814 -402.445981)
			(xy 38.487604 -402.420328) (xy 38.493414 -402.413192) (xy 38.499921 -402.395995) (xy 38.500304 -402.3868)
			(xy 38.500304 -401.893532) (xy 38.499878 -401.884347) (xy 38.493375 -401.867162) (xy 38.487604 -401.860004)
			(xy 38.465798 -401.834368) (xy 38.427852 -401.778778) (xy 38.396821 -401.719052) (xy 38.373151 -401.656045)
			(xy 38.357181 -401.590662) (xy 38.349139 -401.523838) (xy 38.34914 -401.456532) (xy 38.357186 -401.389709)
			(xy 38.37316 -401.324326) (xy 38.396834 -401.261321) (xy 38.427867 -401.201596) (xy 38.465816 -401.146009)
			(xy 38.487604 -401.120356) (xy 38.493402 -401.113212) (xy 38.499916 -401.096021) (xy 38.500304 -401.086828)
			(xy 38.500304 -400.92884) (xy 38.500755 -400.918688) (xy 38.508538 -400.899936) (xy 38.522926 -400.885611)
			(xy 38.541712 -400.87791) (xy 38.551866 -400.877532) (xy 39.268146 -400.877532) (xy 39.278275 -400.877989)
			(xy 39.296995 -400.88573) (xy 39.31135 -400.900025) (xy 39.319169 -400.918714) (xy 39.319708 -400.92884)
			(xy 39.319708 -401.086828) (xy 39.320103 -401.096017) (xy 39.326627 -401.113201) (xy 39.332408 -401.120356)
			(xy 39.354178 -401.146024) (xy 39.392131 -401.201607) (xy 39.423168 -401.261328) (xy 39.446844 -401.32433)
			(xy 39.46282 -401.389711) (xy 39.470866 -401.456533) (xy 39.470868 -401.523837) (xy 39.462825 -401.590659)
			(xy 39.446853 -401.656041) (xy 39.42318 -401.719045) (xy 39.420711 -401.723797) (xy 40.548745 -401.723797)
			(xy 40.548747 -401.65637) (xy 40.556826 -401.58943) (xy 40.572865 -401.523939) (xy 40.596634 -401.460841)
			(xy 40.62779 -401.401044) (xy 40.665885 -401.34541) (xy 40.687752 -401.319746) (xy 40.69356 -401.312609)
			(xy 40.700067 -401.295412) (xy 40.700452 -401.286218) (xy 40.700452 -400.793966) (xy 40.700046 -400.784779)
			(xy 40.693528 -400.767595) (xy 40.687752 -400.760438) (xy 40.665892 -400.734769) (xy 40.6278 -400.679136)
			(xy 40.596646 -400.619341) (xy 40.572879 -400.556244) (xy 40.556842 -400.490755) (xy 40.548764 -400.423817)
			(xy 40.548764 -400.356392) (xy 40.55684 -400.289454) (xy 40.572876 -400.223964) (xy 40.596642 -400.160867)
			(xy 40.627795 -400.101072) (xy 40.665887 -400.045438) (xy 40.687752 -400.019774) (xy 40.693549 -400.012629)
			(xy 40.700062 -399.995438) (xy 40.700452 -399.986246) (xy 40.700452 -399.828766) (xy 40.700899 -399.818636)
			(xy 40.70864 -399.799911) (xy 40.722939 -399.785556) (xy 40.741632 -399.77774) (xy 40.75176 -399.777204)
			(xy 41.46804 -399.777204) (xy 41.478197 -399.777589) (xy 41.496951 -399.785399) (xy 41.511273 -399.799806)
			(xy 41.518971 -399.818606) (xy 41.519348 -399.828766) (xy 41.519348 -399.986246) (xy 41.519796 -399.995429)
			(xy 41.526285 -400.012613) (xy 41.532048 -400.019774) (xy 41.55392 -400.045433) (xy 41.592012 -400.101068)
			(xy 41.623165 -400.160864) (xy 41.646931 -400.223962) (xy 41.662968 -400.289452) (xy 41.671044 -400.356392)
			(xy 41.671043 -400.423817) (xy 41.662966 -400.490757) (xy 41.646928 -400.556247) (xy 41.623161 -400.619344)
			(xy 41.592007 -400.67914) (xy 41.553914 -400.734774) (xy 41.532048 -400.760438) (xy 41.526246 -400.767579)
			(xy 41.519736 -400.784773) (xy 41.519348 -400.793966) (xy 41.519348 -401.286218) (xy 41.519761 -401.295405)
			(xy 41.526274 -401.312588) (xy 41.532048 -401.319746) (xy 41.553892 -401.345428) (xy 41.591985 -401.401059)
			(xy 41.62314 -401.460852) (xy 41.646907 -401.523947) (xy 41.662946 -401.589435) (xy 41.671024 -401.656372)
			(xy 41.671026 -401.723795) (xy 41.662952 -401.790733) (xy 41.646917 -401.856221) (xy 41.623153 -401.919317)
			(xy 41.592002 -401.979113) (xy 41.553912 -402.034746) (xy 41.532048 -402.06041) (xy 41.526258 -402.06756)
			(xy 41.519741 -402.084747) (xy 41.519348 -402.093938) (xy 41.519348 -402.251418) (xy 41.518888 -402.261547)
			(xy 41.511152 -402.280271) (xy 41.496858 -402.294627) (xy 41.478167 -402.302444) (xy 41.46804 -402.30298)
			(xy 40.75176 -402.30298) (xy 40.741601 -402.302611) (xy 40.722844 -402.294798) (xy 40.708521 -402.280385)
			(xy 40.700826 -402.26158) (xy 40.700452 -402.251418) (xy 40.700452 -402.093938) (xy 40.700012 -402.084754)
			(xy 40.693518 -402.06757) (xy 40.687752 -402.06041) (xy 40.665865 -402.034763) (xy 40.627773 -401.979127)
			(xy 40.59662 -401.919329) (xy 40.572855 -401.85623) (xy 40.55682 -401.790738) (xy 40.548745 -401.723797)
			(xy 39.420711 -401.723797) (xy 39.392146 -401.778768) (xy 39.354196 -401.834353) (xy 39.332408 -401.860004)
			(xy 39.326628 -401.867161) (xy 39.320103 -401.884342) (xy 39.319708 -401.893532) (xy 39.319708 -402.3868)
			(xy 39.320116 -402.395987) (xy 39.326631 -402.413172) (xy 39.332408 -402.420328) (xy 39.35415 -402.446018)
			(xy 39.392104 -402.501598) (xy 39.423142 -402.561316) (xy 39.44682 -402.624315) (xy 39.462798 -402.689694)
			(xy 39.470847 -402.756513) (xy 39.470851 -402.823815) (xy 39.470843 -402.823878) (xy 42.748887 -402.823878)
			(xy 42.748892 -402.75645) (xy 42.756972 -402.689509) (xy 42.773013 -402.624017) (xy 42.796782 -402.560918)
			(xy 42.827939 -402.501121) (xy 42.866033 -402.445485) (xy 42.8879 -402.41982) (xy 42.893713 -402.412686)
			(xy 42.900218 -402.395487) (xy 42.9006 -402.386292) (xy 42.9006 -401.89404) (xy 42.900171 -401.884855)
			(xy 42.89367 -401.86767) (xy 42.8879 -401.860512) (xy 42.866016 -401.834863) (xy 42.827928 -401.779226)
			(xy 42.796778 -401.719428) (xy 42.773015 -401.656329) (xy 42.756981 -401.590838) (xy 42.748907 -401.523898)
			(xy 42.748909 -401.456472) (xy 42.756987 -401.389533) (xy 42.773024 -401.324043) (xy 42.796791 -401.260945)
			(xy 42.827944 -401.201148) (xy 42.866035 -401.145513) (xy 42.8879 -401.119848) (xy 42.893701 -401.112706)
			(xy 42.900213 -401.095513) (xy 42.9006 -401.08632) (xy 42.9006 -400.92884) (xy 42.901049 -400.91872)
			(xy 42.908784 -400.900017) (xy 42.923091 -400.885702) (xy 42.941788 -400.877955) (xy 42.951908 -400.877532)
			(xy 43.668188 -400.877532) (xy 43.678314 -400.877927) (xy 43.697023 -400.885677) (xy 43.711339 -400.9)
			(xy 43.719079 -400.918714) (xy 43.719496 -400.92884) (xy 43.719496 -401.08632) (xy 43.719897 -401.095508)
			(xy 43.726417 -401.112692) (xy 43.732196 -401.119848) (xy 43.75404 -401.145529) (xy 43.79213 -401.201162)
			(xy 43.823282 -401.260955) (xy 43.847047 -401.32405) (xy 43.863084 -401.389537) (xy 43.871162 -401.456474)
			(xy 43.871164 -401.523896) (xy 43.86309 -401.590833) (xy 43.847056 -401.656321) (xy 43.823294 -401.719417)
			(xy 43.821044 -401.723737) (xy 44.949064 -401.723737) (xy 44.949066 -401.65643) (xy 44.957113 -401.589606)
			(xy 44.973088 -401.524222) (xy 44.996763 -401.461217) (xy 45.027799 -401.401493) (xy 45.065751 -401.345906)
			(xy 45.08754 -401.320254) (xy 45.093344 -401.313114) (xy 45.099853 -401.295919) (xy 45.10024 -401.286726)
			(xy 45.10024 -400.793458) (xy 45.099841 -400.78427) (xy 45.093319 -400.767086) (xy 45.08754 -400.75993)
			(xy 45.065758 -400.734273) (xy 45.027809 -400.678687) (xy 44.996776 -400.618964) (xy 44.973103 -400.55596)
			(xy 44.957129 -400.490579) (xy 44.949085 -400.423757) (xy 44.949084 -400.356452) (xy 44.957128 -400.28963)
			(xy 44.9731 -400.224248) (xy 44.996772 -400.161244) (xy 45.027805 -400.101521) (xy 45.065753 -400.045934)
			(xy 45.08754 -400.020282) (xy 45.093332 -400.013134) (xy 45.099848 -399.995945) (xy 45.10024 -399.986754)
			(xy 45.10024 -399.828766) (xy 45.100706 -399.818606) (xy 45.108492 -399.799835) (xy 45.122866 -399.785471)
			(xy 45.141641 -399.777698) (xy 45.151802 -399.777204) (xy 45.868082 -399.777204) (xy 45.878234 -399.777747)
			(xy 45.896997 -399.785509) (xy 45.911361 -399.79986) (xy 45.919143 -399.818614) (xy 45.919644 -399.828766)
			(xy 45.919644 -399.986754) (xy 45.920089 -399.995937) (xy 45.92658 -400.013121) (xy 45.932344 -400.020282)
			(xy 45.954138 -400.045929) (xy 45.992088 -400.101516) (xy 46.023122 -400.16124) (xy 46.046795 -400.224245)
			(xy 46.062768 -400.289628) (xy 46.070812 -400.356452) (xy 46.070811 -400.423757) (xy 46.062766 -400.490581)
			(xy 46.046792 -400.555963) (xy 46.023118 -400.618968) (xy 45.992083 -400.678692) (xy 45.954132 -400.734278)
			(xy 45.932344 -400.75993) (xy 45.926545 -400.767073) (xy 45.920033 -400.784266) (xy 45.919644 -400.793458)
			(xy 45.919644 -401.286726) (xy 45.920054 -401.295913) (xy 45.926569 -401.313097) (xy 45.932344 -401.320254)
			(xy 45.95411 -401.345924) (xy 45.992061 -401.401507) (xy 46.023096 -401.461228) (xy 46.046771 -401.524231)
			(xy 46.062746 -401.589611) (xy 46.070792 -401.656432) (xy 46.070794 -401.723735) (xy 46.062752 -401.790557)
			(xy 46.046781 -401.855938) (xy 46.02311 -401.918941) (xy 45.992078 -401.978664) (xy 45.954131 -402.03425)
			(xy 45.932344 -402.059902) (xy 45.926557 -402.067054) (xy 45.920038 -402.084239) (xy 45.919644 -402.09343)
			(xy 45.919644 -402.251418) (xy 45.919181 -402.261579) (xy 45.911397 -402.280352) (xy 45.897022 -402.294718)
			(xy 45.878244 -402.302488) (xy 45.868082 -402.30298) (xy 45.151802 -402.30298) (xy 45.141647 -402.302465)
			(xy 45.122881 -402.294695) (xy 45.108516 -402.280336) (xy 45.100739 -402.261573) (xy 45.10024 -402.251418)
			(xy 45.10024 -402.09343) (xy 45.099806 -402.084246) (xy 45.093308 -402.067061) (xy 45.08754 -402.059902)
			(xy 45.06573 -402.034268) (xy 45.027782 -401.978679) (xy 44.99675 -401.918953) (xy 44.973078 -401.855946)
			(xy 44.957107 -401.790561) (xy 44.949064 -401.723737) (xy 43.821044 -401.723737) (xy 43.792146 -401.779213)
			(xy 43.754059 -401.834847) (xy 43.732196 -401.860512) (xy 43.726411 -401.867666) (xy 43.71989 -401.88485)
			(xy 43.719496 -401.89404) (xy 43.719496 -402.386292) (xy 43.719911 -402.395479) (xy 43.726421 -402.412663)
			(xy 43.732196 -402.41982) (xy 43.754013 -402.445524) (xy 43.792103 -402.501153) (xy 43.823256 -402.560944)
			(xy 43.847023 -402.624036) (xy 43.863062 -402.68952) (xy 43.871142 -402.756454) (xy 43.871146 -402.823874)
			(xy 43.863075 -402.890809) (xy 43.847045 -402.956295) (xy 43.823286 -403.01939) (xy 43.792141 -403.079185)
			(xy 43.754057 -403.134819) (xy 43.732196 -403.160484) (xy 43.726381 -403.167616) (xy 43.719877 -403.184817)
			(xy 43.719496 -403.194012) (xy 43.719496 -403.351492) (xy 43.719077 -403.361614) (xy 43.711331 -403.380319)
			(xy 43.697015 -403.394633) (xy 43.67831 -403.402378) (xy 43.668188 -403.4028) (xy 42.951908 -403.4028)
			(xy 42.941786 -403.402377) (xy 42.923083 -403.394632) (xy 42.908768 -403.380317) (xy 42.901023 -403.361614)
			(xy 42.9006 -403.351492) (xy 42.9006 -403.194012) (xy 42.900184 -403.184825) (xy 42.893674 -403.167641)
			(xy 42.8879 -403.160484) (xy 42.865989 -403.134858) (xy 42.827902 -403.079218) (xy 42.796753 -403.019416)
			(xy 42.772992 -402.956314) (xy 42.756959 -402.89082) (xy 42.748887 -402.823878) (xy 39.470843 -402.823878)
			(xy 39.462811 -402.890635) (xy 39.446841 -402.956016) (xy 39.423172 -403.019018) (xy 39.392141 -403.07874)
			(xy 39.354194 -403.134325) (xy 39.332408 -403.159976) (xy 39.326598 -403.167111) (xy 39.320091 -403.184309)
			(xy 39.319708 -403.193504) (xy 39.319708 -403.351492) (xy 39.319272 -403.361645) (xy 39.311481 -403.380395)
			(xy 39.297088 -403.394719) (xy 39.278301 -403.40242) (xy 39.268146 -403.4028) (xy 38.551866 -403.4028)
			(xy 38.541742 -403.402303) (xy 38.523028 -403.394571) (xy 38.508674 -403.380289) (xy 38.500849 -403.361613)
			(xy 38.500304 -403.351492) (xy 38.500304 -403.193504) (xy 38.499891 -403.184317) (xy 38.493379 -403.167133)
			(xy 38.487604 -403.159976) (xy 38.46577 -403.134362) (xy 38.427825 -403.078769) (xy 38.396796 -403.01904)
			(xy 38.373127 -402.956031) (xy 38.357159 -402.890644) (xy 38.349119 -402.823818) (xy 35.071059 -402.823818)
			(xy 35.071059 -402.823874) (xy 35.062988 -402.890809) (xy 35.046958 -402.956295) (xy 35.023199 -403.01939)
			(xy 34.992055 -403.079185) (xy 34.953973 -403.134819) (xy 34.932112 -403.160484) (xy 34.926299 -403.167617)
			(xy 34.919794 -403.184817) (xy 34.919412 -403.194012) (xy 34.919412 -403.351492) (xy 34.918978 -403.361612)
			(xy 34.911234 -403.380314) (xy 34.896924 -403.394628) (xy 34.878224 -403.402375) (xy 34.868104 -403.4028)
			(xy 34.151824 -403.4028) (xy 34.141703 -403.402365) (xy 34.123 -403.394624) (xy 34.108685 -403.380314)
			(xy 34.100939 -403.361613) (xy 34.100516 -403.351492) (xy 34.100516 -403.194012) (xy 34.100096 -403.184826)
			(xy 34.093589 -403.167642) (xy 34.087816 -403.160484) (xy 34.065904 -403.134858) (xy 34.027816 -403.079218)
			(xy 33.996666 -403.019417) (xy 33.972904 -402.956315) (xy 33.956872 -402.890821) (xy 33.948799 -402.823878)
			(xy 30.670778 -402.823878) (xy 30.662742 -402.890627) (xy 30.646769 -402.956009) (xy 30.623096 -403.019014)
			(xy 30.592062 -403.078738) (xy 30.554112 -403.134324) (xy 30.532324 -403.159976) (xy 30.526515 -403.167113)
			(xy 30.520007 -403.18431) (xy 30.519624 -403.193504) (xy 30.519624 -403.351492) (xy 30.519172 -403.361643)
			(xy 30.511384 -403.38039) (xy 30.496997 -403.394713) (xy 30.478214 -403.402417) (xy 30.468062 -403.4028)
			(xy 29.751782 -403.4028) (xy 29.741659 -403.40229) (xy 29.722945 -403.394563) (xy 29.708591 -403.380285)
			(xy 29.700765 -403.361612) (xy 29.70022 -403.351492) (xy 29.70022 -403.193504) (xy 29.699804 -403.184318)
			(xy 29.693294 -403.167133) (xy 29.68752 -403.159976) (xy 29.665734 -403.134322) (xy 29.627785 -403.078736)
			(xy 29.596752 -403.019013) (xy 29.573079 -402.956008) (xy 29.557106 -402.890626) (xy 29.549061 -402.823804)
			(xy 29.549061 -402.756499) (xy 29.557105 -402.689677) (xy 29.573078 -402.624294) (xy 29.59675 -402.56129)
			(xy 29.627784 -402.501566) (xy 29.665732 -402.44598) (xy 29.68752 -402.420328) (xy 29.693332 -402.413194)
			(xy 29.699837 -402.395995) (xy 29.70022 -402.3868) (xy 29.70022 -401.893532) (xy 29.69979 -401.884347)
			(xy 29.69329 -401.867163) (xy 29.68752 -401.860004) (xy 29.665713 -401.834368) (xy 29.627766 -401.778779)
			(xy 29.596735 -401.719053) (xy 29.573064 -401.656046) (xy 29.557093 -401.590662) (xy 29.549051 -401.523838)
			(xy 28.446989 -401.523838) (xy 28.44703 -401.523948) (xy 28.463067 -401.589436) (xy 28.471145 -401.656372)
			(xy 28.471147 -401.723795) (xy 28.463073 -401.790732) (xy 28.447039 -401.85622) (xy 28.423277 -401.919316)
			(xy 28.392127 -401.979111) (xy 28.354039 -402.034745) (xy 28.332176 -402.06041) (xy 28.32639 -402.067562)
			(xy 28.31987 -402.084748) (xy 28.319476 -402.093938) (xy 28.319476 -402.251418) (xy 28.318989 -402.261544)
			(xy 28.311258 -402.280263) (xy 28.296972 -402.294618) (xy 28.278291 -402.302439) (xy 28.268168 -402.30298)
			(xy 27.551888 -402.30298) (xy 27.541731 -402.302588) (xy 27.522974 -402.294785) (xy 27.50865 -402.280379)
			(xy 27.500954 -402.261578) (xy 27.50058 -402.251418) (xy 27.50058 -402.093938) (xy 27.500156 -402.084752)
			(xy 27.493653 -402.067567) (xy 27.48788 -402.06041) (xy 27.465995 -402.034762) (xy 27.427908 -401.979125)
			(xy 27.39676 -401.919326) (xy 27.372998 -401.856227) (xy 27.356964 -401.790736) (xy 27.348891 -401.723796)
			(xy 0.508 -401.723796) (xy 0.508 -405.623707) (xy 27.348902 -405.623707) (xy 27.348902 -405.556284)
			(xy 27.356979 -405.489345) (xy 27.373014 -405.423856) (xy 27.396778 -405.360759) (xy 27.427928 -405.300963)
			(xy 27.466016 -405.245328) (xy 27.48788 -405.219662) (xy 27.493673 -405.212514) (xy 27.50019 -405.195326)
			(xy 27.50058 -405.186134) (xy 27.50058 -404.693882) (xy 27.500183 -404.684693) (xy 27.493661 -404.667509)
			(xy 27.48788 -404.660354) (xy 27.466038 -404.634671) (xy 27.42795 -404.579038) (xy 27.3968 -404.519244)
			(xy 27.373035 -404.45615) (xy 27.356999 -404.390663) (xy 27.348922 -404.323727) (xy 27.34892 -404.256306)
			(xy 27.356993 -404.189369) (xy 27.373025 -404.123882) (xy 27.396786 -404.060786) (xy 27.427933 -404.00099)
			(xy 27.466018 -403.945356) (xy 27.48788 -403.91969) (xy 27.493661 -403.912534) (xy 27.500186 -403.895352)
			(xy 27.50058 -403.886162) (xy 27.50058 -403.728682) (xy 27.501013 -403.718549) (xy 27.508754 -403.69982)
			(xy 27.523057 -403.685463) (xy 27.541757 -403.677651) (xy 27.551888 -403.67712) (xy 28.268168 -403.67712)
			(xy 28.278323 -403.677548) (xy 28.297078 -403.685337) (xy 28.311404 -403.699732) (xy 28.319101 -403.718525)
			(xy 28.319476 -403.728682) (xy 28.319476 -403.886162) (xy 28.31991 -403.895347) (xy 28.326408 -403.912531)
			(xy 28.332176 -403.91969) (xy 28.354062 -403.945337) (xy 28.392152 -404.000974) (xy 28.423303 -404.060772)
			(xy 28.447067 -404.123871) (xy 28.463102 -404.189363) (xy 28.471176 -404.256304) (xy 28.471174 -404.323729)
			(xy 28.463096 -404.39067) (xy 28.447057 -404.45616) (xy 28.42329 -404.519258) (xy 28.392135 -404.579055)
			(xy 28.354042 -404.634689) (xy 28.332176 -404.660354) (xy 28.326371 -404.667493) (xy 28.319862 -404.684688)
			(xy 28.319476 -404.693882) (xy 28.319476 -405.186134) (xy 28.319875 -405.195322) (xy 28.326397 -405.212506)
			(xy 28.332176 -405.219662) (xy 28.354035 -405.245332) (xy 28.392125 -405.300965) (xy 28.423278 -405.36076)
			(xy 28.447043 -405.423857) (xy 28.46308 -405.489345) (xy 28.471157 -405.556284) (xy 28.471157 -405.623707)
			(xy 28.463081 -405.690646) (xy 28.447046 -405.756135) (xy 28.423281 -405.819231) (xy 28.39213 -405.879027)
			(xy 28.35404 -405.934661) (xy 28.332176 -405.960326) (xy 28.326383 -405.967474) (xy 28.319867 -405.984662)
			(xy 28.319476 -405.993854) (xy 28.319476 -406.151334) (xy 28.319002 -406.161461) (xy 28.311266 -406.18018)
			(xy 28.296976 -406.194534) (xy 28.278293 -406.202355) (xy 28.268168 -406.202896) (xy 27.551888 -406.202896)
			(xy 27.541733 -406.202488) (xy 27.522979 -406.194688) (xy 27.508656 -406.180287) (xy 27.500957 -406.161492)
			(xy 27.50058 -406.151334) (xy 27.50058 -405.993854) (xy 27.500148 -405.984669) (xy 27.49365 -405.967484)
			(xy 27.48788 -405.960326) (xy 27.466011 -405.934665) (xy 27.427924 -405.87903) (xy 27.396774 -405.819233)
			(xy 27.373011 -405.756135) (xy 27.356977 -405.690646) (xy 27.348902 -405.623707) (xy 0.508 -405.623707)
			(xy 0.508 -406.72373) (xy 29.549042 -406.72373) (xy 29.549045 -406.656422) (xy 29.557092 -406.589598)
			(xy 29.573068 -406.524214) (xy 29.596744 -406.461208) (xy 29.627779 -406.401484) (xy 29.665731 -406.345896)
			(xy 29.68752 -406.320244) (xy 29.693325 -406.313105) (xy 29.699834 -406.29591) (xy 29.70022 -406.286716)
			(xy 29.70022 -405.793448) (xy 29.699782 -405.784264) (xy 29.693287 -405.767079) (xy 29.68752 -405.75992)
			(xy 29.665729 -405.734271) (xy 29.627781 -405.678684) (xy 29.596749 -405.618959) (xy 29.573078 -405.555955)
			(xy 29.557105 -405.490572) (xy 29.549062 -405.423749) (xy 29.549062 -405.356444) (xy 29.557107 -405.289622)
			(xy 29.573079 -405.22424) (xy 29.596752 -405.161235) (xy 29.627784 -405.101511) (xy 29.665733 -405.045924)
			(xy 29.68752 -405.020272) (xy 29.693313 -405.013125) (xy 29.699829 -404.995936) (xy 29.70022 -404.986744)
			(xy 29.70022 -404.828756) (xy 29.700586 -404.818597) (xy 29.7084 -404.799839) (xy 29.722814 -404.785517)
			(xy 29.74162 -404.777822) (xy 29.751782 -404.777448) (xy 30.468062 -404.777448) (xy 30.478187 -404.777958)
			(xy 30.496909 -404.785675) (xy 30.511267 -404.799954) (xy 30.519086 -404.818634) (xy 30.519624 -404.828756)
			(xy 30.519624 -404.986744) (xy 30.520008 -404.995934) (xy 30.526539 -405.013118) (xy 30.532324 -405.020272)
			(xy 30.554109 -405.045927) (xy 30.59206 -405.101512) (xy 30.623096 -405.161235) (xy 30.64677 -405.224239)
			(xy 30.662745 -405.289621) (xy 30.67079 -405.356444) (xy 30.67079 -405.42375) (xy 30.662746 -405.490573)
			(xy 30.646772 -405.555955) (xy 30.623098 -405.61896) (xy 30.620661 -405.623649) (xy 31.749197 -405.623649)
			(xy 31.749198 -405.556342) (xy 31.757243 -405.489519) (xy 31.773217 -405.424136) (xy 31.796892 -405.361131)
			(xy 31.827928 -405.301408) (xy 31.865879 -405.245822) (xy 31.887668 -405.22017) (xy 31.893468 -405.213028)
			(xy 31.899979 -405.195835) (xy 31.900368 -405.186642) (xy 31.900368 -404.693374) (xy 31.899955 -404.684187)
			(xy 31.893441 -404.667004) (xy 31.887668 -404.659846) (xy 31.865901 -404.634176) (xy 31.82795 -404.578593)
			(xy 31.796914 -404.518872) (xy 31.773239 -404.45587) (xy 31.757263 -404.39049) (xy 31.749217 -404.323668)
			(xy 31.749215 -404.256365) (xy 31.757257 -404.189543) (xy 31.773229 -404.124162) (xy 31.7969 -404.061158)
			(xy 31.827933 -404.001435) (xy 31.865881 -403.94585) (xy 31.887668 -403.920198) (xy 31.893456 -403.913047)
			(xy 31.899974 -403.895861) (xy 31.900368 -403.88667) (xy 31.900368 -403.728682) (xy 31.90075 -403.718506)
			(xy 31.908547 -403.699705) (xy 31.922945 -403.68532) (xy 31.941753 -403.677541) (xy 31.95193 -403.67712)
			(xy 32.66821 -403.67712) (xy 32.678366 -403.677625) (xy 32.697132 -403.685399) (xy 32.711496 -403.699761)
			(xy 32.719273 -403.718526) (xy 32.719772 -403.728682) (xy 32.719772 -403.88667) (xy 32.720203 -403.895855)
			(xy 32.726703 -403.913039) (xy 32.732472 -403.920198) (xy 32.754281 -403.945832) (xy 32.792229 -404.001422)
			(xy 32.82326 -404.061148) (xy 32.846931 -404.124155) (xy 32.862902 -404.189539) (xy 32.870945 -404.256363)
			(xy 32.870943 -404.32367) (xy 32.862897 -404.390494) (xy 32.846922 -404.455877) (xy 32.823247 -404.518882)
			(xy 32.792212 -404.578607) (xy 32.754261 -404.634194) (xy 32.732472 -404.659846) (xy 32.72667 -404.666987)
			(xy 32.720159 -404.684181) (xy 32.719772 -404.693374) (xy 32.719772 -405.186642) (xy 32.720168 -405.195831)
			(xy 32.726692 -405.213014) (xy 32.732472 -405.22017) (xy 32.754254 -405.245827) (xy 32.792202 -405.301413)
			(xy 32.823235 -405.361136) (xy 32.846907 -405.42414) (xy 32.862881 -405.489521) (xy 32.870925 -405.556343)
			(xy 32.870926 -405.623648) (xy 32.862882 -405.69047) (xy 32.84691 -405.755851) (xy 32.823239 -405.818856)
			(xy 32.792207 -405.878579) (xy 32.754259 -405.934166) (xy 32.732472 -405.959818) (xy 32.726682 -405.966967)
			(xy 32.720164 -405.984155) (xy 32.719772 -405.993346) (xy 32.719772 -406.151334) (xy 32.719295 -406.161493)
			(xy 32.711511 -406.180261) (xy 32.697141 -406.194624) (xy 32.678369 -406.202399) (xy 32.66821 -406.202896)
			(xy 31.95193 -406.202896) (xy 31.941778 -406.202343) (xy 31.923016 -406.194585) (xy 31.908651 -406.180237)
			(xy 31.900869 -406.161485) (xy 31.900368 -406.151334) (xy 31.900368 -405.993346) (xy 31.899921 -405.984163)
			(xy 31.893431 -405.966979) (xy 31.887668 -405.959818) (xy 31.865874 -405.934171) (xy 31.827923 -405.878584)
			(xy 31.796888 -405.81886) (xy 31.773215 -405.755855) (xy 31.757241 -405.690472) (xy 31.749197 -405.623649)
			(xy 30.620661 -405.623649) (xy 30.592063 -405.678683) (xy 30.554113 -405.734268) (xy 30.532324 -405.75992)
			(xy 30.526539 -405.767074) (xy 30.520017 -405.784258) (xy 30.519624 -405.793448) (xy 30.519624 -406.286716)
			(xy 30.520021 -406.295905) (xy 30.526543 -406.313089) (xy 30.532324 -406.320244) (xy 30.554081 -406.345922)
			(xy 30.592034 -406.401503) (xy 30.62307 -406.461223) (xy 30.646746 -406.524224) (xy 30.662723 -406.589604)
			(xy 30.67077 -406.656424) (xy 30.670773 -406.723728) (xy 30.670766 -406.723789) (xy 33.948811 -406.723789)
			(xy 33.948814 -406.656363) (xy 33.956893 -406.589422) (xy 33.972932 -406.523931) (xy 33.996701 -406.460833)
			(xy 34.027856 -406.401036) (xy 34.06595 -406.345401) (xy 34.087816 -406.319736) (xy 34.093624 -406.312599)
			(xy 34.100131 -406.295402) (xy 34.100516 -406.286208) (xy 34.100516 -405.793956) (xy 34.100123 -405.784767)
			(xy 34.093597 -405.767583) (xy 34.087816 -405.760428) (xy 34.065948 -405.734766) (xy 34.027858 -405.679132)
			(xy 33.996706 -405.619335) (xy 33.972942 -405.556238) (xy 33.956906 -405.490748) (xy 33.94883 -405.423809)
			(xy 33.948831 -405.356385) (xy 33.956907 -405.289446) (xy 33.972944 -405.223957) (xy 33.996709 -405.160859)
			(xy 34.027861 -405.101063) (xy 34.065951 -405.045429) (xy 34.087816 -405.019764) (xy 34.093612 -405.012619)
			(xy 34.100127 -404.995428) (xy 34.100516 -404.986236) (xy 34.100516 -404.828756) (xy 34.10095 -404.818642)
			(xy 34.108705 -404.79996) (xy 34.123017 -404.785666) (xy 34.14171 -404.777936) (xy 34.151824 -404.777448)
			(xy 34.868104 -404.777448) (xy 34.878207 -404.777981) (xy 34.896875 -404.78571) (xy 34.911168 -404.799992)
			(xy 34.918911 -404.818654) (xy 34.919412 -404.828756) (xy 34.919412 -404.986236) (xy 34.919802 -404.995425)
			(xy 34.926329 -405.01261) (xy 34.932112 -405.019764) (xy 34.953972 -405.045433) (xy 34.99206 -405.101067)
			(xy 35.02321 -405.160863) (xy 35.046974 -405.223959) (xy 35.063009 -405.289448) (xy 35.071085 -405.356385)
			(xy 35.071085 -405.423809) (xy 35.06301 -405.490746) (xy 35.046976 -405.556235) (xy 35.023212 -405.619332)
			(xy 35.020933 -405.623707) (xy 36.14899 -405.623707) (xy 36.14899 -405.556284) (xy 36.157066 -405.489346)
			(xy 36.173101 -405.423857) (xy 36.196864 -405.36076) (xy 36.228014 -405.300963) (xy 36.266101 -405.245328)
			(xy 36.287964 -405.219662) (xy 36.293767 -405.212522) (xy 36.300276 -405.195327) (xy 36.300664 -405.186134)
			(xy 36.300664 -404.693882) (xy 36.300248 -404.684696) (xy 36.293737 -404.667512) (xy 36.287964 -404.660354)
			(xy 36.266123 -404.63467) (xy 36.228036 -404.579038) (xy 36.196886 -404.519244) (xy 36.173122 -404.456149)
			(xy 36.157087 -404.390663) (xy 36.149009 -404.323727) (xy 36.149007 -404.256306) (xy 36.157081 -404.18937)
			(xy 36.173113 -404.123882) (xy 36.196873 -404.060787) (xy 36.228019 -404.000991) (xy 36.266103 -403.945356)
			(xy 36.287964 -403.91969) (xy 36.293755 -403.912541) (xy 36.300271 -403.895353) (xy 36.300664 -403.886162)
			(xy 36.300664 -403.728682) (xy 36.301112 -403.718551) (xy 36.30885 -403.699825) (xy 36.323149 -403.685468)
			(xy 36.341843 -403.677654) (xy 36.351972 -403.67712) (xy 37.068252 -403.67712) (xy 37.078405 -403.677561)
			(xy 37.097161 -403.685345) (xy 37.111486 -403.699736) (xy 37.119184 -403.718527) (xy 37.11956 -403.728682)
			(xy 37.11956 -403.886162) (xy 37.119998 -403.895346) (xy 37.126493 -403.91253) (xy 37.13226 -403.91969)
			(xy 37.154147 -403.945337) (xy 37.192238 -404.000973) (xy 37.22339 -404.060771) (xy 37.247154 -404.123871)
			(xy 37.26319 -404.189362) (xy 37.271264 -404.256303) (xy 37.271262 -404.32373) (xy 37.263184 -404.39067)
			(xy 37.247145 -404.456161) (xy 37.223376 -404.519259) (xy 37.192221 -404.579055) (xy 37.154127 -404.634689)
			(xy 37.13226 -404.660354) (xy 37.126453 -404.667492) (xy 37.119946 -404.684688) (xy 37.11956 -404.693882)
			(xy 37.11956 -405.186134) (xy 37.119963 -405.195322) (xy 37.126483 -405.212506) (xy 37.13226 -405.219662)
			(xy 37.154119 -405.245331) (xy 37.192211 -405.300964) (xy 37.223364 -405.36076) (xy 37.24713 -405.423856)
			(xy 37.263168 -405.489345) (xy 37.271245 -405.556284) (xy 37.271245 -405.623707) (xy 37.263169 -405.690646)
			(xy 37.247133 -405.756135) (xy 37.223368 -405.819232) (xy 37.192216 -405.879028) (xy 37.154125 -405.934661)
			(xy 37.13226 -405.960326) (xy 37.126465 -405.967472) (xy 37.11995 -405.984662) (xy 37.11956 -405.993854)
			(xy 37.11956 -406.151334) (xy 37.119101 -406.161463) (xy 37.111362 -406.180185) (xy 37.097068 -406.19454)
			(xy 37.078379 -406.202358) (xy 37.068252 -406.202896) (xy 36.351972 -406.202896) (xy 36.341816 -406.202501)
			(xy 36.323062 -406.194696) (xy 36.308739 -406.180291) (xy 36.301041 -406.161493) (xy 36.300664 -406.151334)
			(xy 36.300664 -405.993854) (xy 36.300214 -405.984671) (xy 36.293726 -405.967487) (xy 36.287964 -405.960326)
			(xy 36.266095 -405.934665) (xy 36.228009 -405.879029) (xy 36.196861 -405.819232) (xy 36.173099 -405.756135)
			(xy 36.157065 -405.690645) (xy 36.14899 -405.623707) (xy 35.020933 -405.623707) (xy 34.992063 -405.679128)
			(xy 34.953975 -405.734763) (xy 34.932112 -405.760428) (xy 34.926322 -405.767578) (xy 34.919803 -405.784765)
			(xy 34.919412 -405.793956) (xy 34.919412 -406.286208) (xy 34.919816 -406.295396) (xy 34.926334 -406.31258)
			(xy 34.932112 -406.319736) (xy 34.953944 -406.345427) (xy 34.992033 -406.401058) (xy 35.023184 -406.460851)
			(xy 35.04695 -406.523945) (xy 35.062987 -406.58943) (xy 35.071065 -406.656366) (xy 35.071068 -406.723729)
			(xy 38.34913 -406.723729) (xy 38.349133 -406.656422) (xy 38.35718 -406.589598) (xy 38.373155 -406.524215)
			(xy 38.39683 -406.461209) (xy 38.427865 -406.401484) (xy 38.465815 -406.345897) (xy 38.487604 -406.320244)
			(xy 38.493407 -406.313104) (xy 38.499918 -406.295909) (xy 38.500304 -406.286716) (xy 38.500304 -405.793448)
			(xy 38.49987 -405.784263) (xy 38.493373 -405.767079) (xy 38.487604 -405.75992) (xy 38.465813 -405.734271)
			(xy 38.427867 -405.678683) (xy 38.396836 -405.618959) (xy 38.373165 -405.555954) (xy 38.357193 -405.490572)
			(xy 38.34915 -405.423749) (xy 38.34915 -405.356445) (xy 38.357194 -405.289622) (xy 38.373167 -405.22424)
			(xy 38.396838 -405.161236) (xy 38.42787 -405.101512) (xy 38.465817 -405.045925) (xy 38.487604 -405.020272)
			(xy 38.493395 -405.013123) (xy 38.499913 -404.995935) (xy 38.500304 -404.986744) (xy 38.500304 -404.828756)
			(xy 38.500686 -404.818599) (xy 38.508497 -404.799844) (xy 38.522905 -404.785523) (xy 38.541706 -404.777825)
			(xy 38.551866 -404.777448) (xy 39.268146 -404.777448) (xy 39.278277 -404.777889) (xy 39.297 -404.785634)
			(xy 39.311355 -404.799934) (xy 39.319171 -404.818627) (xy 39.319708 -404.828756) (xy 39.319708 -404.986744)
			(xy 39.320095 -404.995934) (xy 39.326624 -405.013118) (xy 39.332408 -405.020272) (xy 39.354193 -405.045927)
			(xy 39.392146 -405.101512) (xy 39.423182 -405.161234) (xy 39.446858 -405.224239) (xy 39.462832 -405.289621)
			(xy 39.470878 -405.356444) (xy 39.470878 -405.42375) (xy 39.462833 -405.490573) (xy 39.446859 -405.555956)
			(xy 39.423185 -405.61896) (xy 39.420718 -405.623708) (xy 40.548756 -405.623708) (xy 40.548757 -405.556283)
			(xy 40.556834 -405.489343) (xy 40.572872 -405.423853) (xy 40.596639 -405.360756) (xy 40.627793 -405.30096)
			(xy 40.665886 -405.245326) (xy 40.687752 -405.219662) (xy 40.693554 -405.212521) (xy 40.700064 -405.195327)
			(xy 40.700452 -405.186134) (xy 40.700452 -404.693882) (xy 40.700039 -404.684695) (xy 40.693526 -404.667512)
			(xy 40.687752 -404.660354) (xy 40.665908 -404.634672) (xy 40.627815 -404.579041) (xy 40.59666 -404.519248)
			(xy 40.572893 -404.456153) (xy 40.556854 -404.390665) (xy 40.548776 -404.323728) (xy 40.548774 -404.256305)
			(xy 40.556848 -404.189367) (xy 40.572883 -404.123879) (xy 40.596647 -404.060783) (xy 40.627798 -404.000987)
			(xy 40.665888 -403.945354) (xy 40.687752 -403.91969) (xy 40.693542 -403.91254) (xy 40.700059 -403.895353)
			(xy 40.700452 -403.886162) (xy 40.700452 -403.728682) (xy 40.700912 -403.718553) (xy 40.708648 -403.699829)
			(xy 40.722942 -403.685473) (xy 40.741633 -403.677656) (xy 40.75176 -403.67712) (xy 41.46804 -403.67712)
			(xy 41.478199 -403.677489) (xy 41.496956 -403.685302) (xy 41.511279 -403.699715) (xy 41.518974 -403.71852)
			(xy 41.519348 -403.728682) (xy 41.519348 -403.886162) (xy 41.519788 -403.895346) (xy 41.526282 -403.91253)
			(xy 41.532048 -403.91969) (xy 41.553935 -403.945337) (xy 41.592027 -404.000973) (xy 41.62318 -404.060771)
			(xy 41.646945 -404.12387) (xy 41.66298 -404.189362) (xy 41.671055 -404.256303) (xy 41.671053 -404.32373)
			(xy 41.662974 -404.39067) (xy 41.646935 -404.456161) (xy 41.623166 -404.519259) (xy 41.59201 -404.579056)
			(xy 41.553915 -404.63469) (xy 41.532048 -404.660354) (xy 41.52624 -404.667491) (xy 41.519733 -404.684688)
			(xy 41.519348 -404.693882) (xy 41.519348 -405.186134) (xy 41.519754 -405.195321) (xy 41.526272 -405.212505)
			(xy 41.532048 -405.219662) (xy 41.553908 -405.245331) (xy 41.592 -405.300964) (xy 41.623154 -405.360759)
			(xy 41.646921 -405.423856) (xy 41.662958 -405.489345) (xy 41.671036 -405.556283) (xy 41.671036 -405.623708)
			(xy 41.66296 -405.690646) (xy 41.646924 -405.756136) (xy 41.623158 -405.819233) (xy 41.592005 -405.879028)
			(xy 41.553913 -405.934662) (xy 41.532048 -405.960326) (xy 41.526251 -405.967471) (xy 41.519738 -405.984662)
			(xy 41.519348 -405.993854) (xy 41.519348 -406.151334) (xy 41.518901 -406.161464) (xy 41.51116 -406.180189)
			(xy 41.496861 -406.194544) (xy 41.478168 -406.20236) (xy 41.46804 -406.202896) (xy 40.75176 -406.202896)
			(xy 40.741603 -406.202511) (xy 40.722849 -406.194701) (xy 40.708527 -406.180294) (xy 40.700829 -406.161494)
			(xy 40.700452 -406.151334) (xy 40.700452 -405.993854) (xy 40.700004 -405.984671) (xy 40.693515 -405.967487)
			(xy 40.687752 -405.960326) (xy 40.66588 -405.934667) (xy 40.627788 -405.879032) (xy 40.596635 -405.819236)
			(xy 40.572869 -405.756138) (xy 40.556832 -405.690648) (xy 40.548756 -405.623708) (xy 39.420718 -405.623708)
			(xy 39.392149 -405.678683) (xy 39.354197 -405.734269) (xy 39.332408 -405.75992) (xy 39.326621 -405.767072)
			(xy 39.3201 -405.784257) (xy 39.319708 -405.793448) (xy 39.319708 -406.286716) (xy 39.320109 -406.295904)
			(xy 39.326629 -406.313088) (xy 39.332408 -406.320244) (xy 39.354166 -406.345921) (xy 39.392119 -406.401503)
			(xy 39.423157 -406.461222) (xy 39.446834 -406.524224) (xy 39.46281 -406.589604) (xy 39.470858 -406.656424)
			(xy 39.470861 -406.723728) (xy 39.470854 -406.723789) (xy 42.748899 -406.723789) (xy 42.748901 -406.656363)
			(xy 42.756981 -406.589422) (xy 42.773019 -406.523932) (xy 42.796787 -406.460833) (xy 42.827942 -406.401036)
			(xy 42.866034 -406.345401) (xy 42.8879 -406.319736) (xy 42.893706 -406.312598) (xy 42.900215 -406.295402)
			(xy 42.9006 -406.286208) (xy 42.9006 -405.793956) (xy 42.900211 -405.784767) (xy 42.893683 -405.767582)
			(xy 42.8879 -405.760428) (xy 42.866032 -405.734766) (xy 42.827944 -405.679131) (xy 42.796793 -405.619334)
			(xy 42.773029 -405.556237) (xy 42.756994 -405.490748) (xy 42.748918 -405.423809) (xy 42.748919 -405.356385)
			(xy 42.756995 -405.289446) (xy 42.773031 -405.223957) (xy 42.796795 -405.16086) (xy 42.827947 -405.101064)
			(xy 42.866036 -405.045429) (xy 42.8879 -405.019764) (xy 42.893694 -405.012617) (xy 42.90021 -404.995428)
			(xy 42.9006 -404.986236) (xy 42.9006 -404.828756) (xy 42.901049 -404.818644) (xy 42.908801 -404.799965)
			(xy 42.923109 -404.785672) (xy 42.941796 -404.777939) (xy 42.951908 -404.777448) (xy 43.668188 -404.777448)
			(xy 43.67829 -404.777994) (xy 43.696958 -404.785718) (xy 43.711251 -404.799995) (xy 43.718995 -404.818655)
			(xy 43.719496 -404.828756) (xy 43.719496 -404.986236) (xy 43.71989 -404.995425) (xy 43.726415 -405.012609)
			(xy 43.732196 -405.019764) (xy 43.754056 -405.045432) (xy 43.792145 -405.101066) (xy 43.823296 -405.160862)
			(xy 43.847061 -405.223959) (xy 43.863097 -405.289447) (xy 43.871173 -405.356385) (xy 43.871173 -405.423809)
			(xy 43.863098 -405.490747) (xy 43.847063 -405.556236) (xy 43.823299 -405.619332) (xy 43.792148 -405.679128)
			(xy 43.75406 -405.734763) (xy 43.732196 -405.760428) (xy 43.726405 -405.767577) (xy 43.719887 -405.784765)
			(xy 43.719496 -405.793956) (xy 43.719496 -406.286208) (xy 43.719903 -406.295395) (xy 43.726419 -406.31258)
			(xy 43.732196 -406.319736) (xy 43.754029 -406.345427) (xy 43.792119 -406.401058) (xy 43.823271 -406.46085)
			(xy 43.847037 -406.523944) (xy 43.863075 -406.58943) (xy 43.871153 -406.656365) (xy 43.871156 -406.72373)
			(xy 47.149194 -406.72373) (xy 47.149197 -406.656422) (xy 47.157245 -406.589596) (xy 47.173223 -406.524212)
			(xy 47.196901 -406.461206) (xy 47.227941 -406.401481) (xy 47.265897 -406.345896) (xy 47.287688 -406.320244)
			(xy 47.293489 -406.313102) (xy 47.300002 -406.295909) (xy 47.300388 -406.286716) (xy 47.300388 -405.793448)
			(xy 47.299958 -405.784263) (xy 47.293458 -405.767078) (xy 47.287688 -405.75992) (xy 47.265895 -405.734272)
			(xy 47.227943 -405.678686) (xy 47.196907 -405.618962) (xy 47.173232 -405.555957) (xy 47.157258 -405.490574)
			(xy 47.149214 -405.42375) (xy 47.149214 -405.356444) (xy 47.157259 -405.28962) (xy 47.173234 -405.224237)
			(xy 47.19691 -405.161232) (xy 47.227946 -405.101509) (xy 47.265899 -405.045924) (xy 47.287688 -405.020272)
			(xy 47.293478 -405.013122) (xy 47.299997 -404.995935) (xy 47.300388 -404.986744) (xy 47.300388 -404.828756)
			(xy 47.300785 -404.818601) (xy 47.308593 -404.79985) (xy 47.322997 -404.785528) (xy 47.341792 -404.777828)
			(xy 47.35195 -404.777448) (xy 48.06823 -404.777448) (xy 48.07836 -404.777902) (xy 48.097083 -404.785641)
			(xy 48.111439 -404.799937) (xy 48.119255 -404.818629) (xy 48.119792 -404.828756) (xy 48.119792 -404.986744)
			(xy 48.120183 -404.995933) (xy 48.12671 -405.013117) (xy 48.132492 -405.020272) (xy 48.154275 -405.045928)
			(xy 48.192222 -405.101514) (xy 48.223254 -405.161238) (xy 48.246925 -405.224242) (xy 48.262897 -405.289623)
			(xy 48.270941 -405.356445) (xy 48.270942 -405.423749) (xy 48.262899 -405.490571) (xy 48.246927 -405.555952)
			(xy 48.223256 -405.618957) (xy 48.192225 -405.67868) (xy 48.154279 -405.734267) (xy 48.132492 -405.75992)
			(xy 48.126704 -405.767071) (xy 48.120184 -405.784257) (xy 48.119792 -405.793448) (xy 48.119792 -406.286716)
			(xy 48.120196 -406.295904) (xy 48.126714 -406.313088) (xy 48.132492 -406.320244) (xy 48.154247 -406.345922)
			(xy 48.192195 -406.401506) (xy 48.223228 -406.461226) (xy 48.246901 -406.524227) (xy 48.262876 -406.589606)
			(xy 48.270922 -406.656425) (xy 48.270925 -406.723727) (xy 48.262884 -406.790547) (xy 48.246916 -406.855927)
			(xy 48.223248 -406.91893) (xy 48.19222 -406.978653) (xy 48.154277 -407.034239) (xy 48.132492 -407.059892)
			(xy 48.126715 -407.067051) (xy 48.120189 -407.084231) (xy 48.119792 -407.09342) (xy 48.119792 -407.251408)
			(xy 48.119385 -407.261564) (xy 48.111585 -407.280318) (xy 48.097184 -407.294641) (xy 48.078388 -407.302339)
			(xy 48.06823 -407.302716) (xy 47.35195 -407.302716) (xy 47.341821 -407.302231) (xy 47.323093 -407.294512)
			(xy 47.308733 -407.280224) (xy 47.30092 -407.261534) (xy 47.300388 -407.251408) (xy 47.300388 -407.09342)
			(xy 47.299971 -407.084233) (xy 47.293462 -407.067049) (xy 47.287688 -407.059892) (xy 47.265867 -407.034266)
			(xy 47.227916 -406.978677) (xy 47.196882 -406.91895) (xy 47.173209 -406.855942) (xy 47.157236 -406.790556)
			(xy 47.149194 -406.72373) (xy 43.871156 -406.72373) (xy 43.871156 -406.723787) (xy 43.863084 -406.790723)
			(xy 43.847051 -406.85621) (xy 43.823291 -406.919306) (xy 43.792143 -406.979101) (xy 43.754058 -407.034735)
			(xy 43.732196 -407.0604) (xy 43.726416 -407.067557) (xy 43.719892 -407.084739) (xy 43.719496 -407.093928)
			(xy 43.719496 -407.251408) (xy 43.71909 -407.261531) (xy 43.711339 -407.280236) (xy 43.697019 -407.29455)
			(xy 43.678312 -407.302294) (xy 43.668188 -407.302716) (xy 42.951908 -407.302716) (xy 42.941802 -407.302209)
			(xy 42.923127 -407.294477) (xy 42.908832 -407.280187) (xy 42.901094 -407.261514) (xy 42.9006 -407.251408)
			(xy 42.9006 -407.093928) (xy 42.900176 -407.084742) (xy 42.893672 -407.067558) (xy 42.8879 -407.0604)
			(xy 42.866005 -407.034761) (xy 42.827917 -406.979122) (xy 42.796768 -406.919323) (xy 42.773005 -406.856222)
			(xy 42.756972 -406.79073) (xy 42.748899 -406.723789) (xy 39.470854 -406.723789) (xy 39.462819 -406.790549)
			(xy 39.446848 -406.85593) (xy 39.423176 -406.918933) (xy 39.392144 -406.978656) (xy 39.354195 -407.034241)
			(xy 39.332408 -407.059892) (xy 39.326633 -407.067053) (xy 39.320105 -407.084231) (xy 39.319708 -407.09342)
			(xy 39.319708 -407.251408) (xy 39.319285 -407.261562) (xy 39.311488 -407.280313) (xy 39.297092 -407.294635)
			(xy 39.278302 -407.302336) (xy 39.268146 -407.302716) (xy 38.551866 -407.302716) (xy 38.541732 -407.3023)
			(xy 38.523001 -407.294553) (xy 38.508645 -407.280245) (xy 38.500835 -407.261541) (xy 38.500304 -407.251408)
			(xy 38.500304 -407.09342) (xy 38.499883 -407.084234) (xy 38.493377 -407.06705) (xy 38.487604 -407.059892)
			(xy 38.465786 -407.034265) (xy 38.42784 -406.978674) (xy 38.39681 -406.918947) (xy 38.373141 -406.855939)
			(xy 38.357171 -406.790554) (xy 38.34913 -406.723729) (xy 35.071068 -406.723729) (xy 35.071068 -406.723786)
			(xy 35.062996 -406.790722) (xy 35.046964 -406.856209) (xy 35.023204 -406.919305) (xy 34.992058 -406.9791)
			(xy 34.953974 -407.034735) (xy 34.932112 -407.0604) (xy 34.926334 -407.067559) (xy 34.919808 -407.084739)
			(xy 34.919412 -407.093928) (xy 34.919412 -407.251408) (xy 34.918922 -407.261516) (xy 34.911184 -407.280192)
			(xy 34.896888 -407.294486) (xy 34.878212 -407.302222) (xy 34.868104 -407.302716) (xy 34.151824 -407.302716)
			(xy 34.141705 -407.302265) (xy 34.123005 -407.294528) (xy 34.10869 -407.280222) (xy 34.100941 -407.261527)
			(xy 34.100516 -407.251408) (xy 34.100516 -407.093928) (xy 34.100089 -407.084743) (xy 34.093586 -407.067558)
			(xy 34.087816 -407.0604) (xy 34.06592 -407.034761) (xy 34.027831 -406.979123) (xy 33.996681 -406.919323)
			(xy 33.972918 -406.856223) (xy 33.956884 -406.790731) (xy 33.948811 -406.723789) (xy 30.670766 -406.723789)
			(xy 30.662731 -406.790549) (xy 30.646761 -406.855929) (xy 30.62309 -406.918933) (xy 30.592058 -406.978655)
			(xy 30.554111 -407.03424) (xy 30.532324 -407.059892) (xy 30.526551 -407.067054) (xy 30.520022 -407.084232)
			(xy 30.519624 -407.09342) (xy 30.519624 -407.251408) (xy 30.519185 -407.26156) (xy 30.511392 -407.280307)
			(xy 30.497001 -407.29463) (xy 30.478216 -407.302333) (xy 30.468062 -407.302716) (xy 29.751782 -407.302716)
			(xy 29.741649 -407.302287) (xy 29.722919 -407.294545) (xy 29.708561 -407.280241) (xy 29.700751 -407.261539)
			(xy 29.70022 -407.251408) (xy 29.70022 -407.09342) (xy 29.699796 -407.084234) (xy 29.693291 -407.06705)
			(xy 29.68752 -407.059892) (xy 29.665701 -407.034265) (xy 29.627755 -406.978675) (xy 29.596724 -406.918948)
			(xy 29.573054 -406.85594) (xy 29.557084 -406.790555) (xy 29.549042 -406.72373) (xy 0.508 -406.72373)
			(xy 0.508 -409.523886) (xy 27.348881 -409.523886) (xy 27.348884 -409.45646) (xy 27.356963 -409.38952)
			(xy 27.373002 -409.324029) (xy 27.396769 -409.26093) (xy 27.427923 -409.201133) (xy 27.466015 -409.145498)
			(xy 27.48788 -409.119832) (xy 27.493686 -409.112693) (xy 27.500196 -409.095498) (xy 27.50058 -409.086304)
			(xy 27.50058 -408.594052) (xy 27.500149 -408.584867) (xy 27.49365 -408.567682) (xy 27.48788 -408.560524)
			(xy 27.466009 -408.534865) (xy 27.427922 -408.479229) (xy 27.396772 -408.419432) (xy 27.37301 -408.356334)
			(xy 27.356975 -408.290845) (xy 27.3489 -408.223906) (xy 27.348901 -408.156482) (xy 27.356977 -408.089544)
			(xy 27.373013 -408.024054) (xy 27.396777 -407.960957) (xy 27.427928 -407.901161) (xy 27.466016 -407.845526)
			(xy 27.48788 -407.81986) (xy 27.493674 -407.812713) (xy 27.500191 -407.795524) (xy 27.50058 -407.786332)
			(xy 27.50058 -407.628852) (xy 27.501045 -407.618743) (xy 27.508795 -407.600067) (xy 27.523098 -407.585775)
			(xy 27.541778 -407.578038) (xy 27.551888 -407.577544) (xy 28.268168 -407.577544) (xy 28.278268 -407.57811)
			(xy 28.296935 -407.585826) (xy 28.311229 -407.600098) (xy 28.318975 -407.618753) (xy 28.319476 -407.628852)
			(xy 28.319476 -407.786332) (xy 28.319876 -407.79552) (xy 28.326397 -407.812704) (xy 28.332176 -407.81986)
			(xy 28.354033 -407.845531) (xy 28.392123 -407.901164) (xy 28.423276 -407.96096) (xy 28.447042 -408.024056)
			(xy 28.463078 -408.089544) (xy 28.471155 -408.156482) (xy 28.471156 -408.223906) (xy 28.46308 -408.290844)
			(xy 28.447045 -408.356333) (xy 28.423281 -408.419429) (xy 28.39213 -408.479225) (xy 28.35404 -408.534859)
			(xy 28.332176 -408.560524) (xy 28.326384 -408.567672) (xy 28.319867 -408.584861) (xy 28.319476 -408.594052)
			(xy 28.319476 -409.086304) (xy 28.319889 -409.095491) (xy 28.326401 -409.112675) (xy 28.332176 -409.119832)
			(xy 28.354005 -409.145526) (xy 28.392097 -409.201156) (xy 28.42325 -409.260948) (xy 28.447018 -409.324041)
			(xy 28.463056 -409.389527) (xy 28.471135 -409.456462) (xy 28.471139 -409.523884) (xy 28.463066 -409.59082)
			(xy 28.447034 -409.656307) (xy 28.423273 -409.719403) (xy 28.392125 -409.779198) (xy 28.354039 -409.834831)
			(xy 28.332176 -409.860496) (xy 28.326396 -409.867653) (xy 28.319872 -409.884835) (xy 28.319476 -409.894024)
			(xy 28.319476 -410.051504) (xy 28.319087 -410.06163) (xy 28.311333 -410.080338) (xy 28.297008 -410.094653)
			(xy 28.278294 -410.102394) (xy 28.268168 -410.102812) (xy 27.551888 -410.102812) (xy 27.54178 -410.102325)
			(xy 27.523104 -410.094585) (xy 27.50881 -410.080289) (xy 27.501074 -410.061612) (xy 27.50058 -410.051504)
			(xy 27.50058 -409.894024) (xy 27.500163 -409.884837) (xy 27.493655 -409.867653) (xy 27.48788 -409.860496)
			(xy 27.465981 -409.83486) (xy 27.427895 -409.77922) (xy 27.396747 -409.71942) (xy 27.372986 -409.656319)
			(xy 27.356953 -409.590827) (xy 27.348881 -409.523886) (xy 0.508 -409.523886) (xy 0.508 -410.623641)
			(xy 29.549054 -410.623641) (xy 29.549055 -410.556335) (xy 29.5571 -410.489512) (xy 29.573074 -410.424129)
			(xy 29.596748 -410.361124) (xy 29.627782 -410.301399) (xy 29.665732 -410.245812) (xy 29.68752 -410.22016)
			(xy 29.693318 -410.213016) (xy 29.699831 -410.195825) (xy 29.70022 -410.186632) (xy 29.70022 -409.693364)
			(xy 29.699823 -409.684176) (xy 29.6933 -409.666992) (xy 29.68752 -409.659836) (xy 29.665745 -409.634174)
			(xy 29.627797 -409.578588) (xy 29.596764 -409.518866) (xy 29.573091 -409.455863) (xy 29.557118 -409.390482)
			(xy 29.549073 -409.323661) (xy 29.549072 -409.256357) (xy 29.557115 -409.189536) (xy 29.573086 -409.124154)
			(xy 29.596757 -409.06115) (xy 29.627787 -409.001427) (xy 29.665734 -408.94584) (xy 29.68752 -408.920188)
			(xy 29.693306 -408.913036) (xy 29.699827 -408.895851) (xy 29.70022 -408.88666) (xy 29.70022 -408.728672)
			(xy 29.700599 -408.718514) (xy 29.708408 -408.699757) (xy 29.722817 -408.685434) (xy 29.741621 -408.677738)
			(xy 29.751782 -408.677364) (xy 30.468062 -408.677364) (xy 30.478189 -408.677859) (xy 30.496914 -408.685578)
			(xy 30.511272 -408.699863) (xy 30.519089 -408.718547) (xy 30.519624 -408.728672) (xy 30.519624 -408.88666)
			(xy 30.520048 -408.895846) (xy 30.526551 -408.913031) (xy 30.532324 -408.920188) (xy 30.554125 -408.94583)
			(xy 30.592075 -409.001417) (xy 30.62311 -409.061142) (xy 30.646784 -409.124148) (xy 30.662757 -409.189531)
			(xy 30.670801 -409.256356) (xy 30.6708 -409.323662) (xy 30.662754 -409.390486) (xy 30.646779 -409.45587)
			(xy 30.623103 -409.518875) (xy 30.62053 -409.523827) (xy 31.749176 -409.523827) (xy 31.749179 -409.456519)
			(xy 31.757227 -409.389693) (xy 31.773205 -409.324309) (xy 31.796883 -409.261302) (xy 31.827922 -409.201578)
			(xy 31.865877 -409.145992) (xy 31.887668 -409.12034) (xy 31.893481 -409.113207) (xy 31.899984 -409.096007)
			(xy 31.900368 -409.086812) (xy 31.900368 -408.593544) (xy 31.899922 -408.584361) (xy 31.893432 -408.567177)
			(xy 31.887668 -408.560016) (xy 31.865872 -408.534371) (xy 31.827921 -408.478784) (xy 31.796887 -408.41906)
			(xy 31.773213 -408.356054) (xy 31.75724 -408.290671) (xy 31.749196 -408.223847) (xy 31.749197 -408.156541)
			(xy 31.757242 -408.089717) (xy 31.773217 -408.024334) (xy 31.796892 -407.961329) (xy 31.827927 -407.901606)
			(xy 31.865879 -407.84602) (xy 31.887668 -407.820368) (xy 31.893469 -407.813226) (xy 31.899979 -407.796033)
			(xy 31.900368 -407.78684) (xy 31.900368 -407.628852) (xy 31.900782 -407.618699) (xy 31.908587 -407.599952)
			(xy 31.922985 -407.585631) (xy 31.941775 -407.577927) (xy 31.95193 -407.577544) (xy 32.66821 -407.577544)
			(xy 32.678338 -407.578019) (xy 32.69706 -407.58575) (xy 32.711416 -407.60004) (xy 32.719234 -407.618727)
			(xy 32.719772 -407.628852) (xy 32.719772 -407.78684) (xy 32.720169 -407.796028) (xy 32.726693 -407.813212)
			(xy 32.732472 -407.820368) (xy 32.754252 -407.846027) (xy 32.7922 -407.901612) (xy 32.823233 -407.961335)
			(xy 32.846906 -408.024339) (xy 32.862879 -408.08972) (xy 32.870924 -408.156542) (xy 32.870924 -408.223846)
			(xy 32.862881 -408.290668) (xy 32.846909 -408.35605) (xy 32.823238 -408.419054) (xy 32.792206 -408.478777)
			(xy 32.754259 -408.534364) (xy 32.732472 -408.560016) (xy 32.726682 -408.567166) (xy 32.720164 -408.584353)
			(xy 32.719772 -408.593544) (xy 32.719772 -409.086812) (xy 32.720183 -409.095999) (xy 32.726697 -409.113183)
			(xy 32.732472 -409.12034) (xy 32.754224 -409.146022) (xy 32.792173 -409.201604) (xy 32.823207 -409.261324)
			(xy 32.846881 -409.324324) (xy 32.862857 -409.389703) (xy 32.870903 -409.456522) (xy 32.870907 -409.523824)
			(xy 32.862866 -409.590644) (xy 32.846897 -409.656024) (xy 32.823229 -409.719027) (xy 32.792201 -409.778749)
			(xy 32.754257 -409.834336) (xy 32.732472 -409.859988) (xy 32.726652 -409.867116) (xy 32.720152 -409.88432)
			(xy 32.719772 -409.893516) (xy 32.719772 -410.051504) (xy 32.719381 -410.061662) (xy 32.711579 -410.08042)
			(xy 32.697172 -410.094744) (xy 32.67837 -410.102438) (xy 32.66821 -410.102812) (xy 31.95193 -410.102812)
			(xy 31.941812 -410.102251) (xy 31.923101 -410.094542) (xy 31.908745 -410.080279) (xy 31.900916 -410.061619)
			(xy 31.900368 -410.051504) (xy 31.900368 -409.893516) (xy 31.899935 -409.884332) (xy 31.893436 -409.867148)
			(xy 31.887668 -409.859988) (xy 31.865844 -409.834366) (xy 31.827894 -409.778775) (xy 31.796861 -409.719048)
			(xy 31.773189 -409.65604) (xy 31.757217 -409.590654) (xy 31.749176 -409.523827) (xy 30.62053 -409.523827)
			(xy 30.592066 -409.578598) (xy 30.554113 -409.634184) (xy 30.532324 -409.659836) (xy 30.526532 -409.666985)
			(xy 30.520014 -409.684172) (xy 30.519624 -409.693364) (xy 30.519624 -410.186632) (xy 30.520014 -410.195821)
			(xy 30.526541 -410.213006) (xy 30.532324 -410.22016) (xy 30.554097 -410.245825) (xy 30.592049 -410.301408)
			(xy 30.623085 -410.36113) (xy 30.64676 -410.424133) (xy 30.662735 -410.489514) (xy 30.670781 -410.556336)
			(xy 30.670783 -410.62364) (xy 30.670776 -410.623701) (xy 33.948822 -410.623701) (xy 33.948823 -410.556275)
			(xy 33.956901 -410.489336) (xy 33.972939 -410.423846) (xy 33.996705 -410.360748) (xy 34.027859 -410.300951)
			(xy 34.065951 -410.245317) (xy 34.087816 -410.219652) (xy 34.093617 -410.21251) (xy 34.100129 -410.195317)
			(xy 34.100516 -410.186124) (xy 34.100516 -409.693872) (xy 34.100116 -409.684684) (xy 34.093595 -409.6675)
			(xy 34.087816 -409.660344) (xy 34.065963 -409.634669) (xy 34.027873 -409.579037) (xy 33.996721 -409.519242)
			(xy 33.972955 -409.456146) (xy 33.956919 -409.390658) (xy 33.948842 -409.323721) (xy 33.948841 -409.256297)
			(xy 33.956915 -409.18936) (xy 33.97295 -409.123871) (xy 33.996714 -409.060775) (xy 34.027864 -409.000979)
			(xy 34.065952 -408.945345) (xy 34.087816 -408.91968) (xy 34.093605 -408.91253) (xy 34.100124 -408.895343)
			(xy 34.100516 -408.886152) (xy 34.100516 -408.728672) (xy 34.100962 -408.718559) (xy 34.108712 -408.699878)
			(xy 34.123021 -408.685583) (xy 34.141711 -408.677852) (xy 34.151824 -408.677364) (xy 34.868104 -408.677364)
			(xy 34.878209 -408.677881) (xy 34.89688 -408.685613) (xy 34.911173 -408.6999) (xy 34.918914 -408.718568)
			(xy 34.919412 -408.728672) (xy 34.919412 -408.886152) (xy 34.919842 -408.895337) (xy 34.926342 -408.912522)
			(xy 34.932112 -408.91968) (xy 34.953987 -408.945336) (xy 34.992075 -409.000972) (xy 35.023224 -409.06077)
			(xy 35.046987 -409.123868) (xy 35.063022 -409.189358) (xy 35.071096 -409.256297) (xy 35.071095 -409.323721)
			(xy 35.063018 -409.39066) (xy 35.046982 -409.45615) (xy 35.023217 -409.519247) (xy 35.0208 -409.523886)
			(xy 36.148969 -409.523886) (xy 36.148972 -409.45646) (xy 36.157051 -409.38952) (xy 36.173089 -409.324029)
			(xy 36.196856 -409.260931) (xy 36.228009 -409.201134) (xy 36.266099 -409.145498) (xy 36.287964 -409.119832)
			(xy 36.29378 -409.112701) (xy 36.300281 -409.095499) (xy 36.300664 -409.086304) (xy 36.300664 -408.594052)
			(xy 36.300215 -408.584869) (xy 36.293727 -408.567685) (xy 36.287964 -408.560524) (xy 36.266093 -408.534865)
			(xy 36.228007 -408.479228) (xy 36.196859 -408.419431) (xy 36.173097 -408.356334) (xy 36.157063 -408.290844)
			(xy 36.148988 -408.223906) (xy 36.148989 -408.156482) (xy 36.157065 -408.089544) (xy 36.1731 -408.024055)
			(xy 36.196864 -407.960958) (xy 36.228014 -407.901161) (xy 36.266101 -407.845526) (xy 36.287964 -407.81986)
			(xy 36.293768 -407.81272) (xy 36.300276 -407.795525) (xy 36.300664 -407.786332) (xy 36.300664 -407.628852)
			(xy 36.301145 -407.618745) (xy 36.308892 -407.600072) (xy 36.323189 -407.585781) (xy 36.341864 -407.578041)
			(xy 36.351972 -407.577544) (xy 37.068252 -407.577544) (xy 37.078351 -407.578123) (xy 37.097017 -407.585835)
			(xy 37.111312 -407.600102) (xy 37.119058 -407.618754) (xy 37.11956 -407.628852) (xy 37.11956 -407.786332)
			(xy 37.119964 -407.79552) (xy 37.126483 -407.812703) (xy 37.13226 -407.81986) (xy 37.154118 -407.845531)
			(xy 37.192209 -407.901164) (xy 37.223362 -407.960959) (xy 37.247129 -408.024055) (xy 37.263166 -408.089544)
			(xy 37.271243 -408.156482) (xy 37.271244 -408.223906) (xy 37.263168 -408.290844) (xy 37.247132 -408.356333)
			(xy 37.223367 -408.41943) (xy 37.192215 -408.479226) (xy 37.154125 -408.534859) (xy 37.13226 -408.560524)
			(xy 37.126466 -408.567671) (xy 37.119951 -408.58486) (xy 37.11956 -408.594052) (xy 37.11956 -409.086304)
			(xy 37.119977 -409.09549) (xy 37.126487 -409.112674) (xy 37.13226 -409.119832) (xy 37.15409 -409.145526)
			(xy 37.192182 -409.201155) (xy 37.223337 -409.260947) (xy 37.247105 -409.32404) (xy 37.263144 -409.389526)
			(xy 37.271223 -409.456462) (xy 37.271227 -409.523884) (xy 37.263154 -409.59082) (xy 37.247121 -409.656308)
			(xy 37.223359 -409.719403) (xy 37.19221 -409.779198) (xy 37.154123 -409.834831) (xy 37.13226 -409.860496)
			(xy 37.126478 -409.867651) (xy 37.119955 -409.884834) (xy 37.11956 -409.894024) (xy 37.11956 -410.051504)
			(xy 37.119186 -410.061632) (xy 37.111429 -410.080343) (xy 37.097099 -410.094659) (xy 37.07838 -410.102396)
			(xy 37.068252 -410.102812) (xy 36.351972 -410.102812) (xy 36.341863 -410.102338) (xy 36.323186 -410.094594)
			(xy 36.308893 -410.080293) (xy 36.301157 -410.061613) (xy 36.300664 -410.051504) (xy 36.300664 -409.894024)
			(xy 36.300228 -409.88484) (xy 36.293731 -409.867656) (xy 36.287964 -409.860496) (xy 36.266066 -409.834859)
			(xy 36.227981 -409.77922) (xy 36.196834 -409.719419) (xy 36.173073 -409.656319) (xy 36.157041 -409.590827)
			(xy 36.148969 -409.523886) (xy 35.0208 -409.523886) (xy 34.992066 -409.579044) (xy 34.953976 -409.634679)
			(xy 34.932112 -409.660344) (xy 34.926316 -409.667489) (xy 34.9198 -409.68468) (xy 34.919412 -409.693872)
			(xy 34.919412 -410.186124) (xy 34.919808 -410.195313) (xy 34.926331 -410.212497) (xy 34.932112 -410.219652)
			(xy 34.95396 -410.24533) (xy 34.992048 -410.300963) (xy 35.023199 -410.360758) (xy 35.046964 -410.423853)
			(xy 35.063 -410.48934) (xy 35.071077 -410.556277) (xy 35.071078 -410.623641) (xy 38.349141 -410.623641)
			(xy 38.349143 -410.556335) (xy 38.357188 -410.489512) (xy 38.373162 -410.424129) (xy 38.396835 -410.361124)
			(xy 38.427868 -410.3014) (xy 38.465816 -410.245813) (xy 38.487604 -410.22016) (xy 38.493401 -410.213015)
			(xy 38.499915 -410.195824) (xy 38.500304 -410.186632) (xy 38.500304 -409.693364) (xy 38.49991 -409.684175)
			(xy 38.493385 -409.666991) (xy 38.487604 -409.659836) (xy 38.465829 -409.634174) (xy 38.427882 -409.578588)
			(xy 38.39685 -409.518865) (xy 38.373178 -409.455862) (xy 38.357206 -409.390482) (xy 38.349161 -409.323661)
			(xy 38.34916 -409.256357) (xy 38.357202 -409.189536) (xy 38.373173 -409.124155) (xy 38.396843 -409.061151)
			(xy 38.427873 -409.001428) (xy 38.465818 -408.945841) (xy 38.487604 -408.920188) (xy 38.493389 -408.913034)
			(xy 38.49991 -408.89585) (xy 38.500304 -408.88666) (xy 38.500304 -408.728672) (xy 38.500699 -408.718516)
			(xy 38.508504 -408.699762) (xy 38.522909 -408.685439) (xy 38.541707 -408.677741) (xy 38.551866 -408.677364)
			(xy 39.268146 -408.677364) (xy 39.278279 -408.67779) (xy 39.297005 -408.685537) (xy 39.311361 -408.699842)
			(xy 39.319174 -408.718541) (xy 39.319708 -408.728672) (xy 39.319708 -408.88666) (xy 39.320136 -408.895845)
			(xy 39.326637 -408.91303) (xy 39.332408 -408.920188) (xy 39.354209 -408.94583) (xy 39.392161 -409.001416)
			(xy 39.423197 -409.061141) (xy 39.446871 -409.124147) (xy 39.462845 -409.189531) (xy 39.470889 -409.256356)
			(xy 39.470888 -409.323663) (xy 39.462842 -409.390487) (xy 39.446866 -409.45587) (xy 39.423189 -409.518876)
			(xy 39.420585 -409.523887) (xy 40.548735 -409.523887) (xy 40.548738 -409.456459) (xy 40.556818 -409.389518)
			(xy 40.572859 -409.324026) (xy 40.59663 -409.260927) (xy 40.627788 -409.20113) (xy 40.665884 -409.145496)
			(xy 40.687752 -409.119832) (xy 40.693566 -409.1127) (xy 40.700069 -409.095499) (xy 40.700452 -409.086304)
			(xy 40.700452 -408.594052) (xy 40.700005 -408.584869) (xy 40.693516 -408.567685) (xy 40.687752 -408.560524)
			(xy 40.665878 -408.534866) (xy 40.627786 -408.479232) (xy 40.596633 -408.419435) (xy 40.572867 -408.356337)
			(xy 40.556831 -408.290847) (xy 40.548755 -408.223907) (xy 40.548755 -408.156481) (xy 40.556833 -408.089542)
			(xy 40.572871 -408.024051) (xy 40.596638 -407.960954) (xy 40.627793 -407.901158) (xy 40.665886 -407.845524)
			(xy 40.687752 -407.81986) (xy 40.693554 -407.812719) (xy 40.700064 -407.795525) (xy 40.700452 -407.786332)
			(xy 40.700452 -407.628852) (xy 40.700945 -407.618746) (xy 40.708689 -407.600076) (xy 40.722983 -407.585785)
			(xy 40.741654 -407.578043) (xy 40.75176 -407.577544) (xy 41.46804 -407.577544) (xy 41.478144 -407.578051)
			(xy 41.496813 -407.585791) (xy 41.511104 -407.600081) (xy 41.518847 -407.618748) (xy 41.519348 -407.628852)
			(xy 41.519348 -407.786332) (xy 41.519755 -407.795519) (xy 41.526272 -407.812703) (xy 41.532048 -407.81986)
			(xy 41.553906 -407.845531) (xy 41.591998 -407.901163) (xy 41.623152 -407.960958) (xy 41.646919 -408.024055)
			(xy 41.662957 -408.089543) (xy 41.671034 -408.156482) (xy 41.671035 -408.223906) (xy 41.662959 -408.290845)
			(xy 41.646923 -408.356334) (xy 41.623157 -408.419431) (xy 41.592004 -408.479226) (xy 41.553913 -408.53486)
			(xy 41.532048 -408.560524) (xy 41.526252 -408.56767) (xy 41.519739 -408.58486) (xy 41.519348 -408.594052)
			(xy 41.519348 -409.086304) (xy 41.519768 -409.09549) (xy 41.526276 -409.112674) (xy 41.532048 -409.119832)
			(xy 41.553878 -409.145526) (xy 41.591972 -409.201155) (xy 41.623127 -409.260947) (xy 41.646895 -409.32404)
			(xy 41.662935 -409.389526) (xy 41.671014 -409.456462) (xy 41.671018 -409.523884) (xy 41.662945 -409.590821)
			(xy 41.646911 -409.656308) (xy 41.623149 -409.719404) (xy 41.591999 -409.779199) (xy 41.553912 -409.834832)
			(xy 41.532048 -409.860496) (xy 41.526264 -409.86765) (xy 41.519743 -409.884834) (xy 41.519348 -409.894024)
			(xy 41.519348 -410.051504) (xy 41.518819 -410.061607) (xy 41.511089 -410.080276) (xy 41.496806 -410.094569)
			(xy 41.478143 -410.102312) (xy 41.46804 -410.102812) (xy 40.75176 -410.102812) (xy 40.74165 -410.102348)
			(xy 40.722973 -410.094599) (xy 40.70868 -410.080296) (xy 40.700945 -410.061614) (xy 40.700452 -410.051504)
			(xy 40.700452 -409.894024) (xy 40.700019 -409.884839) (xy 40.69352 -409.867655) (xy 40.687752 -409.860496)
			(xy 40.665851 -409.834861) (xy 40.62776 -409.779223) (xy 40.596608 -409.719423) (xy 40.572843 -409.656322)
			(xy 40.556809 -409.590829) (xy 40.548735 -409.523887) (xy 39.420585 -409.523887) (xy 39.392152 -409.578599)
			(xy 39.354198 -409.634185) (xy 39.332408 -409.659836) (xy 39.326615 -409.666984) (xy 39.320098 -409.684172)
			(xy 39.319708 -409.693364) (xy 39.319708 -410.186632) (xy 39.320101 -410.195821) (xy 39.326626 -410.213005)
			(xy 39.332408 -410.22016) (xy 39.354182 -410.245824) (xy 39.392134 -410.301408) (xy 39.423171 -410.361129)
			(xy 39.446847 -410.424132) (xy 39.462823 -410.489513) (xy 39.470869 -410.556336) (xy 39.470871 -410.62364)
			(xy 39.470864 -410.6237) (xy 42.74891 -410.6237) (xy 42.748911 -410.556276) (xy 42.756989 -410.489336)
			(xy 42.773026 -410.423846) (xy 42.796792 -410.360749) (xy 42.827944 -410.300952) (xy 42.866035 -410.245317)
			(xy 42.8879 -410.219652) (xy 42.893699 -410.212509) (xy 42.900212 -410.195317) (xy 42.9006 -410.186124)
			(xy 42.9006 -409.693872) (xy 42.900204 -409.684683) (xy 42.89368 -409.667499) (xy 42.8879 -409.660344)
			(xy 42.866048 -409.634669) (xy 42.827959 -409.579036) (xy 42.796808 -409.519241) (xy 42.773043 -409.456145)
			(xy 42.757006 -409.390658) (xy 42.74893 -409.32372) (xy 42.748928 -409.256298) (xy 42.757003 -409.18936)
			(xy 42.773037 -409.123872) (xy 42.7968 -409.060775) (xy 42.827949 -409.00098) (xy 42.866037 -408.945345)
			(xy 42.8879 -408.91968) (xy 42.893688 -408.912528) (xy 42.900208 -408.895343) (xy 42.9006 -408.886152)
			(xy 42.9006 -408.728672) (xy 42.901062 -408.718561) (xy 42.908809 -408.699883) (xy 42.923113 -408.685589)
			(xy 42.941797 -408.677855) (xy 42.951908 -408.677364) (xy 43.668188 -408.677364) (xy 43.678292 -408.677894)
			(xy 43.696963 -408.685621) (xy 43.711257 -408.699904) (xy 43.718998 -408.718569) (xy 43.719496 -408.728672)
			(xy 43.719496 -408.886152) (xy 43.71993 -408.895337) (xy 43.726427 -408.912521) (xy 43.732196 -408.91968)
			(xy 43.754072 -408.945335) (xy 43.792161 -409.000971) (xy 43.823311 -409.060769) (xy 43.847075 -409.123867)
			(xy 43.863109 -409.189357) (xy 43.871184 -409.256297) (xy 43.871183 -409.323721) (xy 43.863106 -409.390661)
			(xy 43.847069 -409.45615) (xy 43.823304 -409.519248) (xy 43.792151 -409.579044) (xy 43.754061 -409.634679)
			(xy 43.732196 -409.660344) (xy 43.726398 -409.667488) (xy 43.719884 -409.684679) (xy 43.719496 -409.693872)
			(xy 43.719496 -410.186124) (xy 43.719895 -410.195312) (xy 43.726417 -410.212497) (xy 43.732196 -410.219652)
			(xy 43.754044 -410.24533) (xy 43.792134 -410.300963) (xy 43.823285 -410.360757) (xy 43.847051 -410.423852)
			(xy 43.863087 -410.48934) (xy 43.871165 -410.556277) (xy 43.871166 -410.623642) (xy 47.149205 -410.623642)
			(xy 47.149207 -410.556334) (xy 47.157253 -410.48951) (xy 47.173229 -410.424126) (xy 47.196906 -410.361121)
			(xy 47.227944 -410.301397) (xy 47.265898 -410.245812) (xy 47.287688 -410.22016) (xy 47.293483 -410.213013)
			(xy 47.299999 -410.195824) (xy 47.300388 -410.186632) (xy 47.300388 -409.693364) (xy 47.299998 -409.684175)
			(xy 47.293471 -409.66699) (xy 47.287688 -409.659836) (xy 47.265911 -409.634175) (xy 47.227958 -409.578591)
			(xy 47.196922 -409.518869) (xy 47.173246 -409.455866) (xy 47.157271 -409.390484) (xy 47.149225 -409.323662)
			(xy 47.149224 -409.256357) (xy 47.157268 -409.189534) (xy 47.173241 -409.124152) (xy 47.196914 -409.061148)
			(xy 47.227949 -409.001425) (xy 47.2659 -408.945839) (xy 47.287688 -408.920188) (xy 47.293471 -408.913033)
			(xy 47.299994 -408.89585) (xy 47.300388 -408.88666) (xy 47.300388 -408.728672) (xy 47.300798 -408.718518)
			(xy 47.308601 -408.699767) (xy 47.323001 -408.685445) (xy 47.341793 -408.677744) (xy 47.35195 -408.677364)
			(xy 48.06823 -408.677364) (xy 48.078362 -408.677803) (xy 48.097088 -408.685545) (xy 48.111444 -408.699846)
			(xy 48.119258 -408.718542) (xy 48.119792 -408.728672) (xy 48.119792 -408.88666) (xy 48.120223 -408.895845)
			(xy 48.126722 -408.913029) (xy 48.132492 -408.920188) (xy 48.154291 -408.945831) (xy 48.192237 -409.001419)
			(xy 48.223268 -409.061145) (xy 48.246939 -409.12415) (xy 48.26291 -409.189533) (xy 48.270953 -409.256356)
			(xy 48.270952 -409.323662) (xy 48.262907 -409.390485) (xy 48.246933 -409.455867) (xy 48.223261 -409.518872)
			(xy 48.192228 -409.578596) (xy 48.15428 -409.634183) (xy 48.132492 -409.659836) (xy 48.126697 -409.666982)
			(xy 48.120182 -409.684172) (xy 48.119792 -409.693364) (xy 48.119792 -410.186632) (xy 48.120188 -410.195821)
			(xy 48.126712 -410.213005) (xy 48.132492 -410.22016) (xy 48.154263 -410.245825) (xy 48.19221 -410.301411)
			(xy 48.223243 -410.361133) (xy 48.246915 -410.424135) (xy 48.262888 -410.489516) (xy 48.270933 -410.556336)
			(xy 48.270934 -410.62364) (xy 48.262892 -410.690461) (xy 48.246922 -410.755842) (xy 48.223252 -410.818845)
			(xy 48.192223 -410.878569) (xy 48.154278 -410.934155) (xy 48.132492 -410.959808) (xy 48.126709 -410.966963)
			(xy 48.120186 -410.984146) (xy 48.119792 -410.993336) (xy 48.119792 -411.151324) (xy 48.119398 -411.161481)
			(xy 48.111593 -411.180235) (xy 48.097188 -411.194558) (xy 48.078389 -411.202255) (xy 48.06823 -411.202632)
			(xy 47.35195 -411.202632) (xy 47.341823 -411.202132) (xy 47.323098 -411.194415) (xy 47.308739 -411.180132)
			(xy 47.300923 -411.161448) (xy 47.300388 -411.151324) (xy 47.300388 -410.993336) (xy 47.299963 -410.98415)
			(xy 47.29346 -410.966966) (xy 47.287688 -410.959808) (xy 47.265883 -410.934169) (xy 47.227932 -410.878582)
			(xy 47.196896 -410.818857) (xy 47.173222 -410.755851) (xy 47.157249 -410.690466) (xy 47.149205 -410.623642)
			(xy 43.871166 -410.623642) (xy 43.871166 -410.623699) (xy 43.863092 -410.690636) (xy 43.847058 -410.756125)
			(xy 43.823295 -410.819221) (xy 43.792146 -410.879017) (xy 43.754059 -410.934651) (xy 43.732196 -410.960316)
			(xy 43.72641 -410.967468) (xy 43.719889 -410.984653) (xy 43.719496 -410.993844) (xy 43.719496 -411.151324)
			(xy 43.719035 -411.161435) (xy 43.711288 -411.180114) (xy 43.696984 -411.194408) (xy 43.678299 -411.202142)
			(xy 43.668188 -411.202632) (xy 42.951908 -411.202632) (xy 42.941804 -411.202109) (xy 42.923132 -411.19438)
			(xy 42.908838 -411.180095) (xy 42.901097 -411.161428) (xy 42.9006 -411.151324) (xy 42.9006 -410.993844)
			(xy 42.900169 -410.984659) (xy 42.89367 -410.967474) (xy 42.8879 -410.960316) (xy 42.86602 -410.934664)
			(xy 42.827932 -410.879027) (xy 42.796782 -410.819229) (xy 42.773019 -410.756131) (xy 42.756984 -410.69064)
			(xy 42.74891 -410.6237) (xy 39.470864 -410.6237) (xy 39.462827 -410.690463) (xy 39.446854 -410.755845)
			(xy 39.423181 -410.818849) (xy 39.392147 -410.878572) (xy 39.354196 -410.934157) (xy 39.332408 -410.959808)
			(xy 39.326626 -410.966964) (xy 39.320103 -410.984146) (xy 39.319708 -410.993336) (xy 39.319708 -411.151324)
			(xy 39.319298 -411.161479) (xy 39.311496 -411.18023) (xy 39.297096 -411.194552) (xy 39.278303 -411.202253)
			(xy 39.268146 -411.202632) (xy 38.551866 -411.202632) (xy 38.541734 -411.202201) (xy 38.523006 -411.194456)
			(xy 38.50865 -411.180153) (xy 38.500837 -411.161454) (xy 38.500304 -411.151324) (xy 38.500304 -410.993336)
			(xy 38.499876 -410.984151) (xy 38.493375 -410.966966) (xy 38.487604 -410.959808) (xy 38.465802 -410.934168)
			(xy 38.427856 -410.878579) (xy 38.396825 -410.818854) (xy 38.373155 -410.755848) (xy 38.357184 -410.690464)
			(xy 38.349141 -410.623641) (xy 35.071078 -410.623641) (xy 35.071078 -410.623699) (xy 35.063004 -410.690636)
			(xy 35.046971 -410.756124) (xy 35.023209 -410.81922) (xy 34.992061 -410.879016) (xy 34.953975 -410.934651)
			(xy 34.932112 -410.960316) (xy 34.926328 -410.96747) (xy 34.919805 -410.984654) (xy 34.919412 -410.993844)
			(xy 34.919412 -411.151324) (xy 34.918935 -411.161433) (xy 34.911192 -411.180109) (xy 34.896893 -411.194403)
			(xy 34.878213 -411.202139) (xy 34.868104 -411.202632) (xy 34.151824 -411.202632) (xy 34.141721 -411.202096)
			(xy 34.123049 -411.194372) (xy 34.108755 -411.180091) (xy 34.101013 -411.161427) (xy 34.100516 -411.151324)
			(xy 34.100516 -410.993844) (xy 34.100081 -410.98466) (xy 34.093584 -410.967475) (xy 34.087816 -410.960316)
			(xy 34.065936 -410.934664) (xy 34.027846 -410.879028) (xy 33.996696 -410.81923) (xy 33.972932 -410.756131)
			(xy 33.956897 -410.690641) (xy 33.948822 -410.623701) (xy 30.670776 -410.623701) (xy 30.66274 -410.690462)
			(xy 30.646767 -410.755844) (xy 30.623095 -410.818848) (xy 30.592061 -410.878571) (xy 30.554112 -410.934156)
			(xy 30.532324 -410.959808) (xy 30.526544 -410.966965) (xy 30.520019 -410.984146) (xy 30.519624 -410.993336)
			(xy 30.519624 -411.151324) (xy 30.519199 -411.161477) (xy 30.5114 -411.180225) (xy 30.497005 -411.194547)
			(xy 30.478217 -411.20225) (xy 30.468062 -411.202632) (xy 29.751782 -411.202632) (xy 29.741651 -411.202188)
			(xy 29.722924 -411.194449) (xy 29.708567 -411.180149) (xy 29.700753 -411.161453) (xy 29.70022 -411.151324)
			(xy 29.70022 -410.993336) (xy 29.699788 -410.984151) (xy 29.693289 -410.966967) (xy 29.68752 -410.959808)
			(xy 29.665717 -410.934169) (xy 29.62777 -410.87858) (xy 29.596738 -410.818854) (xy 29.573067 -410.755848)
			(xy 29.557096 -410.690465) (xy 29.549054 -410.623641) (xy 0.508 -410.623641) (xy 0.508 -416.589972)
			(xy 0.508522 -416.645779) (xy 0.516863 -416.757081) (xy 0.533498 -416.867448) (xy 0.558335 -416.976264)
			(xy 0.591234 -417.082919) (xy 0.632011 -417.186818) (xy 0.680438 -417.287379) (xy 0.681656 -417.289488)
			(xy 53.073808 -417.289488) (xy 53.073808 -394.27912) (xy 66.477388 -394.27912) (xy 66.525648 -394.32738)
			(xy 66.525648 -397.823885) (xy 71.348788 -397.823885) (xy 71.348792 -397.756458) (xy 71.356871 -397.689518)
			(xy 71.372911 -397.624026) (xy 71.396679 -397.560928) (xy 71.427833 -397.501131) (xy 71.465926 -397.445495)
			(xy 71.487792 -397.41983) (xy 71.4936 -397.412693) (xy 71.500108 -397.395496) (xy 71.500492 -397.386302)
			(xy 71.500492 -396.89405) (xy 71.50006 -396.884865) (xy 71.493562 -396.86768) (xy 71.487792 -396.860522)
			(xy 71.465918 -396.834865) (xy 71.427831 -396.779229) (xy 71.396681 -396.719431) (xy 71.372918 -396.656334)
			(xy 71.356883 -396.590844) (xy 71.348808 -396.523905) (xy 71.348809 -396.45648) (xy 71.356886 -396.389542)
			(xy 71.372922 -396.324052) (xy 71.396687 -396.260955) (xy 71.427838 -396.201158) (xy 71.465928 -396.145523)
			(xy 71.487792 -396.119858) (xy 71.493588 -396.112712) (xy 71.500103 -396.095522) (xy 71.500492 -396.08633)
			(xy 71.500492 -395.92885) (xy 71.501066 -395.918732) (xy 71.508769 -395.900021) (xy 71.523028 -395.885665)
			(xy 71.541686 -395.877836) (xy 71.5518 -395.877288) (xy 72.26808 -395.877288) (xy 72.278231 -395.877738)
			(xy 72.296981 -395.885524) (xy 72.311305 -395.899912) (xy 72.319007 -395.918697) (xy 72.319388 -395.92885)
			(xy 72.319388 -396.08633) (xy 72.319786 -396.095518) (xy 72.326308 -396.112703) (xy 72.332088 -396.119858)
			(xy 72.353943 -396.145531) (xy 72.392032 -396.201164) (xy 72.423184 -396.260959) (xy 72.446949 -396.324055)
			(xy 72.462986 -396.389543) (xy 72.471063 -396.456481) (xy 72.471064 -396.523904) (xy 72.462989 -396.590842)
			(xy 72.446954 -396.656331) (xy 72.42319 -396.719427) (xy 72.39204 -396.779223) (xy 72.353952 -396.834857)
			(xy 72.332088 -396.860522) (xy 72.326298 -396.867672) (xy 72.31978 -396.884859) (xy 72.319388 -396.89405)
			(xy 72.319388 -397.386302) (xy 72.3198 -397.395489) (xy 72.326313 -397.412673) (xy 72.332088 -397.41983)
			(xy 72.353915 -397.445526) (xy 72.392006 -397.501156) (xy 72.420766 -397.556355) (xy 73.54898 -397.556355)
			(xy 73.557023 -397.489534) (xy 73.572995 -397.424152) (xy 73.596666 -397.361148) (xy 73.627698 -397.301425)
			(xy 73.665645 -397.245838) (xy 73.687432 -397.220186) (xy 73.693221 -397.213036) (xy 73.69974 -397.195849)
			(xy 73.700132 -397.186658) (xy 73.700132 -397.028924) (xy 73.700542 -397.018767) (xy 73.708335 -397.000009)
			(xy 73.722736 -396.985684) (xy 73.741535 -396.977989) (xy 73.751694 -396.977616) (xy 74.467974 -396.977616)
			(xy 74.478096 -396.978147) (xy 74.496812 -396.985862) (xy 74.511169 -397.000134) (xy 74.518993 -397.018805)
			(xy 74.519536 -397.028924) (xy 74.519536 -397.186658) (xy 74.519981 -397.195841) (xy 74.526472 -397.213025)
			(xy 74.532236 -397.220186) (xy 74.554034 -397.24583) (xy 74.591984 -397.301417) (xy 74.623019 -397.361141)
			(xy 74.646692 -397.424147) (xy 74.662665 -397.48953) (xy 74.670709 -397.556354) (xy 74.670708 -397.623661)
			(xy 74.662662 -397.690484) (xy 74.646687 -397.755867) (xy 74.623012 -397.818872) (xy 74.620438 -397.823826)
			(xy 75.749084 -397.823826) (xy 75.749087 -397.756517) (xy 75.757136 -397.689691) (xy 75.773114 -397.624306)
			(xy 75.796793 -397.5613) (xy 75.827833 -397.501576) (xy 75.865789 -397.44599) (xy 75.88758 -397.420338)
			(xy 75.893383 -397.413197) (xy 75.899895 -397.396003) (xy 75.90028 -397.38681) (xy 75.90028 -396.893542)
			(xy 75.899854 -396.884356) (xy 75.893352 -396.867172) (xy 75.88758 -396.860014) (xy 75.865781 -396.83437)
			(xy 75.82783 -396.778784) (xy 75.796795 -396.719059) (xy 75.773121 -396.656054) (xy 75.757147 -396.59067)
			(xy 75.749104 -396.523846) (xy 75.749104 -396.456539) (xy 75.75715 -396.389715) (xy 75.773125 -396.324332)
			(xy 75.796801 -396.261327) (xy 75.827838 -396.201603) (xy 75.86579 -396.146018) (xy 75.88758 -396.120366)
			(xy 75.893371 -396.113217) (xy 75.89989 -396.096029) (xy 75.90028 -396.086838) (xy 75.90028 -395.92885)
			(xy 75.900706 -395.918676) (xy 75.908482 -395.899875) (xy 75.922868 -395.885487) (xy 75.941668 -395.877707)
			(xy 75.951842 -395.877288) (xy 76.668122 -395.877288) (xy 76.678301 -395.877647) (xy 76.697106 -395.885449)
			(xy 76.711492 -395.899855) (xy 76.719267 -395.91867) (xy 76.719684 -395.92885) (xy 76.719684 -396.086838)
			(xy 76.720079 -396.096027) (xy 76.726604 -396.113211) (xy 76.732384 -396.120366) (xy 76.754161 -396.146026)
			(xy 76.792109 -396.201612) (xy 76.823141 -396.261335) (xy 76.846814 -396.324338) (xy 76.862787 -396.389719)
			(xy 76.870831 -396.456541) (xy 76.870832 -396.523844) (xy 76.862789 -396.590666) (xy 76.846818 -396.656047)
			(xy 76.823147 -396.719051) (xy 76.792117 -396.778775) (xy 76.75417 -396.834362) (xy 76.732384 -396.860014)
			(xy 76.726597 -396.867166) (xy 76.720077 -396.884351) (xy 76.719684 -396.893542) (xy 76.719684 -397.38681)
			(xy 76.720093 -397.395997) (xy 76.726608 -397.413181) (xy 76.732384 -397.420338) (xy 76.754133 -397.446021)
			(xy 76.792082 -397.501604) (xy 76.820503 -397.556296) (xy 77.948748 -397.556296) (xy 77.956824 -397.489358)
			(xy 77.972859 -397.423869) (xy 77.996623 -397.360772) (xy 78.027774 -397.300977) (xy 78.065864 -397.245343)
			(xy 78.087728 -397.219678) (xy 78.09352 -397.21253) (xy 78.100037 -397.195341) (xy 78.100428 -397.18615)
			(xy 78.100428 -397.028924) (xy 78.100836 -397.0188) (xy 78.108582 -397.000091) (xy 78.122901 -396.985775)
			(xy 78.141611 -396.978034) (xy 78.151736 -396.977616) (xy 78.868016 -396.977616) (xy 78.878142 -396.978003)
			(xy 78.896849 -396.985759) (xy 78.911163 -397.000085) (xy 78.918905 -397.018798) (xy 78.919324 -397.028924)
			(xy 78.919324 -397.18615) (xy 78.919753 -397.195335) (xy 78.926253 -397.21252) (xy 78.932024 -397.219678)
			(xy 78.953897 -397.245336) (xy 78.991984 -397.300972) (xy 79.023133 -397.360769) (xy 79.046895 -397.423867)
			(xy 79.062929 -397.489357) (xy 79.071004 -397.556296) (xy 79.071003 -397.62372) (xy 79.062927 -397.690658)
			(xy 79.046891 -397.756147) (xy 79.023127 -397.819245) (xy 79.02071 -397.823885) (xy 80.148876 -397.823885)
			(xy 80.14888 -397.756458) (xy 80.156959 -397.689518) (xy 80.172998 -397.624027) (xy 80.196765 -397.560929)
			(xy 80.227919 -397.501131) (xy 80.266011 -397.445496) (xy 80.287876 -397.41983) (xy 80.293682 -397.412691)
			(xy 80.300192 -397.395496) (xy 80.300576 -397.386302) (xy 80.300576 -396.89405) (xy 80.300147 -396.884865)
			(xy 80.293647 -396.86768) (xy 80.287876 -396.860522) (xy 80.266003 -396.834864) (xy 80.227916 -396.779228)
			(xy 80.196767 -396.719431) (xy 80.173005 -396.656333) (xy 80.156971 -396.590843) (xy 80.148896 -396.523904)
			(xy 80.148897 -396.45648) (xy 80.156973 -396.389542) (xy 80.173009 -396.324053) (xy 80.196773 -396.260955)
			(xy 80.227924 -396.201159) (xy 80.266012 -396.145524) (xy 80.287876 -396.119858) (xy 80.29367 -396.112711)
			(xy 80.300187 -396.095522) (xy 80.300576 -396.08633) (xy 80.300576 -395.92885) (xy 80.301069 -395.918722)
			(xy 80.308787 -395.899995) (xy 80.323072 -395.885636) (xy 80.341759 -395.877821) (xy 80.351884 -395.877288)
			(xy 81.068164 -395.877288) (xy 81.078314 -395.877751) (xy 81.097063 -395.885532) (xy 81.111388 -395.899917)
			(xy 81.119091 -395.918698) (xy 81.119472 -395.92885) (xy 81.119472 -396.08633) (xy 81.119874 -396.095518)
			(xy 81.126394 -396.112702) (xy 81.132172 -396.119858) (xy 81.154027 -396.145531) (xy 81.192118 -396.201164)
			(xy 81.223271 -396.260959) (xy 81.247037 -396.324054) (xy 81.263074 -396.389543) (xy 81.271151 -396.456481)
			(xy 81.271152 -396.523904) (xy 81.263076 -396.590842) (xy 81.247041 -396.656331) (xy 81.223277 -396.719428)
			(xy 81.192126 -396.779223) (xy 81.154036 -396.834857) (xy 81.132172 -396.860522) (xy 81.12638 -396.86767)
			(xy 81.119863 -396.884859) (xy 81.119472 -396.89405) (xy 81.119472 -397.386302) (xy 81.119887 -397.395489)
			(xy 81.126398 -397.412673) (xy 81.132172 -397.41983) (xy 81.154 -397.445526) (xy 81.192091 -397.501155)
			(xy 81.220853 -397.556356) (xy 82.349068 -397.556356) (xy 82.357111 -397.489534) (xy 82.373082 -397.424153)
			(xy 82.396753 -397.361149) (xy 82.427783 -397.301425) (xy 82.46573 -397.245838) (xy 82.487516 -397.220186)
			(xy 82.493303 -397.213034) (xy 82.499823 -397.195849) (xy 82.500216 -397.186658) (xy 82.500216 -397.028924)
			(xy 82.500641 -397.018769) (xy 82.508432 -397.000014) (xy 82.522828 -396.98569) (xy 82.541621 -396.977992)
			(xy 82.551778 -396.977616) (xy 83.268058 -396.977616) (xy 83.278179 -396.97816) (xy 83.296895 -396.98587)
			(xy 83.311252 -397.000138) (xy 83.319076 -397.018806) (xy 83.31962 -397.028924) (xy 83.31962 -397.186658)
			(xy 83.320046 -397.195844) (xy 83.326548 -397.213028) (xy 83.33232 -397.220186) (xy 83.354119 -397.24583)
			(xy 83.39207 -397.301416) (xy 83.423105 -397.361141) (xy 83.446779 -397.424146) (xy 83.462753 -397.48953)
			(xy 83.470796 -397.556354) (xy 83.470796 -397.623661) (xy 83.46275 -397.690485) (xy 83.446775 -397.755868)
			(xy 83.423099 -397.818873) (xy 83.420495 -397.823884) (xy 84.548667 -397.823884) (xy 84.548671 -397.756458)
			(xy 84.55675 -397.689518) (xy 84.572788 -397.624028) (xy 84.596555 -397.560929) (xy 84.627708 -397.501132)
			(xy 84.665799 -397.445496) (xy 84.687664 -397.41983) (xy 84.693481 -397.412699) (xy 84.699982 -397.395497)
			(xy 84.700364 -397.386302) (xy 84.700364 -396.89405) (xy 84.699916 -396.884867) (xy 84.693427 -396.867683)
			(xy 84.687664 -396.860522) (xy 84.665791 -396.834864) (xy 84.627705 -396.779228) (xy 84.596557 -396.71943)
			(xy 84.572795 -396.656332) (xy 84.556761 -396.590843) (xy 84.548687 -396.523904) (xy 84.548688 -396.456481)
			(xy 84.556764 -396.389542) (xy 84.5728 -396.324053) (xy 84.596563 -396.260956) (xy 84.627713 -396.201159)
			(xy 84.665801 -396.145524) (xy 84.687664 -396.119858) (xy 84.693469 -396.112719) (xy 84.699977 -396.095523)
			(xy 84.700364 -396.08633) (xy 84.700364 -395.92885) (xy 84.700868 -395.918724) (xy 84.708584 -395.899999)
			(xy 84.722866 -395.88564) (xy 84.741548 -395.877823) (xy 84.751672 -395.877288) (xy 85.467952 -395.877288)
			(xy 85.478102 -395.877761) (xy 85.496851 -395.885538) (xy 85.511175 -395.899919) (xy 85.518879 -395.918699)
			(xy 85.51926 -395.92885) (xy 85.51926 -396.08633) (xy 85.519665 -396.095518) (xy 85.526183 -396.112701)
			(xy 85.53196 -396.119858) (xy 85.553816 -396.145531) (xy 85.591907 -396.201163) (xy 85.623061 -396.260958)
			(xy 85.646827 -396.324054) (xy 85.662864 -396.389543) (xy 85.670942 -396.456481) (xy 85.670943 -396.523904)
			(xy 85.662867 -396.590843) (xy 85.646832 -396.656332) (xy 85.623067 -396.719428) (xy 85.591915 -396.779224)
			(xy 85.553825 -396.834857) (xy 85.53196 -396.860522) (xy 85.526167 -396.867669) (xy 85.519651 -396.884858)
			(xy 85.51926 -396.89405) (xy 85.51926 -397.386302) (xy 85.519678 -397.395488) (xy 85.526187 -397.412672)
			(xy 85.53196 -397.41983) (xy 85.553788 -397.445525) (xy 85.591881 -397.501155) (xy 85.620612 -397.556296)
			(xy 86.748836 -397.556296) (xy 86.756911 -397.489358) (xy 86.772946 -397.423869) (xy 86.79671 -397.360773)
			(xy 86.82786 -397.300977) (xy 86.865948 -397.245343) (xy 86.887812 -397.219678) (xy 86.893602 -397.212528)
			(xy 86.90012 -397.195341) (xy 86.900512 -397.18615) (xy 86.900512 -397.028924) (xy 86.900936 -397.018802)
			(xy 86.908678 -397.000096) (xy 86.922993 -396.985781) (xy 86.941698 -396.978037) (xy 86.95182 -396.977616)
			(xy 87.6681 -396.977616) (xy 87.678224 -396.978016) (xy 87.696931 -396.985768) (xy 87.711246 -397.000089)
			(xy 87.718988 -397.018799) (xy 87.719408 -397.028924) (xy 87.719408 -397.18615) (xy 87.71984 -397.195335)
			(xy 87.726338 -397.21252) (xy 87.732108 -397.219678) (xy 87.753982 -397.245335) (xy 87.792069 -397.300971)
			(xy 87.823219 -397.360769) (xy 87.846982 -397.423866) (xy 87.863017 -397.489356) (xy 87.871092 -397.556295)
			(xy 87.871091 -397.62372) (xy 87.863014 -397.690658) (xy 87.846978 -397.756148) (xy 87.823213 -397.819245)
			(xy 87.820827 -397.823826) (xy 88.948962 -397.823826) (xy 88.948966 -397.756517) (xy 88.957014 -397.689692)
			(xy 88.972991 -397.624307) (xy 88.996669 -397.561301) (xy 89.027707 -397.501577) (xy 89.065661 -397.44599)
			(xy 89.087452 -397.420338) (xy 89.093264 -397.413204) (xy 89.099768 -397.396005) (xy 89.100152 -397.38681)
			(xy 89.100152 -396.893542) (xy 89.09971 -396.884358) (xy 89.093217 -396.867175) (xy 89.087452 -396.860014)
			(xy 89.065654 -396.83437) (xy 89.027704 -396.778783) (xy 88.996671 -396.719058) (xy 88.972998 -396.656053)
			(xy 88.957025 -396.590669) (xy 88.948982 -396.523846) (xy 88.948983 -396.456539) (xy 88.957028 -396.389716)
			(xy 88.973003 -396.324333) (xy 88.996677 -396.261328) (xy 89.027712 -396.201604) (xy 89.065663 -396.146018)
			(xy 89.087452 -396.120366) (xy 89.093252 -396.113223) (xy 89.099763 -396.096031) (xy 89.100152 -396.086838)
			(xy 89.100152 -395.92885) (xy 89.100605 -395.91868) (xy 89.108376 -395.899884) (xy 89.122753 -395.885496)
			(xy 89.141544 -395.877712) (xy 89.151714 -395.877288) (xy 89.867994 -395.877288) (xy 89.878171 -395.87767)
			(xy 89.896976 -395.885462) (xy 89.911362 -395.899861) (xy 89.919139 -395.918672) (xy 89.919556 -395.92885)
			(xy 89.919556 -396.086838) (xy 89.919958 -396.096026) (xy 89.926478 -396.11321) (xy 89.932256 -396.120366)
			(xy 89.954034 -396.146026) (xy 89.991983 -396.201611) (xy 90.023017 -396.261334) (xy 90.046691 -396.324337)
			(xy 90.062665 -396.389719) (xy 90.07071 -396.45654) (xy 90.070711 -396.523845) (xy 90.062667 -396.590667)
			(xy 90.046695 -396.656048) (xy 90.023023 -396.719052) (xy 89.991991 -396.778776) (xy 89.954043 -396.834362)
			(xy 89.932256 -396.860014) (xy 89.926465 -396.867163) (xy 89.919948 -396.884351) (xy 89.919556 -396.893542)
			(xy 89.919556 -397.38681) (xy 89.919971 -397.395996) (xy 89.926482 -397.41318) (xy 89.932256 -397.420338)
			(xy 89.954006 -397.446021) (xy 89.991957 -397.501603) (xy 90.020411 -397.556356) (xy 91.149156 -397.556356)
			(xy 91.157198 -397.489535) (xy 91.173169 -397.424153) (xy 91.196839 -397.361149) (xy 91.227869 -397.301426)
			(xy 91.265814 -397.245839) (xy 91.2876 -397.220186) (xy 91.293385 -397.213033) (xy 91.299907 -397.195848)
			(xy 91.3003 -397.186658) (xy 91.3003 -397.028924) (xy 91.300741 -397.018771) (xy 91.308529 -397.000019)
			(xy 91.32292 -396.985695) (xy 91.341708 -396.977995) (xy 91.351862 -396.977616) (xy 92.068142 -396.977616)
			(xy 92.078268 -396.978091) (xy 92.096986 -396.985829) (xy 92.11134 -397.000118) (xy 92.119162 -397.0188)
			(xy 92.119704 -397.028924) (xy 92.119704 -397.186658) (xy 92.120133 -397.195843) (xy 92.126634 -397.213028)
			(xy 92.132404 -397.220186) (xy 92.1542 -397.245831) (xy 92.192146 -397.301419) (xy 92.223176 -397.361144)
			(xy 92.246847 -397.42415) (xy 92.262818 -397.489532) (xy 92.27086 -397.556355) (xy 92.270859 -397.62366)
			(xy 92.262815 -397.690483) (xy 92.246842 -397.755865) (xy 92.22317 -397.81887) (xy 92.220595 -397.823825)
			(xy 115.349226 -397.823825) (xy 115.349229 -397.756518) (xy 115.357277 -397.689693) (xy 115.373253 -397.624309)
			(xy 115.396928 -397.561303) (xy 115.427964 -397.501578) (xy 115.465915 -397.445991) (xy 115.487704 -397.420338)
			(xy 115.49351 -397.413199) (xy 115.500019 -397.396004) (xy 115.500404 -397.38681) (xy 115.500404 -396.893542)
			(xy 115.499973 -396.884357) (xy 115.493474 -396.867173) (xy 115.487704 -396.860014) (xy 115.465908 -396.834369)
			(xy 115.427961 -396.778781) (xy 115.39693 -396.719056) (xy 115.37326 -396.656051) (xy 115.357288 -396.590668)
			(xy 115.349246 -396.523845) (xy 115.349247 -396.45654) (xy 115.357291 -396.389717) (xy 115.373264 -396.324335)
			(xy 115.396937 -396.26133) (xy 115.427969 -396.201606) (xy 115.465917 -396.146019) (xy 115.487704 -396.120366)
			(xy 115.493498 -396.113219) (xy 115.500014 -396.09603) (xy 115.500404 -396.086838) (xy 115.500404 -395.92885)
			(xy 115.500904 -395.918686) (xy 115.508666 -395.899899) (xy 115.523028 -395.885513) (xy 115.541803 -395.87772)
			(xy 115.551966 -395.877288) (xy 116.268246 -395.877288) (xy 116.278427 -395.877627) (xy 116.297232 -395.885437)
			(xy 116.311617 -395.899849) (xy 116.319392 -395.918668) (xy 116.319808 -395.92885) (xy 116.319808 -396.086838)
			(xy 116.320198 -396.096027) (xy 116.326725 -396.113212) (xy 116.332508 -396.120366) (xy 116.354288 -396.146026)
			(xy 116.39224 -396.20161) (xy 116.423277 -396.261332) (xy 116.446952 -396.324335) (xy 116.462928 -396.389717)
			(xy 116.470973 -396.45654) (xy 116.470974 -396.523845) (xy 116.46293 -396.590668) (xy 116.446957 -396.65605)
			(xy 116.423283 -396.719055) (xy 116.392248 -396.778777) (xy 116.354297 -396.834363) (xy 116.332508 -396.860014)
			(xy 116.326724 -396.867168) (xy 116.320202 -396.884352) (xy 116.319808 -396.893542) (xy 116.319808 -397.38681)
			(xy 116.320212 -397.395998) (xy 116.32673 -397.413182) (xy 116.332508 -397.420338) (xy 116.35426 -397.44602)
			(xy 116.392213 -397.501601) (xy 116.42064 -397.556296) (xy 117.548866 -397.556296) (xy 117.556942 -397.489357)
			(xy 117.572978 -397.423868) (xy 117.596743 -397.360771) (xy 117.627896 -397.300976) (xy 117.665987 -397.245342)
			(xy 117.687852 -397.219678) (xy 117.693647 -397.212532) (xy 117.700161 -397.195342) (xy 117.700552 -397.18615)
			(xy 117.700552 -397.028924) (xy 117.701103 -397.018823) (xy 117.708824 -397.000154) (xy 117.7231 -396.98586)
			(xy 117.741759 -396.978116) (xy 117.75186 -396.977616) (xy 118.46814 -396.977616) (xy 118.478253 -396.978053)
			(xy 118.496935 -396.985807) (xy 118.511229 -397.000118) (xy 118.51896 -397.01881) (xy 118.519448 -397.028924)
			(xy 118.519448 -397.18615) (xy 118.519894 -397.195333) (xy 118.526384 -397.212517) (xy 118.532148 -397.219678)
			(xy 118.554024 -397.245334) (xy 118.592115 -397.300969) (xy 118.623269 -397.360766) (xy 118.647035 -397.423864)
			(xy 118.663071 -397.489355) (xy 118.671147 -397.556295) (xy 118.671146 -397.62372) (xy 118.663068 -397.69066)
			(xy 118.64703 -397.75615) (xy 118.623262 -397.819248) (xy 118.620846 -397.823885) (xy 119.748994 -397.823885)
			(xy 119.748998 -397.756458) (xy 119.757077 -397.689517) (xy 119.773117 -397.624026) (xy 119.796885 -397.560928)
			(xy 119.828041 -397.50113) (xy 119.866134 -397.445495) (xy 119.888 -397.41983) (xy 119.893809 -397.412693)
			(xy 119.900316 -397.395496) (xy 119.9007 -397.386302) (xy 119.9007 -396.89405) (xy 119.900266 -396.884865)
			(xy 119.893769 -396.867681) (xy 119.888 -396.860522) (xy 119.866126 -396.834865) (xy 119.828038 -396.779229)
			(xy 119.796888 -396.719432) (xy 119.773124 -396.656334) (xy 119.757089 -396.590844) (xy 119.749014 -396.523905)
			(xy 119.749015 -396.45648) (xy 119.757092 -396.389541) (xy 119.773128 -396.324052) (xy 119.796894 -396.260954)
			(xy 119.828046 -396.201158) (xy 119.866135 -396.145523) (xy 119.888 -396.119858) (xy 119.893797 -396.112713)
			(xy 119.900311 -396.095522) (xy 119.9007 -396.08633) (xy 119.9007 -395.92885) (xy 119.901266 -395.918731)
			(xy 119.90897 -395.900019) (xy 119.923232 -395.885662) (xy 119.941893 -395.877834) (xy 119.952008 -395.877288)
			(xy 120.668288 -395.877288) (xy 120.678408 -395.877725) (xy 120.697109 -395.885467) (xy 120.711424 -395.899777)
			(xy 120.719171 -395.918476) (xy 120.719596 -395.928596) (xy 120.719596 -396.08633) (xy 120.719992 -396.095519)
			(xy 120.726516 -396.112703) (xy 120.732296 -396.119858) (xy 120.75415 -396.145531) (xy 120.79224 -396.201165)
			(xy 120.823391 -396.26096) (xy 120.847156 -396.324055) (xy 120.863192 -396.389544) (xy 120.871269 -396.456481)
			(xy 120.87127 -396.523904) (xy 120.863195 -396.590842) (xy 120.84716 -396.65633) (xy 120.823397 -396.719427)
			(xy 120.792247 -396.779223) (xy 120.75416 -396.834857) (xy 120.732296 -396.860522) (xy 120.726507 -396.867673)
			(xy 120.719988 -396.884859) (xy 120.719596 -396.89405) (xy 120.719596 -397.386302) (xy 120.720006 -397.395489)
			(xy 120.72652 -397.412673) (xy 120.732296 -397.41983) (xy 120.754123 -397.445526) (xy 120.792213 -397.501156)
			(xy 120.820972 -397.556355) (xy 121.949186 -397.556355) (xy 121.95723 -397.489533) (xy 121.973202 -397.424152)
			(xy 121.996873 -397.361148) (xy 122.027905 -397.301425) (xy 122.065853 -397.245838) (xy 122.08764 -397.220186)
			(xy 122.09343 -397.213036) (xy 122.099948 -397.195849) (xy 122.10034 -397.186658) (xy 122.10034 -397.028924)
			(xy 122.100736 -397.018798) (xy 122.108484 -397.000087) (xy 122.122807 -396.985771) (xy 122.141522 -396.978032)
			(xy 122.151648 -396.977616) (xy 122.868182 -396.977616) (xy 122.878305 -396.978141) (xy 122.897021 -396.985858)
			(xy 122.911377 -397.000132) (xy 122.919201 -397.018804) (xy 122.919744 -397.028924) (xy 122.919744 -397.186658)
			(xy 122.920187 -397.195841) (xy 122.926679 -397.213026) (xy 122.932444 -397.220186) (xy 122.954242 -397.24583)
			(xy 122.992192 -397.301417) (xy 123.023225 -397.361142) (xy 123.046898 -397.424147) (xy 123.062871 -397.489531)
			(xy 123.070915 -397.556354) (xy 123.070914 -397.623661) (xy 123.062868 -397.690484) (xy 123.046894 -397.755867)
			(xy 123.023219 -397.818872) (xy 123.020645 -397.823826) (xy 124.14929 -397.823826) (xy 124.149293 -397.756517)
			(xy 124.157342 -397.689691) (xy 124.17332 -397.624306) (xy 124.197 -397.5613) (xy 124.22804 -397.501575)
			(xy 124.265997 -397.44599) (xy 124.287788 -397.420338) (xy 124.293592 -397.413198) (xy 124.300103 -397.396004)
			(xy 124.300488 -397.38681) (xy 124.300488 -396.893542) (xy 124.30006 -396.884357) (xy 124.293559 -396.867172)
			(xy 124.287788 -396.860014) (xy 124.265989 -396.834371) (xy 124.228037 -396.778784) (xy 124.197002 -396.71906)
			(xy 124.173327 -396.656054) (xy 124.157354 -396.59067) (xy 124.14931 -396.523846) (xy 124.14931 -396.456539)
			(xy 124.157356 -396.389715) (xy 124.173332 -396.324332) (xy 124.197008 -396.261327) (xy 124.228045 -396.201603)
			(xy 124.265998 -396.146018) (xy 124.287788 -396.120366) (xy 124.29358 -396.113218) (xy 124.300098 -396.09603)
			(xy 124.300488 -396.086838) (xy 124.300488 -395.92885) (xy 124.300906 -395.918675) (xy 124.308684 -395.899872)
			(xy 124.323072 -395.885484) (xy 124.341875 -395.877706) (xy 124.35205 -395.877288) (xy 125.06833 -395.877288)
			(xy 125.07851 -395.87764) (xy 125.097315 -395.885445) (xy 125.1117 -395.899852) (xy 125.119475 -395.91867)
			(xy 125.119892 -395.92885) (xy 125.119892 -396.086838) (xy 125.120286 -396.096027) (xy 125.126811 -396.113211)
			(xy 125.132592 -396.120366) (xy 125.154369 -396.146027) (xy 125.192316 -396.201613) (xy 125.223348 -396.261335)
			(xy 125.24702 -396.324339) (xy 125.262993 -396.389719) (xy 125.271037 -396.456541) (xy 125.271038 -396.523844)
			(xy 125.262995 -396.590666) (xy 125.247025 -396.656047) (xy 125.223354 -396.719051) (xy 125.192324 -396.778774)
			(xy 125.154378 -396.834361) (xy 125.132592 -396.860014) (xy 125.126806 -396.867167) (xy 125.120285 -396.884351)
			(xy 125.119892 -396.893542) (xy 125.119892 -397.38681) (xy 125.120299 -397.395998) (xy 125.126815 -397.413182)
			(xy 125.132592 -397.420338) (xy 125.154341 -397.446021) (xy 125.192289 -397.501604) (xy 125.22071 -397.556296)
			(xy 126.348954 -397.556296) (xy 126.35703 -397.489357) (xy 126.373065 -397.423869) (xy 126.39683 -397.360772)
			(xy 126.427981 -397.300976) (xy 126.466071 -397.245343) (xy 126.487936 -397.219678) (xy 126.493729 -397.21253)
			(xy 126.500245 -397.195342) (xy 126.500636 -397.18615) (xy 126.500636 -397.028924) (xy 126.501036 -397.018799)
			(xy 126.508783 -397.000089) (xy 126.523105 -396.985772) (xy 126.541818 -396.978032) (xy 126.551944 -396.977616)
			(xy 127.268224 -396.977616) (xy 127.278336 -396.978066) (xy 127.297018 -396.985814) (xy 127.311313 -397.000122)
			(xy 127.319044 -397.018811) (xy 127.319532 -397.028924) (xy 127.319532 -397.18615) (xy 127.319981 -397.195333)
			(xy 127.326469 -397.212517) (xy 127.332232 -397.219678) (xy 127.354105 -397.245336) (xy 127.392191 -397.300972)
			(xy 127.423339 -397.36077) (xy 127.447102 -397.423867) (xy 127.463135 -397.489357) (xy 127.47121 -397.556296)
			(xy 127.471209 -397.623719) (xy 127.463133 -397.690658) (xy 127.447097 -397.756147) (xy 127.423333 -397.819244)
			(xy 127.420946 -397.823826) (xy 128.54908 -397.823826) (xy 128.549084 -397.756517) (xy 128.557132 -397.689691)
			(xy 128.57311 -397.624306) (xy 128.596789 -397.5613) (xy 128.627829 -397.501576) (xy 128.665785 -397.445989)
			(xy 128.687576 -397.420338) (xy 128.693379 -397.413197) (xy 128.69989 -397.396003) (xy 128.700276 -397.38681)
			(xy 128.700276 -396.893542) (xy 128.699851 -396.884356) (xy 128.693348 -396.867171) (xy 128.687576 -396.860014)
			(xy 128.665777 -396.83437) (xy 128.627826 -396.778784) (xy 128.596792 -396.719059) (xy 128.573118 -396.656053)
			(xy 128.557144 -396.59067) (xy 128.5491 -396.523846) (xy 128.549101 -396.456539) (xy 128.557147 -396.389715)
			(xy 128.573122 -396.324332) (xy 128.596798 -396.261327) (xy 128.627834 -396.201604) (xy 128.665787 -396.146018)
			(xy 128.687576 -396.120366) (xy 128.693367 -396.113216) (xy 128.699886 -396.096029) (xy 128.700276 -396.086838)
			(xy 128.700276 -395.92885) (xy 128.700706 -395.918677) (xy 128.708481 -395.899876) (xy 128.722866 -395.885488)
			(xy 128.741665 -395.877708) (xy 128.751838 -395.877288) (xy 129.468118 -395.877288) (xy 129.478297 -395.87765)
			(xy 129.497102 -395.885451) (xy 129.511487 -395.899856) (xy 129.519263 -395.91867) (xy 129.51968 -395.92885)
			(xy 129.51968 -396.086838) (xy 129.520076 -396.096027) (xy 129.5266 -396.113211) (xy 129.53238 -396.120366)
			(xy 129.554157 -396.146026) (xy 129.592105 -396.201612) (xy 129.623138 -396.261335) (xy 129.64681 -396.324338)
			(xy 129.662784 -396.389719) (xy 129.670828 -396.456541) (xy 129.670829 -396.523844) (xy 129.662786 -396.590666)
			(xy 129.646815 -396.656047) (xy 129.623144 -396.719051) (xy 129.592113 -396.778775) (xy 129.554167 -396.834362)
			(xy 129.53238 -396.860014) (xy 129.526593 -396.867166) (xy 129.520073 -396.884351) (xy 129.51968 -396.893542)
			(xy 129.51968 -397.38681) (xy 129.52009 -397.395997) (xy 129.526604 -397.413181) (xy 129.53238 -397.420338)
			(xy 129.55413 -397.446021) (xy 129.592078 -397.501604) (xy 129.620531 -397.556356) (xy 130.749274 -397.556356)
			(xy 130.757317 -397.489534) (xy 130.773288 -397.424152) (xy 130.796959 -397.361148) (xy 130.827991 -397.301425)
			(xy 130.865937 -397.245838) (xy 130.887724 -397.220186) (xy 130.893512 -397.213035) (xy 130.900031 -397.195849)
			(xy 130.900424 -397.186658) (xy 130.900424 -397.028924) (xy 130.900842 -397.018768) (xy 130.908634 -397.000012)
			(xy 130.923032 -396.985687) (xy 130.941828 -396.97799) (xy 130.951986 -396.977616) (xy 131.668266 -396.977616)
			(xy 131.678388 -396.978154) (xy 131.697103 -396.985866) (xy 131.71146 -397.000137) (xy 131.719284 -397.018806)
			(xy 131.719828 -397.028924) (xy 131.719828 -397.186658) (xy 131.720252 -397.195844) (xy 131.726756 -397.213029)
			(xy 131.732528 -397.220186) (xy 131.754326 -397.24583) (xy 131.792277 -397.301417) (xy 131.823312 -397.361141)
			(xy 131.846985 -397.424147) (xy 131.862959 -397.48953) (xy 131.871003 -397.556354) (xy 131.871002 -397.623661)
			(xy 131.862956 -397.690485) (xy 131.846981 -397.755868) (xy 131.823306 -397.818873) (xy 131.792269 -397.878596)
			(xy 131.754317 -397.934182) (xy 131.732528 -397.959834) (xy 131.726726 -397.966975) (xy 131.720217 -397.984169)
			(xy 131.719828 -397.993362) (xy 131.719828 -398.486884) (xy 131.720239 -398.496071) (xy 131.726751 -398.513256)
			(xy 131.732528 -398.520412) (xy 131.754352 -398.546034) (xy 131.792302 -398.601624) (xy 131.823336 -398.661352)
			(xy 131.847008 -398.72436) (xy 131.86298 -398.789746) (xy 131.871021 -398.856573) (xy 131.871018 -398.923881)
			(xy 131.86297 -398.990707) (xy 131.846992 -399.056092) (xy 131.823314 -399.119098) (xy 131.792274 -399.178822)
			(xy 131.754319 -399.234408) (xy 131.732528 -399.26006) (xy 131.726715 -399.267193) (xy 131.720212 -399.284393)
			(xy 131.719828 -399.293588) (xy 131.719828 -399.451576) (xy 131.719359 -399.461725) (xy 131.711577 -399.480472)
			(xy 131.697195 -399.494795) (xy 131.678417 -399.502501) (xy 131.668266 -399.502884) (xy 130.951986 -399.502884)
			(xy 130.941861 -399.502385) (xy 130.923145 -399.494657) (xy 130.90879 -399.480375) (xy 130.900967 -399.461698)
			(xy 130.900424 -399.451576) (xy 130.900424 -399.293588) (xy 130.900014 -399.284401) (xy 130.8935 -399.267217)
			(xy 130.887724 -399.26006) (xy 130.865972 -399.234378) (xy 130.828023 -399.178796) (xy 130.796989 -399.119076)
			(xy 130.773315 -399.056076) (xy 130.75734 -398.990697) (xy 130.749294 -398.923878) (xy 130.74929 -398.856576)
			(xy 130.757331 -398.789756) (xy 130.773299 -398.724376) (xy 130.796967 -398.661373) (xy 130.827996 -398.601651)
			(xy 130.865939 -398.546065) (xy 130.887724 -398.520412) (xy 130.893543 -398.513283) (xy 130.900044 -398.49608)
			(xy 130.900424 -398.486884) (xy 130.900424 -397.993362) (xy 130.900027 -397.984174) (xy 130.893504 -397.96699)
			(xy 130.887724 -397.959834) (xy 130.865946 -397.934174) (xy 130.827998 -397.878588) (xy 130.796965 -397.818865)
			(xy 130.773293 -397.755862) (xy 130.75732 -397.690481) (xy 130.749275 -397.62366) (xy 130.749274 -397.556356)
			(xy 129.620531 -397.556356) (xy 129.623112 -397.561323) (xy 129.646786 -397.624324) (xy 129.662761 -397.689702)
			(xy 129.670808 -397.756521) (xy 129.670811 -397.823822) (xy 129.662771 -397.890642) (xy 129.646803 -397.956022)
			(xy 129.623135 -398.019025) (xy 129.592108 -398.078747) (xy 129.554165 -398.134333) (xy 129.53238 -398.159986)
			(xy 129.526562 -398.167116) (xy 129.520061 -398.184318) (xy 129.51968 -398.193514) (xy 129.51968 -398.351502)
			(xy 129.519169 -398.361658) (xy 129.511397 -398.380423) (xy 129.497037 -398.394788) (xy 129.478274 -398.402565)
			(xy 129.468118 -398.403064) (xy 128.751838 -398.403064) (xy 128.741669 -398.402605) (xy 128.722876 -398.394833)
			(xy 128.70849 -398.380458) (xy 128.700703 -398.361671) (xy 128.700276 -398.351502) (xy 128.700276 -398.193514)
			(xy 128.699865 -398.184327) (xy 128.693352 -398.167142) (xy 128.687576 -398.159986) (xy 128.66575 -398.134365)
			(xy 128.627799 -398.078775) (xy 128.596766 -398.019048) (xy 128.573093 -397.956039) (xy 128.557122 -397.890652)
			(xy 128.54908 -397.823826) (xy 127.420946 -397.823826) (xy 127.392183 -397.879041) (xy 127.354095 -397.934676)
			(xy 127.332232 -397.960342) (xy 127.326427 -397.967481) (xy 127.319919 -397.984676) (xy 127.319532 -397.99387)
			(xy 127.319532 -398.486376) (xy 127.319969 -398.49556) (xy 127.326466 -398.512744) (xy 127.332232 -398.519904)
			(xy 127.35413 -398.545541) (xy 127.392216 -398.60118) (xy 127.423363 -398.66098) (xy 127.447124 -398.724081)
			(xy 127.463156 -398.789573) (xy 127.471228 -398.856514) (xy 127.471225 -398.92394) (xy 127.463146 -398.99088)
			(xy 127.447108 -399.056371) (xy 127.423341 -399.119469) (xy 127.392188 -399.179266) (xy 127.354097 -399.234902)
			(xy 127.332232 -399.260568) (xy 127.326416 -399.267699) (xy 127.319915 -399.284901) (xy 127.319532 -399.294096)
			(xy 127.319532 -399.451576) (xy 127.318996 -399.461679) (xy 127.311272 -399.480351) (xy 127.296991 -399.494645)
			(xy 127.278327 -399.502387) (xy 127.268224 -399.502884) (xy 126.551944 -399.502884) (xy 126.541822 -399.502447)
			(xy 126.523117 -399.494711) (xy 126.5088 -399.4804) (xy 126.501056 -399.461697) (xy 126.500636 -399.451576)
			(xy 126.500636 -399.294096) (xy 126.50022 -399.28491) (xy 126.49371 -399.267726) (xy 126.487936 -399.260568)
			(xy 126.466106 -399.234874) (xy 126.428014 -399.179245) (xy 126.39686 -399.119453) (xy 126.373092 -399.056359)
			(xy 126.357053 -398.990873) (xy 126.348974 -398.923938) (xy 126.34897 -398.856516) (xy 126.357043 -398.78958)
			(xy 126.373076 -398.724092) (xy 126.396838 -398.660997) (xy 126.427986 -398.601202) (xy 126.466073 -398.545569)
			(xy 126.487936 -398.519904) (xy 126.493718 -398.512749) (xy 126.50024 -398.495566) (xy 126.500636 -398.486376)
			(xy 126.500636 -397.99387) (xy 126.500232 -397.984682) (xy 126.493713 -397.967498) (xy 126.487936 -397.960342)
			(xy 126.466081 -397.934669) (xy 126.427989 -397.879037) (xy 126.396836 -397.819242) (xy 126.37307 -397.756146)
			(xy 126.357032 -397.690657) (xy 126.348955 -397.623719) (xy 126.348954 -397.556296) (xy 125.22071 -397.556296)
			(xy 125.223323 -397.561324) (xy 125.246996 -397.624324) (xy 125.262971 -397.689702) (xy 125.271018 -397.756521)
			(xy 125.271021 -397.823822) (xy 125.262981 -397.890642) (xy 125.247013 -397.956021) (xy 125.223346 -398.019024)
			(xy 125.192319 -398.078747) (xy 125.154377 -398.134334) (xy 125.132592 -398.159986) (xy 125.126775 -398.167117)
			(xy 125.120273 -398.184318) (xy 125.119892 -398.193514) (xy 125.119892 -398.351502) (xy 125.119369 -398.361656)
			(xy 125.111599 -398.38042) (xy 125.097243 -398.394784) (xy 125.078484 -398.402563) (xy 125.06833 -398.403064)
			(xy 124.35205 -398.403064) (xy 124.341882 -398.402595) (xy 124.323089 -398.394827) (xy 124.308702 -398.380455)
			(xy 124.300915 -398.36167) (xy 124.300488 -398.351502) (xy 124.300488 -398.193514) (xy 124.300074 -398.184327)
			(xy 124.293563 -398.167143) (xy 124.287788 -398.159986) (xy 124.265961 -398.134365) (xy 124.228011 -398.078775)
			(xy 124.196976 -398.019048) (xy 124.173304 -397.956039) (xy 124.157332 -397.890653) (xy 124.14929 -397.823826)
			(xy 123.020645 -397.823826) (xy 122.992184 -397.878596) (xy 122.954233 -397.934182) (xy 122.932444 -397.959834)
			(xy 122.926644 -397.966976) (xy 122.920133 -397.984169) (xy 122.919744 -397.993362) (xy 122.919744 -398.486884)
			(xy 122.920174 -398.496069) (xy 122.926675 -398.513253) (xy 122.932444 -398.520412) (xy 122.954268 -398.546035)
			(xy 122.992217 -398.601625) (xy 123.023249 -398.661352) (xy 123.046921 -398.724361) (xy 123.062892 -398.789747)
			(xy 123.070933 -398.856573) (xy 123.07093 -398.923881) (xy 123.062882 -398.990707) (xy 123.046905 -399.056091)
			(xy 123.023227 -399.119097) (xy 122.992189 -399.178822) (xy 122.954235 -399.234408) (xy 122.932444 -399.26006)
			(xy 122.926633 -399.267194) (xy 122.920128 -399.284393) (xy 122.919744 -399.293588) (xy 122.919744 -399.451576)
			(xy 122.919196 -399.461678) (xy 122.911475 -399.480347) (xy 122.897197 -399.494641) (xy 122.878537 -399.502385)
			(xy 122.868436 -399.502884) (xy 122.151902 -399.502884) (xy 122.141778 -399.502372) (xy 122.123062 -399.49465)
			(xy 122.108706 -399.480371) (xy 122.100883 -399.461697) (xy 122.10034 -399.451576) (xy 122.10034 -399.293588)
			(xy 122.099927 -399.284401) (xy 122.093414 -399.267217) (xy 122.08764 -399.26006) (xy 122.065888 -399.234379)
			(xy 122.027938 -399.178796) (xy 121.996903 -399.119077) (xy 121.973228 -399.056076) (xy 121.957253 -398.990698)
			(xy 121.949206 -398.923878) (xy 121.949202 -398.856576) (xy 121.957243 -398.789756) (xy 121.973212 -398.724376)
			(xy 121.996881 -398.661373) (xy 122.02791 -398.60165) (xy 122.065855 -398.546064) (xy 122.08764 -398.520412)
			(xy 122.093461 -398.513285) (xy 122.09996 -398.49608) (xy 122.10034 -398.486884) (xy 122.10034 -397.993362)
			(xy 122.099939 -397.984174) (xy 122.093418 -397.96699) (xy 122.08764 -397.959834) (xy 122.065862 -397.934174)
			(xy 122.027913 -397.878588) (xy 121.996879 -397.818866) (xy 121.973206 -397.755863) (xy 121.957232 -397.690481)
			(xy 121.949187 -397.62366) (xy 121.949186 -397.556355) (xy 120.820972 -397.556355) (xy 120.823365 -397.560948)
			(xy 120.847132 -397.624041) (xy 120.86317 -397.689526) (xy 120.871249 -397.756461) (xy 120.871253 -397.823882)
			(xy 120.86318 -397.890818) (xy 120.847149 -397.956305) (xy 120.823389 -398.0194) (xy 120.792242 -398.079195)
			(xy 120.754158 -398.134829) (xy 120.732296 -398.160494) (xy 120.726519 -398.167653) (xy 120.719993 -398.184833)
			(xy 120.719596 -398.194022) (xy 120.719596 -398.351502) (xy 120.719076 -398.361624) (xy 120.711354 -398.380339)
			(xy 120.697079 -398.394694) (xy 120.678408 -398.402519) (xy 120.668288 -398.403064) (xy 119.952008 -398.403064)
			(xy 119.941882 -398.402677) (xy 119.923171 -398.394924) (xy 119.908855 -398.380599) (xy 119.901116 -398.361883)
			(xy 119.9007 -398.351756) (xy 119.9007 -398.194022) (xy 119.900279 -398.184836) (xy 119.893773 -398.167651)
			(xy 119.888 -398.160494) (xy 119.866099 -398.13486) (xy 119.828011 -398.079221) (xy 119.796862 -398.01942)
			(xy 119.7731 -397.956319) (xy 119.757067 -397.890826) (xy 119.748994 -397.823885) (xy 118.620846 -397.823885)
			(xy 118.592108 -397.879044) (xy 118.554014 -397.934678) (xy 118.532148 -397.960342) (xy 118.526345 -397.967482)
			(xy 118.519835 -397.984677) (xy 118.519448 -397.99387) (xy 118.519448 -398.486376) (xy 118.519881 -398.495561)
			(xy 118.52638 -398.512745) (xy 118.532148 -398.519904) (xy 118.554049 -398.545539) (xy 118.59214 -398.601177)
			(xy 118.623292 -398.660977) (xy 118.647057 -398.724078) (xy 118.663091 -398.789571) (xy 118.671165 -398.856513)
			(xy 118.671162 -398.923941) (xy 118.663082 -398.990882) (xy 118.647041 -399.056374) (xy 118.62327 -399.119473)
			(xy 118.592112 -399.17927) (xy 118.554016 -399.234904) (xy 118.532148 -399.260568) (xy 118.526334 -399.2677)
			(xy 118.519831 -399.284901) (xy 118.519448 -399.294096) (xy 118.519448 -399.451576) (xy 118.518897 -399.461677)
			(xy 118.511176 -399.480346) (xy 118.4969 -399.49464) (xy 118.478241 -399.502384) (xy 118.46814 -399.502884)
			(xy 117.75186 -399.502884) (xy 117.741747 -399.502447) (xy 117.723065 -399.494693) (xy 117.708771 -399.480382)
			(xy 117.70104 -399.46169) (xy 117.700552 -399.451576) (xy 117.700552 -399.294096) (xy 117.700132 -399.28491)
			(xy 117.693624 -399.267726) (xy 117.687852 -399.260568) (xy 117.666022 -399.234874) (xy 117.627928 -399.179245)
			(xy 117.596773 -399.119453) (xy 117.573005 -399.05636) (xy 117.556965 -398.990874) (xy 117.548886 -398.923938)
			(xy 117.548882 -398.856516) (xy 117.556955 -398.789579) (xy 117.572989 -398.724092) (xy 117.596751 -398.660996)
			(xy 117.627901 -398.601201) (xy 117.665988 -398.545568) (xy 117.687852 -398.519904) (xy 117.693636 -398.51275)
			(xy 117.700157 -398.495566) (xy 117.700552 -398.486376) (xy 117.700552 -397.99387) (xy 117.700145 -397.984683)
			(xy 117.693628 -397.967499) (xy 117.687852 -397.960342) (xy 117.665996 -397.93467) (xy 117.627904 -397.879037)
			(xy 117.59675 -397.819243) (xy 117.572983 -397.756147) (xy 117.556945 -397.690658) (xy 117.548867 -397.623719)
			(xy 117.548866 -397.556296) (xy 116.42064 -397.556296) (xy 116.423251 -397.56132) (xy 116.446929 -397.624321)
			(xy 116.462906 -397.6897) (xy 116.470954 -397.75652) (xy 116.470957 -397.823823) (xy 116.462916 -397.890644)
			(xy 116.446945 -397.956025) (xy 116.423275 -398.019028) (xy 116.392243 -398.07875) (xy 116.354295 -398.134335)
			(xy 116.332508 -398.159986) (xy 116.326693 -398.167118) (xy 116.320189 -398.184319) (xy 116.319808 -398.193514)
			(xy 116.319808 -398.351502) (xy 116.319269 -398.361654) (xy 116.311503 -398.380415) (xy 116.297152 -398.394778)
			(xy 116.278398 -398.402561) (xy 116.268246 -398.403064) (xy 115.551966 -398.403064) (xy 115.541806 -398.402595)
			(xy 115.523037 -398.394809) (xy 115.508673 -398.380436) (xy 115.500899 -398.361662) (xy 115.500404 -398.351502)
			(xy 115.500404 -398.193514) (xy 115.499986 -398.184328) (xy 115.493478 -398.167143) (xy 115.487704 -398.159986)
			(xy 115.46588 -398.134364) (xy 115.427935 -398.078772) (xy 115.396905 -398.019044) (xy 115.373236 -397.956036)
			(xy 115.357267 -397.89065) (xy 115.349226 -397.823825) (xy 92.220595 -397.823825) (xy 92.192138 -397.878594)
			(xy 92.154191 -397.934181) (xy 92.132404 -397.959834) (xy 92.126611 -397.966982) (xy 92.120094 -397.98417)
			(xy 92.119704 -397.993362) (xy 92.119704 -398.486884) (xy 92.120121 -398.49607) (xy 92.12663 -398.513255)
			(xy 92.132404 -398.520412) (xy 92.154226 -398.546036) (xy 92.192171 -398.601627) (xy 92.2232 -398.661355)
			(xy 92.246869 -398.724363) (xy 92.262838 -398.789748) (xy 92.270879 -398.856574) (xy 92.270875 -398.923881)
			(xy 92.262828 -398.990705) (xy 92.246853 -399.056089) (xy 92.223178 -399.119094) (xy 92.192143 -399.178819)
			(xy 92.154193 -399.234407) (xy 92.132404 -399.26006) (xy 92.1266 -399.2672) (xy 92.12009 -399.284394)
			(xy 92.119704 -399.293588) (xy 92.119704 -399.451576) (xy 92.119259 -399.461728) (xy 92.111472 -399.480479)
			(xy 92.097082 -399.494803) (xy 92.078296 -399.502505) (xy 92.068142 -399.502884) (xy 91.351862 -399.502884)
			(xy 91.341736 -399.502405) (xy 91.323018 -399.494669) (xy 91.308664 -399.480381) (xy 91.300842 -399.4617)
			(xy 91.3003 -399.451576) (xy 91.3003 -399.293588) (xy 91.299895 -399.2844) (xy 91.293378 -399.267216)
			(xy 91.2876 -399.26006) (xy 91.265849 -399.234378) (xy 91.227901 -399.178795) (xy 91.196869 -399.119075)
			(xy 91.173196 -399.056075) (xy 91.157221 -398.990697) (xy 91.149175 -398.923878) (xy 91.149172 -398.856576)
			(xy 91.157212 -398.789757) (xy 91.17318 -398.724377) (xy 91.196847 -398.661374) (xy 91.227874 -398.601651)
			(xy 91.265816 -398.546065) (xy 91.2876 -398.520412) (xy 91.293416 -398.513281) (xy 91.299919 -398.49608)
			(xy 91.3003 -398.486884) (xy 91.3003 -397.993362) (xy 91.299908 -397.984173) (xy 91.293382 -397.966989)
			(xy 91.2876 -397.959834) (xy 91.265823 -397.934173) (xy 91.227877 -397.878587) (xy 91.196845 -397.818864)
			(xy 91.173174 -397.755861) (xy 91.157201 -397.69048) (xy 91.149157 -397.623659) (xy 91.149156 -397.556356)
			(xy 90.020411 -397.556356) (xy 90.022992 -397.561322) (xy 90.046667 -397.624323) (xy 90.062643 -397.689701)
			(xy 90.07069 -397.75652) (xy 90.070693 -397.823822) (xy 90.062653 -397.890643) (xy 90.046684 -397.956023)
			(xy 90.023015 -398.019026) (xy 89.991986 -398.078748) (xy 89.954041 -398.134334) (xy 89.932256 -398.159986)
			(xy 89.926435 -398.167114) (xy 89.919936 -398.184318) (xy 89.919556 -398.193514) (xy 89.919556 -398.351502)
			(xy 89.919138 -398.361674) (xy 89.911351 -398.38047) (xy 89.896964 -398.394855) (xy 89.878167 -398.402639)
			(xy 89.867994 -398.403064) (xy 89.151714 -398.403064) (xy 89.141544 -398.402625) (xy 89.122749 -398.394845)
			(xy 89.108364 -398.380464) (xy 89.100578 -398.361672) (xy 89.100152 -398.351502) (xy 89.100152 -398.193514)
			(xy 89.099724 -398.184329) (xy 89.093221 -398.167145) (xy 89.087452 -398.159986) (xy 89.065626 -398.134365)
			(xy 89.027678 -398.078774) (xy 88.996645 -398.019047) (xy 88.972974 -397.956038) (xy 88.957004 -397.890652)
			(xy 88.948962 -397.823826) (xy 87.820827 -397.823826) (xy 87.792062 -397.879042) (xy 87.753972 -397.934677)
			(xy 87.732108 -397.960342) (xy 87.726312 -397.967488) (xy 87.719797 -397.984678) (xy 87.719408 -397.99387)
			(xy 87.719408 -398.486376) (xy 87.719828 -398.495562) (xy 87.726335 -398.512747) (xy 87.732108 -398.519904)
			(xy 87.754007 -398.54554) (xy 87.792094 -398.601179) (xy 87.823243 -398.660979) (xy 87.847005 -398.72408)
			(xy 87.863037 -398.789573) (xy 87.87111 -398.856514) (xy 87.871107 -398.92394) (xy 87.863028 -398.990881)
			(xy 87.846989 -399.056372) (xy 87.823221 -399.11947) (xy 87.792066 -399.179267) (xy 87.753974 -399.234903)
			(xy 87.732108 -399.260568) (xy 87.726301 -399.267706) (xy 87.719792 -399.284902) (xy 87.719408 -399.294096)
			(xy 87.719408 -399.451576) (xy 87.718965 -399.461696) (xy 87.711226 -399.480398) (xy 87.696918 -399.494712)
			(xy 87.67822 -399.50246) (xy 87.6681 -399.502884) (xy 86.95182 -399.502884) (xy 86.941697 -399.502467)
			(xy 86.922991 -399.494723) (xy 86.908675 -399.480406) (xy 86.900932 -399.461699) (xy 86.900512 -399.451576)
			(xy 86.900512 -399.294096) (xy 86.900101 -399.284909) (xy 86.893587 -399.267725) (xy 86.887812 -399.260568)
			(xy 86.865983 -399.234874) (xy 86.827892 -399.179244) (xy 86.796739 -399.119452) (xy 86.772973 -399.056358)
			(xy 86.756934 -398.990873) (xy 86.748855 -398.923938) (xy 86.748852 -398.856516) (xy 86.756925 -398.78958)
			(xy 86.772957 -398.724093) (xy 86.796717 -398.660998) (xy 86.827865 -398.601203) (xy 86.86595 -398.545569)
			(xy 86.887812 -398.519904) (xy 86.893591 -398.512746) (xy 86.900116 -398.495565) (xy 86.900512 -398.486376)
			(xy 86.900512 -397.99387) (xy 86.900114 -397.984682) (xy 86.893592 -397.967497) (xy 86.887812 -397.960342)
			(xy 86.865957 -397.934669) (xy 86.827868 -397.879036) (xy 86.796716 -397.819241) (xy 86.772951 -397.756145)
			(xy 86.756914 -397.690657) (xy 86.748837 -397.623719) (xy 86.748836 -397.556296) (xy 85.620612 -397.556296)
			(xy 85.623035 -397.560946) (xy 85.646803 -397.624039) (xy 85.662842 -397.689525) (xy 85.670922 -397.756461)
			(xy 85.670925 -397.823882) (xy 85.662853 -397.890819) (xy 85.64682 -397.956306) (xy 85.623058 -398.019402)
			(xy 85.59191 -398.079196) (xy 85.553823 -398.134829) (xy 85.53196 -398.160494) (xy 85.526178 -398.16765)
			(xy 85.519656 -398.184832) (xy 85.51926 -398.194022) (xy 85.51926 -398.351502) (xy 85.518775 -398.361629)
			(xy 85.511047 -398.38035) (xy 85.49676 -398.394706) (xy 85.478076 -398.402525) (xy 85.467952 -398.403064)
			(xy 84.751672 -398.403064) (xy 84.741512 -398.402701) (xy 84.722752 -398.394889) (xy 84.708428 -398.380474)
			(xy 84.700736 -398.361665) (xy 84.700364 -398.351502) (xy 84.700364 -398.194022) (xy 84.699929 -398.184838)
			(xy 84.693431 -398.167654) (xy 84.687664 -398.160494) (xy 84.665764 -398.134859) (xy 84.627679 -398.079219)
			(xy 84.596532 -398.019419) (xy 84.572771 -397.956318) (xy 84.55674 -397.890825) (xy 84.548667 -397.823884)
			(xy 83.420495 -397.823884) (xy 83.392062 -397.878597) (xy 83.35411 -397.934182) (xy 83.33232 -397.959834)
			(xy 83.326529 -397.966983) (xy 83.32001 -397.984171) (xy 83.31962 -397.993362) (xy 83.31962 -398.486884)
			(xy 83.320033 -398.496071) (xy 83.326544 -398.513256) (xy 83.33232 -398.520412) (xy 83.354144 -398.546035)
			(xy 83.392095 -398.601624) (xy 83.423129 -398.661352) (xy 83.446801 -398.72436) (xy 83.462773 -398.789746)
			(xy 83.470815 -398.856573) (xy 83.470812 -398.923881) (xy 83.462763 -398.990707) (xy 83.446785 -399.056092)
			(xy 83.423107 -399.119098) (xy 83.392067 -399.178822) (xy 83.354111 -399.234408) (xy 83.33232 -399.26006)
			(xy 83.326518 -399.267201) (xy 83.320006 -399.284395) (xy 83.31962 -399.293588) (xy 83.31962 -399.451576)
			(xy 83.319159 -399.461726) (xy 83.311375 -399.480474) (xy 83.296991 -399.494798) (xy 83.27821 -399.502502)
			(xy 83.268058 -399.502884) (xy 82.551778 -399.502884) (xy 82.541653 -399.502392) (xy 82.522936 -399.494662)
			(xy 82.508581 -399.480378) (xy 82.500758 -399.461699) (xy 82.500216 -399.451576) (xy 82.500216 -399.293588)
			(xy 82.499808 -399.284401) (xy 82.493293 -399.267216) (xy 82.487516 -399.26006) (xy 82.465765 -399.234378)
			(xy 82.427816 -399.178795) (xy 82.396783 -399.119076) (xy 82.373109 -399.056075) (xy 82.357134 -398.990697)
			(xy 82.349088 -398.923878) (xy 82.349084 -398.856576) (xy 82.357125 -398.789756) (xy 82.373093 -398.724377)
			(xy 82.396761 -398.661374) (xy 82.427788 -398.601651) (xy 82.465731 -398.546065) (xy 82.487516 -398.520412)
			(xy 82.493334 -398.513282) (xy 82.499835 -398.49608) (xy 82.500216 -398.486884) (xy 82.500216 -397.993362)
			(xy 82.499821 -397.984173) (xy 82.493296 -397.966989) (xy 82.487516 -397.959834) (xy 82.465739 -397.934174)
			(xy 82.427791 -397.878588) (xy 82.396759 -397.818865) (xy 82.373086 -397.755862) (xy 82.357113 -397.690481)
			(xy 82.349069 -397.623659) (xy 82.349068 -397.556356) (xy 81.220853 -397.556356) (xy 81.223245 -397.560947)
			(xy 81.247013 -397.62404) (xy 81.263052 -397.689525) (xy 81.271131 -397.756461) (xy 81.271135 -397.823882)
			(xy 81.263062 -397.890818) (xy 81.24703 -397.956306) (xy 81.223269 -398.019401) (xy 81.192121 -398.079196)
			(xy 81.154035 -398.134829) (xy 81.132172 -398.160494) (xy 81.126392 -398.167651) (xy 81.119868 -398.184832)
			(xy 81.119472 -398.194022) (xy 81.119472 -398.351502) (xy 81.118975 -398.361627) (xy 81.111249 -398.380346)
			(xy 81.096966 -398.394702) (xy 81.078287 -398.402523) (xy 81.068164 -398.403064) (xy 80.351884 -398.403064)
			(xy 80.341724 -398.402691) (xy 80.322965 -398.394883) (xy 80.30864 -398.380471) (xy 80.300948 -398.361664)
			(xy 80.300576 -398.351502) (xy 80.300576 -398.194022) (xy 80.300161 -398.184835) (xy 80.293651 -398.16765)
			(xy 80.287876 -398.160494) (xy 80.265976 -398.134859) (xy 80.22789 -398.07922) (xy 80.196742 -398.019419)
			(xy 80.172981 -397.956318) (xy 80.156949 -397.890826) (xy 80.148876 -397.823885) (xy 79.02071 -397.823885)
			(xy 78.991976 -397.879041) (xy 78.953888 -397.934676) (xy 78.932024 -397.960342) (xy 78.92623 -397.967489)
			(xy 78.919713 -397.984678) (xy 78.919324 -397.99387) (xy 78.919324 -398.486376) (xy 78.91974 -398.495563)
			(xy 78.926249 -398.512747) (xy 78.932024 -398.519904) (xy 78.953922 -398.54554) (xy 78.992009 -398.60118)
			(xy 79.023156 -398.66098) (xy 79.046917 -398.724081) (xy 79.06295 -398.789573) (xy 79.071022 -398.856514)
			(xy 79.071019 -398.92394) (xy 79.06294 -398.99088) (xy 79.046901 -399.056371) (xy 79.023134 -399.119469)
			(xy 78.991981 -399.179267) (xy 78.953889 -399.234902) (xy 78.932024 -399.260568) (xy 78.926219 -399.267707)
			(xy 78.919709 -399.284902) (xy 78.919324 -399.294096) (xy 78.919324 -399.451576) (xy 78.918865 -399.461694)
			(xy 78.911129 -399.480393) (xy 78.896826 -399.494707) (xy 78.878134 -399.502457) (xy 78.868016 -399.502884)
			(xy 78.151736 -399.502884) (xy 78.141614 -399.502454) (xy 78.122908 -399.494715) (xy 78.108592 -399.480402)
			(xy 78.100848 -399.461698) (xy 78.100428 -399.451576) (xy 78.100428 -399.294096) (xy 78.100014 -399.284909)
			(xy 78.093502 -399.267725) (xy 78.087728 -399.260568) (xy 78.065898 -399.234874) (xy 78.027807 -399.179244)
			(xy 77.996653 -399.119452) (xy 77.972886 -399.056359) (xy 77.956847 -398.990873) (xy 77.948768 -398.923938)
			(xy 77.948764 -398.856516) (xy 77.956837 -398.78958) (xy 77.972869 -398.724093) (xy 77.996631 -398.660997)
			(xy 78.027779 -398.601202) (xy 78.065865 -398.545569) (xy 78.087728 -398.519904) (xy 78.093509 -398.512748)
			(xy 78.100032 -398.495566) (xy 78.100428 -398.486376) (xy 78.100428 -397.99387) (xy 78.100026 -397.984682)
			(xy 78.093506 -397.967498) (xy 78.087728 -397.960342) (xy 78.065873 -397.934669) (xy 78.027782 -397.879036)
			(xy 77.996629 -397.819241) (xy 77.972863 -397.756146) (xy 77.956826 -397.690657) (xy 77.948749 -397.623719)
			(xy 77.948748 -397.556296) (xy 76.820503 -397.556296) (xy 76.823115 -397.561323) (xy 76.846789 -397.624324)
			(xy 76.862764 -397.689702) (xy 76.870811 -397.756521) (xy 76.870814 -397.823822) (xy 76.862774 -397.890642)
			(xy 76.846806 -397.956022) (xy 76.823139 -398.019024) (xy 76.792111 -398.078747) (xy 76.754168 -398.134333)
			(xy 76.732384 -398.159986) (xy 76.726567 -398.167116) (xy 76.720065 -398.184318) (xy 76.719684 -398.193514)
			(xy 76.719684 -398.351502) (xy 76.719169 -398.361657) (xy 76.711398 -398.380422) (xy 76.697039 -398.394787)
			(xy 76.678277 -398.402565) (xy 76.668122 -398.403064) (xy 75.951842 -398.403064) (xy 75.941673 -398.402602)
			(xy 75.92288 -398.394831) (xy 75.908494 -398.380457) (xy 75.900707 -398.36167) (xy 75.90028 -398.351502)
			(xy 75.90028 -398.193514) (xy 75.899868 -398.184327) (xy 75.893356 -398.167142) (xy 75.88758 -398.159986)
			(xy 75.865754 -398.134365) (xy 75.827803 -398.078775) (xy 75.79677 -398.019048) (xy 75.773097 -397.956039)
			(xy 75.757126 -397.890653) (xy 75.749084 -397.823826) (xy 74.620438 -397.823826) (xy 74.591977 -397.878596)
			(xy 74.554025 -397.934182) (xy 74.532236 -397.959834) (xy 74.526435 -397.966975) (xy 74.519925 -397.984169)
			(xy 74.519536 -397.993362) (xy 74.519536 -398.486884) (xy 74.519968 -398.496069) (xy 74.526468 -398.513252)
			(xy 74.532236 -398.520412) (xy 74.55406 -398.546035) (xy 74.592009 -398.601625) (xy 74.623043 -398.661352)
			(xy 74.646714 -398.724361) (xy 74.662686 -398.789747) (xy 74.670727 -398.856573) (xy 74.670724 -398.923881)
			(xy 74.662676 -398.990707) (xy 74.646698 -399.056091) (xy 74.623021 -399.119097) (xy 74.591982 -399.178822)
			(xy 74.554027 -399.234408) (xy 74.532236 -399.26006) (xy 74.526424 -399.267194) (xy 74.51992 -399.284393)
			(xy 74.519536 -399.293588) (xy 74.519536 -399.451576) (xy 74.51906 -399.461724) (xy 74.511279 -399.480469)
			(xy 74.496899 -399.494792) (xy 74.478124 -399.502499) (xy 74.467974 -399.502884) (xy 73.751694 -399.502884)
			(xy 73.74157 -399.502379) (xy 73.722853 -399.494654) (xy 73.708498 -399.480373) (xy 73.700675 -399.461697)
			(xy 73.700132 -399.451576) (xy 73.700132 -399.293588) (xy 73.699721 -399.284401) (xy 73.693207 -399.267217)
			(xy 73.687432 -399.26006) (xy 73.66568 -399.234378) (xy 73.627731 -399.178796) (xy 73.596696 -399.119077)
			(xy 73.573022 -399.056076) (xy 73.557047 -398.990697) (xy 73.549 -398.923878) (xy 73.548996 -398.856576)
			(xy 73.557037 -398.789756) (xy 73.573006 -398.724376) (xy 73.596674 -398.661373) (xy 73.627703 -398.60165)
			(xy 73.665647 -398.546064) (xy 73.687432 -398.520412) (xy 73.693253 -398.513284) (xy 73.699752 -398.49608)
			(xy 73.700132 -398.486884) (xy 73.700132 -397.993362) (xy 73.699733 -397.984174) (xy 73.693211 -397.96699)
			(xy 73.687432 -397.959834) (xy 73.665654 -397.934174) (xy 73.627705 -397.878588) (xy 73.596672 -397.818866)
			(xy 73.572999 -397.755862) (xy 73.557026 -397.690481) (xy 73.548981 -397.62366) (xy 73.54898 -397.556355)
			(xy 72.420766 -397.556355) (xy 72.423159 -397.560948) (xy 72.446926 -397.62404) (xy 72.462964 -397.689526)
			(xy 72.471043 -397.756461) (xy 72.471047 -397.823882) (xy 72.462974 -397.890818) (xy 72.446942 -397.956305)
			(xy 72.423182 -398.0194) (xy 72.392035 -398.079195) (xy 72.35395 -398.134829) (xy 72.332088 -398.160494)
			(xy 72.32631 -398.167652) (xy 72.319785 -398.184833) (xy 72.319388 -398.194022) (xy 72.319388 -398.351502)
			(xy 72.318876 -398.361625) (xy 72.311153 -398.380341) (xy 72.296875 -398.394696) (xy 72.278201 -398.40252)
			(xy 72.26808 -398.403064) (xy 71.5518 -398.403064) (xy 71.541641 -398.402678) (xy 71.522882 -398.394875)
			(xy 71.508557 -398.380467) (xy 71.500864 -398.361663) (xy 71.500492 -398.351502) (xy 71.500492 -398.194022)
			(xy 71.500073 -398.184836) (xy 71.493566 -398.167651) (xy 71.487792 -398.160494) (xy 71.465891 -398.134859)
			(xy 71.427804 -398.07922) (xy 71.396655 -398.01942) (xy 71.372894 -397.956319) (xy 71.356861 -397.890826)
			(xy 71.348788 -397.823885) (xy 66.525648 -397.823885) (xy 66.525648 -401.723796) (xy 71.3488 -401.723796)
			(xy 71.348802 -401.656371) (xy 71.35688 -401.589431) (xy 71.372917 -401.523941) (xy 71.396683 -401.460843)
			(xy 71.427836 -401.401046) (xy 71.465927 -401.345411) (xy 71.487792 -401.319746) (xy 71.493593 -401.312604)
			(xy 71.500105 -401.295411) (xy 71.500492 -401.286218) (xy 71.500492 -400.793966) (xy 71.5001 -400.784777)
			(xy 71.493574 -400.767592) (xy 71.487792 -400.760438) (xy 71.465934 -400.734768) (xy 71.427846 -400.679134)
			(xy 71.396695 -400.619338) (xy 71.372931 -400.556242) (xy 71.356896 -400.490754) (xy 71.348819 -400.423816)
			(xy 71.348819 -400.356393) (xy 71.356894 -400.289455) (xy 71.372928 -400.223967) (xy 71.396692 -400.16087)
			(xy 71.427841 -400.101074) (xy 71.465929 -400.045439) (xy 71.487792 -400.019774) (xy 71.493581 -400.012623)
			(xy 71.500101 -399.995437) (xy 71.500492 -399.986246) (xy 71.500492 -399.828766) (xy 71.500997 -399.818643)
			(xy 71.508727 -399.79993) (xy 71.523007 -399.785577) (xy 71.54168 -399.77775) (xy 71.5518 -399.777204)
			(xy 72.26808 -399.777204) (xy 72.278233 -399.777638) (xy 72.296986 -399.785428) (xy 72.31131 -399.799821)
			(xy 72.31901 -399.818611) (xy 72.319388 -399.828766) (xy 72.319388 -399.986246) (xy 72.319827 -399.99543)
			(xy 72.326321 -400.012615) (xy 72.332088 -400.019774) (xy 72.353958 -400.045434) (xy 72.392048 -400.101069)
			(xy 72.423199 -400.160866) (xy 72.446963 -400.223963) (xy 72.462999 -400.289453) (xy 72.471074 -400.356392)
			(xy 72.471074 -400.423817) (xy 72.462997 -400.490756) (xy 72.44696 -400.556245) (xy 72.423195 -400.619342)
			(xy 72.392043 -400.679139) (xy 72.353953 -400.734773) (xy 72.332088 -400.760438) (xy 72.326291 -400.767583)
			(xy 72.319777 -400.784774) (xy 72.319388 -400.793966) (xy 72.319388 -401.286218) (xy 72.319792 -401.295406)
			(xy 72.32631 -401.31259) (xy 72.332088 -401.319746) (xy 72.353931 -401.345429) (xy 72.392021 -401.401061)
			(xy 72.423173 -401.460854) (xy 72.446939 -401.523949) (xy 72.462977 -401.589436) (xy 72.471054 -401.656372)
			(xy 72.471056 -401.723795) (xy 72.462982 -401.790732) (xy 72.446949 -401.85622) (xy 72.423187 -401.919316)
			(xy 72.392038 -401.979111) (xy 72.353951 -402.034745) (xy 72.332088 -402.06041) (xy 72.326303 -402.067564)
			(xy 72.319782 -402.084748) (xy 72.319388 -402.093938) (xy 72.319388 -402.251418) (xy 72.318889 -402.261542)
			(xy 72.311161 -402.280259) (xy 72.296879 -402.294614) (xy 72.278202 -402.302437) (xy 72.26808 -402.30298)
			(xy 71.5518 -402.30298) (xy 71.541643 -402.302578) (xy 71.522887 -402.294779) (xy 71.508563 -402.280376)
			(xy 71.500867 -402.261577) (xy 71.500492 -402.251418) (xy 71.500492 -402.093938) (xy 71.500065 -402.084753)
			(xy 71.493563 -402.067568) (xy 71.487792 -402.06041) (xy 71.465907 -402.034762) (xy 71.427819 -401.979125)
			(xy 71.39667 -401.919326) (xy 71.372907 -401.856227) (xy 71.356874 -401.790736) (xy 71.3488 -401.723796)
			(xy 66.525648 -401.723796) (xy 66.525648 -402.823818) (xy 73.54894 -402.823818) (xy 73.548944 -402.75651)
			(xy 73.556993 -402.689684) (xy 73.572971 -402.624299) (xy 73.596649 -402.561293) (xy 73.627687 -402.501568)
			(xy 73.665642 -402.44598) (xy 73.687432 -402.420328) (xy 73.693246 -402.413195) (xy 73.699749 -402.395995)
			(xy 73.700132 -402.3868) (xy 73.700132 -401.893532) (xy 73.699699 -401.884347) (xy 73.6932 -401.867163)
			(xy 73.687432 -401.860004) (xy 73.665625 -401.834368) (xy 73.627677 -401.778779) (xy 73.596645 -401.719053)
			(xy 73.572974 -401.656047) (xy 73.557002 -401.590662) (xy 73.54896 -401.523838) (xy 73.548962 -401.456532)
			(xy 73.557008 -401.389708) (xy 73.572982 -401.324325) (xy 73.596657 -401.261319) (xy 73.627692 -401.201595)
			(xy 73.665643 -401.146008) (xy 73.687432 -401.120356) (xy 73.693234 -401.113215) (xy 73.699745 -401.096021)
			(xy 73.700132 -401.086828) (xy 73.700132 -400.92884) (xy 73.700555 -400.918685) (xy 73.708343 -400.899927)
			(xy 73.722741 -400.885601) (xy 73.741537 -400.877906) (xy 73.751694 -400.877532) (xy 74.467974 -400.877532)
			(xy 74.478098 -400.878047) (xy 74.496817 -400.885765) (xy 74.511174 -400.900043) (xy 74.518996 -400.918719)
			(xy 74.519536 -400.92884) (xy 74.519536 -401.086828) (xy 74.519947 -401.096015) (xy 74.526462 -401.113198)
			(xy 74.532236 -401.120356) (xy 74.554005 -401.146024) (xy 74.591956 -401.201608) (xy 74.622991 -401.261329)
			(xy 74.646666 -401.324331) (xy 74.662641 -401.389712) (xy 74.670687 -401.456533) (xy 74.670689 -401.523837)
			(xy 74.662647 -401.590659) (xy 74.646675 -401.65604) (xy 74.623004 -401.719044) (xy 74.620565 -401.723737)
			(xy 75.749095 -401.723737) (xy 75.749097 -401.65643) (xy 75.757144 -401.589605) (xy 75.773121 -401.524221)
			(xy 75.796798 -401.461215) (xy 75.827836 -401.401492) (xy 75.86579 -401.345906) (xy 75.88758 -401.320254)
			(xy 75.893376 -401.313108) (xy 75.899892 -401.295918) (xy 75.90028 -401.286726) (xy 75.90028 -400.793458)
			(xy 75.899895 -400.784268) (xy 75.893364 -400.767084) (xy 75.88758 -400.75993) (xy 75.865797 -400.734274)
			(xy 75.827845 -400.678689) (xy 75.79681 -400.618966) (xy 75.773135 -400.555962) (xy 75.75716 -400.49058)
			(xy 75.749115 -400.423757) (xy 75.749114 -400.356452) (xy 75.757158 -400.289629) (xy 75.773132 -400.224247)
			(xy 75.796806 -400.161242) (xy 75.827841 -400.101519) (xy 75.865791 -400.045934) (xy 75.88758 -400.020282)
			(xy 75.893364 -400.013128) (xy 75.899887 -399.995944) (xy 75.90028 -399.986754) (xy 75.90028 -399.828766)
			(xy 75.900637 -399.818587) (xy 75.908441 -399.799783) (xy 75.922847 -399.785398) (xy 75.941662 -399.777622)
			(xy 75.951842 -399.777204) (xy 76.668122 -399.777204) (xy 76.678277 -399.777714) (xy 76.69704 -399.78549)
			(xy 76.711404 -399.79985) (xy 76.719183 -399.818611) (xy 76.719684 -399.828766) (xy 76.719684 -399.986754)
			(xy 76.72012 -399.995938) (xy 76.726616 -400.013123) (xy 76.732384 -400.020282) (xy 76.754177 -400.04593)
			(xy 76.792124 -400.101517) (xy 76.823156 -400.161242) (xy 76.846827 -400.224247) (xy 76.862799 -400.289629)
			(xy 76.870842 -400.356452) (xy 76.870842 -400.423757) (xy 76.862798 -400.49058) (xy 76.846825 -400.555962)
			(xy 76.823152 -400.618967) (xy 76.792119 -400.678691) (xy 76.754171 -400.734278) (xy 76.732384 -400.75993)
			(xy 76.72659 -400.767077) (xy 76.720074 -400.784266) (xy 76.719684 -400.793458) (xy 76.719684 -401.286726)
			(xy 76.720085 -401.295914) (xy 76.726605 -401.313098) (xy 76.732384 -401.320254) (xy 76.754149 -401.345924)
			(xy 76.792097 -401.401509) (xy 76.82313 -401.46123) (xy 76.846803 -401.524232) (xy 76.862777 -401.589612)
			(xy 76.870823 -401.656432) (xy 76.870825 -401.723735) (xy 76.862783 -401.790556) (xy 76.846813 -401.855936)
			(xy 76.823144 -401.91894) (xy 76.792114 -401.978663) (xy 76.75417 -402.03425) (xy 76.732384 -402.059902)
			(xy 76.726602 -402.067058) (xy 76.720079 -402.08424) (xy 76.719684 -402.09343) (xy 76.719684 -402.251418)
			(xy 76.719182 -402.261574) (xy 76.711406 -402.28034) (xy 76.697043 -402.294704) (xy 76.678278 -402.302481)
			(xy 76.668122 -402.30298) (xy 75.951842 -402.30298) (xy 75.941675 -402.302502) (xy 75.922885 -402.294734)
			(xy 75.908499 -402.280365) (xy 75.90071 -402.261584) (xy 75.90028 -402.251418) (xy 75.90028 -402.09343)
			(xy 75.89986 -402.084244) (xy 75.893354 -402.067059) (xy 75.88758 -402.059902) (xy 75.865769 -402.034268)
			(xy 75.827819 -401.97868) (xy 75.796784 -401.918954) (xy 75.773111 -401.855947) (xy 75.757138 -401.790562)
			(xy 75.749095 -401.723737) (xy 74.620565 -401.723737) (xy 74.591971 -401.778767) (xy 74.554023 -401.834352)
			(xy 74.532236 -401.860004) (xy 74.526447 -401.867155) (xy 74.51993 -401.884341) (xy 74.519536 -401.893532)
			(xy 74.519536 -402.3868) (xy 74.519961 -402.395985) (xy 74.526466 -402.413169) (xy 74.532236 -402.420328)
			(xy 74.553977 -402.446019) (xy 74.591929 -402.501599) (xy 74.622966 -402.561317) (xy 74.646642 -402.624317)
			(xy 74.662619 -402.689694) (xy 74.670668 -402.756513) (xy 74.670672 -402.823815) (xy 74.670664 -402.823878)
			(xy 77.948708 -402.823878) (xy 77.948713 -402.75645) (xy 77.956794 -402.689508) (xy 77.972835 -402.624016)
			(xy 77.996606 -402.560917) (xy 78.027764 -402.501119) (xy 78.06586 -402.445485) (xy 78.087728 -402.41982)
			(xy 78.093545 -402.412689) (xy 78.100047 -402.395488) (xy 78.100428 -402.386292) (xy 78.100428 -401.89404)
			(xy 78.099992 -401.884856) (xy 78.093496 -401.867671) (xy 78.087728 -401.860512) (xy 78.065843 -401.834863)
			(xy 78.027753 -401.779227) (xy 77.996602 -401.719429) (xy 77.972838 -401.65633) (xy 77.956803 -401.590838)
			(xy 77.948728 -401.523898) (xy 77.94873 -401.456472) (xy 77.956808 -401.389532) (xy 77.972847 -401.324041)
			(xy 77.996614 -401.260944) (xy 78.027769 -401.201147) (xy 78.065862 -401.145513) (xy 78.087728 -401.119848)
			(xy 78.093533 -401.112709) (xy 78.100042 -401.095514) (xy 78.100428 -401.08632) (xy 78.100428 -400.92884)
			(xy 78.10085 -400.918717) (xy 78.10859 -400.900009) (xy 78.122905 -400.885692) (xy 78.141613 -400.87795)
			(xy 78.151736 -400.877532) (xy 78.868016 -400.877532) (xy 78.878144 -400.877903) (xy 78.896854 -400.885663)
			(xy 78.911169 -400.899993) (xy 78.918908 -400.918712) (xy 78.919324 -400.92884) (xy 78.919324 -401.08632)
			(xy 78.919719 -401.095509) (xy 78.926243 -401.112693) (xy 78.932024 -401.119848) (xy 78.953867 -401.14553)
			(xy 78.991955 -401.201163) (xy 79.023105 -401.260957) (xy 79.04687 -401.324051) (xy 79.062906 -401.389538)
			(xy 79.070983 -401.456474) (xy 79.070985 -401.523896) (xy 79.062911 -401.590832) (xy 79.046879 -401.65632)
			(xy 79.023118 -401.719416) (xy 79.020837 -401.723796) (xy 80.148888 -401.723796) (xy 80.14889 -401.656371)
			(xy 80.156967 -401.589432) (xy 80.173004 -401.523942) (xy 80.19677 -401.460844) (xy 80.227922 -401.401047)
			(xy 80.266012 -401.345412) (xy 80.287876 -401.319746) (xy 80.293675 -401.312603) (xy 80.300189 -401.295411)
			(xy 80.300576 -401.286218) (xy 80.300576 -400.793966) (xy 80.300187 -400.784776) (xy 80.293659 -400.767592)
			(xy 80.287876 -400.760438) (xy 80.266019 -400.734767) (xy 80.227931 -400.679133) (xy 80.196782 -400.619337)
			(xy 80.173018 -400.556241) (xy 80.156983 -400.490753) (xy 80.148907 -400.423816) (xy 80.148907 -400.356393)
			(xy 80.156982 -400.289456) (xy 80.173016 -400.223967) (xy 80.196778 -400.160871) (xy 80.227927 -400.101075)
			(xy 80.266013 -400.04544) (xy 80.287876 -400.019774) (xy 80.293663 -400.012622) (xy 80.300184 -399.995437)
			(xy 80.300576 -399.986246) (xy 80.300576 -399.828766) (xy 80.301 -399.818633) (xy 80.308745 -399.799904)
			(xy 80.323051 -399.785548) (xy 80.341753 -399.777736) (xy 80.351884 -399.777204) (xy 81.068164 -399.777204)
			(xy 81.078316 -399.777651) (xy 81.097069 -399.785436) (xy 81.111393 -399.799825) (xy 81.119094 -399.818612)
			(xy 81.119472 -399.828766) (xy 81.119472 -399.986246) (xy 81.119914 -399.99543) (xy 81.126406 -400.012614)
			(xy 81.132172 -400.019774) (xy 81.154043 -400.045434) (xy 81.192133 -400.101069) (xy 81.223285 -400.160865)
			(xy 81.24705 -400.223963) (xy 81.263086 -400.289453) (xy 81.271162 -400.356392) (xy 81.271161 -400.423817)
			(xy 81.263085 -400.490756) (xy 81.247048 -400.556246) (xy 81.223282 -400.619343) (xy 81.192129 -400.679139)
			(xy 81.154037 -400.734773) (xy 81.132172 -400.760438) (xy 81.126373 -400.767581) (xy 81.11986 -400.784773)
			(xy 81.119472 -400.793966) (xy 81.119472 -401.286218) (xy 81.11988 -401.295405) (xy 81.126396 -401.312589)
			(xy 81.132172 -401.319746) (xy 81.154015 -401.345429) (xy 81.192107 -401.40106) (xy 81.22326 -401.460854)
			(xy 81.247026 -401.523948) (xy 81.263064 -401.589435) (xy 81.271142 -401.656372) (xy 81.271144 -401.723795)
			(xy 81.26307 -401.790732) (xy 81.247036 -401.85622) (xy 81.223273 -401.919316) (xy 81.192124 -401.979112)
			(xy 81.154036 -402.034745) (xy 81.132172 -402.06041) (xy 81.126385 -402.067562) (xy 81.119865 -402.084747)
			(xy 81.119472 -402.093938) (xy 81.119472 -402.251418) (xy 81.118989 -402.261544) (xy 81.111257 -402.280264)
			(xy 81.09697 -402.294619) (xy 81.078288 -402.30244) (xy 81.068164 -402.30298) (xy 80.351884 -402.30298)
			(xy 80.341726 -402.302591) (xy 80.32297 -402.294787) (xy 80.308646 -402.28038) (xy 80.30095 -402.261578)
			(xy 80.300576 -402.251418) (xy 80.300576 -402.093938) (xy 80.300153 -402.084752) (xy 80.293649 -402.067567)
			(xy 80.287876 -402.06041) (xy 80.265991 -402.034762) (xy 80.227905 -401.979125) (xy 80.196756 -401.919326)
			(xy 80.172994 -401.856227) (xy 80.156961 -401.790736) (xy 80.148888 -401.723796) (xy 79.020837 -401.723796)
			(xy 78.991971 -401.779212) (xy 78.953886 -401.834846) (xy 78.932024 -401.860512) (xy 78.926243 -401.867668)
			(xy 78.919718 -401.88485) (xy 78.919324 -401.89404) (xy 78.919324 -402.386292) (xy 78.919733 -402.395479)
			(xy 78.926247 -402.412664) (xy 78.932024 -402.41982) (xy 78.95384 -402.445525) (xy 78.991929 -402.501154)
			(xy 79.02308 -402.560945) (xy 79.046846 -402.624037) (xy 79.062884 -402.689521) (xy 79.070963 -402.756454)
			(xy 79.070968 -402.823818) (xy 82.349028 -402.823818) (xy 82.349032 -402.75651) (xy 82.357081 -402.689684)
			(xy 82.373058 -402.6243) (xy 82.396735 -402.561293) (xy 82.427773 -402.501568) (xy 82.465726 -402.44598)
			(xy 82.487516 -402.420328) (xy 82.493327 -402.413193) (xy 82.499833 -402.395995) (xy 82.500216 -402.3868)
			(xy 82.500216 -401.893532) (xy 82.499787 -401.884347) (xy 82.493286 -401.867163) (xy 82.487516 -401.860004)
			(xy 82.465709 -401.834368) (xy 82.427763 -401.778778) (xy 82.396731 -401.719052) (xy 82.373061 -401.656046)
			(xy 82.35709 -401.590662) (xy 82.349048 -401.523838) (xy 82.34905 -401.456532) (xy 82.357095 -401.389708)
			(xy 82.37307 -401.324325) (xy 82.396744 -401.26132) (xy 82.427778 -401.201596) (xy 82.465728 -401.146008)
			(xy 82.487516 -401.120356) (xy 82.493316 -401.113213) (xy 82.499828 -401.096021) (xy 82.500216 -401.086828)
			(xy 82.500216 -400.92884) (xy 82.500655 -400.918687) (xy 82.50844 -400.899932) (xy 82.522832 -400.885607)
			(xy 82.541623 -400.877908) (xy 82.551778 -400.877532) (xy 83.268058 -400.877532) (xy 83.278181 -400.878061)
			(xy 83.2969 -400.885773) (xy 83.311257 -400.900047) (xy 83.319079 -400.91872) (xy 83.31962 -400.92884)
			(xy 83.31962 -401.086828) (xy 83.320012 -401.096017) (xy 83.326538 -401.113202) (xy 83.33232 -401.120356)
			(xy 83.354089 -401.146024) (xy 83.392041 -401.201607) (xy 83.423078 -401.261328) (xy 83.446753 -401.324331)
			(xy 83.462729 -401.389711) (xy 83.470775 -401.456533) (xy 83.470777 -401.523837) (xy 83.462734 -401.590659)
			(xy 83.446762 -401.656041) (xy 83.42309 -401.719044) (xy 83.420621 -401.723796) (xy 84.548678 -401.723796)
			(xy 84.54868 -401.656371) (xy 84.556758 -401.589432) (xy 84.572795 -401.523942) (xy 84.59656 -401.460845)
			(xy 84.627711 -401.401047) (xy 84.6658 -401.345412) (xy 84.687664 -401.319746) (xy 84.693474 -401.312611)
			(xy 84.699979 -401.295412) (xy 84.700364 -401.286218) (xy 84.700364 -400.793966) (xy 84.699956 -400.784779)
			(xy 84.693439 -400.767595) (xy 84.687664 -400.760438) (xy 84.665807 -400.734767) (xy 84.627721 -400.679133)
			(xy 84.596572 -400.619337) (xy 84.572809 -400.556241) (xy 84.556774 -400.490753) (xy 84.548698 -400.423816)
			(xy 84.548698 -400.356393) (xy 84.556772 -400.289456) (xy 84.572806 -400.223968) (xy 84.596568 -400.160871)
			(xy 84.627716 -400.101075) (xy 84.665802 -400.04544) (xy 84.687664 -400.019774) (xy 84.693462 -400.01263)
			(xy 84.699974 -399.995438) (xy 84.700364 -399.986246) (xy 84.700364 -399.828766) (xy 84.700799 -399.818634)
			(xy 84.708543 -399.799908) (xy 84.722845 -399.785552) (xy 84.741542 -399.777738) (xy 84.751672 -399.777204)
			(xy 85.467952 -399.777204) (xy 85.478104 -399.777661) (xy 85.496856 -399.785442) (xy 85.511181 -399.799828)
			(xy 85.518881 -399.818613) (xy 85.51926 -399.828766) (xy 85.51926 -399.986246) (xy 85.519705 -399.995429)
			(xy 85.526196 -400.012613) (xy 85.53196 -400.019774) (xy 85.553831 -400.045434) (xy 85.591922 -400.101068)
			(xy 85.623075 -400.160865) (xy 85.646841 -400.223962) (xy 85.662877 -400.289453) (xy 85.670953 -400.356392)
			(xy 85.670952 -400.423817) (xy 85.662875 -400.490756) (xy 85.646838 -400.556246) (xy 85.623071 -400.619344)
			(xy 85.591918 -400.67914) (xy 85.553826 -400.734773) (xy 85.53196 -400.760438) (xy 85.52616 -400.76758)
			(xy 85.519648 -400.784773) (xy 85.51926 -400.793966) (xy 85.51926 -401.286218) (xy 85.51967 -401.295405)
			(xy 85.526185 -401.312589) (xy 85.53196 -401.319746) (xy 85.553804 -401.345428) (xy 85.591896 -401.40106)
			(xy 85.62305 -401.460853) (xy 85.646817 -401.523948) (xy 85.662855 -401.589435) (xy 85.670933 -401.656372)
			(xy 85.670935 -401.723795) (xy 85.662861 -401.790732) (xy 85.646827 -401.856221) (xy 85.623063 -401.919317)
			(xy 85.591913 -401.979112) (xy 85.553824 -402.034745) (xy 85.53196 -402.06041) (xy 85.526172 -402.067561)
			(xy 85.519653 -402.084747) (xy 85.51926 -402.093938) (xy 85.51926 -402.251418) (xy 85.518788 -402.261546)
			(xy 85.511055 -402.280268) (xy 85.496764 -402.294623) (xy 85.478078 -402.302442) (xy 85.467952 -402.30298)
			(xy 84.751672 -402.30298) (xy 84.741514 -402.302601) (xy 84.722757 -402.294792) (xy 84.708434 -402.280383)
			(xy 84.700738 -402.261579) (xy 84.700364 -402.251418) (xy 84.700364 -402.093938) (xy 84.699921 -402.084755)
			(xy 84.693429 -402.067571) (xy 84.687664 -402.06041) (xy 84.66578 -402.034762) (xy 84.627694 -401.979124)
			(xy 84.596546 -401.919325) (xy 84.572785 -401.856226) (xy 84.556752 -401.790735) (xy 84.548678 -401.723796)
			(xy 83.420621 -401.723796) (xy 83.392057 -401.778767) (xy 83.354108 -401.834352) (xy 83.33232 -401.860004)
			(xy 83.326542 -401.867162) (xy 83.320015 -401.884343) (xy 83.31962 -401.893532) (xy 83.31962 -402.3868)
			(xy 83.320026 -402.395988) (xy 83.326542 -402.413172) (xy 83.33232 -402.420328) (xy 83.354062 -402.446018)
			(xy 83.392015 -402.501598) (xy 83.423052 -402.561316) (xy 83.44673 -402.624316) (xy 83.462707 -402.689694)
			(xy 83.470756 -402.756513) (xy 83.47076 -402.823815) (xy 83.470752 -402.823878) (xy 86.748796 -402.823878)
			(xy 86.748801 -402.75645) (xy 86.756882 -402.689508) (xy 86.772922 -402.624016) (xy 86.796693 -402.560918)
			(xy 86.82785 -402.50112) (xy 86.865945 -402.445485) (xy 86.887812 -402.41982) (xy 86.893626 -402.412687)
			(xy 86.90013 -402.395487) (xy 86.900512 -402.386292) (xy 86.900512 -401.89404) (xy 86.90008 -401.884855)
			(xy 86.893581 -401.867671) (xy 86.887812 -401.860512) (xy 86.865928 -401.834863) (xy 86.827839 -401.779227)
			(xy 86.796689 -401.719428) (xy 86.772925 -401.656329) (xy 86.756891 -401.590838) (xy 86.748816 -401.523898)
			(xy 86.748818 -401.456472) (xy 86.756896 -401.389532) (xy 86.772934 -401.324042) (xy 86.796701 -401.260944)
			(xy 86.827855 -401.201148) (xy 86.865946 -401.145513) (xy 86.887812 -401.119848) (xy 86.893615 -401.112707)
			(xy 86.900125 -401.095513) (xy 86.900512 -401.08632) (xy 86.900512 -400.92884) (xy 86.900949 -400.918719)
			(xy 86.908686 -400.900014) (xy 86.922997 -400.885698) (xy 86.941699 -400.877953) (xy 86.95182 -400.877532)
			(xy 87.6681 -400.877532) (xy 87.678226 -400.877917) (xy 87.696936 -400.885671) (xy 87.711252 -400.899997)
			(xy 87.718991 -400.918713) (xy 87.719408 -400.92884) (xy 87.719408 -401.08632) (xy 87.719807 -401.095508)
			(xy 87.726328 -401.112693) (xy 87.732108 -401.119848) (xy 87.753952 -401.14553) (xy 87.792041 -401.201162)
			(xy 87.823192 -401.260956) (xy 87.846957 -401.324051) (xy 87.862994 -401.389538) (xy 87.871071 -401.456474)
			(xy 87.871073 -401.523896) (xy 87.862999 -401.590833) (xy 87.846966 -401.656321) (xy 87.823204 -401.719417)
			(xy 87.820954 -401.723737) (xy 115.349237 -401.723737) (xy 115.349239 -401.65643) (xy 115.357285 -401.589607)
			(xy 115.373259 -401.524224) (xy 115.396933 -401.461219) (xy 115.427967 -401.401494) (xy 115.465916 -401.345907)
			(xy 115.487704 -401.320254) (xy 115.493503 -401.313111) (xy 115.500016 -401.295919) (xy 115.500404 -401.286726)
			(xy 115.500404 -400.793458) (xy 115.500013 -400.784269) (xy 115.493486 -400.767085) (xy 115.487704 -400.75993)
			(xy 115.465923 -400.734273) (xy 115.427977 -400.678686) (xy 115.396945 -400.618963) (xy 115.373273 -400.555959)
			(xy 115.357301 -400.490578) (xy 115.349257 -400.423756) (xy 115.349256 -400.356453) (xy 115.357299 -400.289631)
			(xy 115.373271 -400.22425) (xy 115.396941 -400.161245) (xy 115.427972 -400.101522) (xy 115.465918 -400.045935)
			(xy 115.487704 -400.020282) (xy 115.493491 -400.01313) (xy 115.500011 -399.995945) (xy 115.500404 -399.986754)
			(xy 115.500404 -399.828766) (xy 115.500905 -399.81861) (xy 115.508684 -399.799847) (xy 115.523047 -399.785484)
			(xy 115.54181 -399.777705) (xy 115.551966 -399.777204) (xy 116.268246 -399.777204) (xy 116.278403 -399.777695)
			(xy 116.297166 -399.785478) (xy 116.311529 -399.799844) (xy 116.319307 -399.818609) (xy 116.319808 -399.828766)
			(xy 116.319808 -399.986754) (xy 116.320238 -399.995939) (xy 116.326738 -400.013124) (xy 116.332508 -400.020282)
			(xy 116.354303 -400.045929) (xy 116.392255 -400.101515) (xy 116.423291 -400.161238) (xy 116.446966 -400.224244)
			(xy 116.46294 -400.289627) (xy 116.470985 -400.356451) (xy 116.470984 -400.423758) (xy 116.462939 -400.490582)
			(xy 116.446963 -400.555965) (xy 116.423288 -400.61897) (xy 116.392251 -400.678693) (xy 116.354298 -400.734279)
			(xy 116.332508 -400.75993) (xy 116.326717 -400.767079) (xy 116.320199 -400.784267) (xy 116.319808 -400.793458)
			(xy 116.319808 -401.286726) (xy 116.320204 -401.295915) (xy 116.326727 -401.313099) (xy 116.332508 -401.320254)
			(xy 116.354276 -401.345923) (xy 116.392229 -401.401506) (xy 116.423266 -401.461227) (xy 116.446942 -401.524229)
			(xy 116.462918 -401.58961) (xy 116.470965 -401.656431) (xy 116.470967 -401.723736) (xy 116.462924 -401.790558)
			(xy 116.446952 -401.855939) (xy 116.423279 -401.918943) (xy 116.392246 -401.978666) (xy 116.354296 -402.034251)
			(xy 116.332508 -402.059902) (xy 116.326729 -402.06706) (xy 116.320204 -402.084241) (xy 116.319808 -402.09343)
			(xy 116.319808 -402.251418) (xy 116.319283 -402.261571) (xy 116.311511 -402.280332) (xy 116.297156 -402.294695)
			(xy 116.278399 -402.302477) (xy 116.268246 -402.30298) (xy 115.551966 -402.30298) (xy 115.541808 -402.302495)
			(xy 115.523042 -402.294713) (xy 115.508678 -402.280345) (xy 115.500902 -402.261576) (xy 115.500404 -402.251418)
			(xy 115.500404 -402.09343) (xy 115.499978 -402.084244) (xy 115.493475 -402.06706) (xy 115.487704 -402.059902)
			(xy 115.465896 -402.034267) (xy 115.42795 -401.978677) (xy 115.396919 -401.918951) (xy 115.373249 -401.855944)
			(xy 115.357279 -401.79056) (xy 115.349237 -401.723737) (xy 87.820954 -401.723737) (xy 87.792056 -401.779212)
			(xy 87.75397 -401.834847) (xy 87.732108 -401.860512) (xy 87.726325 -401.867667) (xy 87.719802 -401.88485)
			(xy 87.719408 -401.89404) (xy 87.719408 -402.386292) (xy 87.71982 -402.395479) (xy 87.726332 -402.412663)
			(xy 87.732108 -402.41982) (xy 87.753925 -402.445524) (xy 87.792014 -402.501153) (xy 87.823166 -402.560944)
			(xy 87.846933 -402.624036) (xy 87.862972 -402.68952) (xy 87.871051 -402.756454) (xy 87.871055 -402.823874)
			(xy 87.871055 -402.823878) (xy 117.548826 -402.823878) (xy 117.548831 -402.75645) (xy 117.556912 -402.689507)
			(xy 117.572954 -402.624015) (xy 117.596726 -402.560916) (xy 117.627885 -402.501119) (xy 117.665983 -402.445484)
			(xy 117.687852 -402.41982) (xy 117.693671 -402.412691) (xy 117.700171 -402.395488) (xy 117.700552 -402.386292)
			(xy 117.700552 -401.89404) (xy 117.700111 -401.884856) (xy 117.693618 -401.867672) (xy 117.687852 -401.860512)
			(xy 117.665967 -401.834864) (xy 117.627875 -401.779228) (xy 117.596722 -401.71943) (xy 117.572957 -401.656331)
			(xy 117.556921 -401.590839) (xy 117.548846 -401.523898) (xy 117.548848 -401.456472) (xy 117.556927 -401.389531)
			(xy 117.572966 -401.32404) (xy 117.596735 -401.260943) (xy 117.627891 -401.201146) (xy 117.665985 -401.145512)
			(xy 117.687852 -401.119848) (xy 117.69366 -401.112711) (xy 117.700166 -401.095514) (xy 117.700552 -401.08632)
			(xy 117.700552 -400.92884) (xy 117.701117 -400.91874) (xy 117.708832 -400.900072) (xy 117.723105 -400.885777)
			(xy 117.741761 -400.878033) (xy 117.75186 -400.877532) (xy 118.46814 -400.877532) (xy 118.478255 -400.877953)
			(xy 118.49694 -400.88571) (xy 118.511235 -400.900027) (xy 118.518963 -400.918724) (xy 118.519448 -400.92884)
			(xy 118.519448 -401.08632) (xy 118.51986 -401.095507) (xy 118.526374 -401.11269) (xy 118.532148 -401.119848)
			(xy 118.553994 -401.145529) (xy 118.592087 -401.20116) (xy 118.623241 -401.260953) (xy 118.647009 -401.324048)
			(xy 118.663047 -401.389536) (xy 118.671126 -401.456473) (xy 118.671127 -401.523897) (xy 118.663053 -401.590834)
			(xy 118.647018 -401.656323) (xy 118.623254 -401.719419) (xy 118.620974 -401.723796) (xy 119.749006 -401.723796)
			(xy 119.749008 -401.656371) (xy 119.757086 -401.589431) (xy 119.773123 -401.523941) (xy 119.79689 -401.460843)
			(xy 119.828043 -401.401046) (xy 119.866135 -401.345411) (xy 119.888 -401.319746) (xy 119.893802 -401.312605)
			(xy 119.900313 -401.295411) (xy 119.9007 -401.286218) (xy 119.9007 -400.793966) (xy 119.900306 -400.784777)
			(xy 119.893781 -400.767593) (xy 119.888 -400.760438) (xy 119.866142 -400.734768) (xy 119.828053 -400.679134)
			(xy 119.796902 -400.619339) (xy 119.773138 -400.556242) (xy 119.757102 -400.490754) (xy 119.749025 -400.423816)
			(xy 119.749025 -400.356393) (xy 119.7571 -400.289455) (xy 119.773135 -400.223966) (xy 119.796898 -400.16087)
			(xy 119.828048 -400.101074) (xy 119.866136 -400.045439) (xy 119.888 -400.019774) (xy 119.89379 -400.012624)
			(xy 119.900309 -399.995437) (xy 119.9007 -399.986246) (xy 119.9007 -399.828766) (xy 119.901197 -399.818642)
			(xy 119.908929 -399.799928) (xy 119.923211 -399.785574) (xy 119.941887 -399.777749) (xy 119.952008 -399.777204)
			(xy 120.668288 -399.777204) (xy 120.67841 -399.777626) (xy 120.697114 -399.785371) (xy 120.711429 -399.799686)
			(xy 120.719174 -399.81839) (xy 120.719596 -399.828512) (xy 120.719596 -399.986246) (xy 120.720033 -399.99543)
			(xy 120.726528 -400.012615) (xy 120.732296 -400.019774) (xy 120.754166 -400.045434) (xy 120.792255 -400.101069)
			(xy 120.823405 -400.160866) (xy 120.847169 -400.223964) (xy 120.863205 -400.289454) (xy 120.87128 -400.356392)
			(xy 120.87128 -400.423817) (xy 120.863203 -400.490755) (xy 120.847167 -400.556245) (xy 120.823402 -400.619342)
			(xy 120.79225 -400.679138) (xy 120.75416 -400.734773) (xy 120.732296 -400.760438) (xy 120.7265 -400.767584)
			(xy 120.719985 -400.784774) (xy 120.719596 -400.793966) (xy 120.719596 -401.286218) (xy 120.719998 -401.295406)
			(xy 120.726517 -401.31259) (xy 120.732296 -401.319746) (xy 120.754138 -401.345429) (xy 120.792228 -401.401061)
			(xy 120.82338 -401.460855) (xy 120.847146 -401.523949) (xy 120.863183 -401.589436) (xy 120.87126 -401.656372)
			(xy 120.871262 -401.723794) (xy 120.863189 -401.790731) (xy 120.847155 -401.856219) (xy 120.823394 -401.919315)
			(xy 120.792245 -401.979111) (xy 120.754159 -402.034745) (xy 120.732296 -402.06041) (xy 120.726512 -402.067564)
			(xy 120.71999 -402.084748) (xy 120.719596 -402.093938) (xy 120.719596 -402.251418) (xy 120.719089 -402.261541)
			(xy 120.711362 -402.280256) (xy 120.697083 -402.294611) (xy 120.678409 -402.302436) (xy 120.668288 -402.30298)
			(xy 119.952008 -402.30298) (xy 119.941884 -402.302577) (xy 119.923176 -402.294828) (xy 119.908861 -402.280507)
			(xy 119.901119 -402.261797) (xy 119.9007 -402.251672) (xy 119.9007 -402.093938) (xy 119.900272 -402.084753)
			(xy 119.893771 -402.067568) (xy 119.888 -402.06041) (xy 119.866114 -402.034763) (xy 119.828026 -401.979126)
			(xy 119.796877 -401.919327) (xy 119.773114 -401.856228) (xy 119.75708 -401.790736) (xy 119.749006 -401.723796)
			(xy 118.620974 -401.723796) (xy 118.592102 -401.779215) (xy 118.554013 -401.834848) (xy 118.532148 -401.860512)
			(xy 118.526357 -401.867661) (xy 118.519841 -401.884849) (xy 118.519448 -401.89404) (xy 118.519448 -402.386292)
			(xy 118.519874 -402.395477) (xy 118.526378 -402.412661) (xy 118.532148 -402.41982) (xy 118.553967 -402.445523)
			(xy 118.59206 -402.501151) (xy 118.623216 -402.560942) (xy 118.646985 -402.624034) (xy 118.663025 -402.689519)
			(xy 118.671106 -402.756454) (xy 118.67111 -402.823818) (xy 121.949146 -402.823818) (xy 121.94915 -402.756509)
			(xy 121.957199 -402.689684) (xy 121.973177 -402.624299) (xy 121.996856 -402.561292) (xy 122.027895 -402.501567)
			(xy 122.065849 -402.44598) (xy 122.08764 -402.420328) (xy 122.093455 -402.413196) (xy 122.099958 -402.395995)
			(xy 122.10034 -402.3868) (xy 122.10034 -401.893532) (xy 122.099905 -401.884348) (xy 122.093408 -401.867164)
			(xy 122.08764 -401.860004) (xy 122.065832 -401.834368) (xy 122.027884 -401.778779) (xy 121.996852 -401.719054)
			(xy 121.97318 -401.656047) (xy 121.957208 -401.590663) (xy 121.949166 -401.523838) (xy 121.949168 -401.456532)
			(xy 121.957214 -401.389708) (xy 121.973189 -401.324324) (xy 121.996864 -401.261319) (xy 122.0279 -401.201595)
			(xy 122.065851 -401.146008) (xy 122.08764 -401.120356) (xy 122.093443 -401.113215) (xy 122.099953 -401.096021)
			(xy 122.10034 -401.086828) (xy 122.10034 -400.92884) (xy 122.10075 -400.918715) (xy 122.108492 -400.900005)
			(xy 122.122812 -400.885688) (xy 122.141523 -400.877948) (xy 122.151648 -400.877532) (xy 122.868182 -400.877532)
			(xy 122.878307 -400.878041) (xy 122.897026 -400.885761) (xy 122.911383 -400.900041) (xy 122.919204 -400.918718)
			(xy 122.919744 -400.92884) (xy 122.919744 -401.086828) (xy 122.920153 -401.096015) (xy 122.926669 -401.113199)
			(xy 122.932444 -401.120356) (xy 122.954212 -401.146024) (xy 122.992163 -401.201608) (xy 123.023198 -401.261329)
			(xy 123.046873 -401.324332) (xy 123.062848 -401.389712) (xy 123.070894 -401.456533) (xy 123.070895 -401.523837)
			(xy 123.062853 -401.590658) (xy 123.046882 -401.65604) (xy 123.02321 -401.719043) (xy 123.020771 -401.723737)
			(xy 124.149301 -401.723737) (xy 124.149303 -401.65643) (xy 124.15735 -401.589605) (xy 124.173327 -401.524221)
			(xy 124.197004 -401.461215) (xy 124.228043 -401.401491) (xy 124.265997 -401.345906) (xy 124.287788 -401.320254)
			(xy 124.293585 -401.313109) (xy 124.3001 -401.295918) (xy 124.300488 -401.286726) (xy 124.300488 -400.793458)
			(xy 124.300101 -400.784268) (xy 124.293572 -400.767084) (xy 124.287788 -400.75993) (xy 124.266005 -400.734274)
			(xy 124.228052 -400.678689) (xy 124.197016 -400.618966) (xy 124.173341 -400.555962) (xy 124.157366 -400.49058)
			(xy 124.149321 -400.423757) (xy 124.14932 -400.356452) (xy 124.157365 -400.289629) (xy 124.173338 -400.224246)
			(xy 124.197013 -400.161242) (xy 124.228048 -400.101519) (xy 124.265999 -400.045933) (xy 124.287788 -400.020282)
			(xy 124.293573 -400.013129) (xy 124.300095 -399.995944) (xy 124.300488 -399.986754) (xy 124.300488 -399.828766)
			(xy 124.300837 -399.818586) (xy 124.308643 -399.799781) (xy 124.323052 -399.785395) (xy 124.341869 -399.777621)
			(xy 124.35205 -399.777204) (xy 125.06833 -399.777204) (xy 125.078486 -399.777708) (xy 125.097249 -399.785486)
			(xy 125.111612 -399.799848) (xy 125.119391 -399.818611) (xy 125.119892 -399.828766) (xy 125.119892 -399.986754)
			(xy 125.120326 -399.995939) (xy 125.126823 -400.013123) (xy 125.132592 -400.020282) (xy 125.154385 -400.04593)
			(xy 125.192331 -400.101518) (xy 125.223363 -400.161242) (xy 125.247034 -400.224247) (xy 125.263005 -400.289629)
			(xy 125.271049 -400.356452) (xy 125.271048 -400.423757) (xy 125.263004 -400.490579) (xy 125.247031 -400.555962)
			(xy 125.223359 -400.618966) (xy 125.192327 -400.67869) (xy 125.154379 -400.734277) (xy 125.132592 -400.75993)
			(xy 125.126799 -400.767078) (xy 125.120283 -400.784266) (xy 125.119892 -400.793458) (xy 125.119892 -401.286726)
			(xy 125.120291 -401.295914) (xy 125.126813 -401.313099) (xy 125.132592 -401.320254) (xy 125.154357 -401.345924)
			(xy 125.192305 -401.401509) (xy 125.223337 -401.46123) (xy 125.24701 -401.524232) (xy 125.262983 -401.589612)
			(xy 125.271029 -401.656432) (xy 125.271031 -401.723735) (xy 125.262989 -401.790555) (xy 125.24702 -401.855936)
			(xy 125.223351 -401.918939) (xy 125.192322 -401.978663) (xy 125.154377 -402.034249) (xy 125.132592 -402.059902)
			(xy 125.126811 -402.067058) (xy 125.120287 -402.08424) (xy 125.119892 -402.09343) (xy 125.119892 -402.251418)
			(xy 125.119382 -402.261573) (xy 125.111608 -402.280337) (xy 125.097247 -402.294701) (xy 125.078485 -402.30248)
			(xy 125.06833 -402.30298) (xy 124.35205 -402.30298) (xy 124.341884 -402.302496) (xy 124.323094 -402.29473)
			(xy 124.308708 -402.280363) (xy 124.300918 -402.261584) (xy 124.300488 -402.251418) (xy 124.300488 -402.09343)
			(xy 124.300066 -402.084244) (xy 124.293561 -402.067059) (xy 124.287788 -402.059902) (xy 124.265977 -402.034268)
			(xy 124.228026 -401.97868) (xy 124.196991 -401.918955) (xy 124.173317 -401.855948) (xy 124.157344 -401.790563)
			(xy 124.149301 -401.723737) (xy 123.020771 -401.723737) (xy 122.992178 -401.778766) (xy 122.954231 -401.834352)
			(xy 122.932444 -401.860004) (xy 122.926656 -401.867155) (xy 122.920138 -401.884341) (xy 122.919744 -401.893532)
			(xy 122.919744 -402.3868) (xy 122.920167 -402.395986) (xy 122.926673 -402.413169) (xy 122.932444 -402.420328)
			(xy 122.954185 -402.446019) (xy 122.992136 -402.501599) (xy 123.023173 -402.561317) (xy 123.046849 -402.624317)
			(xy 123.062826 -402.689695) (xy 123.070874 -402.756513) (xy 123.070878 -402.823815) (xy 123.07087 -402.823878)
			(xy 126.348914 -402.823878) (xy 126.348919 -402.75645) (xy 126.357 -402.689508) (xy 126.373042 -402.624016)
			(xy 126.396813 -402.560916) (xy 126.427971 -402.501119) (xy 126.466068 -402.445485) (xy 126.487936 -402.41982)
			(xy 126.493754 -402.41269) (xy 126.500255 -402.395488) (xy 126.500636 -402.386292) (xy 126.500636 -401.89404)
			(xy 126.500198 -401.884856) (xy 126.493703 -401.867672) (xy 126.487936 -401.860512) (xy 126.466051 -401.834864)
			(xy 126.427961 -401.779227) (xy 126.396809 -401.719429) (xy 126.373044 -401.65633) (xy 126.357009 -401.590839)
			(xy 126.348934 -401.523898) (xy 126.348936 -401.456472) (xy 126.357014 -401.389532) (xy 126.373053 -401.324041)
			(xy 126.396821 -401.260943) (xy 126.427976 -401.201147) (xy 126.46607 -401.145513) (xy 126.487936 -401.119848)
			(xy 126.493742 -401.112709) (xy 126.50025 -401.095514) (xy 126.500636 -401.08632) (xy 126.500636 -400.92884)
			(xy 126.50105 -400.918716) (xy 126.508791 -400.900006) (xy 126.523109 -400.885689) (xy 126.54182 -400.877949)
			(xy 126.551944 -400.877532) (xy 127.268224 -400.877532) (xy 127.278352 -400.877897) (xy 127.297062 -400.885659)
			(xy 127.311377 -400.899991) (xy 127.319116 -400.918711) (xy 127.319532 -400.92884) (xy 127.319532 -401.08632)
			(xy 127.319948 -401.095506) (xy 127.326459 -401.11269) (xy 127.332232 -401.119848) (xy 127.354075 -401.14553)
			(xy 127.392162 -401.201163) (xy 127.423312 -401.260957) (xy 127.447076 -401.324052) (xy 127.463112 -401.389538)
			(xy 127.471189 -401.456474) (xy 127.471191 -401.523896) (xy 127.463117 -401.590832) (xy 127.447085 -401.65632)
			(xy 127.423324 -401.719415) (xy 127.421073 -401.723737) (xy 128.549092 -401.723737) (xy 128.549094 -401.65643)
			(xy 128.557141 -401.589605) (xy 128.573117 -401.524221) (xy 128.596794 -401.461216) (xy 128.627832 -401.401492)
			(xy 128.665786 -401.345906) (xy 128.687576 -401.320254) (xy 128.693372 -401.313108) (xy 128.699888 -401.295918)
			(xy 128.700276 -401.286726) (xy 128.700276 -400.793458) (xy 128.699891 -400.784268) (xy 128.69336 -400.767084)
			(xy 128.687576 -400.75993) (xy 128.665793 -400.734273) (xy 128.627842 -400.678688) (xy 128.596806 -400.618966)
			(xy 128.573131 -400.555962) (xy 128.557157 -400.49058) (xy 128.549112 -400.423757) (xy 128.549111 -400.356452)
			(xy 128.557155 -400.289629) (xy 128.573129 -400.224247) (xy 128.596802 -400.161242) (xy 128.627837 -400.101519)
			(xy 128.665788 -400.045934) (xy 128.687576 -400.020282) (xy 128.69336 -400.013128) (xy 128.699883 -399.995944)
			(xy 128.700276 -399.986754) (xy 128.700276 -399.828766) (xy 128.700637 -399.818587) (xy 128.70844 -399.799785)
			(xy 128.722845 -399.7854) (xy 128.741659 -399.777623) (xy 128.751838 -399.777204) (xy 129.468118 -399.777204)
			(xy 129.478273 -399.777718) (xy 129.497036 -399.785492) (xy 129.511399 -399.799851) (xy 129.519179 -399.818611)
			(xy 129.51968 -399.828766) (xy 129.51968 -399.986754) (xy 129.520117 -399.995938) (xy 129.526612 -400.013123)
			(xy 129.53238 -400.020282) (xy 129.554173 -400.045929) (xy 129.592121 -400.101517) (xy 129.623152 -400.161241)
			(xy 129.646824 -400.224247) (xy 129.662796 -400.289629) (xy 129.670839 -400.356452) (xy 129.670839 -400.423757)
			(xy 129.662794 -400.49058) (xy 129.646821 -400.555962) (xy 129.623149 -400.618967) (xy 129.592116 -400.678691)
			(xy 129.554168 -400.734278) (xy 129.53238 -400.75993) (xy 129.526586 -400.767077) (xy 129.52007 -400.784266)
			(xy 129.51968 -400.793458) (xy 129.51968 -401.286726) (xy 129.520082 -401.295914) (xy 129.526602 -401.313098)
			(xy 129.53238 -401.320254) (xy 129.554146 -401.345924) (xy 129.592094 -401.401508) (xy 129.623127 -401.46123)
			(xy 129.6468 -401.524232) (xy 129.662774 -401.589612) (xy 129.67082 -401.656432) (xy 129.670822 -401.723735)
			(xy 129.66278 -401.790556) (xy 129.64681 -401.855937) (xy 129.623141 -401.91894) (xy 129.592111 -401.978663)
			(xy 129.554166 -402.03425) (xy 129.53238 -402.059902) (xy 129.526598 -402.067057) (xy 129.520075 -402.08424)
			(xy 129.51968 -402.09343) (xy 129.51968 -402.251418) (xy 129.519182 -402.261575) (xy 129.511405 -402.280341)
			(xy 129.497041 -402.294705) (xy 129.478275 -402.302482) (xy 129.468118 -402.30298) (xy 128.751838 -402.30298)
			(xy 128.741671 -402.302505) (xy 128.722881 -402.294736) (xy 128.708495 -402.280366) (xy 128.700706 -402.261584)
			(xy 128.700276 -402.251418) (xy 128.700276 -402.09343) (xy 128.699857 -402.084244) (xy 128.69335 -402.067059)
			(xy 128.687576 -402.059902) (xy 128.665766 -402.034268) (xy 128.627815 -401.97868) (xy 128.596781 -401.918954)
			(xy 128.573108 -401.855947) (xy 128.557135 -401.790562) (xy 128.549092 -401.723737) (xy 127.421073 -401.723737)
			(xy 127.392178 -401.779211) (xy 127.354094 -401.834846) (xy 127.332232 -401.860512) (xy 127.32644 -401.86766)
			(xy 127.319924 -401.884849) (xy 127.319532 -401.89404) (xy 127.319532 -402.386292) (xy 127.319961 -402.395477)
			(xy 127.326463 -402.412661) (xy 127.332232 -402.41982) (xy 127.354048 -402.445525) (xy 127.392136 -402.501154)
			(xy 127.423287 -402.560945) (xy 127.447052 -402.624037) (xy 127.46309 -402.689521) (xy 127.471169 -402.756454)
			(xy 127.471174 -402.823818) (xy 130.749234 -402.823818) (xy 130.749238 -402.75651) (xy 130.757287 -402.689684)
			(xy 130.773265 -402.624299) (xy 130.796942 -402.561293) (xy 130.82798 -402.501568) (xy 130.865934 -402.44598)
			(xy 130.887724 -402.420328) (xy 130.893536 -402.413194) (xy 130.900041 -402.395995) (xy 130.900424 -402.3868)
			(xy 130.900424 -401.893532) (xy 130.899993 -401.884347) (xy 130.893493 -401.867163) (xy 130.887724 -401.860004)
			(xy 130.865917 -401.834368) (xy 130.82797 -401.778779) (xy 130.796938 -401.719053) (xy 130.773267 -401.656046)
			(xy 130.757296 -401.590662) (xy 130.749254 -401.523838) (xy 130.749256 -401.456532) (xy 130.757301 -401.389708)
			(xy 130.773276 -401.324325) (xy 130.79695 -401.26132) (xy 130.827985 -401.201595) (xy 130.865935 -401.146008)
			(xy 130.887724 -401.120356) (xy 130.893525 -401.113214) (xy 130.900036 -401.096021) (xy 130.900424 -401.086828)
			(xy 130.900424 -400.92884) (xy 130.900855 -400.918686) (xy 130.908642 -400.899929) (xy 130.923036 -400.885604)
			(xy 130.94183 -400.877907) (xy 130.951986 -400.877532) (xy 131.668266 -400.877532) (xy 131.67839 -400.878054)
			(xy 131.697108 -400.88577) (xy 131.711465 -400.900045) (xy 131.719287 -400.918719) (xy 131.719828 -400.92884)
			(xy 131.719828 -401.086828) (xy 131.720218 -401.096017) (xy 131.726745 -401.113202) (xy 131.732528 -401.120356)
			(xy 131.754297 -401.146024) (xy 131.792249 -401.201607) (xy 131.823285 -401.261328) (xy 131.84696 -401.324331)
			(xy 131.862935 -401.389712) (xy 131.870981 -401.456533) (xy 131.870983 -401.523837) (xy 131.862941 -401.590659)
			(xy 131.846969 -401.65604) (xy 131.823297 -401.719044) (xy 131.792264 -401.778767) (xy 131.754315 -401.834352)
			(xy 131.732528 -401.860004) (xy 131.726738 -401.867154) (xy 131.720222 -401.884341) (xy 131.719828 -401.893532)
			(xy 131.719828 -402.3868) (xy 131.720232 -402.395988) (xy 131.726749 -402.413173) (xy 131.732528 -402.420328)
			(xy 131.75427 -402.446019) (xy 131.792222 -402.501599) (xy 131.823259 -402.561317) (xy 131.846936 -402.624316)
			(xy 131.862913 -402.689694) (xy 131.870962 -402.756513) (xy 131.870966 -402.823815) (xy 131.862926 -402.890635)
			(xy 131.846957 -402.956015) (xy 131.823289 -403.019017) (xy 131.792259 -403.078739) (xy 131.754314 -403.134324)
			(xy 131.732528 -403.159976) (xy 131.726708 -403.167104) (xy 131.720209 -403.184308) (xy 131.719828 -403.193504)
			(xy 131.719828 -403.351492) (xy 131.719372 -403.361642) (xy 131.711585 -403.380389) (xy 131.697199 -403.394712)
			(xy 131.678418 -403.402417) (xy 131.668266 -403.4028) (xy 130.951986 -403.4028) (xy 130.941863 -403.402286)
			(xy 130.92315 -403.394561) (xy 130.908795 -403.380284) (xy 130.90097 -403.361612) (xy 130.900424 -403.351492)
			(xy 130.900424 -403.193504) (xy 130.900007 -403.184318) (xy 130.893498 -403.167133) (xy 130.887724 -403.159976)
			(xy 130.86589 -403.134362) (xy 130.827943 -403.07877) (xy 130.796913 -403.019041) (xy 130.773243 -402.956032)
			(xy 130.757274 -402.890645) (xy 130.749234 -402.823818) (xy 127.471174 -402.823818) (xy 127.471174 -402.823874)
			(xy 127.463103 -402.890808) (xy 127.447074 -402.956294) (xy 127.423316 -403.019389) (xy 127.392173 -403.079184)
			(xy 127.354092 -403.134818) (xy 127.332232 -403.160484) (xy 127.326409 -403.16761) (xy 127.319912 -403.184816)
			(xy 127.319532 -403.194012) (xy 127.319532 -403.351492) (xy 127.319009 -403.361596) (xy 127.31128 -403.380268)
			(xy 127.296995 -403.394562) (xy 127.278328 -403.402303) (xy 127.268224 -403.4028) (xy 126.551944 -403.4028)
			(xy 126.541824 -403.402348) (xy 126.523122 -403.394614) (xy 126.508806 -403.380308) (xy 126.501059 -403.361611)
			(xy 126.500636 -403.351492) (xy 126.500636 -403.194012) (xy 126.500212 -403.184826) (xy 126.493707 -403.167642)
			(xy 126.487936 -403.160484) (xy 126.466024 -403.134858) (xy 126.427934 -403.079219) (xy 126.396783 -403.019418)
			(xy 126.37302 -402.956315) (xy 126.356987 -402.890821) (xy 126.348914 -402.823878) (xy 123.07087 -402.823878)
			(xy 123.062839 -402.890634) (xy 123.04687 -402.956014) (xy 123.023202 -403.019017) (xy 122.992173 -403.078739)
			(xy 122.954229 -403.134324) (xy 122.932444 -403.159976) (xy 122.926626 -403.167106) (xy 122.920126 -403.184308)
			(xy 122.919744 -403.193504) (xy 122.919744 -403.351492) (xy 122.919209 -403.361595) (xy 122.911483 -403.380264)
			(xy 122.897201 -403.394558) (xy 122.878538 -403.402301) (xy 122.868436 -403.4028) (xy 122.151902 -403.4028)
			(xy 122.14178 -403.402273) (xy 122.123067 -403.394553) (xy 122.108712 -403.38028) (xy 122.100886 -403.361611)
			(xy 122.10034 -403.351492) (xy 122.10034 -403.193504) (xy 122.099919 -403.184318) (xy 122.093412 -403.167134)
			(xy 122.08764 -403.159976) (xy 122.065805 -403.134363) (xy 122.027857 -403.078771) (xy 121.996826 -403.019042)
			(xy 121.973156 -402.956032) (xy 121.957186 -402.890645) (xy 121.949146 -402.823818) (xy 118.67111 -402.823818)
			(xy 118.67111 -402.823874) (xy 118.663038 -402.89081) (xy 118.647006 -402.956297) (xy 118.623245 -403.019392)
			(xy 118.592097 -403.079187) (xy 118.554011 -403.13482) (xy 118.532148 -403.160484) (xy 118.526327 -403.167612)
			(xy 118.519828 -403.184816) (xy 118.519448 -403.194012) (xy 118.519448 -403.351492) (xy 118.51891 -403.361594)
			(xy 118.511183 -403.380263) (xy 118.496903 -403.394557) (xy 118.478242 -403.4023) (xy 118.46814 -403.4028)
			(xy 117.75186 -403.4028) (xy 117.741749 -403.402348) (xy 117.72307 -403.394597) (xy 117.708776 -403.38029)
			(xy 117.701043 -403.361604) (xy 117.700552 -403.351492) (xy 117.700552 -403.194012) (xy 117.700125 -403.184827)
			(xy 117.693622 -403.167643) (xy 117.687852 -403.160484) (xy 117.665939 -403.134859) (xy 117.627848 -403.07922)
			(xy 117.596697 -403.019418) (xy 117.572933 -402.956316) (xy 117.556899 -402.890822) (xy 117.548826 -402.823878)
			(xy 87.871055 -402.823878) (xy 87.862984 -402.890809) (xy 87.846954 -402.956295) (xy 87.823196 -403.01939)
			(xy 87.792051 -403.079185) (xy 87.753969 -403.134819) (xy 87.732108 -403.160484) (xy 87.726294 -403.167617)
			(xy 87.71979 -403.184817) (xy 87.719408 -403.194012) (xy 87.719408 -403.351492) (xy 87.718978 -403.361613)
			(xy 87.711234 -403.380315) (xy 87.696922 -403.394629) (xy 87.678221 -403.402376) (xy 87.6681 -403.4028)
			(xy 86.95182 -403.4028) (xy 86.941699 -403.402368) (xy 86.922996 -403.394626) (xy 86.908681 -403.380315)
			(xy 86.900935 -403.361613) (xy 86.900512 -403.351492) (xy 86.900512 -403.194012) (xy 86.900093 -403.184826)
			(xy 86.893585 -403.167642) (xy 86.887812 -403.160484) (xy 86.8659 -403.134858) (xy 86.827812 -403.079218)
			(xy 86.796663 -403.019417) (xy 86.772901 -402.956315) (xy 86.756869 -402.890821) (xy 86.748796 -402.823878)
			(xy 83.470752 -402.823878) (xy 83.46272 -402.890635) (xy 83.446751 -402.956015) (xy 83.423082 -403.019018)
			(xy 83.392052 -403.07874) (xy 83.354106 -403.134324) (xy 83.33232 -403.159976) (xy 83.326511 -403.167113)
			(xy 83.320003 -403.18431) (xy 83.31962 -403.193504) (xy 83.31962 -403.351492) (xy 83.319172 -403.361643)
			(xy 83.311383 -403.380391) (xy 83.296995 -403.394714) (xy 83.278211 -403.402418) (xy 83.268058 -403.4028)
			(xy 82.551778 -403.4028) (xy 82.541655 -403.402293) (xy 82.522941 -403.394565) (xy 82.508586 -403.380286)
			(xy 82.500761 -403.361613) (xy 82.500216 -403.351492) (xy 82.500216 -403.193504) (xy 82.4998 -403.184318)
			(xy 82.49329 -403.167133) (xy 82.487516 -403.159976) (xy 82.465682 -403.134362) (xy 82.427736 -403.07877)
			(xy 82.396706 -403.019041) (xy 82.373037 -402.956031) (xy 82.357068 -402.890645) (xy 82.349028 -402.823818)
			(xy 79.070968 -402.823818) (xy 79.070968 -402.823874) (xy 79.062897 -402.890808) (xy 79.046867 -402.956294)
			(xy 79.023109 -403.019389) (xy 78.991966 -403.079184) (xy 78.953884 -403.134818) (xy 78.932024 -403.160484)
			(xy 78.926212 -403.167618) (xy 78.919706 -403.184817) (xy 78.919324 -403.194012) (xy 78.919324 -403.351492)
			(xy 78.918809 -403.361597) (xy 78.911078 -403.380271) (xy 78.896791 -403.394565) (xy 78.878121 -403.402304)
			(xy 78.868016 -403.4028) (xy 78.151736 -403.4028) (xy 78.141616 -403.402354) (xy 78.122913 -403.394618)
			(xy 78.108598 -403.38031) (xy 78.100851 -403.361612) (xy 78.100428 -403.351492) (xy 78.100428 -403.194012)
			(xy 78.100006 -403.184826) (xy 78.0935 -403.167642) (xy 78.087728 -403.160484) (xy 78.065816 -403.134858)
			(xy 78.027727 -403.079219) (xy 77.996577 -403.019417) (xy 77.972814 -402.956315) (xy 77.956781 -402.890821)
			(xy 77.948708 -402.823878) (xy 74.670664 -402.823878) (xy 74.662632 -402.890635) (xy 74.646664 -402.956014)
			(xy 74.622995 -403.019017) (xy 74.591966 -403.078739) (xy 74.554022 -403.134324) (xy 74.532236 -403.159976)
			(xy 74.526417 -403.167105) (xy 74.519917 -403.184308) (xy 74.519536 -403.193504) (xy 74.519536 -403.351492)
			(xy 74.519073 -403.361641) (xy 74.511286 -403.380386) (xy 74.496903 -403.394709) (xy 74.478125 -403.402415)
			(xy 74.467974 -403.4028) (xy 73.751694 -403.4028) (xy 73.741572 -403.402279) (xy 73.722858 -403.394557)
			(xy 73.708504 -403.380282) (xy 73.700678 -403.361611) (xy 73.700132 -403.351492) (xy 73.700132 -403.193504)
			(xy 73.699713 -403.184318) (xy 73.693205 -403.167134) (xy 73.687432 -403.159976) (xy 73.665597 -403.134363)
			(xy 73.62765 -403.07877) (xy 73.59662 -403.019041) (xy 73.57295 -402.956032) (xy 73.55698 -402.890645)
			(xy 73.54894 -402.823818) (xy 66.525648 -402.823818) (xy 66.525648 -405.623707) (xy 71.348811 -405.623707)
			(xy 71.348811 -405.556283) (xy 71.356888 -405.489345) (xy 71.372924 -405.423856) (xy 71.396688 -405.360759)
			(xy 71.427839 -405.300962) (xy 71.465928 -405.245327) (xy 71.487792 -405.219662) (xy 71.493586 -405.212515)
			(xy 71.500103 -405.195326) (xy 71.500492 -405.186134) (xy 71.500492 -404.693882) (xy 71.500092 -404.684694)
			(xy 71.493571 -404.667509) (xy 71.487792 -404.660354) (xy 71.46595 -404.634671) (xy 71.427861 -404.579039)
			(xy 71.39671 -404.519245) (xy 71.372945 -404.45615) (xy 71.356908 -404.390664) (xy 71.348831 -404.323727)
			(xy 71.348829 -404.256306) (xy 71.356902 -404.189369) (xy 71.372935 -404.123881) (xy 71.396696 -404.060785)
			(xy 71.427844 -404.00099) (xy 71.46593 -403.945355) (xy 71.487792 -403.91969) (xy 71.493574 -403.912535)
			(xy 71.500098 -403.895352) (xy 71.500492 -403.886162) (xy 71.500492 -403.728682) (xy 71.50101 -403.71856)
			(xy 71.508735 -403.699847) (xy 71.523011 -403.685493) (xy 71.541681 -403.677666) (xy 71.5518 -403.67712)
			(xy 72.26808 -403.67712) (xy 72.278235 -403.677538) (xy 72.296991 -403.685331) (xy 72.311316 -403.699729)
			(xy 72.319013 -403.718525) (xy 72.319388 -403.728682) (xy 72.319388 -403.886162) (xy 72.319819 -403.895347)
			(xy 72.326319 -403.912531) (xy 72.332088 -403.91969) (xy 72.353974 -403.945337) (xy 72.392063 -404.000974)
			(xy 72.423213 -404.060773) (xy 72.446977 -404.123872) (xy 72.463011 -404.189363) (xy 72.471085 -404.256304)
			(xy 72.471083 -404.323729) (xy 72.463005 -404.390669) (xy 72.446967 -404.45616) (xy 72.4232 -404.519258)
			(xy 72.392046 -404.579054) (xy 72.353954 -404.634689) (xy 72.332088 -404.660354) (xy 72.326285 -404.667494)
			(xy 72.319774 -404.684689) (xy 72.319388 -404.693882) (xy 72.319388 -405.186134) (xy 72.319784 -405.195323)
			(xy 72.326308 -405.212507) (xy 72.332088 -405.219662) (xy 72.353946 -405.245332) (xy 72.392036 -405.300965)
			(xy 72.423188 -405.360761) (xy 72.446953 -405.423857) (xy 72.462989 -405.489346) (xy 72.471066 -405.556284)
			(xy 72.471066 -405.623707) (xy 72.462991 -405.690645) (xy 72.446956 -405.756134) (xy 72.423191 -405.819231)
			(xy 72.392041 -405.879027) (xy 72.353952 -405.934661) (xy 72.332088 -405.960326) (xy 72.326297 -405.967475)
			(xy 72.319779 -405.984663) (xy 72.319388 -405.993854) (xy 72.319388 -406.151334) (xy 72.318902 -406.161459)
			(xy 72.311168 -406.180176) (xy 72.296883 -406.19453) (xy 72.278203 -406.202353) (xy 72.26808 -406.202896)
			(xy 71.5518 -406.202896) (xy 71.541645 -406.202478) (xy 71.522892 -406.194682) (xy 71.508569 -406.180284)
			(xy 71.50087 -406.161491) (xy 71.500492 -406.151334) (xy 71.500492 -405.993854) (xy 71.500058 -405.984669)
			(xy 71.493561 -405.967485) (xy 71.487792 -405.960326) (xy 71.465922 -405.934665) (xy 71.427834 -405.87903)
			(xy 71.396684 -405.819233) (xy 71.372921 -405.756136) (xy 71.356886 -405.690646) (xy 71.348811 -405.623707)
			(xy 66.525648 -405.623707) (xy 66.525648 -406.72373) (xy 73.548951 -406.72373) (xy 73.548954 -406.656422)
			(xy 73.557001 -406.589598) (xy 73.572978 -406.524214) (xy 73.596654 -406.461208) (xy 73.62769 -406.401483)
			(xy 73.665642 -406.345896) (xy 73.687432 -406.320244) (xy 73.693239 -406.313106) (xy 73.699747 -406.29591)
			(xy 73.700132 -406.286716) (xy 73.700132 -405.793448) (xy 73.699691 -405.784264) (xy 73.693198 -405.76708)
			(xy 73.687432 -405.75992) (xy 73.66564 -405.734271) (xy 73.627692 -405.678684) (xy 73.596659 -405.61896)
			(xy 73.572987 -405.555955) (xy 73.557015 -405.490572) (xy 73.548971 -405.42375) (xy 73.548971 -405.356444)
			(xy 73.557016 -405.289622) (xy 73.572989 -405.224239) (xy 73.596662 -405.161235) (xy 73.627695 -405.101511)
			(xy 73.665644 -405.045924) (xy 73.687432 -405.020272) (xy 73.693227 -405.013126) (xy 73.699742 -404.995936)
			(xy 73.700132 -404.986744) (xy 73.700132 -404.828756) (xy 73.700486 -404.818595) (xy 73.708302 -404.799836)
			(xy 73.72272 -404.785513) (xy 73.74153 -404.77782) (xy 73.751694 -404.777448) (xy 74.467974 -404.777448)
			(xy 74.4781 -404.777948) (xy 74.496822 -404.785669) (xy 74.51118 -404.799951) (xy 74.518998 -404.818633)
			(xy 74.519536 -404.828756) (xy 74.519536 -404.986744) (xy 74.519939 -404.995932) (xy 74.526459 -405.013115)
			(xy 74.532236 -405.020272) (xy 74.55402 -405.045927) (xy 74.591971 -405.101513) (xy 74.623006 -405.161235)
			(xy 74.64668 -405.22424) (xy 74.662654 -405.289622) (xy 74.670699 -405.356444) (xy 74.670699 -405.42375)
			(xy 74.662655 -405.490572) (xy 74.646682 -405.555955) (xy 74.623008 -405.618959) (xy 74.620571 -405.623649)
			(xy 75.749106 -405.623649) (xy 75.749107 -405.556342) (xy 75.757152 -405.489519) (xy 75.773127 -405.424136)
			(xy 75.796802 -405.361131) (xy 75.827839 -405.301407) (xy 75.865791 -405.245822) (xy 75.88758 -405.22017)
			(xy 75.893369 -405.21302) (xy 75.899889 -405.195833) (xy 75.90028 -405.186642) (xy 75.90028 -404.693374)
			(xy 75.899887 -404.684185) (xy 75.893362 -404.667001) (xy 75.88758 -404.659846) (xy 75.865813 -404.634177)
			(xy 75.827861 -404.578594) (xy 75.796824 -404.518873) (xy 75.773148 -404.45587) (xy 75.757173 -404.39049)
			(xy 75.749126 -404.323669) (xy 75.749124 -404.256365) (xy 75.757167 -404.189543) (xy 75.773138 -404.124161)
			(xy 75.796811 -404.061157) (xy 75.827844 -404.001435) (xy 75.865792 -403.94585) (xy 75.88758 -403.920198)
			(xy 75.893358 -403.913039) (xy 75.899884 -403.895859) (xy 75.90028 -403.88667) (xy 75.90028 -403.728682)
			(xy 75.90065 -403.718504) (xy 75.908449 -403.699701) (xy 75.922851 -403.685315) (xy 75.941664 -403.677538)
			(xy 75.951842 -403.67712) (xy 76.668122 -403.67712) (xy 76.678279 -403.677615) (xy 76.697045 -403.685393)
			(xy 76.711409 -403.699758) (xy 76.719186 -403.718525) (xy 76.719684 -403.728682) (xy 76.719684 -403.88667)
			(xy 76.720112 -403.895855) (xy 76.726614 -403.91304) (xy 76.732384 -403.920198) (xy 76.754193 -403.945833)
			(xy 76.792139 -404.001422) (xy 76.82317 -404.061148) (xy 76.846841 -404.124155) (xy 76.862812 -404.189539)
			(xy 76.870854 -404.256363) (xy 76.870852 -404.32367) (xy 76.862806 -404.390493) (xy 76.846831 -404.455877)
			(xy 76.823157 -404.518882) (xy 76.792122 -404.578606) (xy 76.754172 -404.634194) (xy 76.732384 -404.659846)
			(xy 76.726584 -404.666988) (xy 76.720072 -404.684181) (xy 76.719684 -404.693374) (xy 76.719684 -405.186642)
			(xy 76.720077 -405.195831) (xy 76.726603 -405.213015) (xy 76.732384 -405.22017) (xy 76.754165 -405.245827)
			(xy 76.792113 -405.301414) (xy 76.823145 -405.361137) (xy 76.846817 -405.42414) (xy 76.86279 -405.489522)
			(xy 76.870834 -405.556343) (xy 76.870835 -405.623648) (xy 76.862791 -405.690469) (xy 76.84682 -405.755851)
			(xy 76.823149 -405.818855) (xy 76.792117 -405.878579) (xy 76.754171 -405.934166) (xy 76.732384 -405.959818)
			(xy 76.726595 -405.966969) (xy 76.720077 -405.984155) (xy 76.719684 -405.993346) (xy 76.719684 -406.151334)
			(xy 76.719195 -406.161491) (xy 76.711414 -406.180257) (xy 76.697047 -406.19462) (xy 76.678279 -406.202397)
			(xy 76.668122 -406.202896) (xy 75.951842 -406.202896) (xy 75.941677 -406.202403) (xy 75.92289 -406.194638)
			(xy 75.908505 -406.180274) (xy 75.900712 -406.161498) (xy 75.90028 -406.151334) (xy 75.90028 -405.993346)
			(xy 75.899852 -405.984161) (xy 75.893351 -405.966976) (xy 75.88758 -405.959818) (xy 75.865785 -405.934171)
			(xy 75.827834 -405.878585) (xy 75.796799 -405.818861) (xy 75.773124 -405.755856) (xy 75.757151 -405.690472)
			(xy 75.749106 -405.623649) (xy 74.620571 -405.623649) (xy 74.591974 -405.678682) (xy 74.554024 -405.734268)
			(xy 74.532236 -405.75992) (xy 74.526441 -405.767066) (xy 74.519927 -405.784256) (xy 74.519536 -405.793448)
			(xy 74.519536 -406.286716) (xy 74.519953 -406.295902) (xy 74.526464 -406.313086) (xy 74.532236 -406.320244)
			(xy 74.553993 -406.345922) (xy 74.591944 -406.401504) (xy 74.62298 -406.461224) (xy 74.646656 -406.524225)
			(xy 74.662632 -406.589604) (xy 74.670679 -406.656424) (xy 74.670682 -406.723727) (xy 74.670675 -406.723789)
			(xy 77.94872 -406.723789) (xy 77.948723 -406.656363) (xy 77.956802 -406.589422) (xy 77.972842 -406.52393)
			(xy 77.996611 -406.460832) (xy 78.027767 -406.401035) (xy 78.065861 -406.345401) (xy 78.087728 -406.319736)
			(xy 78.093538 -406.3126) (xy 78.100044 -406.295402) (xy 78.100428 -406.286208) (xy 78.100428 -405.793956)
			(xy 78.100033 -405.784767) (xy 78.093508 -405.767584) (xy 78.087728 -405.760428) (xy 78.065859 -405.734766)
			(xy 78.027769 -405.679132) (xy 77.996617 -405.619336) (xy 77.972851 -405.556238) (xy 77.956815 -405.490748)
			(xy 77.948739 -405.423809) (xy 77.94874 -405.356385) (xy 77.956816 -405.289446) (xy 77.972853 -405.223956)
			(xy 77.996619 -405.160859) (xy 78.027772 -405.101063) (xy 78.065863 -405.045429) (xy 78.087728 -405.019764)
			(xy 78.093526 -405.01262) (xy 78.100039 -404.995428) (xy 78.100428 -404.986236) (xy 78.100428 -404.828756)
			(xy 78.10085 -404.818641) (xy 78.108607 -404.799956) (xy 78.122924 -404.785662) (xy 78.14162 -404.777934)
			(xy 78.151736 -404.777448) (xy 78.868016 -404.777448) (xy 78.878119 -404.777971) (xy 78.896788 -404.785704)
			(xy 78.91108 -404.799989) (xy 78.918823 -404.818653) (xy 78.919324 -404.828756) (xy 78.919324 -404.986236)
			(xy 78.919712 -404.995426) (xy 78.92624 -405.01261) (xy 78.932024 -405.019764) (xy 78.953883 -405.045433)
			(xy 78.99197 -405.101067) (xy 79.02312 -405.160863) (xy 79.046883 -405.22396) (xy 79.062918 -405.289448)
			(xy 79.070994 -405.356386) (xy 79.070995 -405.423808) (xy 79.062919 -405.490746) (xy 79.046885 -405.556235)
			(xy 79.023122 -405.619331) (xy 79.020843 -405.623707) (xy 80.148899 -405.623707) (xy 80.148899 -405.556284)
			(xy 80.156975 -405.489345) (xy 80.173011 -405.423856) (xy 80.196775 -405.360759) (xy 80.227925 -405.300963)
			(xy 80.266013 -405.245328) (xy 80.287876 -405.219662) (xy 80.293668 -405.212514) (xy 80.300186 -405.195326)
			(xy 80.300576 -405.186134) (xy 80.300576 -404.693882) (xy 80.30018 -404.684693) (xy 80.293657 -404.667509)
			(xy 80.287876 -404.660354) (xy 80.266034 -404.634671) (xy 80.227947 -404.579038) (xy 80.196796 -404.519244)
			(xy 80.173032 -404.45615) (xy 80.156996 -404.390663) (xy 80.148918 -404.323727) (xy 80.148917 -404.256306)
			(xy 80.15699 -404.189369) (xy 80.173022 -404.123882) (xy 80.196783 -404.060786) (xy 80.22793 -404.00099)
			(xy 80.266014 -403.945356) (xy 80.287876 -403.91969) (xy 80.293657 -403.912533) (xy 80.300182 -403.895352)
			(xy 80.300576 -403.886162) (xy 80.300576 -403.728682) (xy 80.301013 -403.71855) (xy 80.308753 -403.699821)
			(xy 80.323055 -403.685464) (xy 80.341754 -403.677652) (xy 80.351884 -403.67712) (xy 81.068164 -403.67712)
			(xy 81.078318 -403.677552) (xy 81.097074 -403.685339) (xy 81.111399 -403.699733) (xy 81.119096 -403.718526)
			(xy 81.119472 -403.728682) (xy 81.119472 -403.886162) (xy 81.119907 -403.895346) (xy 81.126404 -403.912531)
			(xy 81.132172 -403.91969) (xy 81.154059 -403.945337) (xy 81.192148 -404.000973) (xy 81.2233 -404.060772)
			(xy 81.247064 -404.123871) (xy 81.263099 -404.189363) (xy 81.271173 -404.256304) (xy 81.271171 -404.32373)
			(xy 81.263093 -404.39067) (xy 81.247054 -404.45616) (xy 81.223286 -404.519258) (xy 81.192131 -404.579055)
			(xy 81.154038 -404.634689) (xy 81.132172 -404.660354) (xy 81.126366 -404.667493) (xy 81.119858 -404.684688)
			(xy 81.119472 -404.693882) (xy 81.119472 -405.186134) (xy 81.119872 -405.195322) (xy 81.126393 -405.212506)
			(xy 81.132172 -405.219662) (xy 81.154031 -405.245332) (xy 81.192122 -405.300965) (xy 81.223274 -405.36076)
			(xy 81.24704 -405.423857) (xy 81.263077 -405.489345) (xy 81.271154 -405.556284) (xy 81.271154 -405.623707)
			(xy 81.263078 -405.690646) (xy 81.247043 -405.756135) (xy 81.223278 -405.819232) (xy 81.192126 -405.879027)
			(xy 81.154037 -405.934661) (xy 81.132172 -405.960326) (xy 81.126378 -405.967473) (xy 81.119862 -405.984662)
			(xy 81.119472 -405.993854) (xy 81.119472 -406.151334) (xy 81.119002 -406.161461) (xy 81.111265 -406.180181)
			(xy 81.096974 -406.194536) (xy 81.078289 -406.202356) (xy 81.068164 -406.202896) (xy 80.351884 -406.202896)
			(xy 80.341728 -406.202492) (xy 80.322975 -406.19469) (xy 80.308652 -406.180288) (xy 80.300953 -406.161492)
			(xy 80.300576 -406.151334) (xy 80.300576 -405.993854) (xy 80.300145 -405.984669) (xy 80.293646 -405.967484)
			(xy 80.287876 -405.960326) (xy 80.266007 -405.934665) (xy 80.22792 -405.879029) (xy 80.196771 -405.819232)
			(xy 80.173008 -405.756135) (xy 80.156974 -405.690646) (xy 80.148899 -405.623707) (xy 79.020843 -405.623707)
			(xy 78.991974 -405.679127) (xy 78.953887 -405.734762) (xy 78.932024 -405.760428) (xy 78.926236 -405.767579)
			(xy 78.919715 -405.784765) (xy 78.919324 -405.793956) (xy 78.919324 -406.286208) (xy 78.919725 -406.295396)
			(xy 78.926244 -406.312581) (xy 78.932024 -406.319736) (xy 78.953856 -406.345428) (xy 78.991944 -406.401059)
			(xy 79.023095 -406.460852) (xy 79.046859 -406.523945) (xy 79.062896 -406.589431) (xy 79.070974 -406.656366)
			(xy 79.070977 -406.72373) (xy 82.349039 -406.72373) (xy 82.349042 -406.656422) (xy 82.357089 -406.589598)
			(xy 82.373065 -406.524214) (xy 82.39674 -406.461209) (xy 82.427776 -406.401484) (xy 82.465727 -406.345896)
			(xy 82.487516 -406.320244) (xy 82.493321 -406.313105) (xy 82.49983 -406.29591) (xy 82.500216 -406.286716)
			(xy 82.500216 -405.793448) (xy 82.499779 -405.784264) (xy 82.493284 -405.767079) (xy 82.487516 -405.75992)
			(xy 82.465725 -405.734271) (xy 82.427778 -405.678683) (xy 82.396746 -405.618959) (xy 82.373074 -405.555954)
			(xy 82.357102 -405.490572) (xy 82.349059 -405.423749) (xy 82.349059 -405.356445) (xy 82.357103 -405.289622)
			(xy 82.373076 -405.22424) (xy 82.396748 -405.161235) (xy 82.427781 -405.101511) (xy 82.465729 -405.045924)
			(xy 82.487516 -405.020272) (xy 82.493309 -405.013124) (xy 82.499825 -404.995936) (xy 82.500216 -404.986744)
			(xy 82.500216 -404.828756) (xy 82.500586 -404.818597) (xy 82.508399 -404.799841) (xy 82.522811 -404.785518)
			(xy 82.541617 -404.777823) (xy 82.551778 -404.777448) (xy 83.268058 -404.777448) (xy 83.278183 -404.777961)
			(xy 83.296905 -404.785677) (xy 83.311263 -404.799955) (xy 83.319082 -404.818634) (xy 83.31962 -404.828756)
			(xy 83.31962 -404.986744) (xy 83.320004 -404.995934) (xy 83.326535 -405.013118) (xy 83.33232 -405.020272)
			(xy 83.354105 -405.045927) (xy 83.392057 -405.101512) (xy 83.423092 -405.161235) (xy 83.446767 -405.224239)
			(xy 83.462742 -405.289621) (xy 83.470787 -405.356444) (xy 83.470787 -405.42375) (xy 83.462743 -405.490573)
			(xy 83.446769 -405.555955) (xy 83.423095 -405.61896) (xy 83.420628 -405.623707) (xy 84.54869 -405.623707)
			(xy 84.54869 -405.556284) (xy 84.556766 -405.489346) (xy 84.572801 -405.423857) (xy 84.596564 -405.36076)
			(xy 84.627714 -405.300963) (xy 84.665801 -405.245328) (xy 84.687664 -405.219662) (xy 84.693467 -405.212522)
			(xy 84.699976 -405.195327) (xy 84.700364 -405.186134) (xy 84.700364 -404.693882) (xy 84.699948 -404.684696)
			(xy 84.693437 -404.667512) (xy 84.687664 -404.660354) (xy 84.665823 -404.63467) (xy 84.627736 -404.579038)
			(xy 84.596586 -404.519244) (xy 84.572822 -404.456149) (xy 84.556787 -404.390663) (xy 84.548709 -404.323727)
			(xy 84.548707 -404.256306) (xy 84.556781 -404.18937) (xy 84.572813 -404.123882) (xy 84.596573 -404.060787)
			(xy 84.627719 -404.000991) (xy 84.665803 -403.945356) (xy 84.687664 -403.91969) (xy 84.693455 -403.912541)
			(xy 84.699971 -403.895353) (xy 84.700364 -403.886162) (xy 84.700364 -403.728682) (xy 84.700812 -403.718551)
			(xy 84.70855 -403.699825) (xy 84.722849 -403.685468) (xy 84.741543 -403.677654) (xy 84.751672 -403.67712)
			(xy 85.467952 -403.67712) (xy 85.478105 -403.677561) (xy 85.496861 -403.685345) (xy 85.511186 -403.699736)
			(xy 85.518884 -403.718527) (xy 85.51926 -403.728682) (xy 85.51926 -403.886162) (xy 85.519698 -403.895346)
			(xy 85.526193 -403.91253) (xy 85.53196 -403.91969) (xy 85.553847 -403.945337) (xy 85.591938 -404.000973)
			(xy 85.62309 -404.060771) (xy 85.646854 -404.123871) (xy 85.66289 -404.189362) (xy 85.670964 -404.256303)
			(xy 85.670962 -404.32373) (xy 85.662884 -404.39067) (xy 85.646845 -404.456161) (xy 85.623076 -404.519259)
			(xy 85.591921 -404.579055) (xy 85.553827 -404.634689) (xy 85.53196 -404.660354) (xy 85.526153 -404.667492)
			(xy 85.519646 -404.684688) (xy 85.51926 -404.693882) (xy 85.51926 -405.186134) (xy 85.519663 -405.195322)
			(xy 85.526183 -405.212506) (xy 85.53196 -405.219662) (xy 85.553819 -405.245331) (xy 85.591911 -405.300964)
			(xy 85.623064 -405.36076) (xy 85.64683 -405.423856) (xy 85.662868 -405.489345) (xy 85.670945 -405.556284)
			(xy 85.670945 -405.623707) (xy 85.662869 -405.690646) (xy 85.646833 -405.756135) (xy 85.623068 -405.819232)
			(xy 85.591916 -405.879028) (xy 85.553825 -405.934661) (xy 85.53196 -405.960326) (xy 85.526165 -405.967472)
			(xy 85.51965 -405.984662) (xy 85.51926 -405.993854) (xy 85.51926 -406.151334) (xy 85.518801 -406.161463)
			(xy 85.511062 -406.180185) (xy 85.496768 -406.19454) (xy 85.478079 -406.202358) (xy 85.467952 -406.202896)
			(xy 84.751672 -406.202896) (xy 84.741516 -406.202501) (xy 84.722762 -406.194696) (xy 84.708439 -406.180291)
			(xy 84.700741 -406.161493) (xy 84.700364 -406.151334) (xy 84.700364 -405.993854) (xy 84.699914 -405.984671)
			(xy 84.693426 -405.967487) (xy 84.687664 -405.960326) (xy 84.665795 -405.934665) (xy 84.627709 -405.879029)
			(xy 84.596561 -405.819232) (xy 84.572799 -405.756135) (xy 84.556765 -405.690645) (xy 84.54869 -405.623707)
			(xy 83.420628 -405.623707) (xy 83.39206 -405.678683) (xy 83.354109 -405.734268) (xy 83.33232 -405.75992)
			(xy 83.326535 -405.767073) (xy 83.320013 -405.784258) (xy 83.31962 -405.793448) (xy 83.31962 -406.286716)
			(xy 83.320018 -406.295905) (xy 83.32654 -406.313089) (xy 83.33232 -406.320244) (xy 83.354077 -406.345921)
			(xy 83.39203 -406.401503) (xy 83.423067 -406.461223) (xy 83.446743 -406.524224) (xy 83.46272 -406.589604)
			(xy 83.470767 -406.656424) (xy 83.47077 -406.723728) (xy 83.470763 -406.723789) (xy 86.748808 -406.723789)
			(xy 86.748811 -406.656363) (xy 86.75689 -406.589422) (xy 86.772929 -406.523931) (xy 86.796697 -406.460833)
			(xy 86.827852 -406.401036) (xy 86.865946 -406.345401) (xy 86.887812 -406.319736) (xy 86.89362 -406.312599)
			(xy 86.900127 -406.295402) (xy 86.900512 -406.286208) (xy 86.900512 -405.793956) (xy 86.90012 -405.784767)
			(xy 86.893594 -405.767583) (xy 86.887812 -405.760428) (xy 86.865944 -405.734766) (xy 86.827854 -405.679131)
			(xy 86.796703 -405.619335) (xy 86.772939 -405.556238) (xy 86.756903 -405.490748) (xy 86.748827 -405.423809)
			(xy 86.748828 -405.356385) (xy 86.756904 -405.289446) (xy 86.77294 -405.223957) (xy 86.796706 -405.16086)
			(xy 86.827857 -405.101063) (xy 86.865947 -405.045429) (xy 86.887812 -405.019764) (xy 86.893608 -405.012618)
			(xy 86.900123 -404.995428) (xy 86.900512 -404.986236) (xy 86.900512 -404.828756) (xy 86.900949 -404.818643)
			(xy 86.908704 -404.799961) (xy 86.923015 -404.785668) (xy 86.941706 -404.777937) (xy 86.95182 -404.777448)
			(xy 87.6681 -404.777448) (xy 87.678202 -404.777984) (xy 87.696871 -404.785712) (xy 87.711163 -404.799993)
			(xy 87.718907 -404.818654) (xy 87.719408 -404.828756) (xy 87.719408 -404.986236) (xy 87.719799 -404.995425)
			(xy 87.726326 -405.01261) (xy 87.732108 -405.019764) (xy 87.753968 -405.045433) (xy 87.792056 -405.101067)
			(xy 87.823206 -405.160863) (xy 87.846971 -405.223959) (xy 87.863006 -405.289448) (xy 87.871082 -405.356385)
			(xy 87.871082 -405.423809) (xy 87.863007 -405.490746) (xy 87.846972 -405.556235) (xy 87.823209 -405.619332)
			(xy 87.792059 -405.679128) (xy 87.753971 -405.734763) (xy 87.732108 -405.760428) (xy 87.726318 -405.767578)
			(xy 87.719799 -405.784765) (xy 87.719408 -405.793956) (xy 87.719408 -406.286208) (xy 87.719813 -406.295396)
			(xy 87.72633 -406.31258) (xy 87.732108 -406.319736) (xy 87.75394 -406.345427) (xy 87.792029 -406.401058)
			(xy 87.823181 -406.460851) (xy 87.846947 -406.523944) (xy 87.862984 -406.58943) (xy 87.871062 -406.656365)
			(xy 87.871065 -406.723729) (xy 91.149127 -406.723729) (xy 91.14913 -406.656423) (xy 91.157177 -406.589598)
			(xy 91.173152 -406.524215) (xy 91.196827 -406.461209) (xy 91.227861 -406.401484) (xy 91.265812 -406.345897)
			(xy 91.2876 -406.320244) (xy 91.293403 -406.313103) (xy 91.299914 -406.295909) (xy 91.3003 -406.286716)
			(xy 91.3003 -405.793448) (xy 91.299867 -405.784263) (xy 91.293369 -405.767079) (xy 91.2876 -405.75992)
			(xy 91.26581 -405.734271) (xy 91.227863 -405.678683) (xy 91.196832 -405.618958) (xy 91.173162 -405.555954)
			(xy 91.15719 -405.490572) (xy 91.149147 -405.423749) (xy 91.149147 -405.356445) (xy 91.157191 -405.289622)
			(xy 91.173163 -405.224241) (xy 91.196835 -405.161236) (xy 91.227866 -405.101512) (xy 91.265813 -405.045925)
			(xy 91.2876 -405.020272) (xy 91.293391 -405.013123) (xy 91.299909 -404.995935) (xy 91.3003 -404.986744)
			(xy 91.3003 -404.828756) (xy 91.300686 -404.818599) (xy 91.308496 -404.799846) (xy 91.322903 -404.785524)
			(xy 91.341703 -404.777826) (xy 91.351862 -404.777448) (xy 92.068142 -404.777448) (xy 92.078272 -404.777892)
			(xy 92.096996 -404.785635) (xy 92.111351 -404.799934) (xy 92.119167 -404.818628) (xy 92.119704 -404.828756)
			(xy 92.119704 -404.986744) (xy 92.120092 -404.995934) (xy 92.126621 -405.013118) (xy 92.132404 -405.020272)
			(xy 92.154186 -405.045928) (xy 92.192133 -405.101515) (xy 92.223164 -405.161238) (xy 92.246835 -405.224242)
			(xy 92.262807 -405.289624) (xy 92.270851 -405.356445) (xy 92.270851 -405.423749) (xy 92.262808 -405.490571)
			(xy 92.246837 -405.555952) (xy 92.223166 -405.618956) (xy 92.220728 -405.623648) (xy 115.349248 -405.623648)
			(xy 115.349249 -405.556343) (xy 115.357293 -405.489521) (xy 115.373266 -405.424139) (xy 115.396938 -405.361134)
			(xy 115.42797 -405.30141) (xy 115.465917 -405.245823) (xy 115.487704 -405.22017) (xy 115.493496 -405.213022)
			(xy 115.500013 -405.195834) (xy 115.500404 -405.186642) (xy 115.500404 -404.693374) (xy 115.500006 -404.684186)
			(xy 115.493484 -404.667001) (xy 115.487704 -404.659846) (xy 115.465939 -404.634176) (xy 115.427992 -404.578591)
			(xy 115.396959 -404.51887) (xy 115.373287 -404.455868) (xy 115.357314 -404.390488) (xy 115.349268 -404.323668)
			(xy 115.349266 -404.256365) (xy 115.357308 -404.189545) (xy 115.373277 -404.124164) (xy 115.396946 -404.061161)
			(xy 115.427975 -404.001437) (xy 115.465919 -403.945851) (xy 115.487704 -403.920198) (xy 115.493484 -403.913041)
			(xy 115.500009 -403.89586) (xy 115.500404 -403.88667) (xy 115.500404 -403.728682) (xy 115.500918 -403.718527)
			(xy 115.508692 -403.699764) (xy 115.523051 -403.685401) (xy 115.541811 -403.677621) (xy 115.551966 -403.67712)
			(xy 116.268246 -403.67712) (xy 116.278404 -403.677595) (xy 116.297171 -403.685382) (xy 116.311534 -403.699752)
			(xy 116.31931 -403.718523) (xy 116.319808 -403.728682) (xy 116.319808 -403.88667) (xy 116.320231 -403.895856)
			(xy 116.326735 -403.91304) (xy 116.332508 -403.920198) (xy 116.354319 -403.945832) (xy 116.392271 -404.00142)
			(xy 116.423306 -404.061145) (xy 116.44698 -404.124152) (xy 116.462953 -404.189537) (xy 116.470996 -404.256363)
			(xy 116.470994 -404.32367) (xy 116.462947 -404.390495) (xy 116.44697 -404.455879) (xy 116.423292 -404.518885)
			(xy 116.392254 -404.578609) (xy 116.354299 -404.634195) (xy 116.332508 -404.659846) (xy 116.32671 -404.66699)
			(xy 116.320196 -404.684181) (xy 116.319808 -404.693374) (xy 116.319808 -405.186642) (xy 116.320196 -405.195832)
			(xy 116.326725 -405.213016) (xy 116.332508 -405.22017) (xy 116.354291 -405.245826) (xy 116.392244 -405.301411)
			(xy 116.42328 -405.361133) (xy 116.446956 -405.424137) (xy 116.462931 -405.48952) (xy 116.470976 -405.556343)
			(xy 116.470977 -405.623648) (xy 116.462932 -405.690471) (xy 116.446958 -405.755854) (xy 116.423284 -405.818858)
			(xy 116.392249 -405.878581) (xy 116.354297 -405.934167) (xy 116.332508 -405.959818) (xy 116.326722 -405.966971)
			(xy 116.320201 -405.984155) (xy 116.319808 -405.993346) (xy 116.319808 -406.151334) (xy 116.319296 -406.161488)
			(xy 116.311519 -406.180249) (xy 116.297159 -406.194612) (xy 116.2784 -406.202393) (xy 116.268246 -406.202896)
			(xy 115.551966 -406.202896) (xy 115.54181 -406.202395) (xy 115.523047 -406.194616) (xy 115.508684 -406.180253)
			(xy 115.500905 -406.16149) (xy 115.500404 -406.151334) (xy 115.500404 -405.993346) (xy 115.499971 -405.984161)
			(xy 115.493473 -405.966977) (xy 115.487704 -405.959818) (xy 115.465911 -405.93417) (xy 115.427965 -405.878582)
			(xy 115.396934 -405.818858) (xy 115.373263 -405.755853) (xy 115.357292 -405.69047) (xy 115.349248 -405.623648)
			(xy 92.220728 -405.623648) (xy 92.192136 -405.67868) (xy 92.15419 -405.734267) (xy 92.132404 -405.75992)
			(xy 92.126617 -405.767072) (xy 92.120096 -405.784257) (xy 92.119704 -405.793448) (xy 92.119704 -406.286716)
			(xy 92.120106 -406.295904) (xy 92.126625 -406.313088) (xy 92.132404 -406.320244) (xy 92.154159 -406.345923)
			(xy 92.192106 -406.401506) (xy 92.223138 -406.461227) (xy 92.246811 -406.524228) (xy 92.262785 -406.589606)
			(xy 92.270831 -406.656425) (xy 92.270834 -406.723727) (xy 92.270826 -406.72379) (xy 117.548838 -406.72379)
			(xy 117.548841 -406.656362) (xy 117.55692 -406.589421) (xy 117.572961 -406.523929) (xy 117.596731 -406.460831)
			(xy 117.627888 -406.401034) (xy 117.665984 -406.3454) (xy 117.687852 -406.319736) (xy 117.693665 -406.312602)
			(xy 117.700168 -406.295403) (xy 117.700552 -406.286208) (xy 117.700552 -405.793956) (xy 117.700151 -405.784768)
			(xy 117.69363 -405.767585) (xy 117.687852 -405.760428) (xy 117.665982 -405.734767) (xy 117.62789 -405.679133)
			(xy 117.596737 -405.619337) (xy 117.572971 -405.556239) (xy 117.556934 -405.490749) (xy 117.548857 -405.42381)
			(xy 117.548858 -405.356384) (xy 117.556935 -405.289445) (xy 117.572972 -405.223955) (xy 117.596739 -405.160858)
			(xy 117.627893 -405.101062) (xy 117.665986 -405.045428) (xy 117.687852 -405.019764) (xy 117.693653 -405.012622)
			(xy 117.700164 -404.995429) (xy 117.700552 -404.986236) (xy 117.700552 -404.828756) (xy 117.701048 -404.81865)
			(xy 117.708791 -404.79998) (xy 117.723084 -404.785689) (xy 117.741754 -404.777947) (xy 117.75186 -404.777448)
			(xy 118.46814 -404.777448) (xy 118.478245 -404.777951) (xy 118.496914 -404.785692) (xy 118.511206 -404.799983)
			(xy 118.518948 -404.818651) (xy 118.519448 -404.828756) (xy 118.519448 -404.986236) (xy 118.519853 -404.995424)
			(xy 118.526372 -405.012607) (xy 118.532148 -405.019764) (xy 118.55401 -405.045432) (xy 118.592102 -405.101065)
			(xy 118.623256 -405.16086) (xy 118.647023 -405.223957) (xy 118.66306 -405.289446) (xy 118.671137 -405.356385)
			(xy 118.671137 -405.423809) (xy 118.663061 -405.490748) (xy 118.647024 -405.556238) (xy 118.623258 -405.619335)
			(xy 118.62098 -405.623708) (xy 119.749017 -405.623708) (xy 119.749017 -405.556283) (xy 119.757094 -405.489345)
			(xy 119.77313 -405.423855) (xy 119.796895 -405.360758) (xy 119.828046 -405.300962) (xy 119.866136 -405.245327)
			(xy 119.888 -405.219662) (xy 119.893795 -405.212516) (xy 119.900311 -405.195326) (xy 119.9007 -405.186134)
			(xy 119.9007 -404.693882) (xy 119.900298 -404.684694) (xy 119.893779 -404.66751) (xy 119.888 -404.660354)
			(xy 119.866158 -404.634671) (xy 119.828068 -404.579039) (xy 119.796917 -404.519245) (xy 119.773151 -404.456151)
			(xy 119.757114 -404.390664) (xy 119.749037 -404.323727) (xy 119.749035 -404.256306) (xy 119.757108 -404.189369)
			(xy 119.773141 -404.123881) (xy 119.796903 -404.060785) (xy 119.828051 -404.000989) (xy 119.866137 -403.945355)
			(xy 119.888 -403.91969) (xy 119.893783 -403.912535) (xy 119.900306 -403.895352) (xy 119.9007 -403.886162)
			(xy 119.9007 -403.728682) (xy 119.90121 -403.718559) (xy 119.908937 -403.699845) (xy 119.923215 -403.685491)
			(xy 119.941888 -403.677665) (xy 119.952008 -403.67712) (xy 120.668288 -403.67712) (xy 120.678412 -403.677526)
			(xy 120.697119 -403.685274) (xy 120.711435 -403.699594) (xy 120.719177 -403.718304) (xy 120.719596 -403.728428)
			(xy 120.719596 -403.886162) (xy 120.720025 -403.895347) (xy 120.726526 -403.912532) (xy 120.732296 -403.91969)
			(xy 120.754182 -403.945337) (xy 120.79227 -404.000974) (xy 120.82342 -404.060773) (xy 120.847183 -404.123872)
			(xy 120.863217 -404.189363) (xy 120.871291 -404.256304) (xy 120.871289 -404.323729) (xy 120.863211 -404.390669)
			(xy 120.847173 -404.456159) (xy 120.823407 -404.519257) (xy 120.792253 -404.579054) (xy 120.754161 -404.634689)
			(xy 120.732296 -404.660354) (xy 120.726494 -404.667495) (xy 120.719983 -404.684689) (xy 120.719596 -404.693882)
			(xy 120.719596 -405.186134) (xy 120.719991 -405.195323) (xy 120.726515 -405.212507) (xy 120.732296 -405.219662)
			(xy 120.754154 -405.245332) (xy 120.792243 -405.300966) (xy 120.823395 -405.360761) (xy 120.847159 -405.423858)
			(xy 120.863195 -405.489346) (xy 120.871272 -405.556284) (xy 120.871272 -405.623707) (xy 120.863197 -405.690645)
			(xy 120.847162 -405.756134) (xy 120.823398 -405.81923) (xy 120.792248 -405.879026) (xy 120.75416 -405.934661)
			(xy 120.732296 -405.960326) (xy 120.726505 -405.967475) (xy 120.719987 -405.984663) (xy 120.719596 -405.993854)
			(xy 120.719596 -406.151334) (xy 120.719102 -406.161458) (xy 120.71137 -406.180174) (xy 120.697087 -406.194527)
			(xy 120.67841 -406.202352) (xy 120.668288 -406.202896) (xy 119.952008 -406.202896) (xy 119.941886 -406.202477)
			(xy 119.923181 -406.194731) (xy 119.908867 -406.180415) (xy 119.901122 -406.16171) (xy 119.9007 -406.151588)
			(xy 119.9007 -405.993854) (xy 119.900264 -405.98467) (xy 119.893768 -405.967485) (xy 119.888 -405.960326)
			(xy 119.86613 -405.934666) (xy 119.828042 -405.87903) (xy 119.796891 -405.819234) (xy 119.773127 -405.756136)
			(xy 119.757092 -405.690646) (xy 119.749017 -405.623708) (xy 118.62098 -405.623708) (xy 118.592105 -405.67913)
			(xy 118.554014 -405.734764) (xy 118.532148 -405.760428) (xy 118.526351 -405.767572) (xy 118.519838 -405.784764)
			(xy 118.519448 -405.793956) (xy 118.519448 -406.286208) (xy 118.519866 -406.295394) (xy 118.526375 -406.312578)
			(xy 118.532148 -406.319736) (xy 118.553982 -406.345426) (xy 118.592075 -406.401056) (xy 118.62323 -406.460848)
			(xy 118.646999 -406.523942) (xy 118.663038 -406.589429) (xy 118.671117 -406.656365) (xy 118.67112 -406.72373)
			(xy 121.949157 -406.72373) (xy 121.94916 -406.656422) (xy 121.957208 -406.589597) (xy 121.973184 -406.524213)
			(xy 121.99686 -406.461207) (xy 122.027897 -406.401483) (xy 122.06585 -406.345896) (xy 122.08764 -406.320244)
			(xy 122.093448 -406.313107) (xy 122.099955 -406.29591) (xy 122.10034 -406.286716) (xy 122.10034 -405.793448)
			(xy 122.099898 -405.784264) (xy 122.093405 -405.76708) (xy 122.08764 -405.75992) (xy 122.065848 -405.734271)
			(xy 122.027899 -405.678684) (xy 121.996866 -405.61896) (xy 121.973194 -405.555955) (xy 121.957221 -405.490573)
			(xy 121.949177 -405.42375) (xy 121.949177 -405.356444) (xy 121.957222 -405.289621) (xy 121.973195 -405.224239)
			(xy 121.996869 -405.161234) (xy 122.027902 -405.101511) (xy 122.065852 -405.045924) (xy 122.08764 -405.020272)
			(xy 122.093436 -405.013127) (xy 122.09995 -404.995936) (xy 122.10034 -404.986744) (xy 122.10034 -404.828756)
			(xy 122.100681 -404.818626) (xy 122.108451 -404.799913) (xy 122.122791 -404.785599) (xy 122.141517 -404.777863)
			(xy 122.151648 -404.777448) (xy 122.868182 -404.777448) (xy 122.878309 -404.777941) (xy 122.897031 -404.785665)
			(xy 122.911388 -404.799949) (xy 122.919207 -404.818632) (xy 122.919744 -404.828756) (xy 122.919744 -404.986744)
			(xy 122.920145 -404.995932) (xy 122.926666 -405.013116) (xy 122.932444 -405.020272) (xy 122.954228 -405.045927)
			(xy 122.992178 -405.101513) (xy 123.023213 -405.161236) (xy 123.046886 -405.22424) (xy 123.06286 -405.289622)
			(xy 123.070905 -405.356444) (xy 123.070905 -405.42375) (xy 123.062861 -405.490572) (xy 123.046888 -405.555954)
			(xy 123.023215 -405.618959) (xy 123.020778 -405.623649) (xy 124.149312 -405.623649) (xy 124.149313 -405.556342)
			(xy 124.157358 -405.489518) (xy 124.173333 -405.424135) (xy 124.197009 -405.36113) (xy 124.228046 -405.301407)
			(xy 124.265998 -405.245822) (xy 124.287788 -405.22017) (xy 124.293578 -405.21302) (xy 124.300097 -405.195833)
			(xy 124.300488 -405.186642) (xy 124.300488 -404.693374) (xy 124.300093 -404.684185) (xy 124.293569 -404.667001)
			(xy 124.287788 -404.659846) (xy 124.26602 -404.634177) (xy 124.228068 -404.578594) (xy 124.197031 -404.518873)
			(xy 124.173355 -404.455871) (xy 124.157379 -404.39049) (xy 124.149332 -404.323669) (xy 124.14933 -404.256364)
			(xy 124.157373 -404.189542) (xy 124.173345 -404.124161) (xy 124.197017 -404.061157) (xy 124.228051 -404.001435)
			(xy 124.266 -403.945849) (xy 124.287788 -403.920198) (xy 124.293567 -403.91304) (xy 124.300092 -403.895859)
			(xy 124.300488 -403.88667) (xy 124.300488 -403.728682) (xy 124.30085 -403.718503) (xy 124.308651 -403.699698)
			(xy 124.323056 -403.685313) (xy 124.34187 -403.677537) (xy 124.35205 -403.67712) (xy 125.06833 -403.67712)
			(xy 125.078487 -403.677608) (xy 125.097254 -403.685389) (xy 125.111617 -403.699756) (xy 125.119394 -403.718524)
			(xy 125.119892 -403.728682) (xy 125.119892 -403.88667) (xy 125.120318 -403.895855) (xy 125.126821 -403.91304)
			(xy 125.132592 -403.920198) (xy 125.1544 -403.945833) (xy 125.192347 -404.001422) (xy 125.223377 -404.061149)
			(xy 125.247047 -404.124155) (xy 125.263018 -404.189539) (xy 125.27106 -404.256363) (xy 125.271058 -404.32367)
			(xy 125.263012 -404.390493) (xy 125.247038 -404.455876) (xy 125.223364 -404.518882) (xy 125.19233 -404.578606)
			(xy 125.15438 -404.634193) (xy 125.132592 -404.659846) (xy 125.126792 -404.666989) (xy 125.12028 -404.684181)
			(xy 125.119892 -404.693374) (xy 125.119892 -405.186642) (xy 125.120284 -405.195831) (xy 125.12681 -405.213015)
			(xy 125.132592 -405.22017) (xy 125.154373 -405.245827) (xy 125.19232 -405.301414) (xy 125.223352 -405.361137)
			(xy 125.247023 -405.424141) (xy 125.262996 -405.489522) (xy 125.27104 -405.556343) (xy 125.271041 -405.623647)
			(xy 125.262998 -405.690469) (xy 125.247026 -405.755851) (xy 125.223355 -405.818855) (xy 125.192325 -405.878578)
			(xy 125.154378 -405.934165) (xy 125.132592 -405.959818) (xy 125.126804 -405.96697) (xy 125.120285 -405.984155)
			(xy 125.119892 -405.993346) (xy 125.119892 -406.151334) (xy 125.119395 -406.16149) (xy 125.111615 -406.180254)
			(xy 125.097251 -406.194617) (xy 125.078486 -406.202396) (xy 125.06833 -406.202896) (xy 124.35205 -406.202896)
			(xy 124.341886 -406.202396) (xy 124.323099 -406.194634) (xy 124.308713 -406.180272) (xy 124.30092 -406.161497)
			(xy 124.300488 -406.151334) (xy 124.300488 -405.993346) (xy 124.300059 -405.984161) (xy 124.293559 -405.966976)
			(xy 124.287788 -405.959818) (xy 124.265993 -405.934171) (xy 124.228041 -405.878585) (xy 124.197005 -405.818861)
			(xy 124.173331 -405.755856) (xy 124.157357 -405.690473) (xy 124.149312 -405.623649) (xy 123.020778 -405.623649)
			(xy 122.992181 -405.678682) (xy 122.954232 -405.734268) (xy 122.932444 -405.75992) (xy 122.92665 -405.767066)
			(xy 122.920135 -405.784256) (xy 122.919744 -405.793448) (xy 122.919744 -406.286716) (xy 122.920159 -406.295902)
			(xy 122.926671 -406.313086) (xy 122.932444 -406.320244) (xy 122.954201 -406.345922) (xy 122.992152 -406.401504)
			(xy 123.023187 -406.461224) (xy 123.046862 -406.524225) (xy 123.062838 -406.589605) (xy 123.070885 -406.656425)
			(xy 123.070888 -406.723727) (xy 123.070881 -406.723789) (xy 126.348926 -406.723789) (xy 126.348929 -406.656363)
			(xy 126.357008 -406.589421) (xy 126.373048 -406.52393) (xy 126.396818 -406.460832) (xy 126.427974 -406.401035)
			(xy 126.466069 -406.345401) (xy 126.487936 -406.319736) (xy 126.493747 -406.312601) (xy 126.500252 -406.295403)
			(xy 126.500636 -406.286208) (xy 126.500636 -405.793956) (xy 126.500239 -405.784768) (xy 126.493715 -405.767584)
			(xy 126.487936 -405.760428) (xy 126.466067 -405.734767) (xy 126.427976 -405.679132) (xy 126.396823 -405.619336)
			(xy 126.373058 -405.556239) (xy 126.357022 -405.490749) (xy 126.348945 -405.423809) (xy 126.348946 -405.356385)
			(xy 126.357023 -405.289445) (xy 126.37306 -405.223956) (xy 126.396826 -405.160859) (xy 126.427979 -405.101062)
			(xy 126.466071 -405.045429) (xy 126.487936 -405.019764) (xy 126.493735 -405.012621) (xy 126.500247 -404.995429)
			(xy 126.500636 -404.986236) (xy 126.500636 -404.828756) (xy 126.50105 -404.81864) (xy 126.508809 -404.799954)
			(xy 126.523128 -404.785659) (xy 126.541827 -404.777933) (xy 126.551944 -404.777448) (xy 127.268224 -404.777448)
			(xy 127.278328 -404.777964) (xy 127.296997 -404.7857) (xy 127.311289 -404.799986) (xy 127.319032 -404.818652)
			(xy 127.319532 -404.828756) (xy 127.319532 -404.986236) (xy 127.31994 -404.995423) (xy 127.326457 -405.012607)
			(xy 127.332232 -405.019764) (xy 127.354091 -405.045433) (xy 127.392178 -405.101068) (xy 127.423327 -405.160864)
			(xy 127.44709 -405.22396) (xy 127.463125 -405.289448) (xy 127.4712 -405.356386) (xy 127.471201 -405.423808)
			(xy 127.463126 -405.490746) (xy 127.447092 -405.556234) (xy 127.423329 -405.619331) (xy 127.42108 -405.623649)
			(xy 128.549103 -405.623649) (xy 128.549104 -405.556342) (xy 128.557149 -405.489519) (xy 128.573124 -405.424136)
			(xy 128.596799 -405.361131) (xy 128.627835 -405.301407) (xy 128.665787 -405.245822) (xy 128.687576 -405.22017)
			(xy 128.693365 -405.213019) (xy 128.699885 -405.195833) (xy 128.700276 -405.186642) (xy 128.700276 -404.693374)
			(xy 128.699884 -404.684185) (xy 128.693358 -404.667) (xy 128.687576 -404.659846) (xy 128.665809 -404.634177)
			(xy 128.627857 -404.578593) (xy 128.596821 -404.518873) (xy 128.573145 -404.45587) (xy 128.557169 -404.39049)
			(xy 128.549123 -404.323669) (xy 128.549121 -404.256365) (xy 128.557164 -404.189543) (xy 128.573135 -404.124161)
			(xy 128.596807 -404.061158) (xy 128.62784 -404.001435) (xy 128.665789 -403.94585) (xy 128.687576 -403.920198)
			(xy 128.693353 -403.913039) (xy 128.69988 -403.895859) (xy 128.700276 -403.88667) (xy 128.700276 -403.728682)
			(xy 128.70065 -403.718505) (xy 128.708448 -403.699702) (xy 128.722849 -403.685317) (xy 128.74166 -403.677539)
			(xy 128.751838 -403.67712) (xy 129.468118 -403.67712) (xy 129.478275 -403.677618) (xy 129.497041 -403.685395)
			(xy 129.511405 -403.699759) (xy 129.519182 -403.718525) (xy 129.51968 -403.728682) (xy 129.51968 -403.88667)
			(xy 129.520109 -403.895855) (xy 129.52661 -403.913039) (xy 129.53238 -403.920198) (xy 129.554189 -403.945833)
			(xy 129.592136 -404.001422) (xy 129.623167 -404.061148) (xy 129.646838 -404.124155) (xy 129.662809 -404.189539)
			(xy 129.670851 -404.256363) (xy 129.670849 -404.32367) (xy 129.662803 -404.390494) (xy 129.646828 -404.455877)
			(xy 129.623154 -404.518882) (xy 129.592119 -404.578606) (xy 129.554169 -404.634194) (xy 129.53238 -404.659846)
			(xy 129.526579 -404.666988) (xy 129.520068 -404.684181) (xy 129.51968 -404.693374) (xy 129.51968 -405.186642)
			(xy 129.520074 -405.195831) (xy 129.5266 -405.213015) (xy 129.53238 -405.22017) (xy 129.554161 -405.245827)
			(xy 129.592109 -405.301413) (xy 129.623142 -405.361136) (xy 129.646814 -405.42414) (xy 129.662787 -405.489522)
			(xy 129.670831 -405.556343) (xy 129.670832 -405.623648) (xy 129.662788 -405.690469) (xy 129.646817 -405.755851)
			(xy 129.623145 -405.818855) (xy 129.592114 -405.878579) (xy 129.554167 -405.934166) (xy 129.53238 -405.959818)
			(xy 129.526591 -405.966968) (xy 129.520072 -405.984155) (xy 129.51968 -405.993346) (xy 129.51968 -406.151334)
			(xy 129.519195 -406.161492) (xy 129.511413 -406.180258) (xy 129.497045 -406.194622) (xy 129.478276 -406.202398)
			(xy 129.468118 -406.202896) (xy 128.751838 -406.202896) (xy 128.741673 -406.202406) (xy 128.722886 -406.19464)
			(xy 128.708501 -406.180275) (xy 128.700708 -406.161498) (xy 128.700276 -406.151334) (xy 128.700276 -405.993346)
			(xy 128.699849 -405.984161) (xy 128.693347 -405.966976) (xy 128.687576 -405.959818) (xy 128.665781 -405.934171)
			(xy 128.62783 -405.878585) (xy 128.596795 -405.818861) (xy 128.573121 -405.755856) (xy 128.557148 -405.690472)
			(xy 128.549103 -405.623649) (xy 127.42108 -405.623649) (xy 127.392181 -405.679127) (xy 127.354095 -405.734762)
			(xy 127.332232 -405.760428) (xy 127.326433 -405.767571) (xy 127.319922 -405.784763) (xy 127.319532 -405.793956)
			(xy 127.319532 -406.286208) (xy 127.319954 -406.295394) (xy 127.326461 -406.312577) (xy 127.332232 -406.319736)
			(xy 127.354063 -406.345428) (xy 127.392151 -406.401059) (xy 127.423301 -406.460852) (xy 127.447066 -406.523945)
			(xy 127.463103 -406.589431) (xy 127.471181 -406.656366) (xy 127.471183 -406.72373) (xy 130.749245 -406.72373)
			(xy 130.749248 -406.656422) (xy 130.757295 -406.589598) (xy 130.773271 -406.524214) (xy 130.796947 -406.461208)
			(xy 130.827983 -406.401484) (xy 130.865935 -406.345896) (xy 130.887724 -406.320244) (xy 130.89353 -406.313105)
			(xy 130.900038 -406.29591) (xy 130.900424 -406.286716) (xy 130.900424 -405.793448) (xy 130.899985 -405.784264)
			(xy 130.893491 -405.76708) (xy 130.887724 -405.75992) (xy 130.865933 -405.734271) (xy 130.827985 -405.678684)
			(xy 130.796953 -405.61896) (xy 130.773281 -405.555955) (xy 130.757309 -405.490572) (xy 130.749265 -405.42375)
			(xy 130.749265 -405.356444) (xy 130.75731 -405.289622) (xy 130.773283 -405.22424) (xy 130.796955 -405.161235)
			(xy 130.827988 -405.101511) (xy 130.865936 -405.045924) (xy 130.887724 -405.020272) (xy 130.893518 -405.013125)
			(xy 130.900033 -404.995936) (xy 130.900424 -404.986744) (xy 130.900424 -404.828756) (xy 130.900786 -404.818596)
			(xy 130.908601 -404.799838) (xy 130.923016 -404.785515) (xy 130.941823 -404.777822) (xy 130.951986 -404.777448)
			(xy 131.668266 -404.777448) (xy 131.678391 -404.777955) (xy 131.697113 -404.785673) (xy 131.711471 -404.799953)
			(xy 131.71929 -404.818633) (xy 131.719828 -404.828756) (xy 131.719828 -404.986744) (xy 131.720211 -404.995934)
			(xy 131.726743 -405.013119) (xy 131.732528 -405.020272) (xy 131.754313 -405.045927) (xy 131.792264 -405.101512)
			(xy 131.823299 -405.161235) (xy 131.846974 -405.224239) (xy 131.862948 -405.289622) (xy 131.870993 -405.356444)
			(xy 131.870993 -405.42375) (xy 131.862949 -405.490573) (xy 131.846975 -405.555955) (xy 131.823302 -405.618959)
			(xy 131.792267 -405.678683) (xy 131.754316 -405.734268) (xy 131.732528 -405.75992) (xy 131.726732 -405.767065)
			(xy 131.720219 -405.784256) (xy 131.719828 -405.793448) (xy 131.719828 -406.286716) (xy 131.720224 -406.295905)
			(xy 131.726747 -406.313089) (xy 131.732528 -406.320244) (xy 131.754285 -406.345922) (xy 131.792237 -406.401504)
			(xy 131.823274 -406.461223) (xy 131.84695 -406.524225) (xy 131.862926 -406.589604) (xy 131.870973 -406.656424)
			(xy 131.870976 -406.723728) (xy 131.862934 -406.790548) (xy 131.846964 -406.855929) (xy 131.823293 -406.918933)
			(xy 131.792262 -406.978655) (xy 131.754315 -407.03424) (xy 131.732528 -407.059892) (xy 131.726744 -407.067045)
			(xy 131.720224 -407.08423) (xy 131.719828 -407.09342) (xy 131.719828 -407.251408) (xy 131.719385 -407.261559)
			(xy 131.711592 -407.280306) (xy 131.697203 -407.294628) (xy 131.678419 -407.302333) (xy 131.668266 -407.302716)
			(xy 130.951986 -407.302716) (xy 130.941853 -407.302283) (xy 130.923123 -407.294543) (xy 130.908766 -407.28024)
			(xy 130.900955 -407.261539) (xy 130.900424 -407.251408) (xy 130.900424 -407.09342) (xy 130.899999 -407.084235)
			(xy 130.893495 -407.06705) (xy 130.887724 -407.059892) (xy 130.865905 -407.034266) (xy 130.827958 -406.978675)
			(xy 130.796927 -406.918948) (xy 130.773257 -406.85594) (xy 130.757287 -406.790555) (xy 130.749245 -406.72373)
			(xy 127.471183 -406.72373) (xy 127.471183 -406.723786) (xy 127.463111 -406.790722) (xy 127.44708 -406.856209)
			(xy 127.423321 -406.919304) (xy 127.392176 -406.9791) (xy 127.354093 -407.034734) (xy 127.332232 -407.0604)
			(xy 127.326445 -407.067551) (xy 127.319926 -407.084737) (xy 127.319532 -407.093928) (xy 127.319532 -407.251408)
			(xy 127.319022 -407.261513) (xy 127.311288 -407.280185) (xy 127.296999 -407.294479) (xy 127.278329 -407.302219)
			(xy 127.268224 -407.302716) (xy 126.551944 -407.302716) (xy 126.541826 -407.302248) (xy 126.523127 -407.294518)
			(xy 126.508812 -407.280217) (xy 126.501062 -407.261525) (xy 126.500636 -407.251408) (xy 126.500636 -407.093928)
			(xy 126.500204 -407.084743) (xy 126.493705 -407.067559) (xy 126.487936 -407.0604) (xy 126.466039 -407.034761)
			(xy 126.427949 -406.979124) (xy 126.396798 -406.919324) (xy 126.373034 -406.856224) (xy 126.357 -406.790731)
			(xy 126.348926 -406.723789) (xy 123.070881 -406.723789) (xy 123.062847 -406.790548) (xy 123.046877 -406.855929)
			(xy 123.023207 -406.918932) (xy 122.992176 -406.978654) (xy 122.95423 -407.03424) (xy 122.932444 -407.059892)
			(xy 122.926661 -407.067047) (xy 122.92014 -407.08423) (xy 122.919744 -407.09342) (xy 122.919744 -407.251408)
			(xy 122.919222 -407.261512) (xy 122.91149 -407.280182) (xy 122.897205 -407.294475) (xy 122.878539 -407.302217)
			(xy 122.868436 -407.302716) (xy 122.151902 -407.302716) (xy 122.14177 -407.30227) (xy 122.123041 -407.294535)
			(xy 122.108683 -407.280236) (xy 122.100871 -407.261538) (xy 122.10034 -407.251408) (xy 122.10034 -407.09342)
			(xy 122.099911 -407.084235) (xy 122.09341 -407.067051) (xy 122.08764 -407.059892) (xy 122.065821 -407.034266)
			(xy 122.027873 -406.978676) (xy 121.996841 -406.918949) (xy 121.97317 -406.855941) (xy 121.957199 -406.790555)
			(xy 121.949157 -406.72373) (xy 118.67112 -406.72373) (xy 118.67112 -406.723787) (xy 118.663047 -406.790724)
			(xy 118.647013 -406.856212) (xy 118.62325 -406.919308) (xy 118.5921 -406.979103) (xy 118.554012 -407.034736)
			(xy 118.532148 -407.0604) (xy 118.526362 -407.067553) (xy 118.519843 -407.084738) (xy 118.519448 -407.093928)
			(xy 118.519448 -407.251408) (xy 118.518922 -407.261511) (xy 118.511191 -407.28018) (xy 118.496907 -407.294473)
			(xy 118.478243 -407.302216) (xy 118.46814 -407.302716) (xy 117.75186 -407.302716) (xy 117.741751 -407.302248)
			(xy 117.723075 -407.2945) (xy 117.708782 -407.280198) (xy 117.701046 -407.261518) (xy 117.700552 -407.251408)
			(xy 117.700552 -407.093928) (xy 117.700117 -407.084744) (xy 117.693619 -407.06756) (xy 117.687852 -407.0604)
			(xy 117.665955 -407.034762) (xy 117.627864 -406.979124) (xy 117.596711 -406.919325) (xy 117.572947 -406.856225)
			(xy 117.556912 -406.790732) (xy 117.548838 -406.72379) (xy 92.270826 -406.72379) (xy 92.262793 -406.790546)
			(xy 92.246825 -406.855926) (xy 92.223158 -406.918929) (xy 92.192131 -406.978652) (xy 92.154188 -407.034239)
			(xy 92.132404 -407.059892) (xy 92.126629 -407.067052) (xy 92.120101 -407.084231) (xy 92.119704 -407.09342)
			(xy 92.119704 -407.251408) (xy 92.119285 -407.261562) (xy 92.111487 -407.280314) (xy 92.09709 -407.294637)
			(xy 92.078298 -407.302337) (xy 92.068142 -407.302716) (xy 91.351862 -407.302716) (xy 91.341727 -407.302303)
			(xy 91.322997 -407.294555) (xy 91.308641 -407.280246) (xy 91.30083 -407.261541) (xy 91.3003 -407.251408)
			(xy 91.3003 -407.09342) (xy 91.29988 -407.084234) (xy 91.293373 -407.067049) (xy 91.2876 -407.059892)
			(xy 91.265782 -407.034265) (xy 91.227837 -406.978674) (xy 91.196807 -406.918947) (xy 91.173138 -406.855939)
			(xy 91.157168 -406.790554) (xy 91.149127 -406.723729) (xy 87.871065 -406.723729) (xy 87.871065 -406.723786)
			(xy 87.862993 -406.790722) (xy 87.846961 -406.85621) (xy 87.823201 -406.919305) (xy 87.792054 -406.9791)
			(xy 87.75397 -407.034735) (xy 87.732108 -407.0604) (xy 87.72633 -407.067558) (xy 87.719804 -407.084739)
			(xy 87.719408 -407.093928) (xy 87.719408 -407.251408) (xy 87.718921 -407.261516) (xy 87.711183 -407.280193)
			(xy 87.696886 -407.294487) (xy 87.678208 -407.302223) (xy 87.6681 -407.302716) (xy 86.95182 -407.302716)
			(xy 86.941701 -407.302268) (xy 86.923001 -407.29453) (xy 86.908686 -407.280223) (xy 86.900937 -407.261527)
			(xy 86.900512 -407.251408) (xy 86.900512 -407.093928) (xy 86.900086 -407.084743) (xy 86.893583 -407.067558)
			(xy 86.887812 -407.0604) (xy 86.865916 -407.034761) (xy 86.827828 -406.979123) (xy 86.796678 -406.919323)
			(xy 86.772915 -406.856223) (xy 86.756881 -406.790731) (xy 86.748808 -406.723789) (xy 83.470763 -406.723789)
			(xy 83.462728 -406.790549) (xy 83.446757 -406.85593) (xy 83.423086 -406.918933) (xy 83.392055 -406.978655)
			(xy 83.354107 -407.03424) (xy 83.33232 -407.059892) (xy 83.326547 -407.067054) (xy 83.320017 -407.084231)
			(xy 83.31962 -407.09342) (xy 83.31962 -407.251408) (xy 83.319185 -407.26156) (xy 83.311391 -407.280309)
			(xy 83.296998 -407.294631) (xy 83.278212 -407.302334) (xy 83.268058 -407.302716) (xy 82.551778 -407.302716)
			(xy 82.541644 -407.30229) (xy 82.522914 -407.294547) (xy 82.508557 -407.280242) (xy 82.500747 -407.26154)
			(xy 82.500216 -407.251408) (xy 82.500216 -407.09342) (xy 82.499792 -407.084234) (xy 82.493288 -407.06705)
			(xy 82.487516 -407.059892) (xy 82.465698 -407.034265) (xy 82.427751 -406.978675) (xy 82.396721 -406.918947)
			(xy 82.373051 -406.85594) (xy 82.35708 -406.790555) (xy 82.349039 -406.72373) (xy 79.070977 -406.72373)
			(xy 79.070977 -406.723786) (xy 79.062905 -406.790722) (xy 79.046874 -406.856209) (xy 79.023114 -406.919304)
			(xy 78.991969 -406.9791) (xy 78.953885 -407.034734) (xy 78.932024 -407.0604) (xy 78.926248 -407.06756)
			(xy 78.91972 -407.084739) (xy 78.919324 -407.093928) (xy 78.919324 -407.251408) (xy 78.918822 -407.261514)
			(xy 78.911086 -407.280188) (xy 78.896795 -407.294482) (xy 78.878122 -407.30222) (xy 78.868016 -407.302716)
			(xy 78.151736 -407.302716) (xy 78.141618 -407.302255) (xy 78.122918 -407.294521) (xy 78.108603 -407.280219)
			(xy 78.100854 -407.261526) (xy 78.100428 -407.251408) (xy 78.100428 -407.093928) (xy 78.099998 -407.084743)
			(xy 78.093497 -407.067559) (xy 78.087728 -407.0604) (xy 78.065832 -407.034761) (xy 78.027742 -406.979124)
			(xy 77.996591 -406.919324) (xy 77.972828 -406.856224) (xy 77.956793 -406.790731) (xy 77.94872 -406.723789)
			(xy 74.670675 -406.723789) (xy 74.662641 -406.790548) (xy 74.64667 -406.855929) (xy 74.623 -406.918932)
			(xy 74.591969 -406.978655) (xy 74.554022 -407.03424) (xy 74.532236 -407.059892) (xy 74.526453 -407.067046)
			(xy 74.519932 -407.08423) (xy 74.519536 -407.09342) (xy 74.519536 -407.251408) (xy 74.519085 -407.261558)
			(xy 74.511294 -407.280304) (xy 74.496907 -407.294625) (xy 74.478126 -407.302331) (xy 74.467974 -407.302716)
			(xy 73.751694 -407.302716) (xy 73.741562 -407.302277) (xy 73.722832 -407.294539) (xy 73.708474 -407.280238)
			(xy 73.700663 -407.261538) (xy 73.700132 -407.251408) (xy 73.700132 -407.09342) (xy 73.699705 -407.084235)
			(xy 73.693202 -407.067051) (xy 73.687432 -407.059892) (xy 73.665613 -407.034266) (xy 73.627666 -406.978675)
			(xy 73.596634 -406.918948) (xy 73.572963 -406.85594) (xy 73.556993 -406.790555) (xy 73.548951 -406.72373)
			(xy 66.525648 -406.72373) (xy 66.525648 -409.523886) (xy 71.34879 -409.523886) (xy 71.348793 -409.45646)
			(xy 71.356872 -409.389519) (xy 71.372911 -409.324028) (xy 71.396679 -409.26093) (xy 71.427834 -409.201133)
			(xy 71.465926 -409.145497) (xy 71.487792 -409.119832) (xy 71.493599 -409.112694) (xy 71.500108 -409.095498)
			(xy 71.500492 -409.086304) (xy 71.500492 -408.594052) (xy 71.500059 -408.584867) (xy 71.493561 -408.567682)
			(xy 71.487792 -408.560524) (xy 71.46592 -408.534865) (xy 71.427833 -408.479229) (xy 71.396683 -408.419432)
			(xy 71.372919 -408.356335) (xy 71.356885 -408.290845) (xy 71.348809 -408.223906) (xy 71.34881 -408.156482)
			(xy 71.356887 -408.089543) (xy 71.372923 -408.024054) (xy 71.396688 -407.960957) (xy 71.427839 -407.90116)
			(xy 71.465928 -407.845525) (xy 71.487792 -407.81986) (xy 71.493587 -407.812714) (xy 71.500103 -407.795524)
			(xy 71.500492 -407.786332) (xy 71.500492 -407.628852) (xy 71.500946 -407.618741) (xy 71.508698 -407.600063)
			(xy 71.523004 -407.585771) (xy 71.541689 -407.578036) (xy 71.5518 -407.577544) (xy 72.26808 -407.577544)
			(xy 72.278181 -407.5781) (xy 72.296848 -407.585821) (xy 72.311141 -407.600095) (xy 72.318887 -407.618752)
			(xy 72.319388 -407.628852) (xy 72.319388 -407.786332) (xy 72.319785 -407.795521) (xy 72.326308 -407.812705)
			(xy 72.332088 -407.81986) (xy 72.353945 -407.845532) (xy 72.392034 -407.901165) (xy 72.423186 -407.96096)
			(xy 72.446951 -408.024056) (xy 72.462988 -408.089545) (xy 72.471064 -408.156482) (xy 72.471065 -408.223906)
			(xy 72.46299 -408.290844) (xy 72.446955 -408.356332) (xy 72.423191 -408.419429) (xy 72.39204 -408.479225)
			(xy 72.353952 -408.534859) (xy 72.332088 -408.560524) (xy 72.326297 -408.567673) (xy 72.31978 -408.584861)
			(xy 72.319388 -408.594052) (xy 72.319388 -409.086304) (xy 72.319799 -409.095491) (xy 72.326313 -409.112675)
			(xy 72.332088 -409.119832) (xy 72.353917 -409.145526) (xy 72.392008 -409.201156) (xy 72.423161 -409.260948)
			(xy 72.446927 -409.324042) (xy 72.462966 -409.389527) (xy 72.471045 -409.456462) (xy 72.471048 -409.523884)
			(xy 72.462975 -409.59082) (xy 72.446943 -409.656307) (xy 72.423183 -409.719402) (xy 72.392035 -409.779197)
			(xy 72.35395 -409.834831) (xy 72.332088 -409.860496) (xy 72.326309 -409.867654) (xy 72.319784 -409.884835)
			(xy 72.319388 -409.894024) (xy 72.319388 -410.051504) (xy 72.318987 -410.061628) (xy 72.311235 -410.080334)
			(xy 72.296914 -410.094649) (xy 72.278204 -410.102392) (xy 72.26808 -410.102812) (xy 71.5518 -410.102812)
			(xy 71.541693 -410.102315) (xy 71.523017 -410.09458) (xy 71.508723 -410.080286) (xy 71.500986 -410.061611)
			(xy 71.500492 -410.051504) (xy 71.500492 -409.894024) (xy 71.500072 -409.884838) (xy 71.493565 -409.867653)
			(xy 71.487792 -409.860496) (xy 71.465893 -409.83486) (xy 71.427806 -409.779221) (xy 71.396657 -409.719421)
			(xy 71.372895 -409.65632) (xy 71.356863 -409.590827) (xy 71.34879 -409.523886) (xy 66.525648 -409.523886)
			(xy 66.525648 -410.623641) (xy 73.548963 -410.623641) (xy 73.548964 -410.556335) (xy 73.55701 -410.489511)
			(xy 73.572984 -410.424128) (xy 73.596658 -410.361123) (xy 73.627693 -410.301399) (xy 73.665643 -410.245812)
			(xy 73.687432 -410.22016) (xy 73.693232 -410.213017) (xy 73.699744 -410.195825) (xy 73.700132 -410.186632)
			(xy 73.700132 -409.693364) (xy 73.699732 -409.684176) (xy 73.69321 -409.666992) (xy 73.687432 -409.659836)
			(xy 73.665656 -409.634174) (xy 73.627707 -409.578589) (xy 73.596674 -409.518867) (xy 73.573001 -409.455863)
			(xy 73.557027 -409.390482) (xy 73.548982 -409.323661) (xy 73.548981 -409.256357) (xy 73.557024 -409.189535)
			(xy 73.572995 -409.124154) (xy 73.596667 -409.06115) (xy 73.627698 -409.001427) (xy 73.665645 -408.94584)
			(xy 73.687432 -408.920188) (xy 73.69322 -408.913037) (xy 73.699739 -408.895851) (xy 73.700132 -408.88666)
			(xy 73.700132 -408.728672) (xy 73.700499 -408.718512) (xy 73.70831 -408.699753) (xy 73.722724 -408.685429)
			(xy 73.741532 -408.677736) (xy 73.751694 -408.677364) (xy 74.467974 -408.677364) (xy 74.478102 -408.677848)
			(xy 74.496827 -408.685572) (xy 74.511185 -408.69986) (xy 74.519001 -408.718546) (xy 74.519536 -408.728672)
			(xy 74.519536 -408.88666) (xy 74.51998 -408.895843) (xy 74.526472 -408.913027) (xy 74.532236 -408.920188)
			(xy 74.554036 -408.94583) (xy 74.591986 -409.001418) (xy 74.62302 -409.061142) (xy 74.646694 -409.124148)
			(xy 74.662666 -409.189532) (xy 74.67071 -409.256356) (xy 74.670709 -409.323662) (xy 74.662663 -409.390486)
			(xy 74.646688 -409.455869) (xy 74.623013 -409.518874) (xy 74.620439 -409.523827) (xy 75.749085 -409.523827)
			(xy 75.749088 -409.456519) (xy 75.757137 -409.389693) (xy 75.773115 -409.324308) (xy 75.796793 -409.261302)
			(xy 75.827833 -409.201578) (xy 75.865789 -409.145992) (xy 75.88758 -409.12034) (xy 75.893382 -409.113199)
			(xy 75.899894 -409.096005) (xy 75.90028 -409.086812) (xy 75.90028 -408.593544) (xy 75.899853 -408.584358)
			(xy 75.893352 -408.567174) (xy 75.88758 -408.560016) (xy 75.865783 -408.534371) (xy 75.827832 -408.478784)
			(xy 75.796797 -408.41906) (xy 75.773123 -408.356055) (xy 75.757149 -408.290671) (xy 75.749105 -408.223847)
			(xy 75.749106 -408.156541) (xy 75.757151 -408.089717) (xy 75.773126 -408.024334) (xy 75.796802 -407.961329)
			(xy 75.827838 -407.901605) (xy 75.865791 -407.84602) (xy 75.88758 -407.820368) (xy 75.89337 -407.813218)
			(xy 75.899889 -407.796031) (xy 75.90028 -407.78684) (xy 75.90028 -407.628852) (xy 75.900682 -407.618697)
			(xy 75.90849 -407.599948) (xy 75.922892 -407.585627) (xy 75.941685 -407.577925) (xy 75.951842 -407.577544)
			(xy 76.668122 -407.577544) (xy 76.678251 -407.578008) (xy 76.696973 -407.585744) (xy 76.711329 -407.600037)
			(xy 76.719147 -407.618726) (xy 76.719684 -407.628852) (xy 76.719684 -407.78684) (xy 76.720078 -407.796029)
			(xy 76.726603 -407.813213) (xy 76.732384 -407.820368) (xy 76.754163 -407.846027) (xy 76.792111 -407.901613)
			(xy 76.823143 -407.961336) (xy 76.846815 -408.024339) (xy 76.862788 -408.08972) (xy 76.870833 -408.156542)
			(xy 76.870833 -408.223846) (xy 76.86279 -408.290668) (xy 76.846819 -408.356049) (xy 76.823148 -408.419053)
			(xy 76.792117 -408.478777) (xy 76.754171 -408.534364) (xy 76.732384 -408.560016) (xy 76.726596 -408.567167)
			(xy 76.720077 -408.584353) (xy 76.719684 -408.593544) (xy 76.719684 -409.086812) (xy 76.720092 -409.095999)
			(xy 76.726607 -409.113184) (xy 76.732384 -409.12034) (xy 76.754135 -409.146022) (xy 76.792084 -409.201605)
			(xy 76.823117 -409.261324) (xy 76.846791 -409.324325) (xy 76.862766 -409.389703) (xy 76.870812 -409.456522)
			(xy 76.870816 -409.523824) (xy 76.862775 -409.590644) (xy 76.846807 -409.656023) (xy 76.823139 -409.719026)
			(xy 76.792112 -409.778749) (xy 76.754169 -409.834335) (xy 76.732384 -409.859988) (xy 76.726566 -409.867118)
			(xy 76.720065 -409.88432) (xy 76.719684 -409.893516) (xy 76.719684 -410.051504) (xy 76.719281 -410.06166)
			(xy 76.711481 -410.080416) (xy 76.697079 -410.09474) (xy 76.678281 -410.102436) (xy 76.668122 -410.102812)
			(xy 75.951842 -410.102812) (xy 75.941724 -410.10224) (xy 75.923014 -410.094536) (xy 75.908658 -410.080276)
			(xy 75.900828 -410.061618) (xy 75.90028 -410.051504) (xy 75.90028 -409.893516) (xy 75.899867 -409.884329)
			(xy 75.893356 -409.867144) (xy 75.88758 -409.859988) (xy 75.865756 -409.834365) (xy 75.827805 -409.778776)
			(xy 75.796771 -409.719048) (xy 75.773099 -409.65604) (xy 75.757127 -409.590654) (xy 75.749085 -409.523827)
			(xy 74.620439 -409.523827) (xy 74.591977 -409.578598) (xy 74.554025 -409.634184) (xy 74.532236 -409.659836)
			(xy 74.526434 -409.666977) (xy 74.519924 -409.684171) (xy 74.519536 -409.693364) (xy 74.519536 -410.186632)
			(xy 74.519945 -410.195819) (xy 74.526461 -410.213002) (xy 74.532236 -410.22016) (xy 74.554009 -410.245825)
			(xy 74.59196 -410.301409) (xy 74.622995 -410.36113) (xy 74.64667 -410.424133) (xy 74.662644 -410.489514)
			(xy 74.67069 -410.556336) (xy 74.670692 -410.62364) (xy 74.670685 -410.623701) (xy 77.948731 -410.623701)
			(xy 77.948732 -410.556275) (xy 77.95681 -410.489335) (xy 77.972848 -410.423845) (xy 77.996615 -410.360747)
			(xy 78.02777 -410.300951) (xy 78.065862 -410.245317) (xy 78.087728 -410.219652) (xy 78.093531 -410.212512)
			(xy 78.100041 -410.195317) (xy 78.100428 -410.186124) (xy 78.100428 -409.693872) (xy 78.100025 -409.684684)
			(xy 78.093506 -409.6675) (xy 78.087728 -409.660344) (xy 78.065875 -409.63467) (xy 78.027784 -409.579037)
			(xy 77.996631 -409.519242) (xy 77.972865 -409.456147) (xy 77.956828 -409.390658) (xy 77.948751 -409.323721)
			(xy 77.94875 -409.256297) (xy 77.956825 -409.189359) (xy 77.97286 -409.123871) (xy 77.996624 -409.060774)
			(xy 78.027775 -409.000979) (xy 78.065864 -408.945345) (xy 78.087728 -408.91968) (xy 78.093519 -408.912531)
			(xy 78.100036 -408.895343) (xy 78.100428 -408.886152) (xy 78.100428 -408.728672) (xy 78.100794 -408.718544)
			(xy 78.108556 -408.699835) (xy 78.122888 -408.68552) (xy 78.141608 -408.677781) (xy 78.151736 -408.677364)
			(xy 78.868016 -408.677364) (xy 78.878121 -408.677871) (xy 78.896793 -408.685608) (xy 78.911086 -408.699897)
			(xy 78.918826 -408.718567) (xy 78.919324 -408.728672) (xy 78.919324 -408.886152) (xy 78.919752 -408.895337)
			(xy 78.926253 -408.912522) (xy 78.932024 -408.91968) (xy 78.953899 -408.945336) (xy 78.991986 -409.000972)
			(xy 79.023135 -409.06077) (xy 79.046897 -409.123868) (xy 79.062931 -409.189358) (xy 79.071005 -409.256297)
			(xy 79.071004 -409.323721) (xy 79.062928 -409.39066) (xy 79.046892 -409.456149) (xy 79.023127 -409.519246)
			(xy 79.02071 -409.523886) (xy 80.148878 -409.523886) (xy 80.148881 -409.45646) (xy 80.15696 -409.38952)
			(xy 80.172999 -409.324029) (xy 80.196766 -409.260931) (xy 80.227919 -409.201133) (xy 80.266011 -409.145498)
			(xy 80.287876 -409.119832) (xy 80.293681 -409.112693) (xy 80.300191 -409.095498) (xy 80.300576 -409.086304)
			(xy 80.300576 -408.594052) (xy 80.300146 -408.584867) (xy 80.293647 -408.567682) (xy 80.287876 -408.560524)
			(xy 80.266005 -408.534865) (xy 80.227918 -408.479229) (xy 80.196769 -408.419432) (xy 80.173006 -408.356334)
			(xy 80.156972 -408.290844) (xy 80.148897 -408.223906) (xy 80.148898 -408.156482) (xy 80.156974 -408.089544)
			(xy 80.17301 -408.024055) (xy 80.196774 -407.960957) (xy 80.227924 -407.901161) (xy 80.266012 -407.845526)
			(xy 80.287876 -407.81986) (xy 80.293669 -407.812712) (xy 80.300187 -407.795524) (xy 80.300576 -407.786332)
			(xy 80.300576 -407.628852) (xy 80.301045 -407.618743) (xy 80.308794 -407.600069) (xy 80.323095 -407.585776)
			(xy 80.341775 -407.578039) (xy 80.351884 -407.577544) (xy 81.068164 -407.577544) (xy 81.078264 -407.578113)
			(xy 81.09693 -407.585829) (xy 81.111224 -407.600099) (xy 81.11897 -407.618753) (xy 81.119472 -407.628852)
			(xy 81.119472 -407.786332) (xy 81.119873 -407.79552) (xy 81.126394 -407.812704) (xy 81.132172 -407.81986)
			(xy 81.154029 -407.845531) (xy 81.19212 -407.901164) (xy 81.223273 -407.960959) (xy 81.247038 -408.024056)
			(xy 81.263075 -408.089544) (xy 81.271152 -408.156482) (xy 81.271153 -408.223906) (xy 81.263077 -408.290844)
			(xy 81.247042 -408.356333) (xy 81.223277 -408.41943) (xy 81.192126 -408.479225) (xy 81.154036 -408.534859)
			(xy 81.132172 -408.560524) (xy 81.126379 -408.567672) (xy 81.119863 -408.58486) (xy 81.119472 -408.594052)
			(xy 81.119472 -409.086304) (xy 81.119886 -409.095491) (xy 81.126398 -409.112675) (xy 81.132172 -409.119832)
			(xy 81.154002 -409.145526) (xy 81.192093 -409.201156) (xy 81.223247 -409.260948) (xy 81.247014 -409.324041)
			(xy 81.263053 -409.389527) (xy 81.271132 -409.456462) (xy 81.271136 -409.523884) (xy 81.263063 -409.59082)
			(xy 81.247031 -409.656307) (xy 81.223269 -409.719403) (xy 81.192121 -409.779198) (xy 81.154035 -409.834831)
			(xy 81.132172 -409.860496) (xy 81.126391 -409.867652) (xy 81.119868 -409.884834) (xy 81.119472 -409.894024)
			(xy 81.119472 -410.051504) (xy 81.119086 -410.06163) (xy 81.111332 -410.080339) (xy 81.097006 -410.094654)
			(xy 81.078291 -410.102394) (xy 81.068164 -410.102812) (xy 80.351884 -410.102812) (xy 80.341776 -410.102328)
			(xy 80.3231 -410.094587) (xy 80.308806 -410.08029) (xy 80.30107 -410.061612) (xy 80.300576 -410.051504)
			(xy 80.300576 -409.894024) (xy 80.30016 -409.884837) (xy 80.293651 -409.867653) (xy 80.287876 -409.860496)
			(xy 80.265978 -409.83486) (xy 80.227891 -409.77922) (xy 80.196744 -409.71942) (xy 80.172983 -409.656319)
			(xy 80.15695 -409.590827) (xy 80.148878 -409.523886) (xy 79.02071 -409.523886) (xy 78.991976 -409.579043)
			(xy 78.953888 -409.634678) (xy 78.932024 -409.660344) (xy 78.926229 -409.667491) (xy 78.919713 -409.68468)
			(xy 78.919324 -409.693872) (xy 78.919324 -410.186124) (xy 78.919717 -410.195313) (xy 78.926242 -410.212497)
			(xy 78.932024 -410.219652) (xy 78.953871 -410.245331) (xy 78.991959 -410.300964) (xy 79.023109 -410.360758)
			(xy 79.046873 -410.423853) (xy 79.062909 -410.489341) (xy 79.070986 -410.556277) (xy 79.070987 -410.623641)
			(xy 82.349051 -410.623641) (xy 82.349052 -410.556335) (xy 82.357097 -410.489512) (xy 82.373071 -410.424129)
			(xy 82.396745 -410.361124) (xy 82.427779 -410.3014) (xy 82.465728 -410.245812) (xy 82.487516 -410.22016)
			(xy 82.493314 -410.213016) (xy 82.499827 -410.195824) (xy 82.500216 -410.186632) (xy 82.500216 -409.693364)
			(xy 82.49982 -409.684175) (xy 82.493296 -409.666991) (xy 82.487516 -409.659836) (xy 82.465741 -409.634174)
			(xy 82.427793 -409.578588) (xy 82.39676 -409.518866) (xy 82.373088 -409.455863) (xy 82.357115 -409.390482)
			(xy 82.34907 -409.323661) (xy 82.349069 -409.256357) (xy 82.357112 -409.189536) (xy 82.373083 -409.124155)
			(xy 82.396753 -409.061151) (xy 82.427784 -409.001427) (xy 82.46573 -408.94584) (xy 82.487516 -408.920188)
			(xy 82.493302 -408.913035) (xy 82.499822 -408.89585) (xy 82.500216 -408.88666) (xy 82.500216 -408.728672)
			(xy 82.500599 -408.718514) (xy 82.508407 -408.699758) (xy 82.522815 -408.685435) (xy 82.541618 -408.677739)
			(xy 82.551778 -408.677364) (xy 83.268058 -408.677364) (xy 83.278185 -408.677862) (xy 83.29691 -408.68558)
			(xy 83.311268 -408.699864) (xy 83.319085 -408.718548) (xy 83.31962 -408.728672) (xy 83.31962 -408.88666)
			(xy 83.320045 -408.895846) (xy 83.326548 -408.913031) (xy 83.33232 -408.920188) (xy 83.354121 -408.94583)
			(xy 83.392072 -409.001417) (xy 83.423107 -409.061141) (xy 83.446781 -409.124147) (xy 83.462754 -409.189531)
			(xy 83.470798 -409.256356) (xy 83.470797 -409.323662) (xy 83.462751 -409.390487) (xy 83.446775 -409.45587)
			(xy 83.423099 -409.518875) (xy 83.420495 -409.523886) (xy 84.548669 -409.523886) (xy 84.548672 -409.45646)
			(xy 84.556751 -409.38952) (xy 84.572789 -409.324029) (xy 84.596556 -409.260931) (xy 84.627709 -409.201134)
			(xy 84.665799 -409.145498) (xy 84.687664 -409.119832) (xy 84.69348 -409.112701) (xy 84.699981 -409.095499)
			(xy 84.700364 -409.086304) (xy 84.700364 -408.594052) (xy 84.699915 -408.584869) (xy 84.693427 -408.567685)
			(xy 84.687664 -408.560524) (xy 84.665793 -408.534865) (xy 84.627707 -408.479228) (xy 84.596559 -408.419431)
			(xy 84.572797 -408.356334) (xy 84.556763 -408.290844) (xy 84.548688 -408.223906) (xy 84.548689 -408.156482)
			(xy 84.556765 -408.089544) (xy 84.5728 -408.024055) (xy 84.596564 -407.960958) (xy 84.627714 -407.901161)
			(xy 84.665801 -407.845526) (xy 84.687664 -407.81986) (xy 84.693468 -407.81272) (xy 84.699976 -407.795525)
			(xy 84.700364 -407.786332) (xy 84.700364 -407.628852) (xy 84.700845 -407.618745) (xy 84.708592 -407.600072)
			(xy 84.722889 -407.585781) (xy 84.741564 -407.578041) (xy 84.751672 -407.577544) (xy 85.467952 -407.577544)
			(xy 85.478051 -407.578123) (xy 85.496717 -407.585835) (xy 85.511012 -407.600102) (xy 85.518758 -407.618754)
			(xy 85.51926 -407.628852) (xy 85.51926 -407.786332) (xy 85.519664 -407.79552) (xy 85.526183 -407.812703)
			(xy 85.53196 -407.81986) (xy 85.553818 -407.845531) (xy 85.591909 -407.901164) (xy 85.623062 -407.960959)
			(xy 85.646829 -408.024055) (xy 85.662866 -408.089544) (xy 85.670943 -408.156482) (xy 85.670944 -408.223906)
			(xy 85.662868 -408.290844) (xy 85.646832 -408.356333) (xy 85.623067 -408.41943) (xy 85.591915 -408.479226)
			(xy 85.553825 -408.534859) (xy 85.53196 -408.560524) (xy 85.526166 -408.567671) (xy 85.519651 -408.58486)
			(xy 85.51926 -408.594052) (xy 85.51926 -409.086304) (xy 85.519677 -409.09549) (xy 85.526187 -409.112674)
			(xy 85.53196 -409.119832) (xy 85.55379 -409.145526) (xy 85.591882 -409.201155) (xy 85.623037 -409.260947)
			(xy 85.646805 -409.32404) (xy 85.662844 -409.389526) (xy 85.670923 -409.456462) (xy 85.670927 -409.523884)
			(xy 85.662854 -409.59082) (xy 85.646821 -409.656308) (xy 85.623059 -409.719403) (xy 85.59191 -409.779198)
			(xy 85.553823 -409.834831) (xy 85.53196 -409.860496) (xy 85.526178 -409.867651) (xy 85.519655 -409.884834)
			(xy 85.51926 -409.894024) (xy 85.51926 -410.051504) (xy 85.518886 -410.061632) (xy 85.511129 -410.080343)
			(xy 85.496799 -410.094659) (xy 85.47808 -410.102396) (xy 85.467952 -410.102812) (xy 84.751672 -410.102812)
			(xy 84.741563 -410.102338) (xy 84.722886 -410.094594) (xy 84.708593 -410.080293) (xy 84.700857 -410.061613)
			(xy 84.700364 -410.051504) (xy 84.700364 -409.894024) (xy 84.699928 -409.88484) (xy 84.693431 -409.867656)
			(xy 84.687664 -409.860496) (xy 84.665766 -409.834859) (xy 84.627681 -409.77922) (xy 84.596534 -409.719419)
			(xy 84.572773 -409.656319) (xy 84.556741 -409.590827) (xy 84.548669 -409.523886) (xy 83.420495 -409.523886)
			(xy 83.392063 -409.578599) (xy 83.35411 -409.634184) (xy 83.33232 -409.659836) (xy 83.326528 -409.666985)
			(xy 83.32001 -409.684172) (xy 83.31962 -409.693364) (xy 83.31962 -410.186632) (xy 83.32001 -410.195821)
			(xy 83.326537 -410.213006) (xy 83.33232 -410.22016) (xy 83.354093 -410.245825) (xy 83.392045 -410.301408)
			(xy 83.423081 -410.36113) (xy 83.446757 -410.424133) (xy 83.462732 -410.489514) (xy 83.470778 -410.556336)
			(xy 83.47078 -410.62364) (xy 83.470773 -410.623701) (xy 86.748819 -410.623701) (xy 86.74882 -410.556275)
			(xy 86.756898 -410.489336) (xy 86.772936 -410.423846) (xy 86.796702 -410.360748) (xy 86.827855 -410.300952)
			(xy 86.865947 -410.245317) (xy 86.887812 -410.219652) (xy 86.893613 -410.21251) (xy 86.900125 -410.195317)
			(xy 86.900512 -410.186124) (xy 86.900512 -409.693872) (xy 86.900113 -409.684684) (xy 86.893591 -409.6675)
			(xy 86.887812 -409.660344) (xy 86.865959 -409.634669) (xy 86.82787 -409.579036) (xy 86.796718 -409.519242)
			(xy 86.772952 -409.456146) (xy 86.756916 -409.390658) (xy 86.748839 -409.32372) (xy 86.748837 -409.256298)
			(xy 86.756912 -409.18936) (xy 86.772947 -409.123871) (xy 86.79671 -409.060775) (xy 86.82786 -409.000979)
			(xy 86.865948 -408.945345) (xy 86.887812 -408.91968) (xy 86.893601 -408.912529) (xy 86.90012 -408.895343)
			(xy 86.900512 -408.886152) (xy 86.900512 -408.728672) (xy 86.900962 -408.71856) (xy 86.908711 -408.699879)
			(xy 86.923019 -408.685585) (xy 86.941708 -408.677853) (xy 86.95182 -408.677364) (xy 87.6681 -408.677364)
			(xy 87.678204 -408.677884) (xy 87.696876 -408.685615) (xy 87.711169 -408.699901) (xy 87.71891 -408.718568)
			(xy 87.719408 -408.728672) (xy 87.719408 -408.886152) (xy 87.719839 -408.895337) (xy 87.726338 -408.912522)
			(xy 87.732108 -408.91968) (xy 87.753983 -408.945336) (xy 87.792071 -409.000972) (xy 87.823221 -409.060769)
			(xy 87.846984 -409.123867) (xy 87.863019 -409.189358) (xy 87.871093 -409.256297) (xy 87.871092 -409.323721)
			(xy 87.863015 -409.39066) (xy 87.846979 -409.45615) (xy 87.823214 -409.519247) (xy 87.792062 -409.579044)
			(xy 87.753972 -409.634679) (xy 87.732108 -409.660344) (xy 87.726311 -409.667489) (xy 87.719796 -409.68468)
			(xy 87.719408 -409.693872) (xy 87.719408 -410.186124) (xy 87.719805 -410.195313) (xy 87.726328 -410.212497)
			(xy 87.732108 -410.219652) (xy 87.753956 -410.24533) (xy 87.792045 -410.300963) (xy 87.823196 -410.360758)
			(xy 87.84696 -410.423853) (xy 87.862997 -410.48934) (xy 87.871074 -410.556277) (xy 87.871075 -410.623641)
			(xy 91.149138 -410.623641) (xy 91.14914 -410.556335) (xy 91.157185 -410.489512) (xy 91.173158 -410.42413)
			(xy 91.196831 -410.361125) (xy 91.227864 -410.3014) (xy 91.265813 -410.245813) (xy 91.2876 -410.22016)
			(xy 91.293396 -410.213014) (xy 91.299911 -410.195824) (xy 91.3003 -410.186632) (xy 91.3003 -409.693364)
			(xy 91.299907 -409.684175) (xy 91.293382 -409.666991) (xy 91.2876 -409.659836) (xy 91.265825 -409.634174)
			(xy 91.227879 -409.578588) (xy 91.196847 -409.518865) (xy 91.173175 -409.455862) (xy 91.157203 -409.390482)
			(xy 91.149158 -409.323661) (xy 91.149157 -409.256357) (xy 91.157199 -409.189536) (xy 91.17317 -409.124155)
			(xy 91.19684 -409.061151) (xy 91.227869 -409.001428) (xy 91.265814 -408.945841) (xy 91.2876 -408.920188)
			(xy 91.293384 -408.913034) (xy 91.299906 -408.89585) (xy 91.3003 -408.88666) (xy 91.3003 -408.728672)
			(xy 91.300699 -408.718516) (xy 91.308503 -408.699763) (xy 91.322907 -408.685441) (xy 91.341704 -408.677742)
			(xy 91.351862 -408.677364) (xy 92.068142 -408.677364) (xy 92.078274 -408.677793) (xy 92.097001 -408.685539)
			(xy 92.111357 -408.699843) (xy 92.11917 -408.718542) (xy 92.119704 -408.728672) (xy 92.119704 -408.88666)
			(xy 92.120132 -408.895845) (xy 92.126633 -408.91303) (xy 92.132404 -408.920188) (xy 92.154202 -408.945831)
			(xy 92.192148 -409.00142) (xy 92.223178 -409.061145) (xy 92.246848 -409.124151) (xy 92.262819 -409.189534)
			(xy 92.270862 -409.256356) (xy 92.270861 -409.323662) (xy 92.262816 -409.390484) (xy 92.246843 -409.455867)
			(xy 92.223171 -409.518871) (xy 92.220596 -409.523827) (xy 115.349227 -409.523827) (xy 115.349231 -409.456519)
			(xy 115.357278 -409.389695) (xy 115.373254 -409.324311) (xy 115.396929 -409.261305) (xy 115.427964 -409.20158)
			(xy 115.465915 -409.145993) (xy 115.487704 -409.12034) (xy 115.493509 -409.113201) (xy 115.500019 -409.096006)
			(xy 115.500404 -409.086812) (xy 115.500404 -408.593544) (xy 115.499972 -408.584359) (xy 115.493473 -408.567175)
			(xy 115.487704 -408.560016) (xy 115.465909 -408.53437) (xy 115.427963 -408.478782) (xy 115.396932 -408.419057)
			(xy 115.373261 -408.356052) (xy 115.35729 -408.290669) (xy 115.349247 -408.223846) (xy 115.349248 -408.156541)
			(xy 115.357292 -408.089719) (xy 115.373265 -408.024337) (xy 115.396937 -407.961332) (xy 115.427969 -407.901608)
			(xy 115.465917 -407.846021) (xy 115.487704 -407.820368) (xy 115.493497 -407.81322) (xy 115.500014 -407.796032)
			(xy 115.500404 -407.78684) (xy 115.500404 -407.628852) (xy 115.500846 -407.61874) (xy 115.5086 -407.60006)
			(xy 115.52291 -407.585767) (xy 115.541599 -407.578034) (xy 115.551712 -407.577544) (xy 116.268246 -407.577544)
			(xy 116.278376 -407.577989) (xy 116.297099 -407.585733) (xy 116.311454 -407.600031) (xy 116.319271 -407.618724)
			(xy 116.319808 -407.628852) (xy 116.319808 -407.78684) (xy 116.320197 -407.79603) (xy 116.326725 -407.813214)
			(xy 116.332508 -407.820368) (xy 116.354289 -407.846026) (xy 116.392242 -407.90161) (xy 116.423279 -407.961333)
			(xy 116.446954 -408.024336) (xy 116.462929 -408.089718) (xy 116.470975 -408.156541) (xy 116.470976 -408.223847)
			(xy 116.462931 -408.29067) (xy 116.446958 -408.356052) (xy 116.423283 -408.419056) (xy 116.392248 -408.478779)
			(xy 116.354297 -408.534365) (xy 116.332508 -408.560016) (xy 116.326723 -408.56717) (xy 116.320201 -408.584354)
			(xy 116.319808 -408.593544) (xy 116.319808 -409.086812) (xy 116.320211 -409.096) (xy 116.326729 -409.113184)
			(xy 116.332508 -409.12034) (xy 116.354262 -409.146021) (xy 116.392215 -409.201602) (xy 116.423253 -409.261321)
			(xy 116.44693 -409.324322) (xy 116.462907 -409.389701) (xy 116.470955 -409.456521) (xy 116.470958 -409.523825)
			(xy 116.462917 -409.590646) (xy 116.446946 -409.656026) (xy 116.423275 -409.71903) (xy 116.392243 -409.778752)
			(xy 116.354295 -409.834337) (xy 116.332508 -409.859988) (xy 116.326692 -409.86712) (xy 116.320189 -409.884321)
			(xy 116.319808 -409.893516) (xy 116.319808 -410.051504) (xy 116.319318 -410.061612) (xy 116.311581 -410.080289)
			(xy 116.297285 -410.094583) (xy 116.278608 -410.102319) (xy 116.2685 -410.102812) (xy 115.551966 -410.102812)
			(xy 115.541844 -410.102303) (xy 115.523131 -410.094574) (xy 115.508778 -410.080295) (xy 115.500951 -410.061624)
			(xy 115.500404 -410.051504) (xy 115.500404 -409.893516) (xy 115.499985 -409.88433) (xy 115.493477 -409.867145)
			(xy 115.487704 -409.859988) (xy 115.465882 -409.834364) (xy 115.427937 -409.778773) (xy 115.396907 -409.719045)
			(xy 115.373238 -409.656037) (xy 115.357268 -409.590652) (xy 115.349227 -409.523827) (xy 92.220596 -409.523827)
			(xy 92.192139 -409.578596) (xy 92.154191 -409.634183) (xy 92.132404 -409.659836) (xy 92.12661 -409.666983)
			(xy 92.120094 -409.684172) (xy 92.119704 -409.693364) (xy 92.119704 -410.186632) (xy 92.120098 -410.195821)
			(xy 92.126623 -410.213005) (xy 92.132404 -410.22016) (xy 92.154175 -410.245826) (xy 92.192121 -410.301411)
			(xy 92.223153 -410.361133) (xy 92.246825 -410.424136) (xy 92.262797 -410.489516) (xy 92.270842 -410.556336)
			(xy 92.270844 -410.623639) (xy 92.270837 -410.623701) (xy 117.548849 -410.623701) (xy 117.54885 -410.556275)
			(xy 117.556929 -410.489335) (xy 117.572967 -410.423844) (xy 117.596736 -410.360746) (xy 117.627891 -410.30095)
			(xy 117.665985 -410.245316) (xy 117.687852 -410.219652) (xy 117.693658 -410.212514) (xy 117.700166 -410.195318)
			(xy 117.700552 -410.186124) (xy 117.700552 -409.693872) (xy 117.700144 -409.684685) (xy 117.693627 -409.667501)
			(xy 117.687852 -409.660344) (xy 117.665998 -409.63467) (xy 117.627906 -409.579038) (xy 117.596751 -409.519243)
			(xy 117.572984 -409.456148) (xy 117.556946 -409.390659) (xy 117.548869 -409.323721) (xy 117.548868 -409.256297)
			(xy 117.556943 -409.189359) (xy 117.572979 -409.12387) (xy 117.596744 -409.060773) (xy 117.627896 -409.000978)
			(xy 117.665987 -408.945344) (xy 117.687852 -408.91968) (xy 117.693646 -408.912533) (xy 117.700161 -408.895344)
			(xy 117.700552 -408.886152) (xy 117.700552 -408.728672) (xy 117.701061 -408.718567) (xy 117.708799 -408.699898)
			(xy 117.723088 -408.685606) (xy 117.741756 -408.677863) (xy 117.75186 -408.677364) (xy 118.46814 -408.677364)
			(xy 118.478247 -408.677852) (xy 118.496919 -408.685596) (xy 118.511211 -408.699891) (xy 118.518951 -408.718565)
			(xy 118.519448 -408.728672) (xy 118.519448 -408.886152) (xy 118.519893 -408.895335) (xy 118.526384 -408.912519)
			(xy 118.532148 -408.91968) (xy 118.554026 -408.945335) (xy 118.592117 -409.000969) (xy 118.62327 -409.060767)
			(xy 118.647036 -409.123865) (xy 118.663072 -409.189356) (xy 118.671148 -409.256296) (xy 118.671147 -409.323722)
			(xy 118.663069 -409.390662) (xy 118.647031 -409.456152) (xy 118.623263 -409.51925) (xy 118.620848 -409.523886)
			(xy 119.748996 -409.523886) (xy 119.748999 -409.45646) (xy 119.757078 -409.389519) (xy 119.773118 -409.324028)
			(xy 119.796886 -409.26093) (xy 119.828041 -409.201132) (xy 119.866134 -409.145497) (xy 119.888 -409.119832)
			(xy 119.893808 -409.112695) (xy 119.900316 -409.095498) (xy 119.9007 -409.086304) (xy 119.9007 -408.594052)
			(xy 119.900265 -408.584867) (xy 119.893769 -408.567683) (xy 119.888 -408.560524) (xy 119.866128 -408.534865)
			(xy 119.82804 -408.47923) (xy 119.796889 -408.419433) (xy 119.773126 -408.356335) (xy 119.757091 -408.290845)
			(xy 119.749015 -408.223906) (xy 119.749016 -408.156482) (xy 119.757093 -408.089543) (xy 119.773129 -408.024054)
			(xy 119.796894 -407.960956) (xy 119.828046 -407.90116) (xy 119.866136 -407.845525) (xy 119.888 -407.81986)
			(xy 119.893796 -407.812714) (xy 119.900311 -407.795524) (xy 119.9007 -407.786332) (xy 119.9007 -407.628852)
			(xy 119.901146 -407.61874) (xy 119.908899 -407.600061) (xy 119.923208 -407.585768) (xy 119.941896 -407.578035)
			(xy 119.952008 -407.577544) (xy 120.668288 -407.577544) (xy 120.678389 -407.578094) (xy 120.697056 -407.585817)
			(xy 120.71135 -407.600093) (xy 120.719095 -407.618752) (xy 120.719596 -407.628852) (xy 120.719596 -407.786332)
			(xy 120.719991 -407.795521) (xy 120.726515 -407.812705) (xy 120.732296 -407.81986) (xy 120.754152 -407.845532)
			(xy 120.792241 -407.901165) (xy 120.823393 -407.96096) (xy 120.847158 -408.024056) (xy 120.863194 -408.089545)
			(xy 120.87127 -408.156482) (xy 120.871271 -408.223906) (xy 120.863196 -408.290843) (xy 120.847161 -408.356332)
			(xy 120.823398 -408.419429) (xy 120.792248 -408.479225) (xy 120.75416 -408.534859) (xy 120.732296 -408.560524)
			(xy 120.726506 -408.567674) (xy 120.719988 -408.584861) (xy 120.719596 -408.594052) (xy 120.719596 -409.086304)
			(xy 120.720005 -409.095491) (xy 120.72652 -409.112675) (xy 120.732296 -409.119832) (xy 120.754125 -409.145526)
			(xy 120.792215 -409.201157) (xy 120.823367 -409.260949) (xy 120.847134 -409.324042) (xy 120.863172 -409.389527)
			(xy 120.871251 -409.456463) (xy 120.871254 -409.523883) (xy 120.863181 -409.590819) (xy 120.84715 -409.656306)
			(xy 120.823389 -409.719402) (xy 120.792243 -409.779197) (xy 120.754158 -409.834831) (xy 120.732296 -409.860496)
			(xy 120.726518 -409.867654) (xy 120.719992 -409.884835) (xy 120.719596 -409.894024) (xy 120.719596 -410.051504)
			(xy 120.719187 -410.061627) (xy 120.711437 -410.080332) (xy 120.697118 -410.094646) (xy 120.678411 -410.10239)
			(xy 120.668288 -410.102812) (xy 119.952008 -410.102812) (xy 119.941888 -410.102378) (xy 119.923186 -410.094634)
			(xy 119.908872 -410.080324) (xy 119.901125 -410.061624) (xy 119.9007 -410.051504) (xy 119.9007 -409.894024)
			(xy 119.900278 -409.884838) (xy 119.893773 -409.867654) (xy 119.888 -409.860496) (xy 119.866101 -409.83486)
			(xy 119.828013 -409.779221) (xy 119.796864 -409.719421) (xy 119.773102 -409.65632) (xy 119.757069 -409.590828)
			(xy 119.748996 -409.523886) (xy 118.620848 -409.523886) (xy 118.592108 -409.579046) (xy 118.554015 -409.63468)
			(xy 118.532148 -409.660344) (xy 118.526344 -409.667484) (xy 118.519835 -409.684679) (xy 118.519448 -409.693872)
			(xy 118.519448 -410.186124) (xy 118.519858 -410.195311) (xy 118.526373 -410.212495) (xy 118.532148 -410.219652)
			(xy 118.553998 -410.245329) (xy 118.592091 -410.300961) (xy 118.623245 -410.360755) (xy 118.647012 -410.42385)
			(xy 118.663051 -410.489338) (xy 118.671128 -410.556276) (xy 118.67113 -410.623641) (xy 121.949169 -410.623641)
			(xy 121.94917 -410.556335) (xy 121.957216 -410.489511) (xy 121.97319 -410.424128) (xy 121.996865 -410.361123)
			(xy 122.0279 -410.301399) (xy 122.065851 -410.245812) (xy 122.08764 -410.22016) (xy 122.093441 -410.213018)
			(xy 122.099952 -410.195825) (xy 122.10034 -410.186632) (xy 122.10034 -409.693364) (xy 122.099938 -409.684176)
			(xy 122.093418 -409.666992) (xy 122.08764 -409.659836) (xy 122.065864 -409.634174) (xy 122.027915 -409.578589)
			(xy 121.996881 -409.518867) (xy 121.973208 -409.455864) (xy 121.957234 -409.390483) (xy 121.949189 -409.323661)
			(xy 121.949188 -409.256357) (xy 121.957231 -409.189535) (xy 121.973202 -409.124154) (xy 121.996874 -409.06115)
			(xy 122.027906 -409.001427) (xy 122.065853 -408.94584) (xy 122.08764 -408.920188) (xy 122.093429 -408.913038)
			(xy 122.099947 -408.895851) (xy 122.10034 -408.88666) (xy 122.10034 -408.728672) (xy 122.100694 -408.718543)
			(xy 122.108459 -408.699831) (xy 122.122795 -408.685516) (xy 122.141518 -408.677779) (xy 122.151648 -408.677364)
			(xy 122.868182 -408.677364) (xy 122.878311 -408.677842) (xy 122.897036 -408.685568) (xy 122.911394 -408.699858)
			(xy 122.919209 -408.718546) (xy 122.919744 -408.728672) (xy 122.919744 -408.88666) (xy 122.920186 -408.895844)
			(xy 122.926679 -408.913028) (xy 122.932444 -408.920188) (xy 122.954244 -408.94583) (xy 122.992193 -409.001418)
			(xy 123.023227 -409.061143) (xy 123.0469 -409.124148) (xy 123.062873 -409.189532) (xy 123.070916 -409.256356)
			(xy 123.070915 -409.323662) (xy 123.062869 -409.390486) (xy 123.046895 -409.455869) (xy 123.02322 -409.518874)
			(xy 123.020646 -409.523827) (xy 124.149291 -409.523827) (xy 124.149295 -409.456519) (xy 124.157343 -409.389693)
			(xy 124.173321 -409.324308) (xy 124.197 -409.261302) (xy 124.22804 -409.201577) (xy 124.265997 -409.145992)
			(xy 124.287788 -409.12034) (xy 124.293591 -409.113199) (xy 124.300102 -409.096005) (xy 124.300488 -409.086812)
			(xy 124.300488 -408.593544) (xy 124.300059 -408.584359) (xy 124.293559 -408.567174) (xy 124.287788 -408.560016)
			(xy 124.265991 -408.534371) (xy 124.228039 -408.478785) (xy 124.197004 -408.419061) (xy 124.173329 -408.356055)
			(xy 124.157355 -408.290671) (xy 124.149311 -408.223847) (xy 124.149312 -408.156541) (xy 124.157357 -408.089717)
			(xy 124.173333 -408.024333) (xy 124.197008 -407.961328) (xy 124.228045 -407.901605) (xy 124.265998 -407.84602)
			(xy 124.287788 -407.820368) (xy 124.293579 -407.813219) (xy 124.300097 -407.796031) (xy 124.300488 -407.78684)
			(xy 124.300488 -407.628852) (xy 124.300946 -407.618742) (xy 124.308697 -407.600065) (xy 124.323002 -407.585772)
			(xy 124.341685 -407.578037) (xy 124.351796 -407.577544) (xy 125.06833 -407.577544) (xy 125.078459 -407.578002)
			(xy 125.097182 -407.58574) (xy 125.111537 -407.600035) (xy 125.119355 -407.618725) (xy 125.119892 -407.628852)
			(xy 125.119892 -407.78684) (xy 125.120285 -407.796029) (xy 125.126811 -407.813213) (xy 125.132592 -407.820368)
			(xy 125.154371 -407.846027) (xy 125.192318 -407.901613) (xy 125.22335 -407.961336) (xy 125.247022 -408.02434)
			(xy 125.262994 -408.089721) (xy 125.271039 -408.156542) (xy 125.271039 -408.223846) (xy 125.262997 -408.290667)
			(xy 125.247025 -408.356049) (xy 125.223355 -408.419053) (xy 125.192324 -408.478776) (xy 125.154378 -408.534363)
			(xy 125.132592 -408.560016) (xy 125.126805 -408.567168) (xy 125.120285 -408.584353) (xy 125.119892 -408.593544)
			(xy 125.119892 -409.086812) (xy 125.120298 -409.096) (xy 125.126815 -409.113184) (xy 125.132592 -409.12034)
			(xy 125.154343 -409.146022) (xy 125.192291 -409.201605) (xy 125.223324 -409.261324) (xy 125.246998 -409.324325)
			(xy 125.262972 -409.389703) (xy 125.271019 -409.456522) (xy 125.271022 -409.523824) (xy 125.262982 -409.590643)
			(xy 125.247014 -409.656023) (xy 125.223347 -409.719026) (xy 125.192319 -409.778749) (xy 125.154377 -409.834336)
			(xy 125.132592 -409.859988) (xy 125.126775 -409.867118) (xy 125.120273 -409.88432) (xy 125.119892 -409.893516)
			(xy 125.119892 -410.051504) (xy 125.119487 -410.061628) (xy 125.111736 -410.080333) (xy 125.097416 -410.094647)
			(xy 125.078708 -410.102391) (xy 125.068584 -410.102812) (xy 124.35205 -410.102812) (xy 124.341933 -410.102234)
			(xy 124.323223 -410.094532) (xy 124.308867 -410.080274) (xy 124.301036 -410.061618) (xy 124.300488 -410.051504)
			(xy 124.300488 -409.893516) (xy 124.300073 -409.884329) (xy 124.293563 -409.867145) (xy 124.287788 -409.859988)
			(xy 124.265963 -409.834366) (xy 124.228013 -409.778776) (xy 124.196978 -409.719049) (xy 124.173305 -409.65604)
			(xy 124.157333 -409.590654) (xy 124.149291 -409.523827) (xy 123.020646 -409.523827) (xy 122.992184 -409.578598)
			(xy 122.954233 -409.634184) (xy 122.932444 -409.659836) (xy 122.926643 -409.666978) (xy 122.920132 -409.684171)
			(xy 122.919744 -409.693364) (xy 122.919744 -410.186632) (xy 122.920151 -410.195819) (xy 122.926668 -410.213003)
			(xy 122.932444 -410.22016) (xy 122.954216 -410.245825) (xy 122.992167 -410.301409) (xy 123.023202 -410.361131)
			(xy 123.046876 -410.424134) (xy 123.062851 -410.489514) (xy 123.070896 -410.556336) (xy 123.070898 -410.62364)
			(xy 123.070891 -410.623701) (xy 126.348937 -410.623701) (xy 126.348938 -410.556275) (xy 126.357016 -410.489335)
			(xy 126.373055 -410.423845) (xy 126.396822 -410.360747) (xy 126.427977 -410.300951) (xy 126.46607 -410.245317)
			(xy 126.487936 -410.219652) (xy 126.49374 -410.212512) (xy 126.500249 -410.195317) (xy 126.500636 -410.186124)
			(xy 126.500636 -409.693872) (xy 126.500231 -409.684684) (xy 126.493713 -409.667501) (xy 126.487936 -409.660344)
			(xy 126.466083 -409.63467) (xy 126.427991 -409.579037) (xy 126.396838 -409.519243) (xy 126.373071 -409.456147)
			(xy 126.357034 -409.390659) (xy 126.348957 -409.323721) (xy 126.348956 -409.256297) (xy 126.357031 -409.189359)
			(xy 126.373066 -409.12387) (xy 126.396831 -409.060774) (xy 126.427982 -409.000978) (xy 126.466071 -408.945345)
			(xy 126.487936 -408.91968) (xy 126.493728 -408.912532) (xy 126.500245 -408.895343) (xy 126.500636 -408.886152)
			(xy 126.500636 -408.728672) (xy 126.500994 -408.718543) (xy 126.508758 -408.699832) (xy 126.523093 -408.685517)
			(xy 126.541815 -408.67778) (xy 126.551944 -408.677364) (xy 127.268224 -408.677364) (xy 127.27833 -408.677864)
			(xy 127.297002 -408.685603) (xy 127.311294 -408.699895) (xy 127.319035 -408.718566) (xy 127.319532 -408.728672)
			(xy 127.319532 -408.886152) (xy 127.31998 -408.895335) (xy 127.326469 -408.912519) (xy 127.332232 -408.91968)
			(xy 127.354107 -408.945336) (xy 127.392193 -409.000973) (xy 127.423341 -409.06077) (xy 127.447103 -409.123868)
			(xy 127.463137 -409.189358) (xy 127.471211 -409.256297) (xy 127.47121 -409.323721) (xy 127.463134 -409.39066)
			(xy 127.447098 -409.456149) (xy 127.423334 -409.519246) (xy 127.420948 -409.523827) (xy 128.549082 -409.523827)
			(xy 128.549085 -409.456519) (xy 128.557133 -409.389693) (xy 128.573111 -409.324308) (xy 128.59679 -409.261302)
			(xy 128.627829 -409.201578) (xy 128.665785 -409.145991) (xy 128.687576 -409.12034) (xy 128.693378 -409.113198)
			(xy 128.69989 -409.096005) (xy 128.700276 -409.086812) (xy 128.700276 -408.593544) (xy 128.69985 -408.584358)
			(xy 128.693348 -408.567174) (xy 128.687576 -408.560016) (xy 128.665779 -408.534371) (xy 128.627828 -408.478784)
			(xy 128.596793 -408.41906) (xy 128.573119 -408.356055) (xy 128.557146 -408.290671) (xy 128.549102 -408.223847)
			(xy 128.549103 -408.156541) (xy 128.557148 -408.089717) (xy 128.573123 -408.024334) (xy 128.596798 -407.961329)
			(xy 128.627835 -407.901605) (xy 128.665787 -407.84602) (xy 128.687576 -407.820368) (xy 128.693366 -407.813218)
			(xy 128.699885 -407.796031) (xy 128.700276 -407.78684) (xy 128.700276 -407.628852) (xy 128.700745 -407.618743)
			(xy 128.708494 -407.600069) (xy 128.722795 -407.585776) (xy 128.741475 -407.578039) (xy 128.751584 -407.577544)
			(xy 129.468118 -407.577544) (xy 129.478246 -407.578012) (xy 129.496969 -407.585746) (xy 129.511325 -407.600038)
			(xy 129.519143 -407.618726) (xy 129.51968 -407.628852) (xy 129.51968 -407.78684) (xy 129.520075 -407.796029)
			(xy 129.5266 -407.813213) (xy 129.53238 -407.820368) (xy 129.554159 -407.846027) (xy 129.592107 -407.901613)
			(xy 129.62314 -407.961336) (xy 129.646812 -408.024339) (xy 129.662785 -408.08972) (xy 129.67083 -408.156542)
			(xy 129.67083 -408.223846) (xy 129.662787 -408.290668) (xy 129.646816 -408.356049) (xy 129.623145 -408.419053)
			(xy 129.592113 -408.478777) (xy 129.554167 -408.534364) (xy 129.53238 -408.560016) (xy 129.526592 -408.567167)
			(xy 129.520073 -408.584353) (xy 129.51968 -408.593544) (xy 129.51968 -409.086812) (xy 129.520089 -409.095999)
			(xy 129.526604 -409.113183) (xy 129.53238 -409.12034) (xy 129.554131 -409.146022) (xy 129.59208 -409.201604)
			(xy 129.623114 -409.261324) (xy 129.646788 -409.324325) (xy 129.662763 -409.389703) (xy 129.670809 -409.456522)
			(xy 129.670813 -409.523824) (xy 129.662772 -409.590644) (xy 129.646804 -409.656024) (xy 129.623136 -409.719026)
			(xy 129.592108 -409.778749) (xy 129.554165 -409.834335) (xy 129.53238 -409.859988) (xy 129.526561 -409.867117)
			(xy 129.52006 -409.88432) (xy 129.51968 -409.893516) (xy 129.51968 -410.051504) (xy 129.519287 -410.061629)
			(xy 129.511534 -410.080337) (xy 129.49721 -410.094651) (xy 129.478497 -410.102393) (xy 129.468372 -410.102812)
			(xy 128.751838 -410.102812) (xy 128.74172 -410.102244) (xy 128.72301 -410.094538) (xy 128.708654 -410.080277)
			(xy 128.700824 -410.061618) (xy 128.700276 -410.051504) (xy 128.700276 -409.893516) (xy 128.699864 -409.884329)
			(xy 128.693352 -409.867144) (xy 128.687576 -409.859988) (xy 128.665751 -409.834366) (xy 128.627801 -409.778776)
			(xy 128.596768 -409.719048) (xy 128.573095 -409.65604) (xy 128.557124 -409.590654) (xy 128.549082 -409.523827)
			(xy 127.420948 -409.523827) (xy 127.392184 -409.579043) (xy 127.354096 -409.634678) (xy 127.332232 -409.660344)
			(xy 127.326426 -409.667482) (xy 127.319919 -409.684678) (xy 127.319532 -409.693872) (xy 127.319532 -410.186124)
			(xy 127.319946 -410.19531) (xy 127.326459 -410.212494) (xy 127.332232 -410.219652) (xy 127.354079 -410.245331)
			(xy 127.392166 -410.300964) (xy 127.423316 -410.360759) (xy 127.44708 -410.423854) (xy 127.463115 -410.489341)
			(xy 127.471192 -410.556277) (xy 127.471193 -410.623641) (xy 130.749257 -410.623641) (xy 130.749258 -410.556335)
			(xy 130.757303 -410.489512) (xy 130.773278 -410.424129) (xy 130.796952 -410.361123) (xy 130.827986 -410.301399)
			(xy 130.865936 -410.245812) (xy 130.887724 -410.22016) (xy 130.893523 -410.213017) (xy 130.900035 -410.195825)
			(xy 130.900424 -410.186632) (xy 130.900424 -409.693364) (xy 130.900026 -409.684176) (xy 130.893503 -409.666992)
			(xy 130.887724 -409.659836) (xy 130.865948 -409.634174) (xy 130.828 -409.578589) (xy 130.796967 -409.518866)
			(xy 130.773294 -409.455863) (xy 130.757321 -409.390482) (xy 130.749276 -409.323661) (xy 130.749275 -409.256357)
			(xy 130.757318 -409.189536) (xy 130.773289 -409.124154) (xy 130.79696 -409.06115) (xy 130.827991 -409.001427)
			(xy 130.865937 -408.94584) (xy 130.887724 -408.920188) (xy 130.893511 -408.913036) (xy 130.900031 -408.895851)
			(xy 130.900424 -408.88666) (xy 130.900424 -408.728672) (xy 130.900799 -408.718513) (xy 130.908608 -408.699755)
			(xy 130.92302 -408.685432) (xy 130.941825 -408.677738) (xy 130.951986 -408.677364) (xy 131.668266 -408.677364)
			(xy 131.678393 -408.677855) (xy 131.697118 -408.685576) (xy 131.711477 -408.699862) (xy 131.719293 -408.718547)
			(xy 131.719828 -408.728672) (xy 131.719828 -408.88666) (xy 131.720251 -408.895846) (xy 131.726755 -408.913031)
			(xy 131.732528 -408.920188) (xy 131.754328 -408.94583) (xy 131.792279 -409.001417) (xy 131.823314 -409.061142)
			(xy 131.846987 -409.124148) (xy 131.86296 -409.189532) (xy 131.871004 -409.256356) (xy 131.871003 -409.323662)
			(xy 131.862957 -409.390486) (xy 131.846982 -409.45587) (xy 131.823306 -409.518875) (xy 131.79227 -409.578598)
			(xy 131.754317 -409.634184) (xy 131.732528 -409.659836) (xy 131.726725 -409.666976) (xy 131.720216 -409.684171)
			(xy 131.719828 -409.693364) (xy 131.719828 -410.186632) (xy 131.720217 -410.195822) (xy 131.726745 -410.213006)
			(xy 131.732528 -410.22016) (xy 131.754301 -410.245825) (xy 131.792252 -410.301409) (xy 131.823288 -410.36113)
			(xy 131.846963 -410.424133) (xy 131.862938 -410.489514) (xy 131.870984 -410.556336) (xy 131.870986 -410.62364)
			(xy 131.862943 -410.690462) (xy 131.84697 -410.755844) (xy 131.823298 -410.818848) (xy 131.792265 -410.878571)
			(xy 131.754316 -410.934156) (xy 131.732528 -410.959808) (xy 131.726737 -410.966957) (xy 131.720221 -410.984145)
			(xy 131.719828 -410.993336) (xy 131.719828 -411.151324) (xy 131.719399 -411.161476) (xy 131.7116 -411.180224)
			(xy 131.697207 -411.194545) (xy 131.67842 -411.202249) (xy 131.668266 -411.202632) (xy 130.951986 -411.202632)
			(xy 130.941855 -411.202184) (xy 130.923128 -411.194446) (xy 130.908772 -411.180148) (xy 130.900958 -411.161453)
			(xy 130.900424 -411.151324) (xy 130.900424 -410.993336) (xy 130.899991 -410.984151) (xy 130.893493 -410.966967)
			(xy 130.887724 -410.959808) (xy 130.865921 -410.934169) (xy 130.827974 -410.87858) (xy 130.796942 -410.818855)
			(xy 130.773271 -410.755848) (xy 130.757299 -410.690465) (xy 130.749257 -410.623641) (xy 127.471193 -410.623641)
			(xy 127.471193 -410.623699) (xy 127.463119 -410.690635) (xy 127.447087 -410.756123) (xy 127.423326 -410.819219)
			(xy 127.392179 -410.879015) (xy 127.354094 -410.93465) (xy 127.332232 -410.960316) (xy 127.326438 -410.967463)
			(xy 127.319924 -410.984652) (xy 127.319532 -410.993844) (xy 127.319532 -411.151324) (xy 127.319035 -411.16143)
			(xy 127.311296 -411.180103) (xy 127.297003 -411.194396) (xy 127.27833 -411.202135) (xy 127.268224 -411.202632)
			(xy 126.551944 -411.202632) (xy 126.541828 -411.202149) (xy 126.523132 -411.194421) (xy 126.508817 -411.180125)
			(xy 126.501065 -411.161439) (xy 126.500636 -411.151324) (xy 126.500636 -410.993844) (xy 126.500196 -410.98466)
			(xy 126.493702 -410.967476) (xy 126.487936 -410.960316) (xy 126.466055 -410.934664) (xy 126.427964 -410.879029)
			(xy 126.396812 -410.819231) (xy 126.373048 -410.756132) (xy 126.357012 -410.690641) (xy 126.348937 -410.623701)
			(xy 123.070891 -410.623701) (xy 123.062855 -410.690462) (xy 123.046883 -410.755843) (xy 123.023211 -410.818847)
			(xy 122.992179 -410.87857) (xy 122.954231 -410.934156) (xy 122.932444 -410.959808) (xy 122.926655 -410.966958)
			(xy 122.920137 -410.984145) (xy 122.919744 -410.993336) (xy 122.919744 -411.151324) (xy 122.919236 -411.161429)
			(xy 122.911498 -411.180099) (xy 122.897209 -411.194392) (xy 122.878541 -411.202133) (xy 122.868436 -411.202632)
			(xy 122.151902 -411.202632) (xy 122.141772 -411.202171) (xy 122.123046 -411.194439) (xy 122.108688 -411.180144)
			(xy 122.100874 -411.161452) (xy 122.10034 -411.151324) (xy 122.10034 -410.993336) (xy 122.099903 -410.984152)
			(xy 122.093407 -410.966968) (xy 122.08764 -410.959808) (xy 122.065836 -410.934169) (xy 122.027888 -410.878581)
			(xy 121.996855 -410.818855) (xy 121.973183 -410.755849) (xy 121.957211 -410.690465) (xy 121.949169 -410.623641)
			(xy 118.67113 -410.623641) (xy 118.67113 -410.6237) (xy 118.663055 -410.690638) (xy 118.647019 -410.756127)
			(xy 118.623255 -410.819223) (xy 118.592103 -410.879018) (xy 118.554013 -410.934652) (xy 118.532148 -410.960316)
			(xy 118.526356 -410.967464) (xy 118.51984 -410.984653) (xy 118.519448 -410.993844) (xy 118.519448 -411.151324)
			(xy 118.518936 -411.161428) (xy 118.511199 -411.180098) (xy 118.496911 -411.19439) (xy 118.478244 -411.202133)
			(xy 118.46814 -411.202632) (xy 117.75186 -411.202632) (xy 117.741753 -411.202148) (xy 117.72308 -411.194404)
			(xy 117.708787 -411.180107) (xy 117.701048 -411.161431) (xy 117.700552 -411.151324) (xy 117.700552 -410.993844)
			(xy 117.700109 -410.984661) (xy 117.693617 -410.967477) (xy 117.687852 -410.960316) (xy 117.66597 -410.934665)
			(xy 117.627879 -410.879029) (xy 117.596726 -410.819232) (xy 117.57296 -410.756133) (xy 117.556924 -410.690642)
			(xy 117.548849 -410.623701) (xy 92.270837 -410.623701) (xy 92.262802 -410.69046) (xy 92.246832 -410.755841)
			(xy 92.223163 -410.818845) (xy 92.192134 -410.878568) (xy 92.154189 -410.934155) (xy 92.132404 -410.959808)
			(xy 92.126622 -410.966964) (xy 92.120098 -410.984146) (xy 92.119704 -410.993336) (xy 92.119704 -411.151324)
			(xy 92.119298 -411.161479) (xy 92.111495 -411.180231) (xy 92.097094 -411.194554) (xy 92.078299 -411.202253)
			(xy 92.068142 -411.202632) (xy 91.351862 -411.202632) (xy 91.341729 -411.202204) (xy 91.323002 -411.194458)
			(xy 91.308646 -411.180154) (xy 91.300833 -411.161455) (xy 91.3003 -411.151324) (xy 91.3003 -410.993336)
			(xy 91.299873 -410.984151) (xy 91.293371 -410.966966) (xy 91.2876 -410.959808) (xy 91.265798 -410.934168)
			(xy 91.227852 -410.878579) (xy 91.196822 -410.818853) (xy 91.173151 -410.755847) (xy 91.157181 -410.690464)
			(xy 91.149138 -410.623641) (xy 87.871075 -410.623641) (xy 87.871075 -410.623699) (xy 87.863001 -410.690636)
			(xy 87.846967 -410.756124) (xy 87.823205 -410.81922) (xy 87.792057 -410.879016) (xy 87.753971 -410.934651)
			(xy 87.732108 -410.960316) (xy 87.726323 -410.96747) (xy 87.719801 -410.984654) (xy 87.719408 -410.993844)
			(xy 87.719408 -411.151324) (xy 87.718935 -411.161433) (xy 87.711191 -411.180111) (xy 87.69689 -411.194404)
			(xy 87.67821 -411.20214) (xy 87.6681 -411.202632) (xy 86.95182 -411.202632) (xy 86.941716 -411.202099)
			(xy 86.923045 -411.194374) (xy 86.90875 -411.180092) (xy 86.901009 -411.161427) (xy 86.900512 -411.151324)
			(xy 86.900512 -410.993844) (xy 86.900078 -410.984659) (xy 86.893581 -410.967475) (xy 86.887812 -410.960316)
			(xy 86.865932 -410.934664) (xy 86.827843 -410.879028) (xy 86.796692 -410.81923) (xy 86.772928 -410.756131)
			(xy 86.756894 -410.69064) (xy 86.748819 -410.623701) (xy 83.470773 -410.623701) (xy 83.462736 -410.690462)
			(xy 83.446764 -410.755844) (xy 83.423091 -410.818848) (xy 83.392058 -410.878571) (xy 83.354108 -410.934156)
			(xy 83.33232 -410.959808) (xy 83.32654 -410.966965) (xy 83.320015 -410.984146) (xy 83.31962 -410.993336)
			(xy 83.31962 -411.151324) (xy 83.319199 -411.161477) (xy 83.311399 -411.180226) (xy 83.297003 -411.194548)
			(xy 83.278213 -411.202251) (xy 83.268058 -411.202632) (xy 82.551778 -411.202632) (xy 82.541646 -411.202191)
			(xy 82.522919 -411.194451) (xy 82.508563 -411.18015) (xy 82.500749 -411.161454) (xy 82.500216 -411.151324)
			(xy 82.500216 -410.993336) (xy 82.499785 -410.984151) (xy 82.493285 -410.966967) (xy 82.487516 -410.959808)
			(xy 82.465713 -410.934169) (xy 82.427766 -410.87858) (xy 82.396735 -410.818854) (xy 82.373064 -410.755848)
			(xy 82.357093 -410.690465) (xy 82.349051 -410.623641) (xy 79.070987 -410.623641) (xy 79.070987 -410.623699)
			(xy 79.062913 -410.690636) (xy 79.04688 -410.756124) (xy 79.023119 -410.81922) (xy 78.991971 -410.879016)
			(xy 78.953886 -410.93465) (xy 78.932024 -410.960316) (xy 78.926241 -410.967471) (xy 78.919717 -410.984654)
			(xy 78.919324 -410.993844) (xy 78.919324 -411.151324) (xy 78.918835 -411.161431) (xy 78.911094 -411.180106)
			(xy 78.896799 -411.194399) (xy 78.878123 -411.202137) (xy 78.868016 -411.202632) (xy 78.151736 -411.202632)
			(xy 78.14162 -411.202155) (xy 78.122923 -411.194425) (xy 78.108609 -411.180127) (xy 78.100857 -411.16144)
			(xy 78.100428 -411.151324) (xy 78.100428 -410.993844) (xy 78.09999 -410.98466) (xy 78.093495 -410.967476)
			(xy 78.087728 -410.960316) (xy 78.065847 -410.934664) (xy 78.027757 -410.879028) (xy 77.996606 -410.819231)
			(xy 77.972841 -410.756132) (xy 77.956806 -410.690641) (xy 77.948731 -410.623701) (xy 74.670685 -410.623701)
			(xy 74.662649 -410.690462) (xy 74.646677 -410.755844) (xy 74.623005 -410.818848) (xy 74.591972 -410.87857)
			(xy 74.554023 -410.934156) (xy 74.532236 -410.959808) (xy 74.526446 -410.966957) (xy 74.519929 -410.984145)
			(xy 74.519536 -410.993336) (xy 74.519536 -411.151324) (xy 74.519099 -411.161475) (xy 74.511302 -411.180221)
			(xy 74.496911 -411.194542) (xy 74.478127 -411.202248) (xy 74.467974 -411.202632) (xy 73.751694 -411.202632)
			(xy 73.741563 -411.202177) (xy 73.722837 -411.194442) (xy 73.70848 -411.180146) (xy 73.700666 -411.161452)
			(xy 73.700132 -411.151324) (xy 73.700132 -410.993336) (xy 73.699697 -410.984152) (xy 73.6932 -410.966967)
			(xy 73.687432 -410.959808) (xy 73.665629 -410.934169) (xy 73.627681 -410.87858) (xy 73.596649 -410.818855)
			(xy 73.572977 -410.755849) (xy 73.557005 -410.690465) (xy 73.548963 -410.623641) (xy 66.525648 -410.623641)
			(xy 66.525648 -417.289488) (xy 66.525648 -417.371276) (xy 141.02334 -417.371276) (xy 141.02334 -394.305282)
			(xy 141.023796 -394.293166) (xy 141.031289 -394.270122) (xy 141.045535 -394.25052) (xy 141.06514 -394.23628)
			(xy 141.088186 -394.228793) (xy 141.100302 -394.22832) (xy 154.426158 -394.22832) (xy 154.57678 -394.378688)
			(xy 154.57678 -397.823825) (xy 159.349135 -397.823825) (xy 159.349138 -397.756518) (xy 159.357186 -397.689693)
			(xy 159.373162 -397.624309) (xy 159.396838 -397.561303) (xy 159.427875 -397.501578) (xy 159.465827 -397.44599)
			(xy 159.487616 -397.420338) (xy 159.493423 -397.4132) (xy 159.499931 -397.396004) (xy 159.500316 -397.38681)
			(xy 159.500316 -396.893542) (xy 159.499882 -396.884357) (xy 159.493384 -396.867173) (xy 159.487616 -396.860014)
			(xy 159.465819 -396.83437) (xy 159.427872 -396.778782) (xy 159.396841 -396.719057) (xy 159.373169 -396.656051)
			(xy 159.357198 -396.590668) (xy 159.349155 -396.523845) (xy 159.349156 -396.45654) (xy 159.3572 -396.389717)
			(xy 159.373174 -396.324334) (xy 159.396847 -396.26133) (xy 159.42788 -396.201606) (xy 159.465828 -396.146018)
			(xy 159.487616 -396.120366) (xy 159.493411 -396.11322) (xy 159.499926 -396.09603) (xy 159.500316 -396.086838)
			(xy 159.500316 -395.92885) (xy 159.500804 -395.918684) (xy 159.508569 -395.899895) (xy 159.522934 -395.885509)
			(xy 159.541713 -395.877718) (xy 159.551878 -395.877288) (xy 160.268158 -395.877288) (xy 160.278333 -395.877699)
			(xy 160.297136 -395.88548) (xy 160.311525 -395.89987) (xy 160.319302 -395.918675) (xy 160.31972 -395.92885)
			(xy 160.31972 -396.086838) (xy 160.320108 -396.096028) (xy 160.326637 -396.113212) (xy 160.33242 -396.120366)
			(xy 160.354199 -396.146026) (xy 160.392151 -396.20161) (xy 160.423187 -396.261332) (xy 160.446862 -396.324336)
			(xy 160.462837 -396.389718) (xy 160.470882 -396.45654) (xy 160.470883 -396.523845) (xy 160.46284 -396.590668)
			(xy 160.446866 -396.65605) (xy 160.423193 -396.719054) (xy 160.392159 -396.778777) (xy 160.354208 -396.834362)
			(xy 160.33242 -396.860014) (xy 160.326637 -396.867169) (xy 160.320114 -396.884352) (xy 160.31972 -396.893542)
			(xy 160.31972 -397.38681) (xy 160.320121 -397.395998) (xy 160.326641 -397.413183) (xy 160.33242 -397.420338)
			(xy 160.354172 -397.44602) (xy 160.392124 -397.501601) (xy 160.420549 -397.556296) (xy 161.5488 -397.556296)
			(xy 161.556874 -397.489359) (xy 161.572908 -397.423871) (xy 161.596669 -397.360775) (xy 161.627817 -397.300979)
			(xy 161.665902 -397.245344) (xy 161.687764 -397.219678) (xy 161.69356 -397.212533) (xy 161.700073 -397.195342)
			(xy 161.700464 -397.18615) (xy 161.700464 -397.028924) (xy 161.701004 -397.018821) (xy 161.708727 -397.00015)
			(xy 161.723007 -396.985856) (xy 161.74167 -396.978114) (xy 161.751772 -396.977616) (xy 162.468052 -396.977616)
			(xy 162.478173 -396.978056) (xy 162.496879 -396.985791) (xy 162.511195 -397.000101) (xy 162.51894 -397.018803)
			(xy 162.51936 -397.028924) (xy 162.51936 -397.18615) (xy 162.519803 -397.195333) (xy 162.526295 -397.212518)
			(xy 162.53206 -397.219678) (xy 162.553935 -397.245334) (xy 162.592026 -397.300969) (xy 162.623179 -397.360766)
			(xy 162.646944 -397.423864) (xy 162.66298 -397.489355) (xy 162.671056 -397.556295) (xy 162.671055 -397.62372)
			(xy 162.662977 -397.69066) (xy 162.64694 -397.75615) (xy 162.623173 -397.819247) (xy 162.620757 -397.823885)
			(xy 163.748903 -397.823885) (xy 163.748907 -397.756458) (xy 163.756987 -397.689517) (xy 163.773027 -397.624026)
			(xy 163.796796 -397.560927) (xy 163.827951 -397.50113) (xy 163.866045 -397.445495) (xy 163.887912 -397.41983)
			(xy 163.893722 -397.412694) (xy 163.900228 -397.395497) (xy 163.900612 -397.386302) (xy 163.900612 -396.89405)
			(xy 163.900175 -396.884866) (xy 163.89368 -396.867681) (xy 163.887912 -396.860522) (xy 163.866038 -396.834865)
			(xy 163.827949 -396.77923) (xy 163.796798 -396.719432) (xy 163.773034 -396.656334) (xy 163.756998 -396.590844)
			(xy 163.748923 -396.523905) (xy 163.748924 -396.45648) (xy 163.757001 -396.389541) (xy 163.773038 -396.324051)
			(xy 163.796804 -396.260954) (xy 163.827956 -396.201157) (xy 163.866047 -396.145523) (xy 163.887912 -396.119858)
			(xy 163.89371 -396.112714) (xy 163.900224 -396.095523) (xy 163.900612 -396.08633) (xy 163.900612 -395.92885)
			(xy 163.901167 -395.91873) (xy 163.908873 -395.900015) (xy 163.923138 -395.885658) (xy 163.941803 -395.877832)
			(xy 163.95192 -395.877288) (xy 164.6682 -395.877288) (xy 164.678353 -395.877721) (xy 164.697103 -395.885515)
			(xy 164.711426 -395.899908) (xy 164.719127 -395.918695) (xy 164.719508 -395.92885) (xy 164.719508 -396.08633)
			(xy 164.719902 -396.095519) (xy 164.726426 -396.112703) (xy 164.732208 -396.119858) (xy 164.754062 -396.145531)
			(xy 164.79215 -396.201165) (xy 164.823301 -396.26096) (xy 164.847065 -396.324056) (xy 164.863101 -396.389544)
			(xy 164.871178 -396.456481) (xy 164.871179 -396.523904) (xy 164.863104 -396.590841) (xy 164.84707 -396.65633)
			(xy 164.823307 -396.719426) (xy 164.792158 -396.779222) (xy 164.754071 -396.834857) (xy 164.732208 -396.860522)
			(xy 164.726421 -396.867674) (xy 164.7199 -396.884859) (xy 164.719508 -396.89405) (xy 164.719508 -397.386302)
			(xy 164.719915 -397.395489) (xy 164.726431 -397.412674) (xy 164.732208 -397.41983) (xy 164.754034 -397.445526)
			(xy 164.792124 -397.501156) (xy 164.823276 -397.560948) (xy 164.846898 -397.62366) (xy 165.949096 -397.62366)
			(xy 165.949096 -397.556355) (xy 165.957139 -397.489533) (xy 165.973111 -397.424151) (xy 165.996783 -397.361147)
			(xy 166.027816 -397.301424) (xy 166.065765 -397.245838) (xy 166.087552 -397.220186) (xy 166.093343 -397.213037)
			(xy 166.09986 -397.195849) (xy 166.100252 -397.186658) (xy 166.100252 -397.028924) (xy 166.10074 -397.018777)
			(xy 166.108519 -397.000035) (xy 166.122895 -396.985712) (xy 166.141666 -396.978003) (xy 166.151814 -396.977616)
			(xy 166.868094 -396.977616) (xy 166.878217 -396.978131) (xy 166.896934 -396.985852) (xy 166.911289 -397.000129)
			(xy 166.919113 -397.018803) (xy 166.919656 -397.028924) (xy 166.919656 -397.186658) (xy 166.920096 -397.195842)
			(xy 166.92659 -397.213026) (xy 166.932356 -397.220186) (xy 166.954154 -397.24583) (xy 166.992103 -397.301417)
			(xy 167.023136 -397.361142) (xy 167.046808 -397.424148) (xy 167.062781 -397.489531) (xy 167.070824 -397.556355)
			(xy 167.070823 -397.62366) (xy 167.062778 -397.690484) (xy 167.046804 -397.755867) (xy 167.02313 -397.818872)
			(xy 167.020556 -397.823825) (xy 168.149223 -397.823825) (xy 168.149226 -397.756518) (xy 168.157274 -397.689693)
			(xy 168.17325 -397.624309) (xy 168.196925 -397.561304) (xy 168.22796 -397.501579) (xy 168.265911 -397.445991)
			(xy 168.2877 -397.420338) (xy 168.293505 -397.413199) (xy 168.300015 -397.396004) (xy 168.3004 -397.38681)
			(xy 168.3004 -396.893542) (xy 168.29997 -396.884357) (xy 168.29347 -396.867172) (xy 168.2877 -396.860014)
			(xy 168.265904 -396.834369) (xy 168.227958 -396.778781) (xy 168.196927 -396.719056) (xy 168.173256 -396.656051)
			(xy 168.157285 -396.590668) (xy 168.149243 -396.523845) (xy 168.149244 -396.45654) (xy 168.157288 -396.389717)
			(xy 168.173261 -396.324335) (xy 168.196933 -396.26133) (xy 168.227965 -396.201606) (xy 168.265913 -396.146019)
			(xy 168.2877 -396.120366) (xy 168.293494 -396.113219) (xy 168.30001 -396.09603) (xy 168.3004 -396.086838)
			(xy 168.3004 -395.92885) (xy 168.300904 -395.918686) (xy 168.308665 -395.8999) (xy 168.323026 -395.885515)
			(xy 168.341799 -395.877721) (xy 168.351962 -395.877288) (xy 169.068242 -395.877288) (xy 169.078423 -395.877631)
			(xy 169.097228 -395.885439) (xy 169.111613 -395.89985) (xy 169.119388 -395.918669) (xy 169.119804 -395.92885)
			(xy 169.119804 -396.086838) (xy 169.120195 -396.096027) (xy 169.126722 -396.113212) (xy 169.132504 -396.120366)
			(xy 169.154281 -396.146027) (xy 169.192227 -396.201613) (xy 169.223258 -396.261336) (xy 169.24693 -396.324339)
			(xy 169.262902 -396.38972) (xy 169.270946 -396.456541) (xy 169.270947 -396.523844) (xy 169.262905 -396.590665)
			(xy 169.246934 -396.656047) (xy 169.223264 -396.71905) (xy 169.192235 -396.778774) (xy 169.15429 -396.834361)
			(xy 169.132504 -396.860014) (xy 169.126719 -396.867168) (xy 169.120197 -396.884352) (xy 169.119804 -396.893542)
			(xy 169.119804 -397.38681) (xy 169.120209 -397.395998) (xy 169.126726 -397.413182) (xy 169.132504 -397.420338)
			(xy 169.154253 -397.446021) (xy 169.1922 -397.501604) (xy 169.22062 -397.556296) (xy 170.348863 -397.556296)
			(xy 170.356939 -397.489357) (xy 170.372975 -397.423868) (xy 170.39674 -397.360771) (xy 170.427892 -397.300976)
			(xy 170.465983 -397.245342) (xy 170.487848 -397.219678) (xy 170.493642 -397.212531) (xy 170.500157 -397.195342)
			(xy 170.500548 -397.18615) (xy 170.500548 -397.028924) (xy 170.501103 -397.018823) (xy 170.508823 -397.000155)
			(xy 170.523098 -396.985862) (xy 170.541756 -396.978117) (xy 170.551856 -396.977616) (xy 171.268136 -396.977616)
			(xy 171.278249 -396.978056) (xy 171.296931 -396.985808) (xy 171.311225 -397.000119) (xy 171.318956 -397.01881)
			(xy 171.319444 -397.028924) (xy 171.319444 -397.18615) (xy 171.319891 -397.195333) (xy 171.326381 -397.212517)
			(xy 171.332144 -397.219678) (xy 171.35402 -397.245334) (xy 171.392112 -397.300969) (xy 171.423265 -397.360766)
			(xy 171.447031 -397.423864) (xy 171.463068 -397.489355) (xy 171.471144 -397.556295) (xy 171.471143 -397.62372)
			(xy 171.463065 -397.69066) (xy 171.447027 -397.756151) (xy 171.423259 -397.819248) (xy 171.420874 -397.823826)
			(xy 172.54899 -397.823826) (xy 172.548993 -397.756517) (xy 172.557042 -397.689691) (xy 172.57302 -397.624306)
			(xy 172.5967 -397.5613) (xy 172.62774 -397.501575) (xy 172.665697 -397.44599) (xy 172.687488 -397.420338)
			(xy 172.693292 -397.413198) (xy 172.699803 -397.396004) (xy 172.700188 -397.38681) (xy 172.700188 -396.893542)
			(xy 172.69976 -396.884357) (xy 172.693259 -396.867172) (xy 172.687488 -396.860014) (xy 172.665689 -396.834371)
			(xy 172.627737 -396.778784) (xy 172.596702 -396.71906) (xy 172.573027 -396.656054) (xy 172.557054 -396.59067)
			(xy 172.54901 -396.523846) (xy 172.54901 -396.456539) (xy 172.557056 -396.389715) (xy 172.573032 -396.324332)
			(xy 172.596708 -396.261327) (xy 172.627745 -396.201603) (xy 172.665698 -396.146018) (xy 172.687488 -396.120366)
			(xy 172.69328 -396.113218) (xy 172.699798 -396.09603) (xy 172.700188 -396.086838) (xy 172.700188 -395.92885)
			(xy 172.700606 -395.918675) (xy 172.708384 -395.899872) (xy 172.722772 -395.885484) (xy 172.741575 -395.877706)
			(xy 172.75175 -395.877288) (xy 173.46803 -395.877288) (xy 173.47821 -395.87764) (xy 173.497015 -395.885445)
			(xy 173.5114 -395.899852) (xy 173.519175 -395.91867) (xy 173.519592 -395.92885) (xy 173.519592 -396.086838)
			(xy 173.519986 -396.096027) (xy 173.526511 -396.113211) (xy 173.532292 -396.120366) (xy 173.554069 -396.146027)
			(xy 173.592016 -396.201613) (xy 173.623048 -396.261335) (xy 173.64672 -396.324339) (xy 173.662693 -396.389719)
			(xy 173.670737 -396.456541) (xy 173.670738 -396.523844) (xy 173.662695 -396.590666) (xy 173.646725 -396.656047)
			(xy 173.623054 -396.719051) (xy 173.592024 -396.778774) (xy 173.554078 -396.834361) (xy 173.532292 -396.860014)
			(xy 173.526506 -396.867167) (xy 173.519985 -396.884351) (xy 173.519592 -396.893542) (xy 173.519592 -397.38681)
			(xy 173.519999 -397.395998) (xy 173.526515 -397.413182) (xy 173.532292 -397.420338) (xy 173.554041 -397.446021)
			(xy 173.591989 -397.501604) (xy 173.620441 -397.556355) (xy 174.749183 -397.556355) (xy 174.757226 -397.489534)
			(xy 174.773198 -397.424152) (xy 174.796869 -397.361148) (xy 174.827901 -397.301424) (xy 174.865849 -397.245838)
			(xy 174.887636 -397.220186) (xy 174.893426 -397.213036) (xy 174.899944 -397.195849) (xy 174.900336 -397.186658)
			(xy 174.900336 -397.028924) (xy 174.900742 -397.018767) (xy 174.908536 -397.000008) (xy 174.922939 -396.985682)
			(xy 174.941739 -396.977988) (xy 174.951898 -396.977616) (xy 175.668178 -396.977616) (xy 175.6783 -396.978144)
			(xy 175.697017 -396.98586) (xy 175.711373 -397.000133) (xy 175.719197 -397.018805) (xy 175.71974 -397.028924)
			(xy 175.71974 -397.186658) (xy 175.720184 -397.195841) (xy 175.726675 -397.213025) (xy 175.73244 -397.220186)
			(xy 175.754238 -397.24583) (xy 175.792188 -397.301417) (xy 175.823222 -397.361142) (xy 175.846895 -397.424147)
			(xy 175.862868 -397.489531) (xy 175.870912 -397.556354) (xy 175.870911 -397.623661) (xy 175.862865 -397.690484)
			(xy 175.846891 -397.755867) (xy 175.823216 -397.818872) (xy 175.79218 -397.878596) (xy 175.754229 -397.934182)
			(xy 175.73244 -397.959834) (xy 175.726639 -397.966976) (xy 175.720129 -397.984169) (xy 175.71974 -397.993362)
			(xy 175.71974 -398.486884) (xy 175.720171 -398.496069) (xy 175.726672 -398.513253) (xy 175.73244 -398.520412)
			(xy 175.754264 -398.546035) (xy 175.792213 -398.601625) (xy 175.823246 -398.661352) (xy 175.846918 -398.724361)
			(xy 175.862889 -398.789747) (xy 175.87093 -398.856573) (xy 175.870927 -398.923881) (xy 175.862879 -398.990707)
			(xy 175.846902 -399.056091) (xy 175.823224 -399.119097) (xy 175.792185 -399.178822) (xy 175.754231 -399.234408)
			(xy 175.73244 -399.26006) (xy 175.726628 -399.267194) (xy 175.720124 -399.284393) (xy 175.71974 -399.293588)
			(xy 175.71974 -399.451576) (xy 175.71926 -399.461724) (xy 175.71148 -399.480468) (xy 175.697101 -399.494791)
			(xy 175.678327 -399.502498) (xy 175.668178 -399.502884) (xy 174.951898 -399.502884) (xy 174.941774 -399.502376)
			(xy 174.923058 -399.494652) (xy 174.908702 -399.480372) (xy 174.900879 -399.461697) (xy 174.900336 -399.451576)
			(xy 174.900336 -399.293588) (xy 174.899924 -399.284401) (xy 174.893411 -399.267217) (xy 174.887636 -399.26006)
			(xy 174.865884 -399.234379) (xy 174.827934 -399.178796) (xy 174.7969 -399.119077) (xy 174.773225 -399.056076)
			(xy 174.75725 -398.990697) (xy 174.749203 -398.923878) (xy 174.749199 -398.856576) (xy 174.75724 -398.789756)
			(xy 174.773209 -398.724376) (xy 174.796878 -398.661373) (xy 174.827906 -398.60165) (xy 174.865851 -398.546064)
			(xy 174.887636 -398.520412) (xy 174.893457 -398.513284) (xy 174.899956 -398.49608) (xy 174.900336 -398.486884)
			(xy 174.900336 -397.993362) (xy 174.899936 -397.984174) (xy 174.893414 -397.96699) (xy 174.887636 -397.959834)
			(xy 174.865858 -397.934174) (xy 174.827909 -397.878588) (xy 174.796876 -397.818866) (xy 174.773202 -397.755863)
			(xy 174.757229 -397.690481) (xy 174.749184 -397.62366) (xy 174.749183 -397.556355) (xy 173.620441 -397.556355)
			(xy 173.623023 -397.561324) (xy 173.646696 -397.624324) (xy 173.662671 -397.689702) (xy 173.670718 -397.756521)
			(xy 173.670721 -397.823822) (xy 173.662681 -397.890642) (xy 173.646713 -397.956021) (xy 173.623046 -398.019024)
			(xy 173.592019 -398.078747) (xy 173.554077 -398.134334) (xy 173.532292 -398.159986) (xy 173.526475 -398.167117)
			(xy 173.519973 -398.184318) (xy 173.519592 -398.193514) (xy 173.519592 -398.351502) (xy 173.519069 -398.361656)
			(xy 173.511299 -398.38042) (xy 173.496943 -398.394784) (xy 173.478184 -398.402563) (xy 173.46803 -398.403064)
			(xy 172.75175 -398.403064) (xy 172.741582 -398.402595) (xy 172.722789 -398.394827) (xy 172.708402 -398.380455)
			(xy 172.700615 -398.36167) (xy 172.700188 -398.351502) (xy 172.700188 -398.193514) (xy 172.699774 -398.184327)
			(xy 172.693263 -398.167143) (xy 172.687488 -398.159986) (xy 172.665661 -398.134365) (xy 172.627711 -398.078775)
			(xy 172.596676 -398.019048) (xy 172.573004 -397.956039) (xy 172.557032 -397.890653) (xy 172.54899 -397.823826)
			(xy 171.420874 -397.823826) (xy 171.392104 -397.879044) (xy 171.354011 -397.934678) (xy 171.332144 -397.960342)
			(xy 171.32634 -397.967482) (xy 171.319831 -397.984677) (xy 171.319444 -397.99387) (xy 171.319444 -398.486376)
			(xy 171.319878 -398.49556) (xy 171.326376 -398.512744) (xy 171.332144 -398.519904) (xy 171.354045 -398.545539)
			(xy 171.392137 -398.601177) (xy 171.423289 -398.660976) (xy 171.447054 -398.724077) (xy 171.463088 -398.789571)
			(xy 171.471162 -398.856513) (xy 171.471159 -398.923941) (xy 171.463078 -398.990883) (xy 171.447037 -399.056374)
			(xy 171.423267 -399.119473) (xy 171.392109 -399.17927) (xy 171.354012 -399.234904) (xy 171.332144 -399.260568)
			(xy 171.326329 -399.2677) (xy 171.319827 -399.284901) (xy 171.319444 -399.294096) (xy 171.319444 -399.451576)
			(xy 171.318896 -399.461678) (xy 171.311175 -399.480347) (xy 171.296897 -399.494641) (xy 171.278237 -399.502385)
			(xy 171.268136 -399.502884) (xy 170.551856 -399.502884) (xy 170.541742 -399.50245) (xy 170.52306 -399.494695)
			(xy 170.508766 -399.480383) (xy 170.501036 -399.46169) (xy 170.500548 -399.451576) (xy 170.500548 -399.294096)
			(xy 170.500129 -399.28491) (xy 170.49362 -399.267726) (xy 170.487848 -399.260568) (xy 170.466018 -399.234874)
			(xy 170.427925 -399.179245) (xy 170.39677 -399.119453) (xy 170.373001 -399.05636) (xy 170.356962 -398.990874)
			(xy 170.348883 -398.923938) (xy 170.348879 -398.856516) (xy 170.356952 -398.789579) (xy 170.372985 -398.724092)
			(xy 170.396748 -398.660996) (xy 170.427897 -398.601201) (xy 170.465984 -398.545568) (xy 170.487848 -398.519904)
			(xy 170.493631 -398.51275) (xy 170.500153 -398.495566) (xy 170.500548 -398.486376) (xy 170.500548 -397.99387)
			(xy 170.500141 -397.984683) (xy 170.493624 -397.967499) (xy 170.487848 -397.960342) (xy 170.465992 -397.934669)
			(xy 170.4279 -397.879037) (xy 170.396746 -397.819242) (xy 170.372979 -397.756146) (xy 170.356942 -397.690658)
			(xy 170.348864 -397.623719) (xy 170.348863 -397.556296) (xy 169.22062 -397.556296) (xy 169.223233 -397.561324)
			(xy 169.246906 -397.624324) (xy 169.26288 -397.689702) (xy 169.270927 -397.756521) (xy 169.27093 -397.823822)
			(xy 169.26289 -397.890641) (xy 169.246923 -397.956021) (xy 169.223256 -398.019024) (xy 169.19223 -398.078746)
			(xy 169.154288 -398.134333) (xy 169.132504 -398.159986) (xy 169.126689 -398.167118) (xy 169.120185 -398.184319)
			(xy 169.119804 -398.193514) (xy 169.119804 -398.351502) (xy 169.119269 -398.361655) (xy 169.111502 -398.380416)
			(xy 169.097149 -398.394779) (xy 169.078394 -398.402561) (xy 169.068242 -398.403064) (xy 168.351962 -398.403064)
			(xy 168.341802 -398.402598) (xy 168.323032 -398.394811) (xy 168.308669 -398.380437) (xy 168.300895 -398.361662)
			(xy 168.3004 -398.351502) (xy 168.3004 -398.193514) (xy 168.299983 -398.184328) (xy 168.293474 -398.167143)
			(xy 168.2877 -398.159986) (xy 168.265876 -398.134364) (xy 168.227931 -398.078772) (xy 168.196902 -398.019044)
			(xy 168.173233 -397.956036) (xy 168.157263 -397.89065) (xy 168.149223 -397.823825) (xy 167.020556 -397.823825)
			(xy 166.992095 -397.878596) (xy 166.954145 -397.934182) (xy 166.932356 -397.959834) (xy 166.926557 -397.966977)
			(xy 166.920045 -397.984169) (xy 166.919656 -397.993362) (xy 166.919656 -398.486884) (xy 166.920084 -398.496069)
			(xy 166.926586 -398.513253) (xy 166.932356 -398.520412) (xy 166.954179 -398.546035) (xy 166.992127 -398.601625)
			(xy 167.023159 -398.661353) (xy 167.04683 -398.724361) (xy 167.062801 -398.789747) (xy 167.070842 -398.856573)
			(xy 167.070839 -398.923881) (xy 167.062791 -398.990706) (xy 167.046814 -399.05609) (xy 167.023137 -399.119097)
			(xy 166.9921 -399.178821) (xy 166.954146 -399.234408) (xy 166.932356 -399.26006) (xy 166.926546 -399.267195)
			(xy 166.92004 -399.284394) (xy 166.919656 -399.293588) (xy 166.919656 -399.451576) (xy 166.91916 -399.461722)
			(xy 166.911383 -399.480463) (xy 166.89701 -399.494785) (xy 166.878241 -399.502496) (xy 166.868094 -399.502884)
			(xy 166.151814 -399.502884) (xy 166.141691 -399.502363) (xy 166.122975 -399.494644) (xy 166.108619 -399.480369)
			(xy 166.100795 -399.461696) (xy 166.100252 -399.451576) (xy 166.100252 -399.293588) (xy 166.099836 -399.284402)
			(xy 166.093325 -399.267218) (xy 166.087552 -399.26006) (xy 166.065799 -399.234379) (xy 166.027849 -399.178797)
			(xy 165.996813 -399.119077) (xy 165.973138 -399.056077) (xy 165.957162 -398.990698) (xy 165.949115 -398.923878)
			(xy 165.949111 -398.856576) (xy 165.957152 -398.789755) (xy 165.973122 -398.724375) (xy 165.996791 -398.661372)
			(xy 166.027821 -398.60165) (xy 166.065766 -398.546064) (xy 166.087552 -398.520412) (xy 166.093375 -398.513286)
			(xy 166.099872 -398.49608) (xy 166.100252 -398.486884) (xy 166.100252 -397.993362) (xy 166.099848 -397.984174)
			(xy 166.093329 -397.966991) (xy 166.087552 -397.959834) (xy 166.065774 -397.934174) (xy 166.027824 -397.878589)
			(xy 165.99679 -397.818866) (xy 165.973116 -397.755863) (xy 165.957142 -397.690482) (xy 165.949096 -397.62366)
			(xy 164.846898 -397.62366) (xy 164.847042 -397.624041) (xy 164.863079 -397.689526) (xy 164.871158 -397.756461)
			(xy 164.871162 -397.823882) (xy 164.86309 -397.890817) (xy 164.847058 -397.956304) (xy 164.823299 -398.019399)
			(xy 164.792153 -398.079195) (xy 164.754069 -398.134829) (xy 164.732208 -398.160494) (xy 164.726432 -398.167654)
			(xy 164.719905 -398.184833) (xy 164.719508 -398.194022) (xy 164.719508 -398.351502) (xy 164.718976 -398.361623)
			(xy 164.711257 -398.380335) (xy 164.696985 -398.394689) (xy 164.678318 -398.402517) (xy 164.6682 -398.403064)
			(xy 163.95192 -398.403064) (xy 163.941763 -398.402661) (xy 163.923004 -398.394866) (xy 163.908678 -398.380462)
			(xy 163.900984 -398.361662) (xy 163.900612 -398.351502) (xy 163.900612 -398.194022) (xy 163.900188 -398.184836)
			(xy 163.893684 -398.167652) (xy 163.887912 -398.160494) (xy 163.86601 -398.13486) (xy 163.827922 -398.079221)
			(xy 163.796772 -398.019421) (xy 163.77301 -397.95632) (xy 163.756976 -397.890827) (xy 163.748903 -397.823885)
			(xy 162.620757 -397.823885) (xy 162.592019 -397.879044) (xy 162.553926 -397.934677) (xy 162.53206 -397.960342)
			(xy 162.526258 -397.967483) (xy 162.519748 -397.984677) (xy 162.51936 -397.99387) (xy 162.51936 -398.486376)
			(xy 162.51979 -398.495561) (xy 162.526291 -398.512745) (xy 162.53206 -398.519904) (xy 162.553961 -398.545539)
			(xy 162.592051 -398.601177) (xy 162.623202 -398.660977) (xy 162.646966 -398.724078) (xy 162.663 -398.789571)
			(xy 162.671074 -398.856513) (xy 162.671071 -398.923941) (xy 162.662991 -398.990882) (xy 162.64695 -399.056374)
			(xy 162.62318 -399.119472) (xy 162.592023 -399.179269) (xy 162.553928 -399.234903) (xy 162.53206 -399.260568)
			(xy 162.526247 -399.267701) (xy 162.519743 -399.284901) (xy 162.51936 -399.294096) (xy 162.51936 -399.451576)
			(xy 162.518964 -399.461702) (xy 162.511216 -399.480413) (xy 162.496893 -399.494729) (xy 162.478178 -399.502468)
			(xy 162.468052 -399.502884) (xy 161.751772 -399.502884) (xy 161.741659 -399.502438) (xy 161.722978 -399.494688)
			(xy 161.708683 -399.480379) (xy 161.700952 -399.461689) (xy 161.700464 -399.451576) (xy 161.700464 -399.294096)
			(xy 161.700041 -399.28491) (xy 161.693535 -399.267727) (xy 161.687764 -399.260568) (xy 161.665937 -399.234873)
			(xy 161.627849 -399.179242) (xy 161.596699 -399.119449) (xy 161.572934 -399.056357) (xy 161.556897 -398.990871)
			(xy 161.548819 -398.923937) (xy 161.548816 -398.856517) (xy 161.556888 -398.789582) (xy 161.572918 -398.724095)
			(xy 161.596677 -398.661) (xy 161.627821 -398.601205) (xy 161.665903 -398.54557) (xy 161.687764 -398.519904)
			(xy 161.693549 -398.512751) (xy 161.700069 -398.495566) (xy 161.700464 -398.486376) (xy 161.700464 -397.99387)
			(xy 161.700054 -397.984683) (xy 161.693538 -397.9675) (xy 161.687764 -397.960342) (xy 161.665911 -397.934668)
			(xy 161.627824 -397.879034) (xy 161.596675 -397.819239) (xy 161.572912 -397.756143) (xy 161.556877 -397.690655)
			(xy 161.548801 -397.623719) (xy 161.5488 -397.556296) (xy 160.420549 -397.556296) (xy 160.423161 -397.561321)
			(xy 160.446838 -397.624321) (xy 160.462815 -397.6897) (xy 160.470863 -397.75652) (xy 160.470866 -397.823823)
			(xy 160.462825 -397.890644) (xy 160.446855 -397.956024) (xy 160.423185 -398.019027) (xy 160.392154 -398.078749)
			(xy 160.354207 -398.134334) (xy 160.33242 -398.159986) (xy 160.326607 -398.16712) (xy 160.320101 -398.184319)
			(xy 160.31972 -398.193514) (xy 160.31972 -398.351502) (xy 160.319337 -398.361679) (xy 160.311543 -398.380482)
			(xy 160.297145 -398.394868) (xy 160.278335 -398.402645) (xy 160.268158 -398.403064) (xy 159.551878 -398.403064)
			(xy 159.541719 -398.402585) (xy 159.52295 -398.394804) (xy 159.508585 -398.380433) (xy 159.500811 -398.361661)
			(xy 159.500316 -398.351502) (xy 159.500316 -398.193514) (xy 159.499895 -398.184328) (xy 159.493388 -398.167144)
			(xy 159.487616 -398.159986) (xy 159.465792 -398.134364) (xy 159.427845 -398.078773) (xy 159.396815 -398.019045)
			(xy 159.373145 -397.956036) (xy 159.357176 -397.890651) (xy 159.349135 -397.823825) (xy 154.57678 -397.823825)
			(xy 154.57678 -401.723737) (xy 159.349146 -401.723737) (xy 159.349148 -401.65643) (xy 159.357194 -401.589607)
			(xy 159.373169 -401.524223) (xy 159.396843 -401.461218) (xy 159.427878 -401.401494) (xy 159.465828 -401.345906)
			(xy 159.487616 -401.320254) (xy 159.493416 -401.313112) (xy 159.499928 -401.295919) (xy 159.500316 -401.286726)
			(xy 159.500316 -400.793458) (xy 159.499923 -400.784269) (xy 159.493397 -400.767085) (xy 159.487616 -400.75993)
			(xy 159.465835 -400.734273) (xy 159.427887 -400.678686) (xy 159.396855 -400.618963) (xy 159.373183 -400.55596)
			(xy 159.35721 -400.490578) (xy 159.349166 -400.423757) (xy 159.349165 -400.356452) (xy 159.357209 -400.289631)
			(xy 159.37318 -400.224249) (xy 159.396851 -400.161245) (xy 159.427883 -400.101521) (xy 159.465829 -400.045934)
			(xy 159.487616 -400.020282) (xy 159.493405 -400.013131) (xy 159.499923 -399.995945) (xy 159.500316 -399.986754)
			(xy 159.500316 -399.828766) (xy 159.500805 -399.818609) (xy 159.508586 -399.799843) (xy 159.522953 -399.78548)
			(xy 159.541721 -399.777703) (xy 159.551878 -399.777204) (xy 160.268158 -399.777204) (xy 160.278323 -399.777697)
			(xy 160.29711 -399.785462) (xy 160.311495 -399.799826) (xy 160.319288 -399.818602) (xy 160.31972 -399.828766)
			(xy 160.31972 -399.986754) (xy 160.320148 -399.995939) (xy 160.326649 -400.013124) (xy 160.33242 -400.020282)
			(xy 160.354215 -400.045929) (xy 160.392166 -400.101515) (xy 160.423201 -400.161239) (xy 160.446876 -400.224244)
			(xy 160.462849 -400.289628) (xy 160.470894 -400.356451) (xy 160.470893 -400.423758) (xy 160.462848 -400.490581)
			(xy 160.446873 -400.555964) (xy 160.423198 -400.618969) (xy 160.392161 -400.678693) (xy 160.354209 -400.734278)
			(xy 160.33242 -400.75993) (xy 160.326631 -400.76708) (xy 160.320111 -400.784267) (xy 160.31972 -400.793458)
			(xy 160.31972 -401.286726) (xy 160.320113 -401.295915) (xy 160.326638 -401.313099) (xy 160.33242 -401.320254)
			(xy 160.354187 -401.345923) (xy 160.392139 -401.401506) (xy 160.423176 -401.461227) (xy 160.446852 -401.52423)
			(xy 160.462827 -401.58961) (xy 160.470874 -401.656431) (xy 160.470876 -401.723735) (xy 160.462833 -401.790557)
			(xy 160.446862 -401.855939) (xy 160.423189 -401.918943) (xy 160.392156 -401.978665) (xy 160.354208 -402.03425)
			(xy 160.33242 -402.059902) (xy 160.326642 -402.067061) (xy 160.320116 -402.084241) (xy 160.31972 -402.09343)
			(xy 160.31972 -402.251418) (xy 160.31935 -402.261596) (xy 160.311551 -402.280399) (xy 160.297149 -402.294785)
			(xy 160.278336 -402.302562) (xy 160.268158 -402.30298) (xy 159.551878 -402.30298) (xy 159.541721 -402.302485)
			(xy 159.522955 -402.294707) (xy 159.508591 -402.280342) (xy 159.500814 -402.261575) (xy 159.500316 -402.251418)
			(xy 159.500316 -402.09343) (xy 159.499888 -402.084245) (xy 159.493386 -402.06706) (xy 159.487616 -402.059902)
			(xy 159.465807 -402.034267) (xy 159.427861 -401.978678) (xy 159.39683 -401.918952) (xy 159.373159 -401.855945)
			(xy 159.357188 -401.790561) (xy 159.349146 -401.723737) (xy 154.57678 -401.723737) (xy 154.57678 -402.823877)
			(xy 161.54876 -402.823877) (xy 161.548765 -402.756451) (xy 161.556845 -402.68951) (xy 161.572884 -402.624018)
			(xy 161.596652 -402.56092) (xy 161.627806 -402.501122) (xy 161.665898 -402.445486) (xy 161.687764 -402.41982)
			(xy 161.693585 -402.412692) (xy 161.700083 -402.395488) (xy 161.700464 -402.386292) (xy 161.700464 -401.89404)
			(xy 161.70002 -401.884857) (xy 161.693528 -401.867673) (xy 161.687764 -401.860512) (xy 161.665882 -401.834862)
			(xy 161.627796 -401.779225) (xy 161.596648 -401.719426) (xy 161.572887 -401.656327) (xy 161.556854 -401.590837)
			(xy 161.54878 -401.523897) (xy 161.548782 -401.456473) (xy 161.556859 -401.389534) (xy 161.572896 -401.324044)
			(xy 161.59666 -401.260946) (xy 161.627811 -401.201149) (xy 161.6659 -401.145514) (xy 161.687764 -401.119848)
			(xy 161.693573 -401.112712) (xy 161.700078 -401.095514) (xy 161.700464 -401.08632) (xy 161.700464 -400.92884)
			(xy 161.700948 -400.918725) (xy 161.708676 -400.900029) (xy 161.722972 -400.885714) (xy 161.741657 -400.877961)
			(xy 161.751772 -400.877532) (xy 162.468052 -400.877532) (xy 162.478175 -400.877956) (xy 162.496884 -400.885694)
			(xy 162.511201 -400.900009) (xy 162.518942 -400.918717) (xy 162.51936 -400.92884) (xy 162.51936 -401.08632)
			(xy 162.519769 -401.095507) (xy 162.526285 -401.112691) (xy 162.53206 -401.119848) (xy 162.553906 -401.145529)
			(xy 162.591998 -401.20116) (xy 162.623151 -401.260954) (xy 162.646919 -401.324049) (xy 162.662957 -401.389536)
			(xy 162.671035 -401.456474) (xy 162.671037 -401.523896) (xy 162.662962 -401.590834) (xy 162.646927 -401.656323)
			(xy 162.623164 -401.719419) (xy 162.620884 -401.723796) (xy 163.748915 -401.723796) (xy 163.748917 -401.656371)
			(xy 163.756995 -401.589431) (xy 163.773033 -401.52394) (xy 163.7968 -401.460842) (xy 163.827954 -401.401046)
			(xy 163.866046 -401.345411) (xy 163.887912 -401.319746) (xy 163.893715 -401.312606) (xy 163.900226 -401.295411)
			(xy 163.900612 -401.286218) (xy 163.900612 -400.793966) (xy 163.900216 -400.784777) (xy 163.893692 -400.767593)
			(xy 163.887912 -400.760438) (xy 163.866054 -400.734768) (xy 163.827964 -400.679135) (xy 163.796812 -400.619339)
			(xy 163.773047 -400.556243) (xy 163.757011 -400.490754) (xy 163.748934 -400.423816) (xy 163.748934 -400.356393)
			(xy 163.757009 -400.289455) (xy 163.773044 -400.223966) (xy 163.796809 -400.160869) (xy 163.827959 -400.101073)
			(xy 163.866048 -400.045439) (xy 163.887912 -400.019774) (xy 163.893703 -400.012625) (xy 163.900221 -399.995437)
			(xy 163.900612 -399.986246) (xy 163.900612 -399.828766) (xy 163.901098 -399.818641) (xy 163.908832 -399.799924)
			(xy 163.923117 -399.78557) (xy 163.941797 -399.777747) (xy 163.95192 -399.777204) (xy 164.6682 -399.777204)
			(xy 164.678355 -399.777622) (xy 164.697108 -399.785418) (xy 164.711431 -399.799816) (xy 164.71913 -399.818609)
			(xy 164.719508 -399.828766) (xy 164.719508 -399.986246) (xy 164.719942 -399.995431) (xy 164.726439 -400.012615)
			(xy 164.732208 -400.019774) (xy 164.754078 -400.045435) (xy 164.792166 -400.10107) (xy 164.823316 -400.160867)
			(xy 164.847079 -400.223964) (xy 164.863114 -400.289454) (xy 164.871189 -400.356393) (xy 164.871189 -400.423817)
			(xy 164.863112 -400.490755) (xy 164.847076 -400.556244) (xy 164.823312 -400.619341) (xy 164.792161 -400.679138)
			(xy 164.754072 -400.734773) (xy 164.732208 -400.760438) (xy 164.726414 -400.767585) (xy 164.719897 -400.784774)
			(xy 164.719508 -400.793966) (xy 164.719508 -401.286218) (xy 164.719908 -401.295406) (xy 164.726429 -401.312591)
			(xy 164.732208 -401.319746) (xy 164.75405 -401.345429) (xy 164.792139 -401.401061) (xy 164.82329 -401.460855)
			(xy 164.847055 -401.52395) (xy 164.863092 -401.589436) (xy 164.871169 -401.656373) (xy 164.871171 -401.723794)
			(xy 164.863098 -401.790731) (xy 164.847065 -401.856219) (xy 164.823304 -401.919315) (xy 164.792156 -401.97911)
			(xy 164.75407 -402.034745) (xy 164.732208 -402.06041) (xy 164.726426 -402.067565) (xy 164.719902 -402.084748)
			(xy 164.719508 -402.093938) (xy 164.719508 -402.251418) (xy 164.71899 -402.26154) (xy 164.711265 -402.280253)
			(xy 164.696989 -402.294607) (xy 164.678319 -402.302434) (xy 164.6682 -402.30298) (xy 163.95192 -402.30298)
			(xy 163.941765 -402.302562) (xy 163.923009 -402.294769) (xy 163.908684 -402.280371) (xy 163.900987 -402.261575)
			(xy 163.900612 -402.251418) (xy 163.900612 -402.093938) (xy 163.900181 -402.084753) (xy 163.893681 -402.067569)
			(xy 163.887912 -402.06041) (xy 163.866026 -402.034763) (xy 163.827937 -401.979126) (xy 163.796787 -401.919327)
			(xy 163.773023 -401.856228) (xy 163.756989 -401.790737) (xy 163.748915 -401.723796) (xy 162.620884 -401.723796)
			(xy 162.592013 -401.779214) (xy 162.553924 -401.834847) (xy 162.53206 -401.860512) (xy 162.526271 -401.867662)
			(xy 162.519753 -401.884849) (xy 162.51936 -401.89404) (xy 162.51936 -402.386292) (xy 162.519783 -402.395478)
			(xy 162.526289 -402.412662) (xy 162.53206 -402.41982) (xy 162.553878 -402.445523) (xy 162.591971 -402.501152)
			(xy 162.623126 -402.560942) (xy 162.646895 -402.624034) (xy 162.662935 -402.689519) (xy 162.671015 -402.756454)
			(xy 162.671019 -402.823818) (xy 165.949055 -402.823818) (xy 165.94906 -402.756509) (xy 165.957109 -402.689683)
			(xy 165.973087 -402.624298) (xy 165.996766 -402.561292) (xy 166.027805 -402.501567) (xy 166.065761 -402.44598)
			(xy 166.087552 -402.420328) (xy 166.093368 -402.413197) (xy 166.09987 -402.395995) (xy 166.100252 -402.3868)
			(xy 166.100252 -401.893532) (xy 166.099815 -401.884348) (xy 166.093319 -401.867164) (xy 166.087552 -401.860004)
			(xy 166.065744 -401.834368) (xy 166.027795 -401.77878) (xy 165.996762 -401.719054) (xy 165.97309 -401.656047)
			(xy 165.957118 -401.590663) (xy 165.949075 -401.523838) (xy 165.949077 -401.456532) (xy 165.957123 -401.389707)
			(xy 165.973098 -401.324324) (xy 165.996774 -401.261318) (xy 166.02781 -401.201594) (xy 166.065762 -401.146008)
			(xy 166.087552 -401.120356) (xy 166.093356 -401.113216) (xy 166.099865 -401.096021) (xy 166.100252 -401.086828)
			(xy 166.100252 -400.92884) (xy 166.100754 -400.918694) (xy 166.108527 -400.899952) (xy 166.122899 -400.885629)
			(xy 166.141667 -400.87792) (xy 166.151814 -400.877532) (xy 166.868094 -400.877532) (xy 166.878219 -400.878031)
			(xy 166.896939 -400.885756) (xy 166.911295 -400.900038) (xy 166.919116 -400.918717) (xy 166.919656 -400.92884)
			(xy 166.919656 -401.086828) (xy 166.920063 -401.096015) (xy 166.92658 -401.113199) (xy 166.932356 -401.120356)
			(xy 166.954124 -401.146024) (xy 166.992074 -401.201608) (xy 167.023108 -401.26133) (xy 167.046782 -401.324332)
			(xy 167.062757 -401.389712) (xy 167.070803 -401.456533) (xy 167.070804 -401.523837) (xy 167.062762 -401.590658)
			(xy 167.046791 -401.656039) (xy 167.02312 -401.719043) (xy 167.020682 -401.723736) (xy 168.149234 -401.723736)
			(xy 168.149236 -401.65643) (xy 168.157282 -401.589607) (xy 168.173256 -401.524224) (xy 168.19693 -401.461219)
			(xy 168.227963 -401.401494) (xy 168.265912 -401.345907) (xy 168.2877 -401.320254) (xy 168.293499 -401.31311)
			(xy 168.300012 -401.295919) (xy 168.3004 -401.286726) (xy 168.3004 -400.793458) (xy 168.30001 -400.784269)
			(xy 168.293482 -400.767084) (xy 168.2877 -400.75993) (xy 168.265919 -400.734272) (xy 168.227973 -400.678686)
			(xy 168.196942 -400.618963) (xy 168.17327 -400.555959) (xy 168.157298 -400.490578) (xy 168.149254 -400.423756)
			(xy 168.149253 -400.356453) (xy 168.157296 -400.289631) (xy 168.173267 -400.22425) (xy 168.196938 -400.161246)
			(xy 168.227968 -400.101522) (xy 168.265914 -400.045935) (xy 168.2877 -400.020282) (xy 168.293487 -400.01313)
			(xy 168.300007 -399.995945) (xy 168.3004 -399.986754) (xy 168.3004 -399.828766) (xy 168.300905 -399.818611)
			(xy 168.308683 -399.799848) (xy 168.323045 -399.785485) (xy 168.341807 -399.777705) (xy 168.351962 -399.777204)
			(xy 169.068242 -399.777204) (xy 169.078398 -399.777698) (xy 169.097162 -399.78548) (xy 169.111524 -399.799845)
			(xy 169.119303 -399.81861) (xy 169.119804 -399.828766) (xy 169.119804 -399.986754) (xy 169.120235 -399.995939)
			(xy 169.126734 -400.013124) (xy 169.132504 -400.020282) (xy 169.154296 -400.04593) (xy 169.192242 -400.101518)
			(xy 169.223273 -400.161243) (xy 169.246943 -400.224248) (xy 169.262915 -400.28963) (xy 169.270958 -400.356452)
			(xy 169.270957 -400.423757) (xy 169.262913 -400.490579) (xy 169.246941 -400.555961) (xy 169.223269 -400.618966)
			(xy 169.192237 -400.67869) (xy 169.154291 -400.734277) (xy 169.132504 -400.75993) (xy 169.126713 -400.767079)
			(xy 169.120195 -400.784267) (xy 169.119804 -400.793458) (xy 169.119804 -401.286726) (xy 169.1202 -401.295915)
			(xy 169.126723 -401.313099) (xy 169.132504 -401.320254) (xy 169.154269 -401.345925) (xy 169.192215 -401.401509)
			(xy 169.223247 -401.461231) (xy 169.246919 -401.524233) (xy 169.262893 -401.589612) (xy 169.270938 -401.656432)
			(xy 169.27094 -401.723735) (xy 169.262899 -401.790555) (xy 169.246929 -401.855936) (xy 169.223261 -401.918939)
			(xy 169.192232 -401.978662) (xy 169.154289 -402.034249) (xy 169.132504 -402.059902) (xy 169.126725 -402.067059)
			(xy 169.1202 -402.084241) (xy 169.119804 -402.09343) (xy 169.119804 -402.251418) (xy 169.119283 -402.261572)
			(xy 169.11151 -402.280333) (xy 169.097154 -402.294697) (xy 169.078396 -402.302478) (xy 169.068242 -402.30298)
			(xy 168.351962 -402.30298) (xy 168.341804 -402.302498) (xy 168.323037 -402.294715) (xy 168.308674 -402.280346)
			(xy 168.300898 -402.261576) (xy 168.3004 -402.251418) (xy 168.3004 -402.09343) (xy 168.299975 -402.084244)
			(xy 168.293472 -402.06706) (xy 168.2877 -402.059902) (xy 168.265892 -402.034267) (xy 168.227946 -401.978677)
			(xy 168.196916 -401.918951) (xy 168.173246 -401.855944) (xy 168.157276 -401.79056) (xy 168.149234 -401.723736)
			(xy 167.020682 -401.723736) (xy 166.992089 -401.778766) (xy 166.954142 -401.834352) (xy 166.932356 -401.860004)
			(xy 166.92657 -401.867156) (xy 166.92005 -401.884342) (xy 166.919656 -401.893532) (xy 166.919656 -402.3868)
			(xy 166.920076 -402.395986) (xy 166.926584 -402.41317) (xy 166.932356 -402.420328) (xy 166.954097 -402.446019)
			(xy 166.992047 -402.5016) (xy 167.023083 -402.561318) (xy 167.046758 -402.624317) (xy 167.062735 -402.689695)
			(xy 167.070783 -402.756513) (xy 167.070787 -402.823815) (xy 167.070779 -402.823878) (xy 170.348823 -402.823878)
			(xy 170.348828 -402.75645) (xy 170.356909 -402.689507) (xy 170.372951 -402.624015) (xy 170.396723 -402.560916)
			(xy 170.427882 -402.501119) (xy 170.465979 -402.445484) (xy 170.487848 -402.41982) (xy 170.493667 -402.412691)
			(xy 170.500167 -402.395488) (xy 170.500548 -402.386292) (xy 170.500548 -401.89404) (xy 170.500108 -401.884856)
			(xy 170.493614 -401.867672) (xy 170.487848 -401.860512) (xy 170.465963 -401.834864) (xy 170.427871 -401.779228)
			(xy 170.396719 -401.71943) (xy 170.372954 -401.656331) (xy 170.356918 -401.590839) (xy 170.348843 -401.523898)
			(xy 170.348845 -401.456472) (xy 170.356924 -401.389531) (xy 170.372963 -401.324041) (xy 170.396731 -401.260943)
			(xy 170.427887 -401.201146) (xy 170.465981 -401.145512) (xy 170.487848 -401.119848) (xy 170.493655 -401.112711)
			(xy 170.500162 -401.095514) (xy 170.500548 -401.08632) (xy 170.500548 -400.92884) (xy 170.501117 -400.91874)
			(xy 170.508832 -400.900073) (xy 170.523102 -400.885779) (xy 170.541757 -400.878033) (xy 170.551856 -400.877532)
			(xy 171.268136 -400.877532) (xy 171.278265 -400.877887) (xy 171.296975 -400.885653) (xy 171.311289 -400.899989)
			(xy 171.319028 -400.918711) (xy 171.319444 -400.92884) (xy 171.319444 -401.08632) (xy 171.319857 -401.095507)
			(xy 171.32637 -401.11269) (xy 171.332144 -401.119848) (xy 171.35399 -401.145528) (xy 171.392083 -401.20116)
			(xy 171.423238 -401.260953) (xy 171.447006 -401.324048) (xy 171.463044 -401.389536) (xy 171.471123 -401.456473)
			(xy 171.471124 -401.523897) (xy 171.46305 -401.590834) (xy 171.447015 -401.656323) (xy 171.42325 -401.719419)
			(xy 171.421001 -401.723737) (xy 172.549001 -401.723737) (xy 172.549003 -401.65643) (xy 172.55705 -401.589605)
			(xy 172.573027 -401.524221) (xy 172.596704 -401.461215) (xy 172.627743 -401.401491) (xy 172.665697 -401.345906)
			(xy 172.687488 -401.320254) (xy 172.693285 -401.313109) (xy 172.6998 -401.295918) (xy 172.700188 -401.286726)
			(xy 172.700188 -400.793458) (xy 172.699801 -400.784268) (xy 172.693272 -400.767084) (xy 172.687488 -400.75993)
			(xy 172.665705 -400.734274) (xy 172.627752 -400.678689) (xy 172.596716 -400.618966) (xy 172.573041 -400.555962)
			(xy 172.557066 -400.49058) (xy 172.549021 -400.423757) (xy 172.54902 -400.356452) (xy 172.557065 -400.289629)
			(xy 172.573038 -400.224246) (xy 172.596713 -400.161242) (xy 172.627748 -400.101519) (xy 172.665699 -400.045933)
			(xy 172.687488 -400.020282) (xy 172.693273 -400.013129) (xy 172.699795 -399.995944) (xy 172.700188 -399.986754)
			(xy 172.700188 -399.828766) (xy 172.700537 -399.818586) (xy 172.708343 -399.799781) (xy 172.722752 -399.785395)
			(xy 172.741569 -399.777621) (xy 172.75175 -399.777204) (xy 173.46803 -399.777204) (xy 173.478186 -399.777708)
			(xy 173.496949 -399.785486) (xy 173.511312 -399.799848) (xy 173.519091 -399.818611) (xy 173.519592 -399.828766)
			(xy 173.519592 -399.986754) (xy 173.520026 -399.995939) (xy 173.526523 -400.013123) (xy 173.532292 -400.020282)
			(xy 173.554085 -400.04593) (xy 173.592031 -400.101518) (xy 173.623063 -400.161242) (xy 173.646734 -400.224247)
			(xy 173.662705 -400.289629) (xy 173.670749 -400.356452) (xy 173.670748 -400.423757) (xy 173.662704 -400.490579)
			(xy 173.646731 -400.555962) (xy 173.623059 -400.618966) (xy 173.592027 -400.67869) (xy 173.554079 -400.734277)
			(xy 173.532292 -400.75993) (xy 173.526499 -400.767078) (xy 173.519983 -400.784266) (xy 173.519592 -400.793458)
			(xy 173.519592 -401.286726) (xy 173.519991 -401.295914) (xy 173.526513 -401.313099) (xy 173.532292 -401.320254)
			(xy 173.554057 -401.345924) (xy 173.592005 -401.401509) (xy 173.623037 -401.46123) (xy 173.64671 -401.524232)
			(xy 173.662683 -401.589612) (xy 173.670729 -401.656432) (xy 173.670731 -401.723735) (xy 173.662689 -401.790555)
			(xy 173.64672 -401.855936) (xy 173.623051 -401.918939) (xy 173.592022 -401.978663) (xy 173.554077 -402.034249)
			(xy 173.532292 -402.059902) (xy 173.526511 -402.067058) (xy 173.519987 -402.08424) (xy 173.519592 -402.09343)
			(xy 173.519592 -402.251418) (xy 173.519082 -402.261573) (xy 173.511308 -402.280337) (xy 173.496947 -402.294701)
			(xy 173.478185 -402.30248) (xy 173.46803 -402.30298) (xy 172.75175 -402.30298) (xy 172.741584 -402.302496)
			(xy 172.722794 -402.29473) (xy 172.708408 -402.280363) (xy 172.700618 -402.261584) (xy 172.700188 -402.251418)
			(xy 172.700188 -402.09343) (xy 172.699766 -402.084244) (xy 172.693261 -402.067059) (xy 172.687488 -402.059902)
			(xy 172.665677 -402.034268) (xy 172.627726 -401.97868) (xy 172.596691 -401.918955) (xy 172.573017 -401.855948)
			(xy 172.557044 -401.790563) (xy 172.549001 -401.723737) (xy 171.421001 -401.723737) (xy 171.392099 -401.779215)
			(xy 171.354009 -401.834848) (xy 171.332144 -401.860512) (xy 171.326353 -401.867661) (xy 171.319836 -401.884849)
			(xy 171.319444 -401.89404) (xy 171.319444 -402.386292) (xy 171.31987 -402.395477) (xy 171.326374 -402.412661)
			(xy 171.332144 -402.41982) (xy 171.353963 -402.445523) (xy 171.392057 -402.501151) (xy 171.423213 -402.560941)
			(xy 171.446982 -402.624033) (xy 171.463022 -402.689518) (xy 171.471103 -402.756453) (xy 171.471107 -402.823818)
			(xy 174.749143 -402.823818) (xy 174.749147 -402.75651) (xy 174.757196 -402.689684) (xy 174.773174 -402.624299)
			(xy 174.796852 -402.561292) (xy 174.827891 -402.501567) (xy 174.865845 -402.44598) (xy 174.887636 -402.420328)
			(xy 174.89345 -402.413195) (xy 174.899953 -402.395995) (xy 174.900336 -402.3868) (xy 174.900336 -401.893532)
			(xy 174.899902 -401.884348) (xy 174.893404 -401.867163) (xy 174.887636 -401.860004) (xy 174.865829 -401.834368)
			(xy 174.827881 -401.778779) (xy 174.796848 -401.719053) (xy 174.773177 -401.656047) (xy 174.757205 -401.590663)
			(xy 174.749163 -401.523838) (xy 174.749165 -401.456532) (xy 174.757211 -401.389708) (xy 174.773186 -401.324324)
			(xy 174.796861 -401.261319) (xy 174.827896 -401.201595) (xy 174.865847 -401.146008) (xy 174.887636 -401.120356)
			(xy 174.893438 -401.113215) (xy 174.899949 -401.096021) (xy 174.900336 -401.086828) (xy 174.900336 -400.92884)
			(xy 174.900755 -400.918684) (xy 174.908544 -400.899926) (xy 174.922943 -400.8856) (xy 174.94174 -400.877905)
			(xy 174.951898 -400.877532) (xy 175.668178 -400.877532) (xy 175.678302 -400.878044) (xy 175.697022 -400.885763)
			(xy 175.711378 -400.900042) (xy 175.7192 -400.918718) (xy 175.71974 -400.92884) (xy 175.71974 -401.086828)
			(xy 175.72015 -401.096015) (xy 175.726665 -401.113198) (xy 175.73244 -401.120356) (xy 175.754209 -401.146024)
			(xy 175.792159 -401.201608) (xy 175.823195 -401.261329) (xy 175.846869 -401.324331) (xy 175.862844 -401.389712)
			(xy 175.870891 -401.456533) (xy 175.870892 -401.523837) (xy 175.86285 -401.590658) (xy 175.846878 -401.65604)
			(xy 175.823207 -401.719044) (xy 175.792175 -401.778766) (xy 175.754227 -401.834352) (xy 175.73244 -401.860004)
			(xy 175.726652 -401.867155) (xy 175.720134 -401.884341) (xy 175.71974 -401.893532) (xy 175.71974 -402.3868)
			(xy 175.720164 -402.395985) (xy 175.726669 -402.413169) (xy 175.73244 -402.420328) (xy 175.754181 -402.446019)
			(xy 175.792133 -402.501599) (xy 175.823169 -402.561317) (xy 175.846846 -402.624317) (xy 175.862823 -402.689694)
			(xy 175.870871 -402.756513) (xy 175.870875 -402.823815) (xy 175.862835 -402.890634) (xy 175.846867 -402.956014)
			(xy 175.823199 -403.019017) (xy 175.79217 -403.078739) (xy 175.754225 -403.134324) (xy 175.73244 -403.159976)
			(xy 175.726621 -403.167105) (xy 175.720122 -403.184308) (xy 175.71974 -403.193504) (xy 175.71974 -403.351492)
			(xy 175.719273 -403.361641) (xy 175.711487 -403.380385) (xy 175.697105 -403.394707) (xy 175.678328 -403.402415)
			(xy 175.668178 -403.4028) (xy 174.951898 -403.4028) (xy 174.941776 -403.402276) (xy 174.923063 -403.394555)
			(xy 174.908708 -403.380281) (xy 174.900882 -403.361611) (xy 174.900336 -403.351492) (xy 174.900336 -403.193504)
			(xy 174.899916 -403.184318) (xy 174.893408 -403.167134) (xy 174.887636 -403.159976) (xy 174.865801 -403.134363)
			(xy 174.827854 -403.078771) (xy 174.796823 -403.019042) (xy 174.773153 -402.956032) (xy 174.757183 -402.890645)
			(xy 174.749143 -402.823818) (xy 171.471107 -402.823818) (xy 171.471107 -402.823874) (xy 171.463035 -402.89081)
			(xy 171.447003 -402.956298) (xy 171.423242 -403.019393) (xy 171.392094 -403.079187) (xy 171.354007 -403.13482)
			(xy 171.332144 -403.160484) (xy 171.326322 -403.167611) (xy 171.319824 -403.184816) (xy 171.319444 -403.194012)
			(xy 171.319444 -403.351492) (xy 171.318909 -403.361595) (xy 171.311183 -403.380264) (xy 171.296901 -403.394558)
			(xy 171.278238 -403.402301) (xy 171.268136 -403.4028) (xy 170.551856 -403.4028) (xy 170.541744 -403.402351)
			(xy 170.523065 -403.394599) (xy 170.508772 -403.380291) (xy 170.501039 -403.361604) (xy 170.500548 -403.351492)
			(xy 170.500548 -403.194012) (xy 170.500121 -403.184827) (xy 170.493618 -403.167643) (xy 170.487848 -403.160484)
			(xy 170.465935 -403.134858) (xy 170.427845 -403.079219) (xy 170.396693 -403.019418) (xy 170.37293 -402.956316)
			(xy 170.356896 -402.890822) (xy 170.348823 -402.823878) (xy 167.070779 -402.823878) (xy 167.062748 -402.890634)
			(xy 167.04678 -402.956014) (xy 167.023112 -403.019016) (xy 166.992084 -403.078738) (xy 166.954141 -403.134324)
			(xy 166.932356 -403.159976) (xy 166.926539 -403.167107) (xy 166.920038 -403.184308) (xy 166.919656 -403.193504)
			(xy 166.919656 -403.351492) (xy 166.919173 -403.361639) (xy 166.911391 -403.38038) (xy 166.897014 -403.394702)
			(xy 166.878242 -403.402412) (xy 166.868094 -403.4028) (xy 166.151814 -403.4028) (xy 166.141693 -403.402263)
			(xy 166.12298 -403.394547) (xy 166.108624 -403.380277) (xy 166.100798 -403.36161) (xy 166.100252 -403.351492)
			(xy 166.100252 -403.193504) (xy 166.099828 -403.184318) (xy 166.093323 -403.167135) (xy 166.087552 -403.159976)
			(xy 166.065717 -403.134363) (xy 166.027768 -403.078771) (xy 165.996736 -403.019042) (xy 165.973066 -402.956033)
			(xy 165.957096 -402.890646) (xy 165.949055 -402.823818) (xy 162.671019 -402.823818) (xy 162.671019 -402.823874)
			(xy 162.662948 -402.89081) (xy 162.646916 -402.956297) (xy 162.623155 -403.019392) (xy 162.592008 -403.079187)
			(xy 162.553923 -403.13482) (xy 162.53206 -403.160484) (xy 162.52624 -403.167613) (xy 162.51974 -403.184816)
			(xy 162.51936 -403.194012) (xy 162.51936 -403.351492) (xy 162.518976 -403.361619) (xy 162.511224 -403.38033)
			(xy 162.496896 -403.394646) (xy 162.478179 -403.402384) (xy 162.468052 -403.4028) (xy 161.751772 -403.4028)
			(xy 161.741661 -403.402338) (xy 161.722983 -403.394591) (xy 161.708689 -403.380287) (xy 161.700955 -403.361603)
			(xy 161.700464 -403.351492) (xy 161.700464 -403.194012) (xy 161.700034 -403.184827) (xy 161.693532 -403.167643)
			(xy 161.687764 -403.160484) (xy 161.665854 -403.134857) (xy 161.627769 -403.079216) (xy 161.596623 -403.019414)
			(xy 161.572863 -402.956313) (xy 161.556832 -402.890819) (xy 161.54876 -402.823877) (xy 154.57678 -402.823877)
			(xy 154.57678 -405.623648) (xy 159.349158 -405.623648) (xy 159.349158 -405.556343) (xy 159.357202 -405.48952)
			(xy 159.373175 -405.424138) (xy 159.396848 -405.361133) (xy 159.427881 -405.301409) (xy 159.465829 -405.245822)
			(xy 159.487616 -405.22017) (xy 159.49341 -405.213023) (xy 159.499926 -405.195834) (xy 159.500316 -405.186642)
			(xy 159.500316 -404.693374) (xy 159.499915 -404.684186) (xy 159.493395 -404.667002) (xy 159.487616 -404.659846)
			(xy 159.465851 -404.634176) (xy 159.427903 -404.578591) (xy 159.39687 -404.51887) (xy 159.373197 -404.455868)
			(xy 159.357223 -404.390488) (xy 159.349177 -404.323668) (xy 159.349175 -404.256365) (xy 159.357217 -404.189544)
			(xy 159.373187 -404.124164) (xy 159.396856 -404.06116) (xy 159.427886 -404.001437) (xy 159.46583 -403.94585)
			(xy 159.487616 -403.920198) (xy 159.493398 -403.913042) (xy 159.499921 -403.89586) (xy 159.500316 -403.88667)
			(xy 159.500316 -403.728682) (xy 159.500818 -403.718526) (xy 159.508594 -403.69976) (xy 159.522957 -403.685396)
			(xy 159.541722 -403.677619) (xy 159.551878 -403.67712) (xy 160.268158 -403.67712) (xy 160.278325 -403.677598)
			(xy 160.297115 -403.685366) (xy 160.311501 -403.699735) (xy 160.31929 -403.718516) (xy 160.31972 -403.728682)
			(xy 160.31972 -403.88667) (xy 160.32014 -403.895856) (xy 160.326646 -403.913041) (xy 160.33242 -403.920198)
			(xy 160.354231 -403.945832) (xy 160.392181 -404.00142) (xy 160.423216 -404.061146) (xy 160.446889 -404.124153)
			(xy 160.462862 -404.189538) (xy 160.470905 -404.256363) (xy 160.470903 -404.32367) (xy 160.462856 -404.390495)
			(xy 160.446879 -404.455879) (xy 160.423202 -404.518885) (xy 160.392164 -404.578608) (xy 160.35421 -404.634194)
			(xy 160.33242 -404.659846) (xy 160.326624 -404.666992) (xy 160.320108 -404.684182) (xy 160.31972 -404.693374)
			(xy 160.31972 -405.186642) (xy 160.320105 -405.195832) (xy 160.326636 -405.213016) (xy 160.33242 -405.22017)
			(xy 160.354203 -405.245826) (xy 160.392155 -405.301411) (xy 160.42319 -405.361134) (xy 160.446865 -405.424138)
			(xy 160.46284 -405.48952) (xy 160.470885 -405.556343) (xy 160.470886 -405.623648) (xy 160.462842 -405.690471)
			(xy 160.446868 -405.755853) (xy 160.423194 -405.818858) (xy 160.392159 -405.878581) (xy 160.354209 -405.934166)
			(xy 160.33242 -405.959818) (xy 160.326636 -405.966972) (xy 160.320113 -405.984156) (xy 160.31972 -405.993346)
			(xy 160.31972 -406.151334) (xy 160.319363 -406.161513) (xy 160.311559 -406.180317) (xy 160.297153 -406.194702)
			(xy 160.278338 -406.202478) (xy 160.268158 -406.202896) (xy 159.551878 -406.202896) (xy 159.541723 -406.202386)
			(xy 159.52296 -406.19461) (xy 159.508596 -406.18025) (xy 159.500817 -406.161489) (xy 159.500316 -406.151334)
			(xy 159.500316 -405.993346) (xy 159.49988 -405.984162) (xy 159.493384 -405.966977) (xy 159.487616 -405.959818)
			(xy 159.465823 -405.93417) (xy 159.427876 -405.878583) (xy 159.396844 -405.818858) (xy 159.373173 -405.755853)
			(xy 159.357201 -405.690471) (xy 159.349158 -405.623648) (xy 154.57678 -405.623648) (xy 154.57678 -406.723789)
			(xy 161.548771 -406.723789) (xy 161.548774 -406.656363) (xy 161.556853 -406.589423) (xy 161.572891 -406.523933)
			(xy 161.596657 -406.460835) (xy 161.627809 -406.401038) (xy 161.665899 -406.345402) (xy 161.687764 -406.319736)
			(xy 161.693578 -406.312604) (xy 161.70008 -406.295403) (xy 161.700464 -406.286208) (xy 161.700464 -405.793956)
			(xy 161.700061 -405.784768) (xy 161.693541 -405.767585) (xy 161.687764 -405.760428) (xy 161.665897 -405.734765)
			(xy 161.627811 -405.67913) (xy 161.596663 -405.619333) (xy 161.5729 -405.556236) (xy 161.556866 -405.490747)
			(xy 161.548791 -405.423809) (xy 161.548792 -405.356385) (xy 161.556867 -405.289447) (xy 161.572902 -405.223959)
			(xy 161.596665 -405.160862) (xy 161.627814 -405.101065) (xy 161.665901 -405.04543) (xy 161.687764 -405.019764)
			(xy 161.693566 -405.012623) (xy 161.700076 -404.995429) (xy 161.700464 -404.986236) (xy 161.700464 -404.828756)
			(xy 161.700948 -404.818649) (xy 161.708694 -404.799977) (xy 161.72299 -404.785685) (xy 161.741665 -404.777945)
			(xy 161.751772 -404.777448) (xy 162.468052 -404.777448) (xy 162.478165 -404.777954) (xy 162.496858 -404.785677)
			(xy 162.511172 -404.799965) (xy 162.518928 -404.818644) (xy 162.51936 -404.828756) (xy 162.51936 -404.986236)
			(xy 162.519762 -404.995424) (xy 162.526282 -405.012608) (xy 162.53206 -405.019764) (xy 162.553921 -405.045432)
			(xy 162.592013 -405.101065) (xy 162.623166 -405.16086) (xy 162.646932 -405.223957) (xy 162.662969 -405.289446)
			(xy 162.671046 -405.356385) (xy 162.671046 -405.423809) (xy 162.66297 -405.490748) (xy 162.646934 -405.556237)
			(xy 162.623168 -405.619334) (xy 162.620889 -405.623708) (xy 163.748926 -405.623708) (xy 163.748926 -405.556283)
			(xy 163.757003 -405.489344) (xy 163.77304 -405.423855) (xy 163.796805 -405.360758) (xy 163.827957 -405.300961)
			(xy 163.866047 -405.245327) (xy 163.887912 -405.219662) (xy 163.893709 -405.212517) (xy 163.900223 -405.195326)
			(xy 163.900612 -405.186134) (xy 163.900612 -404.693882) (xy 163.900208 -404.684694) (xy 163.89369 -404.66751)
			(xy 163.887912 -404.660354) (xy 163.866069 -404.634671) (xy 163.827979 -404.579039) (xy 163.796827 -404.519246)
			(xy 163.773061 -404.456151) (xy 163.757023 -404.390664) (xy 163.748946 -404.323728) (xy 163.748944 -404.256305)
			(xy 163.757018 -404.189368) (xy 163.773051 -404.12388) (xy 163.796813 -404.060784) (xy 163.827962 -404.000989)
			(xy 163.866049 -403.945355) (xy 163.887912 -403.91969) (xy 163.893697 -403.912536) (xy 163.900218 -403.895352)
			(xy 163.900612 -403.886162) (xy 163.900612 -403.728682) (xy 163.901111 -403.718558) (xy 163.908839 -403.699841)
			(xy 163.923121 -403.685486) (xy 163.941798 -403.677663) (xy 163.95192 -403.67712) (xy 164.6682 -403.67712)
			(xy 164.678357 -403.677522) (xy 164.697113 -403.685321) (xy 164.711437 -403.699724) (xy 164.719133 -403.718523)
			(xy 164.719508 -403.728682) (xy 164.719508 -403.886162) (xy 164.719935 -403.895347) (xy 164.726437 -403.912532)
			(xy 164.732208 -403.91969) (xy 164.754093 -403.945338) (xy 164.792181 -404.000975) (xy 164.82333 -404.060774)
			(xy 164.847093 -404.123873) (xy 164.863126 -404.189364) (xy 164.8712 -404.256304) (xy 164.871198 -404.323729)
			(xy 164.86312 -404.390669) (xy 164.847083 -404.456159) (xy 164.823317 -404.519257) (xy 164.792164 -404.579054)
			(xy 164.754073 -404.634689) (xy 164.732208 -404.660354) (xy 164.726407 -404.667496) (xy 164.719895 -404.684689)
			(xy 164.719508 -404.693882) (xy 164.719508 -405.186134) (xy 164.7199 -405.195323) (xy 164.726426 -405.212508)
			(xy 164.732208 -405.219662) (xy 164.754066 -405.245332) (xy 164.792154 -405.300966) (xy 164.823305 -405.360762)
			(xy 164.847069 -405.423858) (xy 164.863104 -405.489346) (xy 164.871181 -405.556284) (xy 164.871181 -405.623707)
			(xy 164.863106 -405.690645) (xy 164.847072 -405.756133) (xy 164.823308 -405.81923) (xy 164.792159 -405.879026)
			(xy 164.754071 -405.934661) (xy 164.732208 -405.960326) (xy 164.726419 -405.967477) (xy 164.719899 -405.984663)
			(xy 164.719508 -405.993854) (xy 164.719508 -406.151334) (xy 164.719003 -406.161457) (xy 164.711273 -406.18017)
			(xy 164.696993 -406.194523) (xy 164.67832 -406.20235) (xy 164.6682 -406.202896) (xy 163.95192 -406.202896)
			(xy 163.941767 -406.202462) (xy 163.923014 -406.194672) (xy 163.90869 -406.180279) (xy 163.90099 -406.161489)
			(xy 163.900612 -406.151334) (xy 163.900612 -405.993854) (xy 163.900173 -405.98467) (xy 163.893679 -405.967485)
			(xy 163.887912 -405.960326) (xy 163.866042 -405.934666) (xy 163.827952 -405.879031) (xy 163.796801 -405.819234)
			(xy 163.773037 -405.756137) (xy 163.757001 -405.690647) (xy 163.748926 -405.623708) (xy 162.620889 -405.623708)
			(xy 162.592016 -405.67913) (xy 162.553925 -405.734763) (xy 162.53206 -405.760428) (xy 162.526264 -405.767573)
			(xy 162.51975 -405.784764) (xy 162.51936 -405.793956) (xy 162.51936 -406.286208) (xy 162.519775 -406.295394)
			(xy 162.526286 -406.312578) (xy 162.53206 -406.319736) (xy 162.553894 -406.345426) (xy 162.591986 -406.401056)
			(xy 162.623141 -406.460849) (xy 162.646908 -406.523942) (xy 162.662947 -406.589429) (xy 162.671026 -406.656365)
			(xy 162.671029 -406.72373) (xy 165.949066 -406.72373) (xy 165.949069 -406.656422) (xy 165.957117 -406.589597)
			(xy 165.973094 -406.524213) (xy 165.996771 -406.461207) (xy 166.027808 -406.401483) (xy 166.065762 -406.345896)
			(xy 166.087552 -406.320244) (xy 166.093361 -406.313108) (xy 166.099867 -406.29591) (xy 166.100252 -406.286716)
			(xy 166.100252 -405.793448) (xy 166.099807 -405.784265) (xy 166.093316 -405.767081) (xy 166.087552 -405.75992)
			(xy 166.06576 -405.734271) (xy 166.027811 -405.678685) (xy 165.996777 -405.618961) (xy 165.973104 -405.555956)
			(xy 165.957131 -405.490573) (xy 165.949087 -405.42375) (xy 165.949087 -405.356444) (xy 165.957132 -405.289621)
			(xy 165.973105 -405.224239) (xy 165.996779 -405.161234) (xy 166.027814 -405.10151) (xy 166.065764 -405.045924)
			(xy 166.087552 -405.020272) (xy 166.093349 -405.013128) (xy 166.099862 -404.995936) (xy 166.100252 -404.986744)
			(xy 166.100252 -404.828756) (xy 166.100685 -404.818605) (xy 166.108486 -404.799861) (xy 166.122878 -404.785541)
			(xy 166.141661 -404.777834) (xy 166.151814 -404.777448) (xy 166.868094 -404.777448) (xy 166.878221 -404.777932)
			(xy 166.896944 -404.785659) (xy 166.911301 -404.799946) (xy 166.919119 -404.818631) (xy 166.919656 -404.828756)
			(xy 166.919656 -404.986744) (xy 166.920055 -404.995932) (xy 166.926578 -405.013116) (xy 166.932356 -405.020272)
			(xy 166.95414 -405.045927) (xy 166.992089 -405.101513) (xy 167.023123 -405.161236) (xy 167.046796 -405.22424)
			(xy 167.062769 -405.289622) (xy 167.070814 -405.356445) (xy 167.070814 -405.423749) (xy 167.06277 -405.490572)
			(xy 167.046798 -405.555954) (xy 167.023125 -405.618958) (xy 167.020688 -405.623648) (xy 168.149245 -405.623648)
			(xy 168.149246 -405.556343) (xy 168.15729 -405.489521) (xy 168.173263 -405.424139) (xy 168.196934 -405.361134)
			(xy 168.227966 -405.30141) (xy 168.265913 -405.245823) (xy 168.2877 -405.22017) (xy 168.293492 -405.213021)
			(xy 168.300009 -405.195834) (xy 168.3004 -405.186642) (xy 168.3004 -404.693374) (xy 168.300003 -404.684185)
			(xy 168.29348 -404.667001) (xy 168.2877 -404.659846) (xy 168.265935 -404.634176) (xy 168.227988 -404.578591)
			(xy 168.196956 -404.518869) (xy 168.173284 -404.455867) (xy 168.15731 -404.390488) (xy 168.149265 -404.323668)
			(xy 168.149263 -404.256365) (xy 168.157305 -404.189545) (xy 168.173274 -404.124164) (xy 168.196943 -404.061161)
			(xy 168.227971 -404.001438) (xy 168.265915 -403.945851) (xy 168.2877 -403.920198) (xy 168.29348 -403.913041)
			(xy 168.300005 -403.89586) (xy 168.3004 -403.88667) (xy 168.3004 -403.728682) (xy 168.300917 -403.718528)
			(xy 168.308691 -403.699765) (xy 168.323049 -403.685402) (xy 168.341808 -403.677621) (xy 168.351962 -403.67712)
			(xy 169.068242 -403.67712) (xy 169.0784 -403.677599) (xy 169.097167 -403.685383) (xy 169.11153 -403.699753)
			(xy 169.119306 -403.718524) (xy 169.119804 -403.728682) (xy 169.119804 -403.88667) (xy 169.120228 -403.895856)
			(xy 169.126732 -403.91304) (xy 169.132504 -403.920198) (xy 169.154312 -403.945833) (xy 169.192257 -404.001423)
			(xy 169.223287 -404.061149) (xy 169.246957 -404.124156) (xy 169.262927 -404.18954) (xy 169.270969 -404.256364)
			(xy 169.270967 -404.32367) (xy 169.262921 -404.390493) (xy 169.246947 -404.455876) (xy 169.223274 -404.518881)
			(xy 169.19224 -404.578606) (xy 169.154292 -404.634193) (xy 169.132504 -404.659846) (xy 169.126706 -404.66699)
			(xy 169.120192 -404.684181) (xy 169.119804 -404.693374) (xy 169.119804 -405.186642) (xy 169.120193 -405.195832)
			(xy 169.126721 -405.213016) (xy 169.132504 -405.22017) (xy 169.154284 -405.245828) (xy 169.192231 -405.301414)
			(xy 169.223262 -405.361137) (xy 169.246933 -405.424141) (xy 169.262905 -405.489522) (xy 169.270949 -405.556344)
			(xy 169.27095 -405.623647) (xy 169.262907 -405.690469) (xy 169.246936 -405.75585) (xy 169.223266 -405.818854)
			(xy 169.192235 -405.878578) (xy 169.15429 -405.934165) (xy 169.132504 -405.959818) (xy 169.126718 -405.966971)
			(xy 169.120197 -405.984155) (xy 169.119804 -405.993346) (xy 169.119804 -406.151334) (xy 169.119296 -406.161489)
			(xy 169.111518 -406.180251) (xy 169.097157 -406.194613) (xy 169.078397 -406.202394) (xy 169.068242 -406.202896)
			(xy 168.351962 -406.202896) (xy 168.341806 -406.202399) (xy 168.323042 -406.194618) (xy 168.30868 -406.180254)
			(xy 168.300901 -406.16149) (xy 168.3004 -406.151334) (xy 168.3004 -405.993346) (xy 168.299968 -405.984161)
			(xy 168.293469 -405.966977) (xy 168.2877 -405.959818) (xy 168.265908 -405.93417) (xy 168.227961 -405.878582)
			(xy 168.196931 -405.818858) (xy 168.17326 -405.755853) (xy 168.157289 -405.69047) (xy 168.149245 -405.623648)
			(xy 167.020688 -405.623648) (xy 166.992092 -405.678681) (xy 166.954143 -405.734268) (xy 166.932356 -405.75992)
			(xy 166.926563 -405.767067) (xy 166.920047 -405.784256) (xy 166.919656 -405.793448) (xy 166.919656 -406.286716)
			(xy 166.920068 -406.295903) (xy 166.926582 -406.313087) (xy 166.932356 -406.320244) (xy 166.954112 -406.345922)
			(xy 166.992062 -406.401505) (xy 167.023097 -406.461225) (xy 167.046772 -406.524226) (xy 167.062747 -406.589605)
			(xy 167.070794 -406.656425) (xy 167.070797 -406.723727) (xy 167.070789 -406.72379) (xy 170.348835 -406.72379)
			(xy 170.348838 -406.656362) (xy 170.356917 -406.589421) (xy 170.372958 -406.52393) (xy 170.396728 -406.460831)
			(xy 170.427885 -406.401034) (xy 170.46598 -406.3454) (xy 170.487848 -406.319736) (xy 170.49366 -406.312602)
			(xy 170.500164 -406.295403) (xy 170.500548 -406.286208) (xy 170.500548 -405.793956) (xy 170.500148 -405.784768)
			(xy 170.493626 -405.767584) (xy 170.487848 -405.760428) (xy 170.465978 -405.734767) (xy 170.427887 -405.679133)
			(xy 170.396733 -405.619337) (xy 170.372967 -405.556239) (xy 170.356931 -405.490749) (xy 170.348854 -405.423809)
			(xy 170.348855 -405.356385) (xy 170.356932 -405.289445) (xy 170.372969 -405.223955) (xy 170.396736 -405.160858)
			(xy 170.42789 -405.101062) (xy 170.465982 -405.045428) (xy 170.487848 -405.019764) (xy 170.493648 -405.012622)
			(xy 170.500159 -404.995429) (xy 170.500548 -404.986236) (xy 170.500548 -404.828756) (xy 170.501048 -404.818651)
			(xy 170.50879 -404.799982) (xy 170.523082 -404.78569) (xy 170.541751 -404.777948) (xy 170.551856 -404.777448)
			(xy 171.268136 -404.777448) (xy 171.278241 -404.777954) (xy 171.29691 -404.785694) (xy 171.311201 -404.799984)
			(xy 171.318944 -404.818651) (xy 171.319444 -404.828756) (xy 171.319444 -404.986236) (xy 171.31985 -404.995423)
			(xy 171.326368 -405.012607) (xy 171.332144 -405.019764) (xy 171.354006 -405.045432) (xy 171.392099 -405.101064)
			(xy 171.423253 -405.16086) (xy 171.447019 -405.223956) (xy 171.463057 -405.289446) (xy 171.471134 -405.356385)
			(xy 171.471134 -405.423809) (xy 171.463058 -405.490748) (xy 171.447021 -405.556238) (xy 171.423255 -405.619335)
			(xy 171.421007 -405.623649) (xy 172.549012 -405.623649) (xy 172.549013 -405.556342) (xy 172.557058 -405.489518)
			(xy 172.573033 -405.424135) (xy 172.596709 -405.36113) (xy 172.627746 -405.301407) (xy 172.665698 -405.245822)
			(xy 172.687488 -405.22017) (xy 172.693278 -405.21302) (xy 172.699797 -405.195833) (xy 172.700188 -405.186642)
			(xy 172.700188 -404.693374) (xy 172.699793 -404.684185) (xy 172.693269 -404.667001) (xy 172.687488 -404.659846)
			(xy 172.66572 -404.634177) (xy 172.627768 -404.578594) (xy 172.596731 -404.518873) (xy 172.573055 -404.455871)
			(xy 172.557079 -404.39049) (xy 172.549032 -404.323669) (xy 172.54903 -404.256364) (xy 172.557073 -404.189542)
			(xy 172.573045 -404.124161) (xy 172.596717 -404.061157) (xy 172.627751 -404.001435) (xy 172.6657 -403.945849)
			(xy 172.687488 -403.920198) (xy 172.693267 -403.91304) (xy 172.699792 -403.895859) (xy 172.700188 -403.88667)
			(xy 172.700188 -403.728682) (xy 172.70055 -403.718503) (xy 172.708351 -403.699698) (xy 172.722756 -403.685313)
			(xy 172.74157 -403.677537) (xy 172.75175 -403.67712) (xy 173.46803 -403.67712) (xy 173.478187 -403.677608)
			(xy 173.496954 -403.685389) (xy 173.511317 -403.699756) (xy 173.519094 -403.718524) (xy 173.519592 -403.728682)
			(xy 173.519592 -403.88667) (xy 173.520018 -403.895855) (xy 173.526521 -403.91304) (xy 173.532292 -403.920198)
			(xy 173.5541 -403.945833) (xy 173.592047 -404.001422) (xy 173.623077 -404.061149) (xy 173.646747 -404.124155)
			(xy 173.662718 -404.189539) (xy 173.67076 -404.256363) (xy 173.670758 -404.32367) (xy 173.662712 -404.390493)
			(xy 173.646738 -404.455876) (xy 173.623064 -404.518882) (xy 173.59203 -404.578606) (xy 173.55408 -404.634193)
			(xy 173.532292 -404.659846) (xy 173.526492 -404.666989) (xy 173.51998 -404.684181) (xy 173.519592 -404.693374)
			(xy 173.519592 -405.186642) (xy 173.519984 -405.195831) (xy 173.52651 -405.213015) (xy 173.532292 -405.22017)
			(xy 173.554073 -405.245827) (xy 173.59202 -405.301414) (xy 173.623052 -405.361137) (xy 173.646723 -405.424141)
			(xy 173.662696 -405.489522) (xy 173.67074 -405.556343) (xy 173.670741 -405.623647) (xy 173.662698 -405.690469)
			(xy 173.646726 -405.755851) (xy 173.623055 -405.818855) (xy 173.592025 -405.878578) (xy 173.554078 -405.934165)
			(xy 173.532292 -405.959818) (xy 173.526504 -405.96697) (xy 173.519985 -405.984155) (xy 173.519592 -405.993346)
			(xy 173.519592 -406.151334) (xy 173.519095 -406.16149) (xy 173.511315 -406.180254) (xy 173.496951 -406.194617)
			(xy 173.478186 -406.202396) (xy 173.46803 -406.202896) (xy 172.75175 -406.202896) (xy 172.741586 -406.202396)
			(xy 172.722799 -406.194634) (xy 172.708413 -406.180272) (xy 172.70062 -406.161497) (xy 172.700188 -406.151334)
			(xy 172.700188 -405.993346) (xy 172.699759 -405.984161) (xy 172.693259 -405.966976) (xy 172.687488 -405.959818)
			(xy 172.665693 -405.934171) (xy 172.627741 -405.878585) (xy 172.596705 -405.818861) (xy 172.573031 -405.755856)
			(xy 172.557057 -405.690473) (xy 172.549012 -405.623649) (xy 171.421007 -405.623649) (xy 171.392102 -405.67913)
			(xy 171.35401 -405.734764) (xy 171.332144 -405.760428) (xy 171.326346 -405.767572) (xy 171.319834 -405.784764)
			(xy 171.319444 -405.793956) (xy 171.319444 -406.286208) (xy 171.319863 -406.295394) (xy 171.326372 -406.312578)
			(xy 171.332144 -406.319736) (xy 171.353978 -406.345426) (xy 171.392072 -406.401056) (xy 171.423227 -406.460848)
			(xy 171.446996 -406.523942) (xy 171.463035 -406.589428) (xy 171.471114 -406.656365) (xy 171.471117 -406.72373)
			(xy 174.749154 -406.72373) (xy 174.749157 -406.656422) (xy 174.757205 -406.589597) (xy 174.773181 -406.524213)
			(xy 174.796857 -406.461208) (xy 174.827894 -406.401483) (xy 174.865846 -406.345896) (xy 174.887636 -406.320244)
			(xy 174.893443 -406.313107) (xy 174.899951 -406.29591) (xy 174.900336 -406.286716) (xy 174.900336 -405.793448)
			(xy 174.899895 -405.784264) (xy 174.893402 -405.76708) (xy 174.887636 -405.75992) (xy 174.865844 -405.734271)
			(xy 174.827896 -405.678684) (xy 174.796863 -405.61896) (xy 174.77319 -405.555955) (xy 174.757218 -405.490573)
			(xy 174.749174 -405.42375) (xy 174.749174 -405.356444) (xy 174.757219 -405.289621) (xy 174.773192 -405.224239)
			(xy 174.796865 -405.161234) (xy 174.827899 -405.101511) (xy 174.865848 -405.045924) (xy 174.887636 -405.020272)
			(xy 174.893432 -405.013126) (xy 174.899946 -404.995936) (xy 174.900336 -404.986744) (xy 174.900336 -404.828756)
			(xy 174.900686 -404.818594) (xy 174.908503 -404.799834) (xy 174.922922 -404.785511) (xy 174.941734 -404.77782)
			(xy 174.951898 -404.777448) (xy 175.668178 -404.777448) (xy 175.678304 -404.777945) (xy 175.697027 -404.785667)
			(xy 175.711384 -404.79995) (xy 175.719202 -404.818632) (xy 175.71974 -404.828756) (xy 175.71974 -404.986744)
			(xy 175.720142 -404.995932) (xy 175.726663 -405.013115) (xy 175.73244 -405.020272) (xy 175.754224 -405.045927)
			(xy 175.792175 -405.101513) (xy 175.823209 -405.161236) (xy 175.846883 -405.22424) (xy 175.862857 -405.289622)
			(xy 175.870902 -405.356444) (xy 175.870902 -405.42375) (xy 175.862858 -405.490572) (xy 175.846885 -405.555954)
			(xy 175.823212 -405.618959) (xy 175.792178 -405.678682) (xy 175.754228 -405.734268) (xy 175.73244 -405.75992)
			(xy 175.726645 -405.767066) (xy 175.720131 -405.784256) (xy 175.71974 -405.793448) (xy 175.71974 -406.286716)
			(xy 175.720156 -406.295902) (xy 175.726667 -406.313086) (xy 175.73244 -406.320244) (xy 175.754197 -406.345922)
			(xy 175.792148 -406.401504) (xy 175.823184 -406.461224) (xy 175.846859 -406.524225) (xy 175.862835 -406.589604)
			(xy 175.870882 -406.656424) (xy 175.870885 -406.723727) (xy 175.862844 -406.790548) (xy 175.846873 -406.855929)
			(xy 175.823203 -406.918932) (xy 175.792173 -406.978655) (xy 175.754226 -407.03424) (xy 175.73244 -407.059892)
			(xy 175.726657 -407.067046) (xy 175.720136 -407.08423) (xy 175.71974 -407.09342) (xy 175.71974 -407.251408)
			(xy 175.719286 -407.261558) (xy 175.711495 -407.280302) (xy 175.697109 -407.294624) (xy 175.678329 -407.302331)
			(xy 175.668178 -407.302716) (xy 174.951898 -407.302716) (xy 174.941766 -407.302274) (xy 174.923036 -407.294537)
			(xy 174.908679 -407.280237) (xy 174.900867 -407.261538) (xy 174.900336 -407.251408) (xy 174.900336 -407.09342)
			(xy 174.899908 -407.084235) (xy 174.893406 -407.067051) (xy 174.887636 -407.059892) (xy 174.865817 -407.034266)
			(xy 174.827869 -406.978676) (xy 174.796837 -406.918948) (xy 174.773167 -406.85594) (xy 174.757196 -406.790555)
			(xy 174.749154 -406.72373) (xy 171.471117 -406.72373) (xy 171.471117 -406.723787) (xy 171.463044 -406.790724)
			(xy 171.44701 -406.856212) (xy 171.423247 -406.919308) (xy 171.392097 -406.979103) (xy 171.354008 -407.034736)
			(xy 171.332144 -407.0604) (xy 171.326358 -407.067552) (xy 171.319839 -407.084738) (xy 171.319444 -407.093928)
			(xy 171.319444 -407.251408) (xy 171.318922 -407.261512) (xy 171.31119 -407.280182) (xy 171.296905 -407.294475)
			(xy 171.278239 -407.302217) (xy 171.268136 -407.302716) (xy 170.551856 -407.302716) (xy 170.541746 -407.302251)
			(xy 170.52307 -407.294502) (xy 170.508778 -407.280199) (xy 170.501042 -407.261518) (xy 170.500548 -407.251408)
			(xy 170.500548 -407.093928) (xy 170.500114 -407.084744) (xy 170.493616 -407.067559) (xy 170.487848 -407.0604)
			(xy 170.465951 -407.034762) (xy 170.42786 -406.979124) (xy 170.396708 -406.919325) (xy 170.372944 -406.856224)
			(xy 170.356909 -406.790732) (xy 170.348835 -406.72379) (xy 167.070789 -406.72379) (xy 167.062756 -406.790548)
			(xy 167.046786 -406.855928) (xy 167.023117 -406.918931) (xy 166.992087 -406.978654) (xy 166.954142 -407.03424)
			(xy 166.932356 -407.059892) (xy 166.926575 -407.067048) (xy 166.920052 -407.08423) (xy 166.919656 -407.09342)
			(xy 166.919656 -407.251408) (xy 166.919186 -407.261556) (xy 166.911398 -407.280297) (xy 166.897017 -407.294618)
			(xy 166.878243 -407.302328) (xy 166.868094 -407.302716) (xy 166.151814 -407.302716) (xy 166.141683 -407.302261)
			(xy 166.122954 -407.294529) (xy 166.108595 -407.280233) (xy 166.100783 -407.261537) (xy 166.100252 -407.251408)
			(xy 166.100252 -407.09342) (xy 166.099821 -407.084235) (xy 166.093321 -407.067051) (xy 166.087552 -407.059892)
			(xy 166.065732 -407.034266) (xy 166.027784 -406.978676) (xy 165.996751 -406.918949) (xy 165.973079 -406.855941)
			(xy 165.957108 -406.790556) (xy 165.949066 -406.72373) (xy 162.671029 -406.72373) (xy 162.671029 -406.723787)
			(xy 162.662956 -406.790724) (xy 162.646923 -406.856212) (xy 162.62316 -406.919307) (xy 162.592011 -406.979102)
			(xy 162.553923 -407.034735) (xy 162.53206 -407.0604) (xy 162.526276 -407.067554) (xy 162.519755 -407.084738)
			(xy 162.51936 -407.093928) (xy 162.51936 -407.251408) (xy 162.518989 -407.261536) (xy 162.511231 -407.280247)
			(xy 162.4969 -407.294563) (xy 162.47818 -407.3023) (xy 162.468052 -407.302716) (xy 161.751772 -407.302716)
			(xy 161.741663 -407.302238) (xy 161.722988 -407.294494) (xy 161.708694 -407.280196) (xy 161.700958 -407.261517)
			(xy 161.700464 -407.251408) (xy 161.700464 -407.093928) (xy 161.700026 -407.084744) (xy 161.69353 -407.06756)
			(xy 161.687764 -407.0604) (xy 161.66587 -407.03476) (xy 161.627784 -406.979121) (xy 161.596637 -406.919321)
			(xy 161.572876 -406.856221) (xy 161.556844 -406.790729) (xy 161.548771 -406.723789) (xy 154.57678 -406.723789)
			(xy 154.57678 -409.523827) (xy 159.349136 -409.523827) (xy 159.34914 -409.456519) (xy 159.357187 -409.389695)
			(xy 159.373163 -409.324311) (xy 159.396839 -409.261305) (xy 159.427875 -409.20158) (xy 159.465827 -409.145992)
			(xy 159.487616 -409.12034) (xy 159.493422 -409.113202) (xy 159.499931 -409.096006) (xy 159.500316 -409.086812)
			(xy 159.500316 -408.593544) (xy 159.499881 -408.58436) (xy 159.493384 -408.567175) (xy 159.487616 -408.560016)
			(xy 159.465821 -408.53437) (xy 159.427874 -408.478782) (xy 159.396842 -408.419058) (xy 159.373171 -408.356052)
			(xy 159.357199 -408.29067) (xy 159.349156 -408.223847) (xy 159.349157 -408.156541) (xy 159.357201 -408.089719)
			(xy 159.373175 -408.024336) (xy 159.396847 -407.961331) (xy 159.42788 -407.901607) (xy 159.465828 -407.84602)
			(xy 159.487616 -407.820368) (xy 159.49341 -407.813221) (xy 159.499926 -407.796032) (xy 159.500316 -407.78684)
			(xy 159.500316 -407.628852) (xy 159.500683 -407.618693) (xy 159.508497 -407.599936) (xy 159.522911 -407.585614)
			(xy 159.541716 -407.577919) (xy 159.551878 -407.577544) (xy 160.268158 -407.577544) (xy 160.278283 -407.578061)
			(xy 160.297003 -407.585776) (xy 160.311361 -407.600053) (xy 160.319181 -407.61873) (xy 160.31972 -407.628852)
			(xy 160.31972 -407.78684) (xy 160.320107 -407.79603) (xy 160.326636 -407.813214) (xy 160.33242 -407.820368)
			(xy 160.354201 -407.846026) (xy 160.392153 -407.901611) (xy 160.423189 -407.961333) (xy 160.446864 -408.024337)
			(xy 160.462838 -408.089719) (xy 160.470884 -408.156541) (xy 160.470885 -408.223847) (xy 160.462841 -408.290669)
			(xy 160.446867 -408.356052) (xy 160.423194 -408.419056) (xy 160.392159 -408.478779) (xy 160.354208 -408.534364)
			(xy 160.33242 -408.560016) (xy 160.326636 -408.567171) (xy 160.320113 -408.584354) (xy 160.31972 -408.593544)
			(xy 160.31972 -409.086812) (xy 160.32012 -409.096) (xy 160.32664 -409.113185) (xy 160.33242 -409.12034)
			(xy 160.354174 -409.146021) (xy 160.392126 -409.201602) (xy 160.423163 -409.261321) (xy 160.44684 -409.324322)
			(xy 160.462817 -409.389701) (xy 160.470864 -409.456521) (xy 160.470867 -409.523824) (xy 160.462826 -409.590645)
			(xy 160.446856 -409.656026) (xy 160.423185 -409.719029) (xy 160.392154 -409.778751) (xy 160.354207 -409.834336)
			(xy 160.33242 -409.859988) (xy 160.326606 -409.867121) (xy 160.320101 -409.884321) (xy 160.31972 -409.893516)
			(xy 160.31972 -410.051504) (xy 160.319282 -410.061656) (xy 160.311489 -410.080404) (xy 160.297098 -410.094727)
			(xy 160.278312 -410.10243) (xy 160.268158 -410.102812) (xy 159.551878 -410.102812) (xy 159.541756 -410.102293)
			(xy 159.523044 -410.094568) (xy 159.508691 -410.080292) (xy 159.500863 -410.061623) (xy 159.500316 -410.051504)
			(xy 159.500316 -409.893516) (xy 159.499894 -409.88433) (xy 159.493388 -409.867146) (xy 159.487616 -409.859988)
			(xy 159.465794 -409.834365) (xy 159.427847 -409.778774) (xy 159.396817 -409.719046) (xy 159.373147 -409.656038)
			(xy 159.357177 -409.590652) (xy 159.349136 -409.523827) (xy 154.57678 -409.523827) (xy 154.57678 -410.6237)
			(xy 161.548783 -410.6237) (xy 161.548784 -410.556276) (xy 161.556861 -410.489337) (xy 161.572897 -410.423848)
			(xy 161.596662 -410.36075) (xy 161.627812 -410.300953) (xy 161.6659 -410.245318) (xy 161.687764 -410.219652)
			(xy 161.693571 -410.212515) (xy 161.700078 -410.195318) (xy 161.700464 -410.186124) (xy 161.700464 -409.693872)
			(xy 161.700053 -409.684685) (xy 161.693538 -409.667502) (xy 161.687764 -409.660344) (xy 161.665913 -409.634668)
			(xy 161.627826 -409.579035) (xy 161.596677 -409.519239) (xy 161.572914 -409.456144) (xy 161.556879 -409.390657)
			(xy 161.548802 -409.32372) (xy 161.548801 -409.256298) (xy 161.556875 -409.189361) (xy 161.572909 -409.123873)
			(xy 161.59667 -409.060777) (xy 161.627817 -409.000981) (xy 161.665902 -408.945346) (xy 161.687764 -408.91968)
			(xy 161.693559 -408.912534) (xy 161.700073 -408.895344) (xy 161.700464 -408.886152) (xy 161.700464 -408.728672)
			(xy 161.700961 -408.718566) (xy 161.708701 -408.699894) (xy 161.722994 -408.685601) (xy 161.741666 -408.677861)
			(xy 161.751772 -408.677364) (xy 162.468052 -408.677364) (xy 162.478167 -408.677854) (xy 162.496863 -408.68558)
			(xy 162.511177 -408.699874) (xy 162.518931 -408.718558) (xy 162.51936 -408.728672) (xy 162.51936 -408.886152)
			(xy 162.519802 -408.895336) (xy 162.526295 -408.91252) (xy 162.53206 -408.91968) (xy 162.553937 -408.945335)
			(xy 162.592028 -409.00097) (xy 162.623181 -409.060767) (xy 162.646946 -409.123866) (xy 162.662982 -409.189356)
			(xy 162.671057 -409.256296) (xy 162.671056 -409.323722) (xy 162.662978 -409.390662) (xy 162.64694 -409.456152)
			(xy 162.623173 -409.519249) (xy 162.620757 -409.523886) (xy 163.748905 -409.523886) (xy 163.748908 -409.45646)
			(xy 163.756988 -409.389519) (xy 163.773027 -409.324027) (xy 163.796796 -409.260929) (xy 163.827952 -409.201132)
			(xy 163.866045 -409.145497) (xy 163.887912 -409.119832) (xy 163.893721 -409.112696) (xy 163.900228 -409.095498)
			(xy 163.900612 -409.086304) (xy 163.900612 -408.594052) (xy 163.900174 -408.584868) (xy 163.893679 -408.567683)
			(xy 163.887912 -408.560524) (xy 163.86604 -408.534865) (xy 163.82795 -408.47923) (xy 163.796799 -408.419433)
			(xy 163.773035 -408.356335) (xy 163.757 -408.290845) (xy 163.748925 -408.223906) (xy 163.748925 -408.156482)
			(xy 163.757002 -408.089543) (xy 163.773039 -408.024053) (xy 163.796804 -407.960956) (xy 163.827957 -407.901159)
			(xy 163.866047 -407.845525) (xy 163.887912 -407.81986) (xy 163.893709 -407.812715) (xy 163.900223 -407.795524)
			(xy 163.900612 -407.786332) (xy 163.900612 -407.628852) (xy 163.901046 -407.618739) (xy 163.908802 -407.600057)
			(xy 163.923114 -407.585764) (xy 163.941806 -407.578033) (xy 163.95192 -407.577544) (xy 164.6682 -407.577544)
			(xy 164.678302 -407.578084) (xy 164.696969 -407.585811) (xy 164.711262 -407.60009) (xy 164.719007 -407.618751)
			(xy 164.719508 -407.628852) (xy 164.719508 -407.786332) (xy 164.719901 -407.795521) (xy 164.726426 -407.812705)
			(xy 164.732208 -407.81986) (xy 164.754064 -407.845532) (xy 164.792152 -407.901166) (xy 164.823303 -407.960961)
			(xy 164.847067 -408.024057) (xy 164.863103 -408.089545) (xy 164.871179 -408.156483) (xy 164.87118 -408.223905)
			(xy 164.863105 -408.290843) (xy 164.847071 -408.356332) (xy 164.823308 -408.419428) (xy 164.792158 -408.479224)
			(xy 164.754071 -408.534859) (xy 164.732208 -408.560524) (xy 164.72642 -408.567675) (xy 164.7199 -408.584861)
			(xy 164.719508 -408.594052) (xy 164.719508 -409.086304) (xy 164.719915 -409.095492) (xy 164.726431 -409.112676)
			(xy 164.732208 -409.119832) (xy 164.754036 -409.145527) (xy 164.792126 -409.201157) (xy 164.823277 -409.260949)
			(xy 164.847043 -409.324042) (xy 164.863081 -409.389528) (xy 164.87116 -409.456463) (xy 164.871163 -409.523883)
			(xy 164.863091 -409.590819) (xy 164.847059 -409.656306) (xy 164.8233 -409.719401) (xy 164.792153 -409.779196)
			(xy 164.75407 -409.834831) (xy 164.732208 -409.860496) (xy 164.726432 -409.867656) (xy 164.719905 -409.884835)
			(xy 164.719508 -409.894024) (xy 164.719508 -410.051504) (xy 164.719018 -410.061612) (xy 164.711281 -410.080289)
			(xy 164.696985 -410.094583) (xy 164.678308 -410.102319) (xy 164.6682 -410.102812) (xy 163.95192 -410.102812)
			(xy 163.9418 -410.102368) (xy 163.923099 -410.094629) (xy 163.908785 -410.080321) (xy 163.901037 -410.061624)
			(xy 163.900612 -410.051504) (xy 163.900612 -409.894024) (xy 163.900188 -409.884838) (xy 163.893683 -409.867654)
			(xy 163.887912 -409.860496) (xy 163.866012 -409.83486) (xy 163.827924 -409.779222) (xy 163.796774 -409.719422)
			(xy 163.773011 -409.656321) (xy 163.756978 -409.590828) (xy 163.748905 -409.523886) (xy 162.620757 -409.523886)
			(xy 162.592019 -409.579046) (xy 162.553926 -409.634679) (xy 162.53206 -409.660344) (xy 162.526257 -409.667485)
			(xy 162.519747 -409.684679) (xy 162.51936 -409.693872) (xy 162.51936 -410.186124) (xy 162.519768 -410.195311)
			(xy 162.526284 -410.212495) (xy 162.53206 -410.219652) (xy 162.55391 -410.24533) (xy 162.592001 -410.300961)
			(xy 162.623155 -410.360755) (xy 162.646922 -410.423851) (xy 162.66296 -410.489339) (xy 162.671038 -410.556276)
			(xy 162.671039 -410.623641) (xy 165.949078 -410.623641) (xy 165.949079 -410.556335) (xy 165.957125 -410.489511)
			(xy 165.9731 -410.424127) (xy 165.996775 -410.361122) (xy 166.027811 -410.301398) (xy 166.065763 -410.245812)
			(xy 166.087552 -410.22016) (xy 166.093354 -410.213019) (xy 166.099864 -410.195825) (xy 166.100252 -410.186632)
			(xy 166.100252 -409.693364) (xy 166.099847 -409.684176) (xy 166.093328 -409.666993) (xy 166.087552 -409.659836)
			(xy 166.065776 -409.634174) (xy 166.027826 -409.578589) (xy 165.996791 -409.518867) (xy 165.973117 -409.455864)
			(xy 165.957143 -409.390483) (xy 165.949098 -409.323661) (xy 165.949097 -409.256357) (xy 165.95714 -409.189535)
			(xy 165.973112 -409.124153) (xy 165.996784 -409.061149) (xy 166.027817 -409.001426) (xy 166.065765 -408.94584)
			(xy 166.087552 -408.920188) (xy 166.093343 -408.913039) (xy 166.099859 -408.895851) (xy 166.100252 -408.88666)
			(xy 166.100252 -408.728672) (xy 166.100698 -408.718522) (xy 166.108493 -408.699778) (xy 166.122882 -408.685458)
			(xy 166.141662 -408.67775) (xy 166.151814 -408.677364) (xy 166.868094 -408.677364) (xy 166.878223 -408.677832)
			(xy 166.896949 -408.685562) (xy 166.911306 -408.699855) (xy 166.919121 -408.718545) (xy 166.919656 -408.728672)
			(xy 166.919656 -408.88666) (xy 166.920095 -408.895844) (xy 166.92659 -408.913028) (xy 166.932356 -408.920188)
			(xy 166.954156 -408.94583) (xy 166.992105 -409.001418) (xy 167.023138 -409.061143) (xy 167.04681 -409.124149)
			(xy 167.062782 -409.189532) (xy 167.070826 -409.256356) (xy 167.070824 -409.323662) (xy 167.062779 -409.390486)
			(xy 167.046805 -409.455869) (xy 167.02313 -409.518874) (xy 167.020557 -409.523826) (xy 168.149224 -409.523826)
			(xy 168.149228 -409.456519) (xy 168.157275 -409.389695) (xy 168.17325 -409.324311) (xy 168.196925 -409.261305)
			(xy 168.227961 -409.201581) (xy 168.265911 -409.145993) (xy 168.2877 -409.12034) (xy 168.293505 -409.1132)
			(xy 168.300014 -409.096006) (xy 168.3004 -409.086812) (xy 168.3004 -408.593544) (xy 168.299969 -408.584359)
			(xy 168.29347 -408.567174) (xy 168.2877 -408.560016) (xy 168.265906 -408.53437) (xy 168.22796 -408.478782)
			(xy 168.196929 -408.419057) (xy 168.173258 -408.356052) (xy 168.157287 -408.290669) (xy 168.149244 -408.223846)
			(xy 168.149245 -408.156542) (xy 168.157289 -408.089719) (xy 168.173262 -408.024337) (xy 168.196934 -407.961332)
			(xy 168.227966 -407.901608) (xy 168.265913 -407.846021) (xy 168.2877 -407.820368) (xy 168.293493 -407.81322)
			(xy 168.30001 -407.796032) (xy 168.3004 -407.78684) (xy 168.3004 -407.628852) (xy 168.300782 -407.618695)
			(xy 168.308594 -407.599941) (xy 168.323002 -407.58562) (xy 168.341802 -407.577922) (xy 168.351962 -407.577544)
			(xy 169.068242 -407.577544) (xy 169.078372 -407.577992) (xy 169.097095 -407.585735) (xy 169.11145 -407.600032)
			(xy 169.119267 -407.618724) (xy 169.119804 -407.628852) (xy 169.119804 -407.78684) (xy 169.120194 -407.796029)
			(xy 169.126721 -407.813214) (xy 169.132504 -407.820368) (xy 169.154283 -407.846027) (xy 169.192229 -407.901614)
			(xy 169.22326 -407.961337) (xy 169.246931 -408.02434) (xy 169.262904 -408.089721) (xy 169.270948 -408.156542)
			(xy 169.270948 -408.223846) (xy 169.262906 -408.290667) (xy 169.246935 -408.356048) (xy 169.223265 -408.419052)
			(xy 169.192235 -408.478776) (xy 169.15429 -408.534363) (xy 169.132504 -408.560016) (xy 169.126719 -408.567169)
			(xy 169.120197 -408.584354) (xy 169.119804 -408.593544) (xy 169.119804 -409.086812) (xy 169.120208 -409.096)
			(xy 169.126726 -409.113184) (xy 169.132504 -409.12034) (xy 169.154255 -409.146022) (xy 169.192202 -409.201605)
			(xy 169.223235 -409.261325) (xy 169.246908 -409.324325) (xy 169.262882 -409.389704) (xy 169.270928 -409.456522)
			(xy 169.270931 -409.523824) (xy 169.262891 -409.590643) (xy 169.246924 -409.656023) (xy 169.223257 -409.719026)
			(xy 169.19223 -409.778748) (xy 169.154288 -409.834335) (xy 169.132504 -409.859988) (xy 169.126688 -409.86712)
			(xy 169.120185 -409.88432) (xy 169.119804 -409.893516) (xy 169.119804 -410.051504) (xy 169.119382 -410.061658)
			(xy 169.111586 -410.08041) (xy 169.097189 -410.094733) (xy 169.078398 -410.102433) (xy 169.068242 -410.102812)
			(xy 168.351962 -410.102812) (xy 168.341839 -410.102306) (xy 168.323127 -410.094575) (xy 168.308774 -410.080296)
			(xy 168.300947 -410.061624) (xy 168.3004 -410.051504) (xy 168.3004 -409.893516) (xy 168.299982 -409.88433)
			(xy 168.293474 -409.867145) (xy 168.2877 -409.859988) (xy 168.265878 -409.834364) (xy 168.227933 -409.778773)
			(xy 168.196903 -409.719045) (xy 168.173234 -409.656037) (xy 168.157265 -409.590652) (xy 168.149224 -409.523826)
			(xy 167.020557 -409.523826) (xy 166.992095 -409.578598) (xy 166.954145 -409.634184) (xy 166.932356 -409.659836)
			(xy 166.926556 -409.666979) (xy 166.920045 -409.684171) (xy 166.919656 -409.693364) (xy 166.919656 -410.186632)
			(xy 166.920061 -410.19582) (xy 166.926579 -410.213003) (xy 166.932356 -410.22016) (xy 166.954128 -410.245825)
			(xy 166.992078 -410.30141) (xy 167.023112 -410.361131) (xy 167.046786 -410.424134) (xy 167.06276 -410.489515)
			(xy 167.070805 -410.556336) (xy 167.070807 -410.62364) (xy 167.0708 -410.623701) (xy 170.348846 -410.623701)
			(xy 170.348847 -410.556275) (xy 170.356926 -410.489335) (xy 170.372964 -410.423844) (xy 170.396732 -410.360747)
			(xy 170.427888 -410.30095) (xy 170.465981 -410.245316) (xy 170.487848 -410.219652) (xy 170.493653 -410.212513)
			(xy 170.500162 -410.195318) (xy 170.500548 -410.186124) (xy 170.500548 -409.693872) (xy 170.50014 -409.684685)
			(xy 170.493624 -409.667501) (xy 170.487848 -409.660344) (xy 170.465994 -409.63467) (xy 170.427902 -409.579038)
			(xy 170.396748 -409.519243) (xy 170.372981 -409.456147) (xy 170.356943 -409.390659) (xy 170.348866 -409.323721)
			(xy 170.348865 -409.256297) (xy 170.35694 -409.189359) (xy 170.372976 -409.12387) (xy 170.396741 -409.060773)
			(xy 170.427893 -409.000978) (xy 170.465983 -408.945344) (xy 170.487848 -408.91968) (xy 170.493642 -408.912533)
			(xy 170.500157 -408.895344) (xy 170.500548 -408.886152) (xy 170.500548 -408.728672) (xy 170.501061 -408.718568)
			(xy 170.508798 -408.699899) (xy 170.523086 -408.685607) (xy 170.541752 -408.677864) (xy 170.551856 -408.677364)
			(xy 171.268136 -408.677364) (xy 171.278243 -408.677855) (xy 171.296915 -408.685598) (xy 171.311207 -408.699892)
			(xy 171.318947 -408.718565) (xy 171.319444 -408.728672) (xy 171.319444 -408.886152) (xy 171.31989 -408.895335)
			(xy 171.32638 -408.912519) (xy 171.332144 -408.91968) (xy 171.354022 -408.945335) (xy 171.392114 -409.000969)
			(xy 171.423267 -409.060766) (xy 171.447033 -409.123865) (xy 171.463069 -409.189356) (xy 171.471145 -409.256296)
			(xy 171.471144 -409.323722) (xy 171.463066 -409.390662) (xy 171.447028 -409.456152) (xy 171.42326 -409.51925)
			(xy 171.420875 -409.523827) (xy 172.548991 -409.523827) (xy 172.548995 -409.456519) (xy 172.557043 -409.389693)
			(xy 172.573021 -409.324308) (xy 172.5967 -409.261302) (xy 172.62774 -409.201577) (xy 172.665697 -409.145992)
			(xy 172.687488 -409.12034) (xy 172.693291 -409.113199) (xy 172.699802 -409.096005) (xy 172.700188 -409.086812)
			(xy 172.700188 -408.593544) (xy 172.699759 -408.584359) (xy 172.693259 -408.567174) (xy 172.687488 -408.560016)
			(xy 172.665691 -408.534371) (xy 172.627739 -408.478785) (xy 172.596704 -408.419061) (xy 172.573029 -408.356055)
			(xy 172.557055 -408.290671) (xy 172.549011 -408.223847) (xy 172.549012 -408.156541) (xy 172.557057 -408.089717)
			(xy 172.573033 -408.024333) (xy 172.596708 -407.961328) (xy 172.627745 -407.901605) (xy 172.665698 -407.84602)
			(xy 172.687488 -407.820368) (xy 172.693279 -407.813219) (xy 172.699797 -407.796031) (xy 172.700188 -407.78684)
			(xy 172.700188 -407.628852) (xy 172.700582 -407.618696) (xy 172.708391 -407.599945) (xy 172.722796 -407.585624)
			(xy 172.741592 -407.577924) (xy 172.75175 -407.577544) (xy 173.46803 -407.577544) (xy 173.478159 -407.578002)
			(xy 173.496882 -407.58574) (xy 173.511237 -407.600035) (xy 173.519055 -407.618725) (xy 173.519592 -407.628852)
			(xy 173.519592 -407.78684) (xy 173.519985 -407.796029) (xy 173.526511 -407.813213) (xy 173.532292 -407.820368)
			(xy 173.554071 -407.846027) (xy 173.592018 -407.901613) (xy 173.62305 -407.961336) (xy 173.646722 -408.02434)
			(xy 173.662694 -408.089721) (xy 173.670739 -408.156542) (xy 173.670739 -408.223846) (xy 173.662697 -408.290667)
			(xy 173.646725 -408.356049) (xy 173.623055 -408.419053) (xy 173.592024 -408.478776) (xy 173.554078 -408.534363)
			(xy 173.532292 -408.560016) (xy 173.526505 -408.567168) (xy 173.519985 -408.584353) (xy 173.519592 -408.593544)
			(xy 173.519592 -409.086812) (xy 173.519998 -409.096) (xy 173.526515 -409.113184) (xy 173.532292 -409.12034)
			(xy 173.554043 -409.146022) (xy 173.591991 -409.201605) (xy 173.623024 -409.261324) (xy 173.646698 -409.324325)
			(xy 173.662672 -409.389703) (xy 173.670719 -409.456522) (xy 173.670722 -409.523824) (xy 173.662682 -409.590643)
			(xy 173.646714 -409.656023) (xy 173.623047 -409.719026) (xy 173.592019 -409.778749) (xy 173.554077 -409.834336)
			(xy 173.532292 -409.859988) (xy 173.526475 -409.867118) (xy 173.519973 -409.88432) (xy 173.519592 -409.893516)
			(xy 173.519592 -410.051504) (xy 173.519181 -410.061659) (xy 173.511383 -410.080413) (xy 173.496983 -410.094737)
			(xy 173.478187 -410.102435) (xy 173.46803 -410.102812) (xy 172.75175 -410.102812) (xy 172.741633 -410.102234)
			(xy 172.722923 -410.094532) (xy 172.708567 -410.080274) (xy 172.700736 -410.061618) (xy 172.700188 -410.051504)
			(xy 172.700188 -409.893516) (xy 172.699773 -409.884329) (xy 172.693263 -409.867145) (xy 172.687488 -409.859988)
			(xy 172.665663 -409.834366) (xy 172.627713 -409.778776) (xy 172.596678 -409.719049) (xy 172.573005 -409.65604)
			(xy 172.557033 -409.590654) (xy 172.548991 -409.523827) (xy 171.420875 -409.523827) (xy 171.392104 -409.579046)
			(xy 171.354011 -409.63468) (xy 171.332144 -409.660344) (xy 171.326339 -409.667483) (xy 171.319831 -409.684679)
			(xy 171.319444 -409.693872) (xy 171.319444 -410.186124) (xy 171.319855 -410.195311) (xy 171.32637 -410.212494)
			(xy 171.332144 -410.219652) (xy 171.353994 -410.245329) (xy 171.392087 -410.300961) (xy 171.423242 -410.360755)
			(xy 171.447009 -410.42385) (xy 171.463047 -410.489338) (xy 171.471125 -410.556276) (xy 171.471127 -410.623641)
			(xy 174.749166 -410.623641) (xy 174.749167 -410.556335) (xy 174.757213 -410.489511) (xy 174.773187 -410.424128)
			(xy 174.796862 -410.361123) (xy 174.827897 -410.301399) (xy 174.865847 -410.245812) (xy 174.887636 -410.22016)
			(xy 174.893437 -410.213018) (xy 174.899948 -410.195825) (xy 174.900336 -410.186632) (xy 174.900336 -409.693364)
			(xy 174.899935 -409.684176) (xy 174.893414 -409.666992) (xy 174.887636 -409.659836) (xy 174.86586 -409.634174)
			(xy 174.827911 -409.578589) (xy 174.796878 -409.518867) (xy 174.773205 -409.455863) (xy 174.757231 -409.390482)
			(xy 174.749186 -409.323661) (xy 174.749185 -409.256357) (xy 174.757228 -409.189535) (xy 174.773199 -409.124154)
			(xy 174.79687 -409.06115) (xy 174.827902 -409.001427) (xy 174.865849 -408.94584) (xy 174.887636 -408.920188)
			(xy 174.893425 -408.913037) (xy 174.899943 -408.895851) (xy 174.900336 -408.88666) (xy 174.900336 -408.728672)
			(xy 174.900699 -408.718512) (xy 174.908511 -408.699752) (xy 174.922926 -408.685428) (xy 174.941735 -408.677736)
			(xy 174.951898 -408.677364) (xy 175.668178 -408.677364) (xy 175.678306 -408.677845) (xy 175.697032 -408.68557)
			(xy 175.711389 -408.699859) (xy 175.719205 -408.718546) (xy 175.71974 -408.728672) (xy 175.71974 -408.88666)
			(xy 175.720183 -408.895843) (xy 175.726675 -408.913028) (xy 175.73244 -408.920188) (xy 175.75424 -408.94583)
			(xy 175.79219 -409.001418) (xy 175.823224 -409.061142) (xy 175.846897 -409.124148) (xy 175.862869 -409.189532)
			(xy 175.870913 -409.256356) (xy 175.870912 -409.323662) (xy 175.862866 -409.390486) (xy 175.846891 -409.455869)
			(xy 175.823216 -409.518874) (xy 175.792181 -409.578598) (xy 175.754229 -409.634184) (xy 175.73244 -409.659836)
			(xy 175.726638 -409.666977) (xy 175.720128 -409.684171) (xy 175.71974 -409.693364) (xy 175.71974 -410.186632)
			(xy 175.720148 -410.195819) (xy 175.726665 -410.213003) (xy 175.73244 -410.22016) (xy 175.754213 -410.245825)
			(xy 175.792163 -410.301409) (xy 175.823198 -410.361131) (xy 175.846873 -410.424134) (xy 175.862848 -410.489514)
			(xy 175.870893 -410.556336) (xy 175.870895 -410.62364) (xy 175.862852 -410.690462) (xy 175.84688 -410.755843)
			(xy 175.823208 -410.818847) (xy 175.792176 -410.87857) (xy 175.754227 -410.934156) (xy 175.73244 -410.959808)
			(xy 175.72665 -410.966958) (xy 175.720133 -410.984145) (xy 175.71974 -410.993336) (xy 175.71974 -411.151324)
			(xy 175.719299 -411.161475) (xy 175.711503 -411.18022) (xy 175.697113 -411.194541) (xy 175.678331 -411.202247)
			(xy 175.668178 -411.202632) (xy 174.951898 -411.202632) (xy 174.941768 -411.202174) (xy 174.923041 -411.194441)
			(xy 174.908684 -411.180145) (xy 174.90087 -411.161452) (xy 174.900336 -411.151324) (xy 174.900336 -410.993336)
			(xy 174.8999 -410.984152) (xy 174.893403 -410.966968) (xy 174.887636 -410.959808) (xy 174.865833 -410.934169)
			(xy 174.827884 -410.87858) (xy 174.796852 -410.818855) (xy 174.77318 -410.755849) (xy 174.757208 -410.690465)
			(xy 174.749166 -410.623641) (xy 171.471127 -410.623641) (xy 171.471127 -410.6237) (xy 171.463052 -410.690638)
			(xy 171.447016 -410.756127) (xy 171.423251 -410.819223) (xy 171.392099 -410.879019) (xy 171.354009 -410.934652)
			(xy 171.332144 -410.960316) (xy 171.326351 -410.967464) (xy 171.319836 -410.984653) (xy 171.319444 -410.993844)
			(xy 171.319444 -411.151324) (xy 171.318936 -411.161429) (xy 171.311198 -411.180099) (xy 171.296909 -411.194392)
			(xy 171.278241 -411.202133) (xy 171.268136 -411.202632) (xy 170.551856 -411.202632) (xy 170.541748 -411.202152)
			(xy 170.523075 -411.194405) (xy 170.508783 -411.180108) (xy 170.501044 -411.161432) (xy 170.500548 -411.151324)
			(xy 170.500548 -410.993844) (xy 170.500106 -410.98466) (xy 170.493613 -410.967476) (xy 170.487848 -410.960316)
			(xy 170.465967 -410.934665) (xy 170.427875 -410.879029) (xy 170.396723 -410.819232) (xy 170.372957 -410.756133)
			(xy 170.356921 -410.690641) (xy 170.348846 -410.623701) (xy 167.0708 -410.623701) (xy 167.062764 -410.690461)
			(xy 167.046793 -410.755843) (xy 167.023122 -410.818847) (xy 166.99209 -410.87857) (xy 166.954143 -410.934156)
			(xy 166.932356 -410.959808) (xy 166.926568 -410.966959) (xy 166.920049 -410.984145) (xy 166.919656 -410.993336)
			(xy 166.919656 -411.151324) (xy 166.919199 -411.161473) (xy 166.911406 -411.180215) (xy 166.897021 -411.194535)
			(xy 166.878245 -411.202244) (xy 166.868094 -411.202632) (xy 166.151814 -411.202632) (xy 166.141685 -411.202161)
			(xy 166.122959 -411.194433) (xy 166.108601 -411.180141) (xy 166.100786 -411.161451) (xy 166.100252 -411.151324)
			(xy 166.100252 -410.993336) (xy 166.099813 -410.984152) (xy 166.093318 -410.966968) (xy 166.087552 -410.959808)
			(xy 166.065748 -410.934169) (xy 166.027799 -410.878581) (xy 165.996765 -410.818856) (xy 165.973093 -410.75585)
			(xy 165.957121 -410.690466) (xy 165.949078 -410.623641) (xy 162.671039 -410.623641) (xy 162.671039 -410.6237)
			(xy 162.662964 -410.690637) (xy 162.646929 -410.756126) (xy 162.623165 -410.819223) (xy 162.592014 -410.879018)
			(xy 162.553924 -410.934651) (xy 162.53206 -410.960316) (xy 162.526269 -410.967465) (xy 162.519752 -410.984653)
			(xy 162.51936 -410.993844) (xy 162.51936 -411.151324) (xy 162.519003 -411.161453) (xy 162.511239 -411.180165)
			(xy 162.496904 -411.19448) (xy 162.478182 -411.202217) (xy 162.468052 -411.202632) (xy 161.751772 -411.202632)
			(xy 161.741665 -411.202139) (xy 161.722993 -411.194398) (xy 161.7087 -411.180104) (xy 161.700961 -411.161431)
			(xy 161.700464 -411.151324) (xy 161.700464 -410.993844) (xy 161.700019 -410.984661) (xy 161.693528 -410.967477)
			(xy 161.687764 -410.960316) (xy 161.665886 -410.934663) (xy 161.6278 -410.879026) (xy 161.596652 -410.819228)
			(xy 161.57289 -410.756129) (xy 161.556857 -410.690639) (xy 161.548783 -410.6237) (xy 154.57678 -410.6237)
			(xy 154.57678 -417.371276) (xy 154.576371 -417.383441) (xy 154.568857 -417.406581) (xy 154.554556 -417.426265)
			(xy 154.53487 -417.440562) (xy 154.511729 -417.448073) (xy 154.499564 -417.448492) (xy 141.100302 -417.448492)
			(xy 141.088157 -417.448035) (xy 141.06506 -417.440516) (xy 141.045426 -417.426216) (xy 141.031183 -417.406541)
			(xy 141.02373 -417.383422) (xy 141.02334 -417.371276) (xy 66.525648 -417.371276) (xy 66.525648 -417.533836)
			(xy 66.525172 -417.545883) (xy 66.517735 -417.568802) (xy 66.503597 -417.588313) (xy 66.484133 -417.602517)
			(xy 66.46124 -417.610031) (xy 66.449194 -417.610544) (xy 53.151024 -417.610544) (xy 53.138954 -417.610016)
			(xy 53.115994 -417.602564) (xy 53.09646 -417.588383) (xy 53.082263 -417.56886) (xy 53.074793 -417.545905)
			(xy 53.074316 -417.533836) (xy 53.074316 -417.289488) (xy 53.073808 -417.289488) (xy 0.681656 -417.289488)
			(xy 0.736245 -417.384039) (xy 0.79912 -417.476259) (xy 0.86871 -417.563523) (xy 0.944627 -417.645342)
			(xy 1.026446 -417.721259) (xy 1.113709 -417.790849) (xy 1.205929 -417.853724) (xy 1.302589 -417.909531)
			(xy 1.40315 -417.957958) (xy 1.507049 -417.998736) (xy 1.613704 -418.031635) (xy 1.72252 -418.056471)
			(xy 1.832887 -418.073107) (xy 1.944189 -418.081448) (xy 1.999996 -418.081968)
		)
		(stroke
			(width 0)
			(type solid)
		)
		(fill yes)
		(layer "In6.Cu")
		(net "GND")
	)
	(gr_circle
		(center 36.849812 -314.899802)
		(end 37.103812 -314.899802)
		(stroke
			(width 0.1016)
			(type default)
		)
		(fill no)
		(layer "In6.Cu")
	)
	(gr_circle
		(center 36.849812 -312.049922)
		(end 37.103812 -312.049922)
		(stroke
			(width 0.1016)
			(type default)
		)
		(fill no)
		(layer "In6.Cu")
	)
	(gr_circle
		(center 37.799772 -314.899802)
		(end 38.053772 -314.899802)
		(stroke
			(width 0.1016)
			(type default)
		)
		(fill no)
		(layer "In6.Cu")
	)
	(gr_circle
		(center 37.799772 -312.049922)
		(end 38.053772 -312.049922)
		(stroke
			(width 0.1016)
			(type default)
		)
		(fill no)
		(layer "In6.Cu")
	)
	(gr_circle
		(center 38.749986 -313.949842)
		(end 39.003986 -313.949842)
		(stroke
			(width 0.1016)
			(type default)
		)
		(fill no)
		(layer "In6.Cu")
	)
	(gr_circle
		(center 38.749986 -312.999882)
		(end 39.003986 -312.999882)
		(stroke
			(width 0.1016)
			(type default)
		)
		(fill no)
		(layer "In6.Cu")
	)
	(gr_circle
		(center 39.699946 -312.049922)
		(end 39.953946 -312.049922)
		(stroke
			(width 0.1016)
			(type default)
		)
		(fill no)
		(layer "In6.Cu")
	)
	(gr_circle
		(center 39.699946 -311.099962)
		(end 39.953946 -311.099962)
		(stroke
			(width 0.1016)
			(type default)
		)
		(fill no)
		(layer "In6.Cu")
	)
	(gr_circle
		(center 40.649906 -313.949842)
		(end 40.903906 -313.949842)
		(stroke
			(width 0.1016)
			(type default)
		)
		(fill no)
		(layer "In6.Cu")
	)
	(gr_circle
		(center 40.649906 -312.999882)
		(end 40.903906 -312.999882)
		(stroke
			(width 0.1016)
			(type default)
		)
		(fill no)
		(layer "In6.Cu")
	)
	(gr_circle
		(center 41.599866 -312.049922)
		(end 41.853866 -312.049922)
		(stroke
			(width 0.1016)
			(type default)
		)
		(fill no)
		(layer "In6.Cu")
	)
	(gr_circle
		(center 41.599866 -311.099962)
		(end 41.853866 -311.099962)
		(stroke
			(width 0.1016)
			(type default)
		)
		(fill no)
		(layer "In6.Cu")
	)
	(gr_circle
		(center 41.599866 -309.199788)
		(end 41.853866 -309.199788)
		(stroke
			(width 0.1016)
			(type default)
		)
		(fill no)
		(layer "In6.Cu")
	)
	(gr_circle
		(center 41.599866 -307.299868)
		(end 41.853866 -307.299868)
		(stroke
			(width 0.1016)
			(type default)
		)
		(fill no)
		(layer "In6.Cu")
	)
	(gr_circle
		(center 41.599866 -305.399948)
		(end 41.853866 -305.399948)
		(stroke
			(width 0.1016)
			(type default)
		)
		(fill no)
		(layer "In6.Cu")
	)
	(gr_circle
		(center 41.599866 -303.499774)
		(end 41.853866 -303.499774)
		(stroke
			(width 0.1016)
			(type default)
		)
		(fill no)
		(layer "In6.Cu")
	)
	(gr_circle
		(center 41.599866 -301.599854)
		(end 41.853866 -301.599854)
		(stroke
			(width 0.1016)
			(type default)
		)
		(fill no)
		(layer "In6.Cu")
	)
	(gr_circle
		(center 42.549826 -313.949842)
		(end 42.803826 -313.949842)
		(stroke
			(width 0.1016)
			(type default)
		)
		(fill no)
		(layer "In6.Cu")
	)
	(gr_circle
		(center 42.549826 -312.999882)
		(end 42.803826 -312.999882)
		(stroke
			(width 0.1016)
			(type default)
		)
		(fill no)
		(layer "In6.Cu")
	)
	(gr_circle
		(center 42.549826 -309.199788)
		(end 42.803826 -309.199788)
		(stroke
			(width 0.1016)
			(type default)
		)
		(fill no)
		(layer "In6.Cu")
	)
	(gr_circle
		(center 42.549826 -307.299868)
		(end 42.803826 -307.299868)
		(stroke
			(width 0.1016)
			(type default)
		)
		(fill no)
		(layer "In6.Cu")
	)
	(gr_circle
		(center 42.549826 -305.399948)
		(end 42.803826 -305.399948)
		(stroke
			(width 0.1016)
			(type default)
		)
		(fill no)
		(layer "In6.Cu")
	)
	(gr_circle
		(center 42.549826 -303.499774)
		(end 42.803826 -303.499774)
		(stroke
			(width 0.1016)
			(type default)
		)
		(fill no)
		(layer "In6.Cu")
	)
	(gr_circle
		(center 42.549826 -301.599854)
		(end 42.803826 -301.599854)
		(stroke
			(width 0.1016)
			(type default)
		)
		(fill no)
		(layer "In6.Cu")
	)
	(gr_circle
		(center 43.499786 -312.049922)
		(end 43.753786 -312.049922)
		(stroke
			(width 0.1016)
			(type default)
		)
		(fill no)
		(layer "In6.Cu")
	)
	(gr_circle
		(center 43.499786 -311.099962)
		(end 43.753786 -311.099962)
		(stroke
			(width 0.1016)
			(type default)
		)
		(fill no)
		(layer "In6.Cu")
	)
	(gr_circle
		(center 43.499786 -308.249828)
		(end 43.753786 -308.249828)
		(stroke
			(width 0.1016)
			(type default)
		)
		(fill no)
		(layer "In6.Cu")
	)
	(gr_circle
		(center 43.499786 -306.349908)
		(end 43.753786 -306.349908)
		(stroke
			(width 0.1016)
			(type default)
		)
		(fill no)
		(layer "In6.Cu")
	)
	(gr_circle
		(center 43.499786 -304.449734)
		(end 43.753786 -304.449734)
		(stroke
			(width 0.1016)
			(type default)
		)
		(fill no)
		(layer "In6.Cu")
	)
	(gr_circle
		(center 43.499786 -302.549814)
		(end 43.753786 -302.549814)
		(stroke
			(width 0.1016)
			(type default)
		)
		(fill no)
		(layer "In6.Cu")
	)
	(gr_circle
		(center 44.449746 -313.949842)
		(end 44.703746 -313.949842)
		(stroke
			(width 0.1016)
			(type default)
		)
		(fill no)
		(layer "In6.Cu")
	)
	(gr_circle
		(center 44.449746 -312.999882)
		(end 44.703746 -312.999882)
		(stroke
			(width 0.1016)
			(type default)
		)
		(fill no)
		(layer "In6.Cu")
	)
	(gr_circle
		(center 44.449746 -308.249828)
		(end 44.703746 -308.249828)
		(stroke
			(width 0.1016)
			(type default)
		)
		(fill no)
		(layer "In6.Cu")
	)
	(gr_circle
		(center 44.449746 -306.349908)
		(end 44.703746 -306.349908)
		(stroke
			(width 0.1016)
			(type default)
		)
		(fill no)
		(layer "In6.Cu")
	)
	(gr_circle
		(center 44.449746 -304.449734)
		(end 44.703746 -304.449734)
		(stroke
			(width 0.1016)
			(type default)
		)
		(fill no)
		(layer "In6.Cu")
	)
	(gr_circle
		(center 44.449746 -302.549814)
		(end 44.703746 -302.549814)
		(stroke
			(width 0.1016)
			(type default)
		)
		(fill no)
		(layer "In6.Cu")
	)
	(gr_circle
		(center 44.449746 -278.799798)
		(end 44.703746 -278.799798)
		(stroke
			(width 0.1016)
			(type default)
		)
		(fill no)
		(layer "In6.Cu")
	)
	(gr_circle
		(center 44.449746 -277.849838)
		(end 44.703746 -277.849838)
		(stroke
			(width 0.1016)
			(type default)
		)
		(fill no)
		(layer "In6.Cu")
	)
	(gr_circle
		(center 44.449746 -274.049744)
		(end 44.703746 -274.049744)
		(stroke
			(width 0.1016)
			(type default)
		)
		(fill no)
		(layer "In6.Cu")
	)
	(gr_circle
		(center 44.449746 -273.099784)
		(end 44.703746 -273.099784)
		(stroke
			(width 0.1016)
			(type default)
		)
		(fill no)
		(layer "In6.Cu")
	)
	(gr_circle
		(center 45.39996 -312.049922)
		(end 45.65396 -312.049922)
		(stroke
			(width 0.1016)
			(type default)
		)
		(fill no)
		(layer "In6.Cu")
	)
	(gr_circle
		(center 45.39996 -311.099962)
		(end 45.65396 -311.099962)
		(stroke
			(width 0.1016)
			(type default)
		)
		(fill no)
		(layer "In6.Cu")
	)
	(gr_circle
		(center 45.39996 -280.699464)
		(end 45.65396 -280.699464)
		(stroke
			(width 0.1016)
			(type default)
		)
		(fill no)
		(layer "In6.Cu")
	)
	(gr_circle
		(center 45.39996 -279.749504)
		(end 45.65396 -279.749504)
		(stroke
			(width 0.1016)
			(type default)
		)
		(fill no)
		(layer "In6.Cu")
	)
	(gr_circle
		(center 45.39996 -275.949918)
		(end 45.65396 -275.949918)
		(stroke
			(width 0.1016)
			(type default)
		)
		(fill no)
		(layer "In6.Cu")
	)
	(gr_circle
		(center 45.39996 -274.999958)
		(end 45.65396 -274.999958)
		(stroke
			(width 0.1016)
			(type default)
		)
		(fill no)
		(layer "In6.Cu")
	)
	(gr_circle
		(center 46.34992 -313.949842)
		(end 46.60392 -313.949842)
		(stroke
			(width 0.1016)
			(type default)
		)
		(fill no)
		(layer "In6.Cu")
	)
	(gr_circle
		(center 46.34992 -312.999882)
		(end 46.60392 -312.999882)
		(stroke
			(width 0.1016)
			(type default)
		)
		(fill no)
		(layer "In6.Cu")
	)
	(gr_circle
		(center 46.34992 -278.799798)
		(end 46.60392 -278.799798)
		(stroke
			(width 0.1016)
			(type default)
		)
		(fill no)
		(layer "In6.Cu")
	)
	(gr_circle
		(center 46.34992 -277.849838)
		(end 46.60392 -277.849838)
		(stroke
			(width 0.1016)
			(type default)
		)
		(fill no)
		(layer "In6.Cu")
	)
	(gr_circle
		(center 46.34992 -274.049744)
		(end 46.60392 -274.049744)
		(stroke
			(width 0.1016)
			(type default)
		)
		(fill no)
		(layer "In6.Cu")
	)
	(gr_circle
		(center 46.34992 -273.099784)
		(end 46.60392 -273.099784)
		(stroke
			(width 0.1016)
			(type default)
		)
		(fill no)
		(layer "In6.Cu")
	)
	(gr_circle
		(center 47.29988 -312.049922)
		(end 47.55388 -312.049922)
		(stroke
			(width 0.1016)
			(type default)
		)
		(fill no)
		(layer "In6.Cu")
	)
	(gr_circle
		(center 47.29988 -311.099962)
		(end 47.55388 -311.099962)
		(stroke
			(width 0.1016)
			(type default)
		)
		(fill no)
		(layer "In6.Cu")
	)
	(gr_circle
		(center 47.29988 -280.699464)
		(end 47.55388 -280.699464)
		(stroke
			(width 0.1016)
			(type default)
		)
		(fill no)
		(layer "In6.Cu")
	)
	(gr_circle
		(center 47.29988 -279.749504)
		(end 47.55388 -279.749504)
		(stroke
			(width 0.1016)
			(type default)
		)
		(fill no)
		(layer "In6.Cu")
	)
	(gr_circle
		(center 47.29988 -275.949918)
		(end 47.55388 -275.949918)
		(stroke
			(width 0.1016)
			(type default)
		)
		(fill no)
		(layer "In6.Cu")
	)
	(gr_circle
		(center 47.29988 -274.999958)
		(end 47.55388 -274.999958)
		(stroke
			(width 0.1016)
			(type default)
		)
		(fill no)
		(layer "In6.Cu")
	)
	(gr_circle
		(center 48.24984 -313.949842)
		(end 48.50384 -313.949842)
		(stroke
			(width 0.1016)
			(type default)
		)
		(fill no)
		(layer "In6.Cu")
	)
	(gr_circle
		(center 48.24984 -312.999882)
		(end 48.50384 -312.999882)
		(stroke
			(width 0.1016)
			(type default)
		)
		(fill no)
		(layer "In6.Cu")
	)
	(gr_circle
		(center 48.24984 -278.799798)
		(end 48.50384 -278.799798)
		(stroke
			(width 0.1016)
			(type default)
		)
		(fill no)
		(layer "In6.Cu")
	)
	(gr_circle
		(center 48.24984 -277.849838)
		(end 48.50384 -277.849838)
		(stroke
			(width 0.1016)
			(type default)
		)
		(fill no)
		(layer "In6.Cu")
	)
	(gr_circle
		(center 48.24984 -274.049744)
		(end 48.50384 -274.049744)
		(stroke
			(width 0.1016)
			(type default)
		)
		(fill no)
		(layer "In6.Cu")
	)
	(gr_circle
		(center 48.24984 -273.099784)
		(end 48.50384 -273.099784)
		(stroke
			(width 0.1016)
			(type default)
		)
		(fill no)
		(layer "In6.Cu")
	)
	(gr_circle
		(center 49.1998 -312.049922)
		(end 49.4538 -312.049922)
		(stroke
			(width 0.1016)
			(type default)
		)
		(fill no)
		(layer "In6.Cu")
	)
	(gr_circle
		(center 49.1998 -311.099962)
		(end 49.4538 -311.099962)
		(stroke
			(width 0.1016)
			(type default)
		)
		(fill no)
		(layer "In6.Cu")
	)
	(gr_circle
		(center 49.1998 -280.699464)
		(end 49.4538 -280.699464)
		(stroke
			(width 0.1016)
			(type default)
		)
		(fill no)
		(layer "In6.Cu")
	)
	(gr_circle
		(center 49.1998 -279.749504)
		(end 49.4538 -279.749504)
		(stroke
			(width 0.1016)
			(type default)
		)
		(fill no)
		(layer "In6.Cu")
	)
	(gr_circle
		(center 49.1998 -275.949918)
		(end 49.4538 -275.949918)
		(stroke
			(width 0.1016)
			(type default)
		)
		(fill no)
		(layer "In6.Cu")
	)
	(gr_circle
		(center 49.1998 -274.999958)
		(end 49.4538 -274.999958)
		(stroke
			(width 0.1016)
			(type default)
		)
		(fill no)
		(layer "In6.Cu")
	)
	(gr_circle
		(center 50.14976 -313.949842)
		(end 50.40376 -313.949842)
		(stroke
			(width 0.1016)
			(type default)
		)
		(fill no)
		(layer "In6.Cu")
	)
	(gr_circle
		(center 50.14976 -312.999882)
		(end 50.40376 -312.999882)
		(stroke
			(width 0.1016)
			(type default)
		)
		(fill no)
		(layer "In6.Cu")
	)
	(gr_circle
		(center 50.14976 -278.799798)
		(end 50.40376 -278.799798)
		(stroke
			(width 0.1016)
			(type default)
		)
		(fill no)
		(layer "In6.Cu")
	)
	(gr_circle
		(center 50.14976 -277.849838)
		(end 50.40376 -277.849838)
		(stroke
			(width 0.1016)
			(type default)
		)
		(fill no)
		(layer "In6.Cu")
	)
	(gr_circle
		(center 50.14976 -274.049744)
		(end 50.40376 -274.049744)
		(stroke
			(width 0.1016)
			(type default)
		)
		(fill no)
		(layer "In6.Cu")
	)
	(gr_circle
		(center 50.14976 -273.099784)
		(end 50.40376 -273.099784)
		(stroke
			(width 0.1016)
			(type default)
		)
		(fill no)
		(layer "In6.Cu")
	)
	(gr_circle
		(center 51.099974 -316.799722)
		(end 51.353974 -316.799722)
		(stroke
			(width 0.1016)
			(type default)
		)
		(fill no)
		(layer "In6.Cu")
	)
	(gr_circle
		(center 51.099974 -315.849762)
		(end 51.353974 -315.849762)
		(stroke
			(width 0.1016)
			(type default)
		)
		(fill no)
		(layer "In6.Cu")
	)
	(gr_circle
		(center 51.099974 -312.049922)
		(end 51.353974 -312.049922)
		(stroke
			(width 0.1016)
			(type default)
		)
		(fill no)
		(layer "In6.Cu")
	)
	(gr_circle
		(center 51.099974 -311.099962)
		(end 51.353974 -311.099962)
		(stroke
			(width 0.1016)
			(type default)
		)
		(fill no)
		(layer "In6.Cu")
	)
	(gr_circle
		(center 51.099974 -280.699464)
		(end 51.353974 -280.699464)
		(stroke
			(width 0.1016)
			(type default)
		)
		(fill no)
		(layer "In6.Cu")
	)
	(gr_circle
		(center 51.099974 -279.749504)
		(end 51.353974 -279.749504)
		(stroke
			(width 0.1016)
			(type default)
		)
		(fill no)
		(layer "In6.Cu")
	)
	(gr_circle
		(center 51.099974 -275.949918)
		(end 51.353974 -275.949918)
		(stroke
			(width 0.1016)
			(type default)
		)
		(fill no)
		(layer "In6.Cu")
	)
	(gr_circle
		(center 51.099974 -274.999958)
		(end 51.353974 -274.999958)
		(stroke
			(width 0.1016)
			(type default)
		)
		(fill no)
		(layer "In6.Cu")
	)
	(gr_circle
		(center 52.049934 -318.699896)
		(end 52.303934 -318.699896)
		(stroke
			(width 0.1016)
			(type default)
		)
		(fill no)
		(layer "In6.Cu")
	)
	(gr_circle
		(center 52.049934 -317.749936)
		(end 52.303934 -317.749936)
		(stroke
			(width 0.1016)
			(type default)
		)
		(fill no)
		(layer "In6.Cu")
	)
	(gr_circle
		(center 52.049934 -313.949842)
		(end 52.303934 -313.949842)
		(stroke
			(width 0.1016)
			(type default)
		)
		(fill no)
		(layer "In6.Cu")
	)
	(gr_circle
		(center 52.049934 -312.999882)
		(end 52.303934 -312.999882)
		(stroke
			(width 0.1016)
			(type default)
		)
		(fill no)
		(layer "In6.Cu")
	)
	(gr_circle
		(center 52.049934 -278.799798)
		(end 52.303934 -278.799798)
		(stroke
			(width 0.1016)
			(type default)
		)
		(fill no)
		(layer "In6.Cu")
	)
	(gr_circle
		(center 52.049934 -277.849838)
		(end 52.303934 -277.849838)
		(stroke
			(width 0.1016)
			(type default)
		)
		(fill no)
		(layer "In6.Cu")
	)
	(gr_circle
		(center 52.049934 -274.049744)
		(end 52.303934 -274.049744)
		(stroke
			(width 0.1016)
			(type default)
		)
		(fill no)
		(layer "In6.Cu")
	)
	(gr_circle
		(center 52.049934 -273.099784)
		(end 52.303934 -273.099784)
		(stroke
			(width 0.1016)
			(type default)
		)
		(fill no)
		(layer "In6.Cu")
	)
	(gr_circle
		(center 52.999894 -316.799722)
		(end 53.253894 -316.799722)
		(stroke
			(width 0.1016)
			(type default)
		)
		(fill no)
		(layer "In6.Cu")
	)
	(gr_circle
		(center 52.999894 -315.849762)
		(end 53.253894 -315.849762)
		(stroke
			(width 0.1016)
			(type default)
		)
		(fill no)
		(layer "In6.Cu")
	)
	(gr_circle
		(center 52.999894 -312.049922)
		(end 53.253894 -312.049922)
		(stroke
			(width 0.1016)
			(type default)
		)
		(fill no)
		(layer "In6.Cu")
	)
	(gr_circle
		(center 52.999894 -311.099962)
		(end 53.253894 -311.099962)
		(stroke
			(width 0.1016)
			(type default)
		)
		(fill no)
		(layer "In6.Cu")
	)
	(gr_circle
		(center 52.999894 -280.699464)
		(end 53.253894 -280.699464)
		(stroke
			(width 0.1016)
			(type default)
		)
		(fill no)
		(layer "In6.Cu")
	)
	(gr_circle
		(center 52.999894 -279.749504)
		(end 53.253894 -279.749504)
		(stroke
			(width 0.1016)
			(type default)
		)
		(fill no)
		(layer "In6.Cu")
	)
	(gr_circle
		(center 52.999894 -275.949918)
		(end 53.253894 -275.949918)
		(stroke
			(width 0.1016)
			(type default)
		)
		(fill no)
		(layer "In6.Cu")
	)
	(gr_circle
		(center 52.999894 -274.999958)
		(end 53.253894 -274.999958)
		(stroke
			(width 0.1016)
			(type default)
		)
		(fill no)
		(layer "In6.Cu")
	)
	(gr_circle
		(center 53.949854 -318.699896)
		(end 54.203854 -318.699896)
		(stroke
			(width 0.1016)
			(type default)
		)
		(fill no)
		(layer "In6.Cu")
	)
	(gr_circle
		(center 53.949854 -317.749936)
		(end 54.203854 -317.749936)
		(stroke
			(width 0.1016)
			(type default)
		)
		(fill no)
		(layer "In6.Cu")
	)
	(gr_circle
		(center 53.949854 -313.949842)
		(end 54.203854 -313.949842)
		(stroke
			(width 0.1016)
			(type default)
		)
		(fill no)
		(layer "In6.Cu")
	)
	(gr_circle
		(center 53.949854 -312.999882)
		(end 54.203854 -312.999882)
		(stroke
			(width 0.1016)
			(type default)
		)
		(fill no)
		(layer "In6.Cu")
	)
	(gr_circle
		(center 53.949854 -278.799798)
		(end 54.203854 -278.799798)
		(stroke
			(width 0.1016)
			(type default)
		)
		(fill no)
		(layer "In6.Cu")
	)
	(gr_circle
		(center 53.949854 -277.849838)
		(end 54.203854 -277.849838)
		(stroke
			(width 0.1016)
			(type default)
		)
		(fill no)
		(layer "In6.Cu")
	)
	(gr_circle
		(center 53.949854 -274.049744)
		(end 54.203854 -274.049744)
		(stroke
			(width 0.1016)
			(type default)
		)
		(fill no)
		(layer "In6.Cu")
	)
	(gr_circle
		(center 53.949854 -273.099784)
		(end 54.203854 -273.099784)
		(stroke
			(width 0.1016)
			(type default)
		)
		(fill no)
		(layer "In6.Cu")
	)
	(gr_circle
		(center 54.899814 -316.799722)
		(end 55.153814 -316.799722)
		(stroke
			(width 0.1016)
			(type default)
		)
		(fill no)
		(layer "In6.Cu")
	)
	(gr_circle
		(center 54.899814 -315.849762)
		(end 55.153814 -315.849762)
		(stroke
			(width 0.1016)
			(type default)
		)
		(fill no)
		(layer "In6.Cu")
	)
	(gr_circle
		(center 54.899814 -312.049922)
		(end 55.153814 -312.049922)
		(stroke
			(width 0.1016)
			(type default)
		)
		(fill no)
		(layer "In6.Cu")
	)
	(gr_circle
		(center 54.899814 -311.099962)
		(end 55.153814 -311.099962)
		(stroke
			(width 0.1016)
			(type default)
		)
		(fill no)
		(layer "In6.Cu")
	)
	(gr_circle
		(center 54.899814 -280.699464)
		(end 55.153814 -280.699464)
		(stroke
			(width 0.1016)
			(type default)
		)
		(fill no)
		(layer "In6.Cu")
	)
	(gr_circle
		(center 54.899814 -279.749504)
		(end 55.153814 -279.749504)
		(stroke
			(width 0.1016)
			(type default)
		)
		(fill no)
		(layer "In6.Cu")
	)
	(gr_circle
		(center 54.899814 -275.949918)
		(end 55.153814 -275.949918)
		(stroke
			(width 0.1016)
			(type default)
		)
		(fill no)
		(layer "In6.Cu")
	)
	(gr_circle
		(center 54.899814 -274.999958)
		(end 55.153814 -274.999958)
		(stroke
			(width 0.1016)
			(type default)
		)
		(fill no)
		(layer "In6.Cu")
	)
	(gr_circle
		(center 55.849774 -318.699896)
		(end 56.103774 -318.699896)
		(stroke
			(width 0.1016)
			(type default)
		)
		(fill no)
		(layer "In6.Cu")
	)
	(gr_circle
		(center 55.849774 -317.749936)
		(end 56.103774 -317.749936)
		(stroke
			(width 0.1016)
			(type default)
		)
		(fill no)
		(layer "In6.Cu")
	)
	(gr_circle
		(center 55.849774 -313.949842)
		(end 56.103774 -313.949842)
		(stroke
			(width 0.1016)
			(type default)
		)
		(fill no)
		(layer "In6.Cu")
	)
	(gr_circle
		(center 55.849774 -312.999882)
		(end 56.103774 -312.999882)
		(stroke
			(width 0.1016)
			(type default)
		)
		(fill no)
		(layer "In6.Cu")
	)
	(gr_circle
		(center 55.849774 -278.799798)
		(end 56.103774 -278.799798)
		(stroke
			(width 0.1016)
			(type default)
		)
		(fill no)
		(layer "In6.Cu")
	)
	(gr_circle
		(center 55.849774 -277.849838)
		(end 56.103774 -277.849838)
		(stroke
			(width 0.1016)
			(type default)
		)
		(fill no)
		(layer "In6.Cu")
	)
	(gr_circle
		(center 55.849774 -274.049744)
		(end 56.103774 -274.049744)
		(stroke
			(width 0.1016)
			(type default)
		)
		(fill no)
		(layer "In6.Cu")
	)
	(gr_circle
		(center 55.849774 -273.099784)
		(end 56.103774 -273.099784)
		(stroke
			(width 0.1016)
			(type default)
		)
		(fill no)
		(layer "In6.Cu")
	)
	(gr_circle
		(center 56.799734 -280.699464)
		(end 57.053734 -280.699464)
		(stroke
			(width 0.1016)
			(type default)
		)
		(fill no)
		(layer "In6.Cu")
	)
	(gr_circle
		(center 56.799734 -279.749504)
		(end 57.053734 -279.749504)
		(stroke
			(width 0.1016)
			(type default)
		)
		(fill no)
		(layer "In6.Cu")
	)
	(gr_circle
		(center 56.799988 -316.799722)
		(end 57.053988 -316.799722)
		(stroke
			(width 0.1016)
			(type default)
		)
		(fill no)
		(layer "In6.Cu")
	)
	(gr_circle
		(center 56.799988 -315.849762)
		(end 57.053988 -315.849762)
		(stroke
			(width 0.1016)
			(type default)
		)
		(fill no)
		(layer "In6.Cu")
	)
	(gr_circle
		(center 56.799988 -312.049922)
		(end 57.053988 -312.049922)
		(stroke
			(width 0.1016)
			(type default)
		)
		(fill no)
		(layer "In6.Cu")
	)
	(gr_circle
		(center 56.799988 -311.099962)
		(end 57.053988 -311.099962)
		(stroke
			(width 0.1016)
			(type default)
		)
		(fill no)
		(layer "In6.Cu")
	)
	(gr_circle
		(center 56.799988 -275.949918)
		(end 57.053988 -275.949918)
		(stroke
			(width 0.1016)
			(type default)
		)
		(fill no)
		(layer "In6.Cu")
	)
	(gr_circle
		(center 56.799988 -274.999958)
		(end 57.053988 -274.999958)
		(stroke
			(width 0.1016)
			(type default)
		)
		(fill no)
		(layer "In6.Cu")
	)
	(gr_circle
		(center 57.749948 -318.699896)
		(end 58.003948 -318.699896)
		(stroke
			(width 0.1016)
			(type default)
		)
		(fill no)
		(layer "In6.Cu")
	)
	(gr_circle
		(center 57.749948 -317.749936)
		(end 58.003948 -317.749936)
		(stroke
			(width 0.1016)
			(type default)
		)
		(fill no)
		(layer "In6.Cu")
	)
	(gr_circle
		(center 57.749948 -313.949842)
		(end 58.003948 -313.949842)
		(stroke
			(width 0.1016)
			(type default)
		)
		(fill no)
		(layer "In6.Cu")
	)
	(gr_circle
		(center 57.749948 -312.999882)
		(end 58.003948 -312.999882)
		(stroke
			(width 0.1016)
			(type default)
		)
		(fill no)
		(layer "In6.Cu")
	)
	(gr_circle
		(center 57.749948 -278.799798)
		(end 58.003948 -278.799798)
		(stroke
			(width 0.1016)
			(type default)
		)
		(fill no)
		(layer "In6.Cu")
	)
	(gr_circle
		(center 57.749948 -277.849838)
		(end 58.003948 -277.849838)
		(stroke
			(width 0.1016)
			(type default)
		)
		(fill no)
		(layer "In6.Cu")
	)
	(gr_circle
		(center 57.749948 -274.049744)
		(end 58.003948 -274.049744)
		(stroke
			(width 0.1016)
			(type default)
		)
		(fill no)
		(layer "In6.Cu")
	)
	(gr_circle
		(center 57.749948 -273.099784)
		(end 58.003948 -273.099784)
		(stroke
			(width 0.1016)
			(type default)
		)
		(fill no)
		(layer "In6.Cu")
	)
	(gr_circle
		(center 58.699908 -316.799722)
		(end 58.953908 -316.799722)
		(stroke
			(width 0.1016)
			(type default)
		)
		(fill no)
		(layer "In6.Cu")
	)
	(gr_circle
		(center 58.699908 -315.849762)
		(end 58.953908 -315.849762)
		(stroke
			(width 0.1016)
			(type default)
		)
		(fill no)
		(layer "In6.Cu")
	)
	(gr_circle
		(center 58.699908 -312.049922)
		(end 58.953908 -312.049922)
		(stroke
			(width 0.1016)
			(type default)
		)
		(fill no)
		(layer "In6.Cu")
	)
	(gr_circle
		(center 58.699908 -311.099962)
		(end 58.953908 -311.099962)
		(stroke
			(width 0.1016)
			(type default)
		)
		(fill no)
		(layer "In6.Cu")
	)
	(gr_circle
		(center 58.699908 -280.699464)
		(end 58.953908 -280.699464)
		(stroke
			(width 0.1016)
			(type default)
		)
		(fill no)
		(layer "In6.Cu")
	)
	(gr_circle
		(center 58.699908 -279.749504)
		(end 58.953908 -279.749504)
		(stroke
			(width 0.1016)
			(type default)
		)
		(fill no)
		(layer "In6.Cu")
	)
	(gr_circle
		(center 58.699908 -275.949918)
		(end 58.953908 -275.949918)
		(stroke
			(width 0.1016)
			(type default)
		)
		(fill no)
		(layer "In6.Cu")
	)
	(gr_circle
		(center 58.699908 -274.999958)
		(end 58.953908 -274.999958)
		(stroke
			(width 0.1016)
			(type default)
		)
		(fill no)
		(layer "In6.Cu")
	)
	(gr_circle
		(center 59.649614 -278.799798)
		(end 59.903614 -278.799798)
		(stroke
			(width 0.1016)
			(type default)
		)
		(fill no)
		(layer "In6.Cu")
	)
	(gr_circle
		(center 59.649614 -277.849838)
		(end 59.903614 -277.849838)
		(stroke
			(width 0.1016)
			(type default)
		)
		(fill no)
		(layer "In6.Cu")
	)
	(gr_circle
		(center 59.649868 -318.699896)
		(end 59.903868 -318.699896)
		(stroke
			(width 0.1016)
			(type default)
		)
		(fill no)
		(layer "In6.Cu")
	)
	(gr_circle
		(center 59.649868 -317.749936)
		(end 59.903868 -317.749936)
		(stroke
			(width 0.1016)
			(type default)
		)
		(fill no)
		(layer "In6.Cu")
	)
	(gr_circle
		(center 59.649868 -313.949842)
		(end 59.903868 -313.949842)
		(stroke
			(width 0.1016)
			(type default)
		)
		(fill no)
		(layer "In6.Cu")
	)
	(gr_circle
		(center 59.649868 -312.999882)
		(end 59.903868 -312.999882)
		(stroke
			(width 0.1016)
			(type default)
		)
		(fill no)
		(layer "In6.Cu")
	)
	(gr_circle
		(center 60.599828 -316.799722)
		(end 60.853828 -316.799722)
		(stroke
			(width 0.1016)
			(type default)
		)
		(fill no)
		(layer "In6.Cu")
	)
	(gr_circle
		(center 60.599828 -315.849762)
		(end 60.853828 -315.849762)
		(stroke
			(width 0.1016)
			(type default)
		)
		(fill no)
		(layer "In6.Cu")
	)
	(gr_circle
		(center 60.599828 -312.049922)
		(end 60.853828 -312.049922)
		(stroke
			(width 0.1016)
			(type default)
		)
		(fill no)
		(layer "In6.Cu")
	)
	(gr_circle
		(center 60.599828 -311.099962)
		(end 60.853828 -311.099962)
		(stroke
			(width 0.1016)
			(type default)
		)
		(fill no)
		(layer "In6.Cu")
	)
	(gr_circle
		(center 60.599828 -280.699464)
		(end 60.853828 -280.699464)
		(stroke
			(width 0.1016)
			(type default)
		)
		(fill no)
		(layer "In6.Cu")
	)
	(gr_circle
		(center 60.599828 -279.749504)
		(end 60.853828 -279.749504)
		(stroke
			(width 0.1016)
			(type default)
		)
		(fill no)
		(layer "In6.Cu")
	)
	(gr_circle
		(center 61.549534 -278.799798)
		(end 61.803534 -278.799798)
		(stroke
			(width 0.1016)
			(type default)
		)
		(fill no)
		(layer "In6.Cu")
	)
	(gr_circle
		(center 61.549534 -277.849838)
		(end 61.803534 -277.849838)
		(stroke
			(width 0.1016)
			(type default)
		)
		(fill no)
		(layer "In6.Cu")
	)
	(gr_circle
		(center 61.549788 -318.699896)
		(end 61.803788 -318.699896)
		(stroke
			(width 0.1016)
			(type default)
		)
		(fill no)
		(layer "In6.Cu")
	)
	(gr_circle
		(center 61.549788 -317.749936)
		(end 61.803788 -317.749936)
		(stroke
			(width 0.1016)
			(type default)
		)
		(fill no)
		(layer "In6.Cu")
	)
	(gr_circle
		(center 61.549788 -313.949842)
		(end 61.803788 -313.949842)
		(stroke
			(width 0.1016)
			(type default)
		)
		(fill no)
		(layer "In6.Cu")
	)
	(gr_circle
		(center 61.549788 -312.999882)
		(end 61.803788 -312.999882)
		(stroke
			(width 0.1016)
			(type default)
		)
		(fill no)
		(layer "In6.Cu")
	)
	(gr_circle
		(center 62.499748 -316.799722)
		(end 62.753748 -316.799722)
		(stroke
			(width 0.1016)
			(type default)
		)
		(fill no)
		(layer "In6.Cu")
	)
	(gr_circle
		(center 62.499748 -315.849762)
		(end 62.753748 -315.849762)
		(stroke
			(width 0.1016)
			(type default)
		)
		(fill no)
		(layer "In6.Cu")
	)
	(gr_circle
		(center 62.499748 -312.049922)
		(end 62.753748 -312.049922)
		(stroke
			(width 0.1016)
			(type default)
		)
		(fill no)
		(layer "In6.Cu")
	)
	(gr_circle
		(center 62.499748 -311.099962)
		(end 62.753748 -311.099962)
		(stroke
			(width 0.1016)
			(type default)
		)
		(fill no)
		(layer "In6.Cu")
	)
	(gr_circle
		(center 62.499748 -280.699464)
		(end 62.753748 -280.699464)
		(stroke
			(width 0.1016)
			(type default)
		)
		(fill no)
		(layer "In6.Cu")
	)
	(gr_circle
		(center 62.499748 -279.749504)
		(end 62.753748 -279.749504)
		(stroke
			(width 0.1016)
			(type default)
		)
		(fill no)
		(layer "In6.Cu")
	)
	(gr_circle
		(center 63.449708 -278.799798)
		(end 63.703708 -278.799798)
		(stroke
			(width 0.1016)
			(type default)
		)
		(fill no)
		(layer "In6.Cu")
	)
	(gr_circle
		(center 63.449708 -277.849838)
		(end 63.703708 -277.849838)
		(stroke
			(width 0.1016)
			(type default)
		)
		(fill no)
		(layer "In6.Cu")
	)
	(gr_circle
		(center 63.449962 -318.699896)
		(end 63.703962 -318.699896)
		(stroke
			(width 0.1016)
			(type default)
		)
		(fill no)
		(layer "In6.Cu")
	)
	(gr_circle
		(center 63.449962 -317.749936)
		(end 63.703962 -317.749936)
		(stroke
			(width 0.1016)
			(type default)
		)
		(fill no)
		(layer "In6.Cu")
	)
	(gr_circle
		(center 63.449962 -313.949842)
		(end 63.703962 -313.949842)
		(stroke
			(width 0.1016)
			(type default)
		)
		(fill no)
		(layer "In6.Cu")
	)
	(gr_circle
		(center 63.449962 -312.999882)
		(end 63.703962 -312.999882)
		(stroke
			(width 0.1016)
			(type default)
		)
		(fill no)
		(layer "In6.Cu")
	)
	(gr_circle
		(center 64.399922 -316.799722)
		(end 64.653922 -316.799722)
		(stroke
			(width 0.1016)
			(type default)
		)
		(fill no)
		(layer "In6.Cu")
	)
	(gr_circle
		(center 64.399922 -315.849762)
		(end 64.653922 -315.849762)
		(stroke
			(width 0.1016)
			(type default)
		)
		(fill no)
		(layer "In6.Cu")
	)
	(gr_circle
		(center 64.399922 -312.049922)
		(end 64.653922 -312.049922)
		(stroke
			(width 0.1016)
			(type default)
		)
		(fill no)
		(layer "In6.Cu")
	)
	(gr_circle
		(center 64.399922 -311.099962)
		(end 64.653922 -311.099962)
		(stroke
			(width 0.1016)
			(type default)
		)
		(fill no)
		(layer "In6.Cu")
	)
	(gr_circle
		(center 64.399922 -280.699464)
		(end 64.653922 -280.699464)
		(stroke
			(width 0.1016)
			(type default)
		)
		(fill no)
		(layer "In6.Cu")
	)
	(gr_circle
		(center 64.399922 -279.749504)
		(end 64.653922 -279.749504)
		(stroke
			(width 0.1016)
			(type default)
		)
		(fill no)
		(layer "In6.Cu")
	)
	(gr_circle
		(center 65.349628 -278.799798)
		(end 65.603628 -278.799798)
		(stroke
			(width 0.1016)
			(type default)
		)
		(fill no)
		(layer "In6.Cu")
	)
	(gr_circle
		(center 65.349628 -277.849838)
		(end 65.603628 -277.849838)
		(stroke
			(width 0.1016)
			(type default)
		)
		(fill no)
		(layer "In6.Cu")
	)
	(gr_circle
		(center 65.349882 -318.699896)
		(end 65.603882 -318.699896)
		(stroke
			(width 0.1016)
			(type default)
		)
		(fill no)
		(layer "In6.Cu")
	)
	(gr_circle
		(center 65.349882 -317.749936)
		(end 65.603882 -317.749936)
		(stroke
			(width 0.1016)
			(type default)
		)
		(fill no)
		(layer "In6.Cu")
	)
	(gr_circle
		(center 65.349882 -313.949842)
		(end 65.603882 -313.949842)
		(stroke
			(width 0.1016)
			(type default)
		)
		(fill no)
		(layer "In6.Cu")
	)
	(gr_circle
		(center 65.349882 -312.999882)
		(end 65.603882 -312.999882)
		(stroke
			(width 0.1016)
			(type default)
		)
		(fill no)
		(layer "In6.Cu")
	)
	(gr_circle
		(center 66.299842 -312.049922)
		(end 66.553842 -312.049922)
		(stroke
			(width 0.1016)
			(type default)
		)
		(fill no)
		(layer "In6.Cu")
	)
	(gr_circle
		(center 66.299842 -311.099962)
		(end 66.553842 -311.099962)
		(stroke
			(width 0.1016)
			(type default)
		)
		(fill no)
		(layer "In6.Cu")
	)
	(gr_circle
		(center 66.299842 -280.699464)
		(end 66.553842 -280.699464)
		(stroke
			(width 0.1016)
			(type default)
		)
		(fill no)
		(layer "In6.Cu")
	)
	(gr_circle
		(center 66.299842 -279.749504)
		(end 66.553842 -279.749504)
		(stroke
			(width 0.1016)
			(type default)
		)
		(fill no)
		(layer "In6.Cu")
	)
	(gr_circle
		(center 67.249548 -278.799798)
		(end 67.503548 -278.799798)
		(stroke
			(width 0.1016)
			(type default)
		)
		(fill no)
		(layer "In6.Cu")
	)
	(gr_circle
		(center 67.249548 -277.849838)
		(end 67.503548 -277.849838)
		(stroke
			(width 0.1016)
			(type default)
		)
		(fill no)
		(layer "In6.Cu")
	)
	(gr_circle
		(center 67.249802 -313.949842)
		(end 67.503802 -313.949842)
		(stroke
			(width 0.1016)
			(type default)
		)
		(fill no)
		(layer "In6.Cu")
	)
	(gr_circle
		(center 67.249802 -312.999882)
		(end 67.503802 -312.999882)
		(stroke
			(width 0.1016)
			(type default)
		)
		(fill no)
		(layer "In6.Cu")
	)
	(gr_circle
		(center 68.199762 -312.049922)
		(end 68.453762 -312.049922)
		(stroke
			(width 0.1016)
			(type default)
		)
		(fill no)
		(layer "In6.Cu")
	)
	(gr_circle
		(center 68.199762 -311.099962)
		(end 68.453762 -311.099962)
		(stroke
			(width 0.1016)
			(type default)
		)
		(fill no)
		(layer "In6.Cu")
	)
	(gr_circle
		(center 68.199762 -280.699464)
		(end 68.453762 -280.699464)
		(stroke
			(width 0.1016)
			(type default)
		)
		(fill no)
		(layer "In6.Cu")
	)
	(gr_circle
		(center 68.199762 -279.749504)
		(end 68.453762 -279.749504)
		(stroke
			(width 0.1016)
			(type default)
		)
		(fill no)
		(layer "In6.Cu")
	)
	(gr_circle
		(center 69.149722 -278.799798)
		(end 69.403722 -278.799798)
		(stroke
			(width 0.1016)
			(type default)
		)
		(fill no)
		(layer "In6.Cu")
	)
	(gr_circle
		(center 69.149722 -277.849838)
		(end 69.403722 -277.849838)
		(stroke
			(width 0.1016)
			(type default)
		)
		(fill no)
		(layer "In6.Cu")
	)
	(gr_circle
		(center 69.149976 -313.949842)
		(end 69.403976 -313.949842)
		(stroke
			(width 0.1016)
			(type default)
		)
		(fill no)
		(layer "In6.Cu")
	)
	(gr_circle
		(center 69.149976 -312.999882)
		(end 69.403976 -312.999882)
		(stroke
			(width 0.1016)
			(type default)
		)
		(fill no)
		(layer "In6.Cu")
	)
	(gr_circle
		(center 70.099936 -312.049922)
		(end 70.353936 -312.049922)
		(stroke
			(width 0.1016)
			(type default)
		)
		(fill no)
		(layer "In6.Cu")
	)
	(gr_circle
		(center 70.099936 -311.099962)
		(end 70.353936 -311.099962)
		(stroke
			(width 0.1016)
			(type default)
		)
		(fill no)
		(layer "In6.Cu")
	)
	(gr_circle
		(center 70.099936 -280.699464)
		(end 70.353936 -280.699464)
		(stroke
			(width 0.1016)
			(type default)
		)
		(fill no)
		(layer "In6.Cu")
	)
	(gr_circle
		(center 70.099936 -279.749504)
		(end 70.353936 -279.749504)
		(stroke
			(width 0.1016)
			(type default)
		)
		(fill no)
		(layer "In6.Cu")
	)
	(gr_circle
		(center 71.049642 -278.799798)
		(end 71.303642 -278.799798)
		(stroke
			(width 0.1016)
			(type default)
		)
		(fill no)
		(layer "In6.Cu")
	)
	(gr_circle
		(center 71.049642 -277.849838)
		(end 71.303642 -277.849838)
		(stroke
			(width 0.1016)
			(type default)
		)
		(fill no)
		(layer "In6.Cu")
	)
	(gr_circle
		(center 71.049896 -313.949842)
		(end 71.303896 -313.949842)
		(stroke
			(width 0.1016)
			(type default)
		)
		(fill no)
		(layer "In6.Cu")
	)
	(gr_circle
		(center 71.049896 -312.999882)
		(end 71.303896 -312.999882)
		(stroke
			(width 0.1016)
			(type default)
		)
		(fill no)
		(layer "In6.Cu")
	)
	(gr_circle
		(center 71.999856 -312.049922)
		(end 72.253856 -312.049922)
		(stroke
			(width 0.1016)
			(type default)
		)
		(fill no)
		(layer "In6.Cu")
	)
	(gr_circle
		(center 71.999856 -311.099962)
		(end 72.253856 -311.099962)
		(stroke
			(width 0.1016)
			(type default)
		)
		(fill no)
		(layer "In6.Cu")
	)
	(gr_circle
		(center 71.999856 -280.699464)
		(end 72.253856 -280.699464)
		(stroke
			(width 0.1016)
			(type default)
		)
		(fill no)
		(layer "In6.Cu")
	)
	(gr_circle
		(center 71.999856 -279.749504)
		(end 72.253856 -279.749504)
		(stroke
			(width 0.1016)
			(type default)
		)
		(fill no)
		(layer "In6.Cu")
	)
	(gr_circle
		(center 72.949562 -278.799798)
		(end 73.203562 -278.799798)
		(stroke
			(width 0.1016)
			(type default)
		)
		(fill no)
		(layer "In6.Cu")
	)
	(gr_circle
		(center 72.949562 -277.849838)
		(end 73.203562 -277.849838)
		(stroke
			(width 0.1016)
			(type default)
		)
		(fill no)
		(layer "In6.Cu")
	)
	(gr_circle
		(center 72.949816 -313.949842)
		(end 73.203816 -313.949842)
		(stroke
			(width 0.1016)
			(type default)
		)
		(fill no)
		(layer "In6.Cu")
	)
	(gr_circle
		(center 72.949816 -312.999882)
		(end 73.203816 -312.999882)
		(stroke
			(width 0.1016)
			(type default)
		)
		(fill no)
		(layer "In6.Cu")
	)
	(gr_circle
		(center 73.899776 -316.799722)
		(end 74.153776 -316.799722)
		(stroke
			(width 0.1016)
			(type default)
		)
		(fill no)
		(layer "In6.Cu")
	)
	(gr_circle
		(center 73.899776 -315.849762)
		(end 74.153776 -315.849762)
		(stroke
			(width 0.1016)
			(type default)
		)
		(fill no)
		(layer "In6.Cu")
	)
	(gr_circle
		(center 73.899776 -312.049922)
		(end 74.153776 -312.049922)
		(stroke
			(width 0.1016)
			(type default)
		)
		(fill no)
		(layer "In6.Cu")
	)
	(gr_circle
		(center 73.899776 -311.099962)
		(end 74.153776 -311.099962)
		(stroke
			(width 0.1016)
			(type default)
		)
		(fill no)
		(layer "In6.Cu")
	)
	(gr_circle
		(center 73.899776 -280.699464)
		(end 74.153776 -280.699464)
		(stroke
			(width 0.1016)
			(type default)
		)
		(fill no)
		(layer "In6.Cu")
	)
	(gr_circle
		(center 73.899776 -279.749504)
		(end 74.153776 -279.749504)
		(stroke
			(width 0.1016)
			(type default)
		)
		(fill no)
		(layer "In6.Cu")
	)
	(gr_circle
		(center 74.849736 -278.799798)
		(end 75.103736 -278.799798)
		(stroke
			(width 0.1016)
			(type default)
		)
		(fill no)
		(layer "In6.Cu")
	)
	(gr_circle
		(center 74.849736 -277.849838)
		(end 75.103736 -277.849838)
		(stroke
			(width 0.1016)
			(type default)
		)
		(fill no)
		(layer "In6.Cu")
	)
	(gr_circle
		(center 74.84999 -318.699896)
		(end 75.10399 -318.699896)
		(stroke
			(width 0.1016)
			(type default)
		)
		(fill no)
		(layer "In6.Cu")
	)
	(gr_circle
		(center 74.84999 -317.749936)
		(end 75.10399 -317.749936)
		(stroke
			(width 0.1016)
			(type default)
		)
		(fill no)
		(layer "In6.Cu")
	)
	(gr_circle
		(center 74.84999 -313.949842)
		(end 75.10399 -313.949842)
		(stroke
			(width 0.1016)
			(type default)
		)
		(fill no)
		(layer "In6.Cu")
	)
	(gr_circle
		(center 74.84999 -312.999882)
		(end 75.10399 -312.999882)
		(stroke
			(width 0.1016)
			(type default)
		)
		(fill no)
		(layer "In6.Cu")
	)
	(gr_circle
		(center 74.84999 -308.249828)
		(end 75.10399 -308.249828)
		(stroke
			(width 0.1016)
			(type default)
		)
		(fill no)
		(layer "In6.Cu")
	)
	(gr_circle
		(center 74.84999 -306.349908)
		(end 75.10399 -306.349908)
		(stroke
			(width 0.1016)
			(type default)
		)
		(fill no)
		(layer "In6.Cu")
	)
	(gr_circle
		(center 74.84999 -304.449734)
		(end 75.10399 -304.449734)
		(stroke
			(width 0.1016)
			(type default)
		)
		(fill no)
		(layer "In6.Cu")
	)
	(gr_circle
		(center 74.84999 -287.349946)
		(end 75.10399 -287.349946)
		(stroke
			(width 0.1016)
			(type default)
		)
		(fill no)
		(layer "In6.Cu")
	)
	(gr_circle
		(center 74.84999 -285.449772)
		(end 75.10399 -285.449772)
		(stroke
			(width 0.1016)
			(type default)
		)
		(fill no)
		(layer "In6.Cu")
	)
	(gr_circle
		(center 74.84999 -283.549852)
		(end 75.10399 -283.549852)
		(stroke
			(width 0.1016)
			(type default)
		)
		(fill no)
		(layer "In6.Cu")
	)
	(gr_circle
		(center 75.79995 -316.799722)
		(end 76.05395 -316.799722)
		(stroke
			(width 0.1016)
			(type default)
		)
		(fill no)
		(layer "In6.Cu")
	)
	(gr_circle
		(center 75.79995 -315.849762)
		(end 76.05395 -315.849762)
		(stroke
			(width 0.1016)
			(type default)
		)
		(fill no)
		(layer "In6.Cu")
	)
	(gr_circle
		(center 75.79995 -312.049922)
		(end 76.05395 -312.049922)
		(stroke
			(width 0.1016)
			(type default)
		)
		(fill no)
		(layer "In6.Cu")
	)
	(gr_circle
		(center 75.79995 -311.099962)
		(end 76.05395 -311.099962)
		(stroke
			(width 0.1016)
			(type default)
		)
		(fill no)
		(layer "In6.Cu")
	)
	(gr_circle
		(center 75.79995 -308.249828)
		(end 76.05395 -308.249828)
		(stroke
			(width 0.1016)
			(type default)
		)
		(fill no)
		(layer "In6.Cu")
	)
	(gr_circle
		(center 75.79995 -306.349908)
		(end 76.05395 -306.349908)
		(stroke
			(width 0.1016)
			(type default)
		)
		(fill no)
		(layer "In6.Cu")
	)
	(gr_circle
		(center 75.79995 -304.449734)
		(end 76.05395 -304.449734)
		(stroke
			(width 0.1016)
			(type default)
		)
		(fill no)
		(layer "In6.Cu")
	)
	(gr_circle
		(center 75.79995 -287.349946)
		(end 76.05395 -287.349946)
		(stroke
			(width 0.1016)
			(type default)
		)
		(fill no)
		(layer "In6.Cu")
	)
	(gr_circle
		(center 75.79995 -285.449772)
		(end 76.05395 -285.449772)
		(stroke
			(width 0.1016)
			(type default)
		)
		(fill no)
		(layer "In6.Cu")
	)
	(gr_circle
		(center 75.79995 -283.549852)
		(end 76.05395 -283.549852)
		(stroke
			(width 0.1016)
			(type default)
		)
		(fill no)
		(layer "In6.Cu")
	)
	(gr_circle
		(center 75.79995 -280.699464)
		(end 76.05395 -280.699464)
		(stroke
			(width 0.1016)
			(type default)
		)
		(fill no)
		(layer "In6.Cu")
	)
	(gr_circle
		(center 75.79995 -279.749504)
		(end 76.05395 -279.749504)
		(stroke
			(width 0.1016)
			(type default)
		)
		(fill no)
		(layer "In6.Cu")
	)
	(gr_circle
		(center 76.749656 -278.799798)
		(end 77.003656 -278.799798)
		(stroke
			(width 0.1016)
			(type default)
		)
		(fill no)
		(layer "In6.Cu")
	)
	(gr_circle
		(center 76.749656 -277.849838)
		(end 77.003656 -277.849838)
		(stroke
			(width 0.1016)
			(type default)
		)
		(fill no)
		(layer "In6.Cu")
	)
	(gr_circle
		(center 76.74991 -318.699896)
		(end 77.00391 -318.699896)
		(stroke
			(width 0.1016)
			(type default)
		)
		(fill no)
		(layer "In6.Cu")
	)
	(gr_circle
		(center 76.74991 -317.749936)
		(end 77.00391 -317.749936)
		(stroke
			(width 0.1016)
			(type default)
		)
		(fill no)
		(layer "In6.Cu")
	)
	(gr_circle
		(center 76.74991 -313.949842)
		(end 77.00391 -313.949842)
		(stroke
			(width 0.1016)
			(type default)
		)
		(fill no)
		(layer "In6.Cu")
	)
	(gr_circle
		(center 76.74991 -312.999882)
		(end 77.00391 -312.999882)
		(stroke
			(width 0.1016)
			(type default)
		)
		(fill no)
		(layer "In6.Cu")
	)
	(gr_circle
		(center 76.74991 -309.199788)
		(end 77.00391 -309.199788)
		(stroke
			(width 0.1016)
			(type default)
		)
		(fill no)
		(layer "In6.Cu")
	)
	(gr_circle
		(center 76.74991 -307.299868)
		(end 77.00391 -307.299868)
		(stroke
			(width 0.1016)
			(type default)
		)
		(fill no)
		(layer "In6.Cu")
	)
	(gr_circle
		(center 76.74991 -305.399948)
		(end 77.00391 -305.399948)
		(stroke
			(width 0.1016)
			(type default)
		)
		(fill no)
		(layer "In6.Cu")
	)
	(gr_circle
		(center 76.74991 -288.299906)
		(end 77.00391 -288.299906)
		(stroke
			(width 0.1016)
			(type default)
		)
		(fill no)
		(layer "In6.Cu")
	)
	(gr_circle
		(center 76.74991 -286.399986)
		(end 77.00391 -286.399986)
		(stroke
			(width 0.1016)
			(type default)
		)
		(fill no)
		(layer "In6.Cu")
	)
	(gr_circle
		(center 76.74991 -284.499812)
		(end 77.00391 -284.499812)
		(stroke
			(width 0.1016)
			(type default)
		)
		(fill no)
		(layer "In6.Cu")
	)
	(gr_circle
		(center 76.74991 -282.599892)
		(end 77.00391 -282.599892)
		(stroke
			(width 0.1016)
			(type default)
		)
		(fill no)
		(layer "In6.Cu")
	)
	(gr_circle
		(center 77.69987 -316.799722)
		(end 77.95387 -316.799722)
		(stroke
			(width 0.1016)
			(type default)
		)
		(fill no)
		(layer "In6.Cu")
	)
	(gr_circle
		(center 77.69987 -315.849762)
		(end 77.95387 -315.849762)
		(stroke
			(width 0.1016)
			(type default)
		)
		(fill no)
		(layer "In6.Cu")
	)
	(gr_circle
		(center 77.69987 -312.049922)
		(end 77.95387 -312.049922)
		(stroke
			(width 0.1016)
			(type default)
		)
		(fill no)
		(layer "In6.Cu")
	)
	(gr_circle
		(center 77.69987 -311.099962)
		(end 77.95387 -311.099962)
		(stroke
			(width 0.1016)
			(type default)
		)
		(fill no)
		(layer "In6.Cu")
	)
	(gr_circle
		(center 77.69987 -309.199788)
		(end 77.95387 -309.199788)
		(stroke
			(width 0.1016)
			(type default)
		)
		(fill no)
		(layer "In6.Cu")
	)
	(gr_circle
		(center 77.69987 -307.299868)
		(end 77.95387 -307.299868)
		(stroke
			(width 0.1016)
			(type default)
		)
		(fill no)
		(layer "In6.Cu")
	)
	(gr_circle
		(center 77.69987 -305.399948)
		(end 77.95387 -305.399948)
		(stroke
			(width 0.1016)
			(type default)
		)
		(fill no)
		(layer "In6.Cu")
	)
	(gr_circle
		(center 77.69987 -288.299906)
		(end 77.95387 -288.299906)
		(stroke
			(width 0.1016)
			(type default)
		)
		(fill no)
		(layer "In6.Cu")
	)
	(gr_circle
		(center 77.69987 -286.399986)
		(end 77.95387 -286.399986)
		(stroke
			(width 0.1016)
			(type default)
		)
		(fill no)
		(layer "In6.Cu")
	)
	(gr_circle
		(center 77.69987 -284.499812)
		(end 77.95387 -284.499812)
		(stroke
			(width 0.1016)
			(type default)
		)
		(fill no)
		(layer "In6.Cu")
	)
	(gr_circle
		(center 77.69987 -282.599892)
		(end 77.95387 -282.599892)
		(stroke
			(width 0.1016)
			(type default)
		)
		(fill no)
		(layer "In6.Cu")
	)
	(gr_circle
		(center 77.69987 -280.699464)
		(end 77.95387 -280.699464)
		(stroke
			(width 0.1016)
			(type default)
		)
		(fill no)
		(layer "In6.Cu")
	)
	(gr_circle
		(center 77.69987 -279.749504)
		(end 77.95387 -279.749504)
		(stroke
			(width 0.1016)
			(type default)
		)
		(fill no)
		(layer "In6.Cu")
	)
	(gr_circle
		(center 78.649576 -278.799798)
		(end 78.903576 -278.799798)
		(stroke
			(width 0.1016)
			(type default)
		)
		(fill no)
		(layer "In6.Cu")
	)
	(gr_circle
		(center 78.649576 -277.849838)
		(end 78.903576 -277.849838)
		(stroke
			(width 0.1016)
			(type default)
		)
		(fill no)
		(layer "In6.Cu")
	)
	(gr_circle
		(center 78.64983 -318.699896)
		(end 78.90383 -318.699896)
		(stroke
			(width 0.1016)
			(type default)
		)
		(fill no)
		(layer "In6.Cu")
	)
	(gr_circle
		(center 78.64983 -317.749936)
		(end 78.90383 -317.749936)
		(stroke
			(width 0.1016)
			(type default)
		)
		(fill no)
		(layer "In6.Cu")
	)
	(gr_circle
		(center 78.64983 -313.949842)
		(end 78.90383 -313.949842)
		(stroke
			(width 0.1016)
			(type default)
		)
		(fill no)
		(layer "In6.Cu")
	)
	(gr_circle
		(center 78.64983 -312.999882)
		(end 78.90383 -312.999882)
		(stroke
			(width 0.1016)
			(type default)
		)
		(fill no)
		(layer "In6.Cu")
	)
	(gr_circle
		(center 79.59979 -316.799722)
		(end 79.85379 -316.799722)
		(stroke
			(width 0.1016)
			(type default)
		)
		(fill no)
		(layer "In6.Cu")
	)
	(gr_circle
		(center 79.59979 -315.849762)
		(end 79.85379 -315.849762)
		(stroke
			(width 0.1016)
			(type default)
		)
		(fill no)
		(layer "In6.Cu")
	)
	(gr_circle
		(center 79.59979 -312.049922)
		(end 79.85379 -312.049922)
		(stroke
			(width 0.1016)
			(type default)
		)
		(fill no)
		(layer "In6.Cu")
	)
	(gr_circle
		(center 79.59979 -311.099962)
		(end 79.85379 -311.099962)
		(stroke
			(width 0.1016)
			(type default)
		)
		(fill no)
		(layer "In6.Cu")
	)
	(gr_circle
		(center 79.59979 -309.199788)
		(end 79.85379 -309.199788)
		(stroke
			(width 0.1016)
			(type default)
		)
		(fill no)
		(layer "In6.Cu")
	)
	(gr_circle
		(center 79.59979 -307.299868)
		(end 79.85379 -307.299868)
		(stroke
			(width 0.1016)
			(type default)
		)
		(fill no)
		(layer "In6.Cu")
	)
	(gr_circle
		(center 79.59979 -305.399948)
		(end 79.85379 -305.399948)
		(stroke
			(width 0.1016)
			(type default)
		)
		(fill no)
		(layer "In6.Cu")
	)
	(gr_circle
		(center 79.59979 -280.699718)
		(end 79.85379 -280.699718)
		(stroke
			(width 0.1016)
			(type default)
		)
		(fill no)
		(layer "In6.Cu")
	)
	(gr_circle
		(center 79.59979 -279.749758)
		(end 79.85379 -279.749758)
		(stroke
			(width 0.1016)
			(type default)
		)
		(fill no)
		(layer "In6.Cu")
	)
	(gr_circle
		(center 80.54975 -318.699896)
		(end 80.80375 -318.699896)
		(stroke
			(width 0.1016)
			(type default)
		)
		(fill no)
		(layer "In6.Cu")
	)
	(gr_circle
		(center 80.54975 -317.749936)
		(end 80.80375 -317.749936)
		(stroke
			(width 0.1016)
			(type default)
		)
		(fill no)
		(layer "In6.Cu")
	)
	(gr_circle
		(center 80.54975 -313.949842)
		(end 80.80375 -313.949842)
		(stroke
			(width 0.1016)
			(type default)
		)
		(fill no)
		(layer "In6.Cu")
	)
	(gr_circle
		(center 80.54975 -312.999882)
		(end 80.80375 -312.999882)
		(stroke
			(width 0.1016)
			(type default)
		)
		(fill no)
		(layer "In6.Cu")
	)
	(gr_circle
		(center 80.54975 -309.199788)
		(end 80.80375 -309.199788)
		(stroke
			(width 0.1016)
			(type default)
		)
		(fill no)
		(layer "In6.Cu")
	)
	(gr_circle
		(center 80.54975 -307.299868)
		(end 80.80375 -307.299868)
		(stroke
			(width 0.1016)
			(type default)
		)
		(fill no)
		(layer "In6.Cu")
	)
	(gr_circle
		(center 80.54975 -305.399948)
		(end 80.80375 -305.399948)
		(stroke
			(width 0.1016)
			(type default)
		)
		(fill no)
		(layer "In6.Cu")
	)
	(gr_circle
		(center 80.54975 -278.799798)
		(end 80.80375 -278.799798)
		(stroke
			(width 0.1016)
			(type default)
		)
		(fill no)
		(layer "In6.Cu")
	)
	(gr_circle
		(center 80.54975 -277.849838)
		(end 80.80375 -277.849838)
		(stroke
			(width 0.1016)
			(type default)
		)
		(fill no)
		(layer "In6.Cu")
	)
	(gr_circle
		(center 81.499964 -316.799722)
		(end 81.753964 -316.799722)
		(stroke
			(width 0.1016)
			(type default)
		)
		(fill no)
		(layer "In6.Cu")
	)
	(gr_circle
		(center 81.499964 -314.899802)
		(end 81.753964 -314.899802)
		(stroke
			(width 0.1016)
			(type default)
		)
		(fill no)
		(layer "In6.Cu")
	)
	(gr_circle
		(center 81.499964 -312.049922)
		(end 81.753964 -312.049922)
		(stroke
			(width 0.1016)
			(type default)
		)
		(fill no)
		(layer "In6.Cu")
	)
	(gr_circle
		(center 81.499964 -310.149748)
		(end 81.753964 -310.149748)
		(stroke
			(width 0.1016)
			(type default)
		)
		(fill no)
		(layer "In6.Cu")
	)
	(gr_circle
		(center 81.499964 -308.249828)
		(end 81.753964 -308.249828)
		(stroke
			(width 0.1016)
			(type default)
		)
		(fill no)
		(layer "In6.Cu")
	)
	(gr_circle
		(center 81.499964 -306.349908)
		(end 81.753964 -306.349908)
		(stroke
			(width 0.1016)
			(type default)
		)
		(fill no)
		(layer "In6.Cu")
	)
	(gr_circle
		(center 81.499964 -304.449734)
		(end 81.753964 -304.449734)
		(stroke
			(width 0.1016)
			(type default)
		)
		(fill no)
		(layer "In6.Cu")
	)
	(gr_circle
		(center 81.499964 -279.749758)
		(end 81.753964 -279.749758)
		(stroke
			(width 0.1016)
			(type default)
		)
		(fill no)
		(layer "In6.Cu")
	)
	(gr_circle
		(center 81.499964 -276.899878)
		(end 81.753964 -276.899878)
		(stroke
			(width 0.1016)
			(type default)
		)
		(fill no)
		(layer "In6.Cu")
	)
	(gr_circle
		(center 82.449924 -316.799722)
		(end 82.703924 -316.799722)
		(stroke
			(width 0.1016)
			(type default)
		)
		(fill no)
		(layer "In6.Cu")
	)
	(gr_circle
		(center 82.449924 -314.899802)
		(end 82.703924 -314.899802)
		(stroke
			(width 0.1016)
			(type default)
		)
		(fill no)
		(layer "In6.Cu")
	)
	(gr_circle
		(center 82.449924 -312.049922)
		(end 82.703924 -312.049922)
		(stroke
			(width 0.1016)
			(type default)
		)
		(fill no)
		(layer "In6.Cu")
	)
	(gr_circle
		(center 82.449924 -310.149748)
		(end 82.703924 -310.149748)
		(stroke
			(width 0.1016)
			(type default)
		)
		(fill no)
		(layer "In6.Cu")
	)
	(gr_circle
		(center 82.449924 -308.249828)
		(end 82.703924 -308.249828)
		(stroke
			(width 0.1016)
			(type default)
		)
		(fill no)
		(layer "In6.Cu")
	)
	(gr_circle
		(center 82.449924 -306.349908)
		(end 82.703924 -306.349908)
		(stroke
			(width 0.1016)
			(type default)
		)
		(fill no)
		(layer "In6.Cu")
	)
	(gr_circle
		(center 82.449924 -304.449734)
		(end 82.703924 -304.449734)
		(stroke
			(width 0.1016)
			(type default)
		)
		(fill no)
		(layer "In6.Cu")
	)
	(gr_circle
		(center 82.449924 -279.749758)
		(end 82.703924 -279.749758)
		(stroke
			(width 0.1016)
			(type default)
		)
		(fill no)
		(layer "In6.Cu")
	)
	(gr_circle
		(center 82.449924 -276.899878)
		(end 82.703924 -276.899878)
		(stroke
			(width 0.1016)
			(type default)
		)
		(fill no)
		(layer "In6.Cu")
	)
	(gr_circle
		(center 152.94991 -316.799722)
		(end 153.20391 -316.799722)
		(stroke
			(width 0.1016)
			(type default)
		)
		(fill no)
		(layer "In6.Cu")
	)
	(gr_circle
		(center 152.94991 -314.899802)
		(end 153.20391 -314.899802)
		(stroke
			(width 0.1016)
			(type default)
		)
		(fill no)
		(layer "In6.Cu")
	)
	(gr_circle
		(center 152.94991 -312.049922)
		(end 153.20391 -312.049922)
		(stroke
			(width 0.1016)
			(type default)
		)
		(fill no)
		(layer "In6.Cu")
	)
	(gr_circle
		(center 152.94991 -310.149748)
		(end 153.20391 -310.149748)
		(stroke
			(width 0.1016)
			(type default)
		)
		(fill no)
		(layer "In6.Cu")
	)
	(gr_circle
		(center 152.94991 -308.249828)
		(end 153.20391 -308.249828)
		(stroke
			(width 0.1016)
			(type default)
		)
		(fill no)
		(layer "In6.Cu")
	)
	(gr_circle
		(center 152.94991 -306.349908)
		(end 153.20391 -306.349908)
		(stroke
			(width 0.1016)
			(type default)
		)
		(fill no)
		(layer "In6.Cu")
	)
	(gr_circle
		(center 152.94991 -304.449734)
		(end 153.20391 -304.449734)
		(stroke
			(width 0.1016)
			(type default)
		)
		(fill no)
		(layer "In6.Cu")
	)
	(gr_circle
		(center 152.94991 -302.549814)
		(end 153.20391 -302.549814)
		(stroke
			(width 0.1016)
			(type default)
		)
		(fill no)
		(layer "In6.Cu")
	)
	(gr_circle
		(center 153.89987 -316.799722)
		(end 154.15387 -316.799722)
		(stroke
			(width 0.1016)
			(type default)
		)
		(fill no)
		(layer "In6.Cu")
	)
	(gr_circle
		(center 153.89987 -314.899802)
		(end 154.15387 -314.899802)
		(stroke
			(width 0.1016)
			(type default)
		)
		(fill no)
		(layer "In6.Cu")
	)
	(gr_circle
		(center 153.89987 -312.049922)
		(end 154.15387 -312.049922)
		(stroke
			(width 0.1016)
			(type default)
		)
		(fill no)
		(layer "In6.Cu")
	)
	(gr_circle
		(center 153.89987 -310.149748)
		(end 154.15387 -310.149748)
		(stroke
			(width 0.1016)
			(type default)
		)
		(fill no)
		(layer "In6.Cu")
	)
	(gr_circle
		(center 153.89987 -308.249828)
		(end 154.15387 -308.249828)
		(stroke
			(width 0.1016)
			(type default)
		)
		(fill no)
		(layer "In6.Cu")
	)
	(gr_circle
		(center 153.89987 -306.349908)
		(end 154.15387 -306.349908)
		(stroke
			(width 0.1016)
			(type default)
		)
		(fill no)
		(layer "In6.Cu")
	)
	(gr_circle
		(center 153.89987 -304.449734)
		(end 154.15387 -304.449734)
		(stroke
			(width 0.1016)
			(type default)
		)
		(fill no)
		(layer "In6.Cu")
	)
	(gr_circle
		(center 153.89987 -302.549814)
		(end 154.15387 -302.549814)
		(stroke
			(width 0.1016)
			(type default)
		)
		(fill no)
		(layer "In6.Cu")
	)
	(gr_circle
		(center 154.850084 -318.699896)
		(end 155.104084 -318.699896)
		(stroke
			(width 0.1016)
			(type default)
		)
		(fill no)
		(layer "In6.Cu")
	)
	(gr_circle
		(center 154.850084 -317.749936)
		(end 155.104084 -317.749936)
		(stroke
			(width 0.1016)
			(type default)
		)
		(fill no)
		(layer "In6.Cu")
	)
	(gr_circle
		(center 154.850084 -313.949842)
		(end 155.104084 -313.949842)
		(stroke
			(width 0.1016)
			(type default)
		)
		(fill no)
		(layer "In6.Cu")
	)
	(gr_circle
		(center 154.850084 -312.999882)
		(end 155.104084 -312.999882)
		(stroke
			(width 0.1016)
			(type default)
		)
		(fill no)
		(layer "In6.Cu")
	)
	(gr_circle
		(center 154.850084 -309.199788)
		(end 155.104084 -309.199788)
		(stroke
			(width 0.1016)
			(type default)
		)
		(fill no)
		(layer "In6.Cu")
	)
	(gr_circle
		(center 154.850084 -307.299868)
		(end 155.104084 -307.299868)
		(stroke
			(width 0.1016)
			(type default)
		)
		(fill no)
		(layer "In6.Cu")
	)
	(gr_circle
		(center 154.850084 -305.399948)
		(end 155.104084 -305.399948)
		(stroke
			(width 0.1016)
			(type default)
		)
		(fill no)
		(layer "In6.Cu")
	)
	(gr_circle
		(center 154.850084 -303.499774)
		(end 155.104084 -303.499774)
		(stroke
			(width 0.1016)
			(type default)
		)
		(fill no)
		(layer "In6.Cu")
	)
	(gr_circle
		(center 154.850084 -301.599854)
		(end 155.104084 -301.599854)
		(stroke
			(width 0.1016)
			(type default)
		)
		(fill no)
		(layer "In6.Cu")
	)
	(gr_circle
		(center 155.800044 -316.799722)
		(end 156.054044 -316.799722)
		(stroke
			(width 0.1016)
			(type default)
		)
		(fill no)
		(layer "In6.Cu")
	)
	(gr_circle
		(center 155.800044 -315.849762)
		(end 156.054044 -315.849762)
		(stroke
			(width 0.1016)
			(type default)
		)
		(fill no)
		(layer "In6.Cu")
	)
	(gr_circle
		(center 155.800044 -312.049922)
		(end 156.054044 -312.049922)
		(stroke
			(width 0.1016)
			(type default)
		)
		(fill no)
		(layer "In6.Cu")
	)
	(gr_circle
		(center 155.800044 -311.099962)
		(end 156.054044 -311.099962)
		(stroke
			(width 0.1016)
			(type default)
		)
		(fill no)
		(layer "In6.Cu")
	)
	(gr_circle
		(center 155.800044 -309.199788)
		(end 156.054044 -309.199788)
		(stroke
			(width 0.1016)
			(type default)
		)
		(fill no)
		(layer "In6.Cu")
	)
	(gr_circle
		(center 155.800044 -307.299868)
		(end 156.054044 -307.299868)
		(stroke
			(width 0.1016)
			(type default)
		)
		(fill no)
		(layer "In6.Cu")
	)
	(gr_circle
		(center 155.800044 -305.399948)
		(end 156.054044 -305.399948)
		(stroke
			(width 0.1016)
			(type default)
		)
		(fill no)
		(layer "In6.Cu")
	)
	(gr_circle
		(center 155.800044 -303.499774)
		(end 156.054044 -303.499774)
		(stroke
			(width 0.1016)
			(type default)
		)
		(fill no)
		(layer "In6.Cu")
	)
	(gr_circle
		(center 155.800044 -301.599854)
		(end 156.054044 -301.599854)
		(stroke
			(width 0.1016)
			(type default)
		)
		(fill no)
		(layer "In6.Cu")
	)
	(gr_circle
		(center 156.750004 -318.699896)
		(end 157.004004 -318.699896)
		(stroke
			(width 0.1016)
			(type default)
		)
		(fill no)
		(layer "In6.Cu")
	)
	(gr_circle
		(center 156.750004 -317.749936)
		(end 157.004004 -317.749936)
		(stroke
			(width 0.1016)
			(type default)
		)
		(fill no)
		(layer "In6.Cu")
	)
	(gr_circle
		(center 156.750004 -313.949842)
		(end 157.004004 -313.949842)
		(stroke
			(width 0.1016)
			(type default)
		)
		(fill no)
		(layer "In6.Cu")
	)
	(gr_circle
		(center 156.750004 -312.999882)
		(end 157.004004 -312.999882)
		(stroke
			(width 0.1016)
			(type default)
		)
		(fill no)
		(layer "In6.Cu")
	)
	(gr_circle
		(center 157.699964 -316.799722)
		(end 157.953964 -316.799722)
		(stroke
			(width 0.1016)
			(type default)
		)
		(fill no)
		(layer "In6.Cu")
	)
	(gr_circle
		(center 157.699964 -315.849762)
		(end 157.953964 -315.849762)
		(stroke
			(width 0.1016)
			(type default)
		)
		(fill no)
		(layer "In6.Cu")
	)
	(gr_circle
		(center 157.699964 -312.049922)
		(end 157.953964 -312.049922)
		(stroke
			(width 0.1016)
			(type default)
		)
		(fill no)
		(layer "In6.Cu")
	)
	(gr_circle
		(center 157.699964 -311.099962)
		(end 157.953964 -311.099962)
		(stroke
			(width 0.1016)
			(type default)
		)
		(fill no)
		(layer "In6.Cu")
	)
	(gr_circle
		(center 157.699964 -309.199788)
		(end 157.953964 -309.199788)
		(stroke
			(width 0.1016)
			(type default)
		)
		(fill no)
		(layer "In6.Cu")
	)
	(gr_circle
		(center 157.699964 -307.299868)
		(end 157.953964 -307.299868)
		(stroke
			(width 0.1016)
			(type default)
		)
		(fill no)
		(layer "In6.Cu")
	)
	(gr_circle
		(center 157.699964 -305.399948)
		(end 157.953964 -305.399948)
		(stroke
			(width 0.1016)
			(type default)
		)
		(fill no)
		(layer "In6.Cu")
	)
	(gr_circle
		(center 157.699964 -303.499774)
		(end 157.953964 -303.499774)
		(stroke
			(width 0.1016)
			(type default)
		)
		(fill no)
		(layer "In6.Cu")
	)
	(gr_circle
		(center 157.699964 -301.599854)
		(end 157.953964 -301.599854)
		(stroke
			(width 0.1016)
			(type default)
		)
		(fill no)
		(layer "In6.Cu")
	)
	(gr_circle
		(center 158.649924 -318.699896)
		(end 158.903924 -318.699896)
		(stroke
			(width 0.1016)
			(type default)
		)
		(fill no)
		(layer "In6.Cu")
	)
	(gr_circle
		(center 158.649924 -317.749936)
		(end 158.903924 -317.749936)
		(stroke
			(width 0.1016)
			(type default)
		)
		(fill no)
		(layer "In6.Cu")
	)
	(gr_circle
		(center 158.649924 -313.949842)
		(end 158.903924 -313.949842)
		(stroke
			(width 0.1016)
			(type default)
		)
		(fill no)
		(layer "In6.Cu")
	)
	(gr_circle
		(center 158.649924 -312.999882)
		(end 158.903924 -312.999882)
		(stroke
			(width 0.1016)
			(type default)
		)
		(fill no)
		(layer "In6.Cu")
	)
	(gr_circle
		(center 158.649924 -309.199788)
		(end 158.903924 -309.199788)
		(stroke
			(width 0.1016)
			(type default)
		)
		(fill no)
		(layer "In6.Cu")
	)
	(gr_circle
		(center 158.649924 -307.299868)
		(end 158.903924 -307.299868)
		(stroke
			(width 0.1016)
			(type default)
		)
		(fill no)
		(layer "In6.Cu")
	)
	(gr_circle
		(center 158.649924 -305.399948)
		(end 158.903924 -305.399948)
		(stroke
			(width 0.1016)
			(type default)
		)
		(fill no)
		(layer "In6.Cu")
	)
	(gr_circle
		(center 158.649924 -303.499774)
		(end 158.903924 -303.499774)
		(stroke
			(width 0.1016)
			(type default)
		)
		(fill no)
		(layer "In6.Cu")
	)
	(gr_circle
		(center 158.649924 -301.599854)
		(end 158.903924 -301.599854)
		(stroke
			(width 0.1016)
			(type default)
		)
		(fill no)
		(layer "In6.Cu")
	)
	(gr_circle
		(center 159.599884 -316.799722)
		(end 159.853884 -316.799722)
		(stroke
			(width 0.1016)
			(type default)
		)
		(fill no)
		(layer "In6.Cu")
	)
	(gr_circle
		(center 159.599884 -315.849762)
		(end 159.853884 -315.849762)
		(stroke
			(width 0.1016)
			(type default)
		)
		(fill no)
		(layer "In6.Cu")
	)
	(gr_circle
		(center 159.599884 -312.049922)
		(end 159.853884 -312.049922)
		(stroke
			(width 0.1016)
			(type default)
		)
		(fill no)
		(layer "In6.Cu")
	)
	(gr_circle
		(center 159.599884 -311.099962)
		(end 159.853884 -311.099962)
		(stroke
			(width 0.1016)
			(type default)
		)
		(fill no)
		(layer "In6.Cu")
	)
	(gr_circle
		(center 159.599884 -308.249828)
		(end 159.853884 -308.249828)
		(stroke
			(width 0.1016)
			(type default)
		)
		(fill no)
		(layer "In6.Cu")
	)
	(gr_circle
		(center 159.599884 -306.349908)
		(end 159.853884 -306.349908)
		(stroke
			(width 0.1016)
			(type default)
		)
		(fill no)
		(layer "In6.Cu")
	)
	(gr_circle
		(center 159.599884 -304.449734)
		(end 159.853884 -304.449734)
		(stroke
			(width 0.1016)
			(type default)
		)
		(fill no)
		(layer "In6.Cu")
	)
	(gr_circle
		(center 159.599884 -302.549814)
		(end 159.853884 -302.549814)
		(stroke
			(width 0.1016)
			(type default)
		)
		(fill no)
		(layer "In6.Cu")
	)
	(gr_circle
		(center 160.549844 -318.699896)
		(end 160.803844 -318.699896)
		(stroke
			(width 0.1016)
			(type default)
		)
		(fill no)
		(layer "In6.Cu")
	)
	(gr_circle
		(center 160.549844 -317.749936)
		(end 160.803844 -317.749936)
		(stroke
			(width 0.1016)
			(type default)
		)
		(fill no)
		(layer "In6.Cu")
	)
	(gr_circle
		(center 160.549844 -313.949842)
		(end 160.803844 -313.949842)
		(stroke
			(width 0.1016)
			(type default)
		)
		(fill no)
		(layer "In6.Cu")
	)
	(gr_circle
		(center 160.549844 -312.999882)
		(end 160.803844 -312.999882)
		(stroke
			(width 0.1016)
			(type default)
		)
		(fill no)
		(layer "In6.Cu")
	)
	(gr_circle
		(center 160.549844 -308.249828)
		(end 160.803844 -308.249828)
		(stroke
			(width 0.1016)
			(type default)
		)
		(fill no)
		(layer "In6.Cu")
	)
	(gr_circle
		(center 160.549844 -306.349908)
		(end 160.803844 -306.349908)
		(stroke
			(width 0.1016)
			(type default)
		)
		(fill no)
		(layer "In6.Cu")
	)
	(gr_circle
		(center 160.549844 -304.449734)
		(end 160.803844 -304.449734)
		(stroke
			(width 0.1016)
			(type default)
		)
		(fill no)
		(layer "In6.Cu")
	)
	(gr_circle
		(center 160.549844 -302.549814)
		(end 160.803844 -302.549814)
		(stroke
			(width 0.1016)
			(type default)
		)
		(fill no)
		(layer "In6.Cu")
	)
	(gr_circle
		(center 160.549844 -278.799798)
		(end 160.803844 -278.799798)
		(stroke
			(width 0.1016)
			(type default)
		)
		(fill no)
		(layer "In6.Cu")
	)
	(gr_circle
		(center 160.549844 -277.849838)
		(end 160.803844 -277.849838)
		(stroke
			(width 0.1016)
			(type default)
		)
		(fill no)
		(layer "In6.Cu")
	)
	(gr_circle
		(center 160.549844 -274.049744)
		(end 160.803844 -274.049744)
		(stroke
			(width 0.1016)
			(type default)
		)
		(fill no)
		(layer "In6.Cu")
	)
	(gr_circle
		(center 160.549844 -273.099784)
		(end 160.803844 -273.099784)
		(stroke
			(width 0.1016)
			(type default)
		)
		(fill no)
		(layer "In6.Cu")
	)
	(gr_circle
		(center 161.500058 -316.799722)
		(end 161.754058 -316.799722)
		(stroke
			(width 0.1016)
			(type default)
		)
		(fill no)
		(layer "In6.Cu")
	)
	(gr_circle
		(center 161.500058 -315.849762)
		(end 161.754058 -315.849762)
		(stroke
			(width 0.1016)
			(type default)
		)
		(fill no)
		(layer "In6.Cu")
	)
	(gr_circle
		(center 161.500058 -312.049922)
		(end 161.754058 -312.049922)
		(stroke
			(width 0.1016)
			(type default)
		)
		(fill no)
		(layer "In6.Cu")
	)
	(gr_circle
		(center 161.500058 -311.099962)
		(end 161.754058 -311.099962)
		(stroke
			(width 0.1016)
			(type default)
		)
		(fill no)
		(layer "In6.Cu")
	)
	(gr_circle
		(center 161.500058 -280.699464)
		(end 161.754058 -280.699464)
		(stroke
			(width 0.1016)
			(type default)
		)
		(fill no)
		(layer "In6.Cu")
	)
	(gr_circle
		(center 161.500058 -279.749504)
		(end 161.754058 -279.749504)
		(stroke
			(width 0.1016)
			(type default)
		)
		(fill no)
		(layer "In6.Cu")
	)
	(gr_circle
		(center 161.500058 -275.949918)
		(end 161.754058 -275.949918)
		(stroke
			(width 0.1016)
			(type default)
		)
		(fill no)
		(layer "In6.Cu")
	)
	(gr_circle
		(center 161.500058 -274.999958)
		(end 161.754058 -274.999958)
		(stroke
			(width 0.1016)
			(type default)
		)
		(fill no)
		(layer "In6.Cu")
	)
	(gr_circle
		(center 162.450018 -318.699896)
		(end 162.704018 -318.699896)
		(stroke
			(width 0.1016)
			(type default)
		)
		(fill no)
		(layer "In6.Cu")
	)
	(gr_circle
		(center 162.450018 -317.749936)
		(end 162.704018 -317.749936)
		(stroke
			(width 0.1016)
			(type default)
		)
		(fill no)
		(layer "In6.Cu")
	)
	(gr_circle
		(center 162.450018 -313.949842)
		(end 162.704018 -313.949842)
		(stroke
			(width 0.1016)
			(type default)
		)
		(fill no)
		(layer "In6.Cu")
	)
	(gr_circle
		(center 162.450018 -312.999882)
		(end 162.704018 -312.999882)
		(stroke
			(width 0.1016)
			(type default)
		)
		(fill no)
		(layer "In6.Cu")
	)
	(gr_circle
		(center 162.450018 -278.799798)
		(end 162.704018 -278.799798)
		(stroke
			(width 0.1016)
			(type default)
		)
		(fill no)
		(layer "In6.Cu")
	)
	(gr_circle
		(center 162.450018 -277.849838)
		(end 162.704018 -277.849838)
		(stroke
			(width 0.1016)
			(type default)
		)
		(fill no)
		(layer "In6.Cu")
	)
	(gr_circle
		(center 162.450018 -274.049744)
		(end 162.704018 -274.049744)
		(stroke
			(width 0.1016)
			(type default)
		)
		(fill no)
		(layer "In6.Cu")
	)
	(gr_circle
		(center 162.450018 -273.099784)
		(end 162.704018 -273.099784)
		(stroke
			(width 0.1016)
			(type default)
		)
		(fill no)
		(layer "In6.Cu")
	)
	(gr_circle
		(center 163.399978 -316.799722)
		(end 163.653978 -316.799722)
		(stroke
			(width 0.1016)
			(type default)
		)
		(fill no)
		(layer "In6.Cu")
	)
	(gr_circle
		(center 163.399978 -315.849762)
		(end 163.653978 -315.849762)
		(stroke
			(width 0.1016)
			(type default)
		)
		(fill no)
		(layer "In6.Cu")
	)
	(gr_circle
		(center 163.399978 -312.049922)
		(end 163.653978 -312.049922)
		(stroke
			(width 0.1016)
			(type default)
		)
		(fill no)
		(layer "In6.Cu")
	)
	(gr_circle
		(center 163.399978 -311.099962)
		(end 163.653978 -311.099962)
		(stroke
			(width 0.1016)
			(type default)
		)
		(fill no)
		(layer "In6.Cu")
	)
	(gr_circle
		(center 163.399978 -280.699464)
		(end 163.653978 -280.699464)
		(stroke
			(width 0.1016)
			(type default)
		)
		(fill no)
		(layer "In6.Cu")
	)
	(gr_circle
		(center 163.399978 -279.749504)
		(end 163.653978 -279.749504)
		(stroke
			(width 0.1016)
			(type default)
		)
		(fill no)
		(layer "In6.Cu")
	)
	(gr_circle
		(center 163.399978 -275.949918)
		(end 163.653978 -275.949918)
		(stroke
			(width 0.1016)
			(type default)
		)
		(fill no)
		(layer "In6.Cu")
	)
	(gr_circle
		(center 163.399978 -274.999958)
		(end 163.653978 -274.999958)
		(stroke
			(width 0.1016)
			(type default)
		)
		(fill no)
		(layer "In6.Cu")
	)
	(gr_circle
		(center 164.349938 -318.699896)
		(end 164.603938 -318.699896)
		(stroke
			(width 0.1016)
			(type default)
		)
		(fill no)
		(layer "In6.Cu")
	)
	(gr_circle
		(center 164.349938 -317.749936)
		(end 164.603938 -317.749936)
		(stroke
			(width 0.1016)
			(type default)
		)
		(fill no)
		(layer "In6.Cu")
	)
	(gr_circle
		(center 164.349938 -313.949842)
		(end 164.603938 -313.949842)
		(stroke
			(width 0.1016)
			(type default)
		)
		(fill no)
		(layer "In6.Cu")
	)
	(gr_circle
		(center 164.349938 -312.999882)
		(end 164.603938 -312.999882)
		(stroke
			(width 0.1016)
			(type default)
		)
		(fill no)
		(layer "In6.Cu")
	)
	(gr_circle
		(center 164.349938 -278.799798)
		(end 164.603938 -278.799798)
		(stroke
			(width 0.1016)
			(type default)
		)
		(fill no)
		(layer "In6.Cu")
	)
	(gr_circle
		(center 164.349938 -277.849838)
		(end 164.603938 -277.849838)
		(stroke
			(width 0.1016)
			(type default)
		)
		(fill no)
		(layer "In6.Cu")
	)
	(gr_circle
		(center 164.349938 -274.049744)
		(end 164.603938 -274.049744)
		(stroke
			(width 0.1016)
			(type default)
		)
		(fill no)
		(layer "In6.Cu")
	)
	(gr_circle
		(center 164.349938 -273.099784)
		(end 164.603938 -273.099784)
		(stroke
			(width 0.1016)
			(type default)
		)
		(fill no)
		(layer "In6.Cu")
	)
	(gr_circle
		(center 165.299898 -316.799722)
		(end 165.553898 -316.799722)
		(stroke
			(width 0.1016)
			(type default)
		)
		(fill no)
		(layer "In6.Cu")
	)
	(gr_circle
		(center 165.299898 -315.849762)
		(end 165.553898 -315.849762)
		(stroke
			(width 0.1016)
			(type default)
		)
		(fill no)
		(layer "In6.Cu")
	)
	(gr_circle
		(center 165.299898 -312.049922)
		(end 165.553898 -312.049922)
		(stroke
			(width 0.1016)
			(type default)
		)
		(fill no)
		(layer "In6.Cu")
	)
	(gr_circle
		(center 165.299898 -311.099962)
		(end 165.553898 -311.099962)
		(stroke
			(width 0.1016)
			(type default)
		)
		(fill no)
		(layer "In6.Cu")
	)
	(gr_circle
		(center 165.299898 -280.699464)
		(end 165.553898 -280.699464)
		(stroke
			(width 0.1016)
			(type default)
		)
		(fill no)
		(layer "In6.Cu")
	)
	(gr_circle
		(center 165.299898 -279.749504)
		(end 165.553898 -279.749504)
		(stroke
			(width 0.1016)
			(type default)
		)
		(fill no)
		(layer "In6.Cu")
	)
	(gr_circle
		(center 165.299898 -275.949918)
		(end 165.553898 -275.949918)
		(stroke
			(width 0.1016)
			(type default)
		)
		(fill no)
		(layer "In6.Cu")
	)
	(gr_circle
		(center 165.299898 -274.999958)
		(end 165.553898 -274.999958)
		(stroke
			(width 0.1016)
			(type default)
		)
		(fill no)
		(layer "In6.Cu")
	)
	(gr_circle
		(center 166.249858 -318.699896)
		(end 166.503858 -318.699896)
		(stroke
			(width 0.1016)
			(type default)
		)
		(fill no)
		(layer "In6.Cu")
	)
	(gr_circle
		(center 166.249858 -317.749936)
		(end 166.503858 -317.749936)
		(stroke
			(width 0.1016)
			(type default)
		)
		(fill no)
		(layer "In6.Cu")
	)
	(gr_circle
		(center 166.249858 -313.949842)
		(end 166.503858 -313.949842)
		(stroke
			(width 0.1016)
			(type default)
		)
		(fill no)
		(layer "In6.Cu")
	)
	(gr_circle
		(center 166.249858 -312.999882)
		(end 166.503858 -312.999882)
		(stroke
			(width 0.1016)
			(type default)
		)
		(fill no)
		(layer "In6.Cu")
	)
	(gr_circle
		(center 166.249858 -278.799798)
		(end 166.503858 -278.799798)
		(stroke
			(width 0.1016)
			(type default)
		)
		(fill no)
		(layer "In6.Cu")
	)
	(gr_circle
		(center 166.249858 -277.849838)
		(end 166.503858 -277.849838)
		(stroke
			(width 0.1016)
			(type default)
		)
		(fill no)
		(layer "In6.Cu")
	)
	(gr_circle
		(center 166.249858 -274.049744)
		(end 166.503858 -274.049744)
		(stroke
			(width 0.1016)
			(type default)
		)
		(fill no)
		(layer "In6.Cu")
	)
	(gr_circle
		(center 166.249858 -273.099784)
		(end 166.503858 -273.099784)
		(stroke
			(width 0.1016)
			(type default)
		)
		(fill no)
		(layer "In6.Cu")
	)
	(gr_circle
		(center 167.200072 -312.049922)
		(end 167.454072 -312.049922)
		(stroke
			(width 0.1016)
			(type default)
		)
		(fill no)
		(layer "In6.Cu")
	)
	(gr_circle
		(center 167.200072 -311.099962)
		(end 167.454072 -311.099962)
		(stroke
			(width 0.1016)
			(type default)
		)
		(fill no)
		(layer "In6.Cu")
	)
	(gr_circle
		(center 167.200072 -280.699464)
		(end 167.454072 -280.699464)
		(stroke
			(width 0.1016)
			(type default)
		)
		(fill no)
		(layer "In6.Cu")
	)
	(gr_circle
		(center 167.200072 -279.749504)
		(end 167.454072 -279.749504)
		(stroke
			(width 0.1016)
			(type default)
		)
		(fill no)
		(layer "In6.Cu")
	)
	(gr_circle
		(center 167.200072 -275.949918)
		(end 167.454072 -275.949918)
		(stroke
			(width 0.1016)
			(type default)
		)
		(fill no)
		(layer "In6.Cu")
	)
	(gr_circle
		(center 167.200072 -274.999958)
		(end 167.454072 -274.999958)
		(stroke
			(width 0.1016)
			(type default)
		)
		(fill no)
		(layer "In6.Cu")
	)
	(gr_circle
		(center 168.150032 -313.949842)
		(end 168.404032 -313.949842)
		(stroke
			(width 0.1016)
			(type default)
		)
		(fill no)
		(layer "In6.Cu")
	)
	(gr_circle
		(center 168.150032 -312.999882)
		(end 168.404032 -312.999882)
		(stroke
			(width 0.1016)
			(type default)
		)
		(fill no)
		(layer "In6.Cu")
	)
	(gr_circle
		(center 168.150032 -278.799798)
		(end 168.404032 -278.799798)
		(stroke
			(width 0.1016)
			(type default)
		)
		(fill no)
		(layer "In6.Cu")
	)
	(gr_circle
		(center 168.150032 -277.849838)
		(end 168.404032 -277.849838)
		(stroke
			(width 0.1016)
			(type default)
		)
		(fill no)
		(layer "In6.Cu")
	)
	(gr_circle
		(center 168.150032 -274.049744)
		(end 168.404032 -274.049744)
		(stroke
			(width 0.1016)
			(type default)
		)
		(fill no)
		(layer "In6.Cu")
	)
	(gr_circle
		(center 168.150032 -273.099784)
		(end 168.404032 -273.099784)
		(stroke
			(width 0.1016)
			(type default)
		)
		(fill no)
		(layer "In6.Cu")
	)
	(gr_circle
		(center 169.099992 -312.049922)
		(end 169.353992 -312.049922)
		(stroke
			(width 0.1016)
			(type default)
		)
		(fill no)
		(layer "In6.Cu")
	)
	(gr_circle
		(center 169.099992 -311.099962)
		(end 169.353992 -311.099962)
		(stroke
			(width 0.1016)
			(type default)
		)
		(fill no)
		(layer "In6.Cu")
	)
	(gr_circle
		(center 169.099992 -280.699464)
		(end 169.353992 -280.699464)
		(stroke
			(width 0.1016)
			(type default)
		)
		(fill no)
		(layer "In6.Cu")
	)
	(gr_circle
		(center 169.099992 -279.749504)
		(end 169.353992 -279.749504)
		(stroke
			(width 0.1016)
			(type default)
		)
		(fill no)
		(layer "In6.Cu")
	)
	(gr_circle
		(center 169.099992 -275.949918)
		(end 169.353992 -275.949918)
		(stroke
			(width 0.1016)
			(type default)
		)
		(fill no)
		(layer "In6.Cu")
	)
	(gr_circle
		(center 169.099992 -274.999958)
		(end 169.353992 -274.999958)
		(stroke
			(width 0.1016)
			(type default)
		)
		(fill no)
		(layer "In6.Cu")
	)
	(gr_circle
		(center 170.049952 -313.949842)
		(end 170.303952 -313.949842)
		(stroke
			(width 0.1016)
			(type default)
		)
		(fill no)
		(layer "In6.Cu")
	)
	(gr_circle
		(center 170.049952 -312.999882)
		(end 170.303952 -312.999882)
		(stroke
			(width 0.1016)
			(type default)
		)
		(fill no)
		(layer "In6.Cu")
	)
	(gr_circle
		(center 170.049952 -278.799798)
		(end 170.303952 -278.799798)
		(stroke
			(width 0.1016)
			(type default)
		)
		(fill no)
		(layer "In6.Cu")
	)
	(gr_circle
		(center 170.049952 -277.849838)
		(end 170.303952 -277.849838)
		(stroke
			(width 0.1016)
			(type default)
		)
		(fill no)
		(layer "In6.Cu")
	)
	(gr_circle
		(center 170.049952 -274.049744)
		(end 170.303952 -274.049744)
		(stroke
			(width 0.1016)
			(type default)
		)
		(fill no)
		(layer "In6.Cu")
	)
	(gr_circle
		(center 170.049952 -273.099784)
		(end 170.303952 -273.099784)
		(stroke
			(width 0.1016)
			(type default)
		)
		(fill no)
		(layer "In6.Cu")
	)
	(gr_circle
		(center 170.999912 -312.049922)
		(end 171.253912 -312.049922)
		(stroke
			(width 0.1016)
			(type default)
		)
		(fill no)
		(layer "In6.Cu")
	)
	(gr_circle
		(center 170.999912 -311.099962)
		(end 171.253912 -311.099962)
		(stroke
			(width 0.1016)
			(type default)
		)
		(fill no)
		(layer "In6.Cu")
	)
	(gr_circle
		(center 170.999912 -280.699464)
		(end 171.253912 -280.699464)
		(stroke
			(width 0.1016)
			(type default)
		)
		(fill no)
		(layer "In6.Cu")
	)
	(gr_circle
		(center 170.999912 -279.749504)
		(end 171.253912 -279.749504)
		(stroke
			(width 0.1016)
			(type default)
		)
		(fill no)
		(layer "In6.Cu")
	)
	(gr_circle
		(center 170.999912 -275.949918)
		(end 171.253912 -275.949918)
		(stroke
			(width 0.1016)
			(type default)
		)
		(fill no)
		(layer "In6.Cu")
	)
	(gr_circle
		(center 170.999912 -274.999958)
		(end 171.253912 -274.999958)
		(stroke
			(width 0.1016)
			(type default)
		)
		(fill no)
		(layer "In6.Cu")
	)
	(gr_circle
		(center 171.949872 -313.949842)
		(end 172.203872 -313.949842)
		(stroke
			(width 0.1016)
			(type default)
		)
		(fill no)
		(layer "In6.Cu")
	)
	(gr_circle
		(center 171.949872 -312.999882)
		(end 172.203872 -312.999882)
		(stroke
			(width 0.1016)
			(type default)
		)
		(fill no)
		(layer "In6.Cu")
	)
	(gr_circle
		(center 171.949872 -278.799798)
		(end 172.203872 -278.799798)
		(stroke
			(width 0.1016)
			(type default)
		)
		(fill no)
		(layer "In6.Cu")
	)
	(gr_circle
		(center 171.949872 -277.849838)
		(end 172.203872 -277.849838)
		(stroke
			(width 0.1016)
			(type default)
		)
		(fill no)
		(layer "In6.Cu")
	)
	(gr_circle
		(center 171.949872 -274.049744)
		(end 172.203872 -274.049744)
		(stroke
			(width 0.1016)
			(type default)
		)
		(fill no)
		(layer "In6.Cu")
	)
	(gr_circle
		(center 171.949872 -273.099784)
		(end 172.203872 -273.099784)
		(stroke
			(width 0.1016)
			(type default)
		)
		(fill no)
		(layer "In6.Cu")
	)
	(gr_circle
		(center 172.899832 -280.699464)
		(end 173.153832 -280.699464)
		(stroke
			(width 0.1016)
			(type default)
		)
		(fill no)
		(layer "In6.Cu")
	)
	(gr_circle
		(center 172.899832 -279.749504)
		(end 173.153832 -279.749504)
		(stroke
			(width 0.1016)
			(type default)
		)
		(fill no)
		(layer "In6.Cu")
	)
	(gr_circle
		(center 172.900086 -312.049922)
		(end 173.154086 -312.049922)
		(stroke
			(width 0.1016)
			(type default)
		)
		(fill no)
		(layer "In6.Cu")
	)
	(gr_circle
		(center 172.900086 -311.099962)
		(end 173.154086 -311.099962)
		(stroke
			(width 0.1016)
			(type default)
		)
		(fill no)
		(layer "In6.Cu")
	)
	(gr_circle
		(center 172.900086 -275.949918)
		(end 173.154086 -275.949918)
		(stroke
			(width 0.1016)
			(type default)
		)
		(fill no)
		(layer "In6.Cu")
	)
	(gr_circle
		(center 172.900086 -274.999958)
		(end 173.154086 -274.999958)
		(stroke
			(width 0.1016)
			(type default)
		)
		(fill no)
		(layer "In6.Cu")
	)
	(gr_circle
		(center 173.850046 -313.949842)
		(end 174.104046 -313.949842)
		(stroke
			(width 0.1016)
			(type default)
		)
		(fill no)
		(layer "In6.Cu")
	)
	(gr_circle
		(center 173.850046 -312.999882)
		(end 174.104046 -312.999882)
		(stroke
			(width 0.1016)
			(type default)
		)
		(fill no)
		(layer "In6.Cu")
	)
	(gr_circle
		(center 173.850046 -278.799798)
		(end 174.104046 -278.799798)
		(stroke
			(width 0.1016)
			(type default)
		)
		(fill no)
		(layer "In6.Cu")
	)
	(gr_circle
		(center 173.850046 -277.849838)
		(end 174.104046 -277.849838)
		(stroke
			(width 0.1016)
			(type default)
		)
		(fill no)
		(layer "In6.Cu")
	)
	(gr_circle
		(center 173.850046 -274.049744)
		(end 174.104046 -274.049744)
		(stroke
			(width 0.1016)
			(type default)
		)
		(fill no)
		(layer "In6.Cu")
	)
	(gr_circle
		(center 173.850046 -273.099784)
		(end 174.104046 -273.099784)
		(stroke
			(width 0.1016)
			(type default)
		)
		(fill no)
		(layer "In6.Cu")
	)
	(gr_circle
		(center 174.800006 -312.049922)
		(end 175.054006 -312.049922)
		(stroke
			(width 0.1016)
			(type default)
		)
		(fill no)
		(layer "In6.Cu")
	)
	(gr_circle
		(center 174.800006 -311.099962)
		(end 175.054006 -311.099962)
		(stroke
			(width 0.1016)
			(type default)
		)
		(fill no)
		(layer "In6.Cu")
	)
	(gr_circle
		(center 174.800006 -280.699464)
		(end 175.054006 -280.699464)
		(stroke
			(width 0.1016)
			(type default)
		)
		(fill no)
		(layer "In6.Cu")
	)
	(gr_circle
		(center 174.800006 -279.749504)
		(end 175.054006 -279.749504)
		(stroke
			(width 0.1016)
			(type default)
		)
		(fill no)
		(layer "In6.Cu")
	)
	(gr_circle
		(center 174.800006 -275.949918)
		(end 175.054006 -275.949918)
		(stroke
			(width 0.1016)
			(type default)
		)
		(fill no)
		(layer "In6.Cu")
	)
	(gr_circle
		(center 174.800006 -274.999958)
		(end 175.054006 -274.999958)
		(stroke
			(width 0.1016)
			(type default)
		)
		(fill no)
		(layer "In6.Cu")
	)
	(gr_circle
		(center 175.749712 -278.799798)
		(end 176.003712 -278.799798)
		(stroke
			(width 0.1016)
			(type default)
		)
		(fill no)
		(layer "In6.Cu")
	)
	(gr_circle
		(center 175.749712 -277.849838)
		(end 176.003712 -277.849838)
		(stroke
			(width 0.1016)
			(type default)
		)
		(fill no)
		(layer "In6.Cu")
	)
	(gr_circle
		(center 175.749966 -313.949842)
		(end 176.003966 -313.949842)
		(stroke
			(width 0.1016)
			(type default)
		)
		(fill no)
		(layer "In6.Cu")
	)
	(gr_circle
		(center 175.749966 -312.999882)
		(end 176.003966 -312.999882)
		(stroke
			(width 0.1016)
			(type default)
		)
		(fill no)
		(layer "In6.Cu")
	)
	(gr_circle
		(center 176.699926 -312.049922)
		(end 176.953926 -312.049922)
		(stroke
			(width 0.1016)
			(type default)
		)
		(fill no)
		(layer "In6.Cu")
	)
	(gr_circle
		(center 176.699926 -311.099962)
		(end 176.953926 -311.099962)
		(stroke
			(width 0.1016)
			(type default)
		)
		(fill no)
		(layer "In6.Cu")
	)
	(gr_circle
		(center 176.699926 -280.699464)
		(end 176.953926 -280.699464)
		(stroke
			(width 0.1016)
			(type default)
		)
		(fill no)
		(layer "In6.Cu")
	)
	(gr_circle
		(center 176.699926 -279.749504)
		(end 176.953926 -279.749504)
		(stroke
			(width 0.1016)
			(type default)
		)
		(fill no)
		(layer "In6.Cu")
	)
	(gr_circle
		(center 177.649632 -278.799798)
		(end 177.903632 -278.799798)
		(stroke
			(width 0.1016)
			(type default)
		)
		(fill no)
		(layer "In6.Cu")
	)
	(gr_circle
		(center 177.649632 -277.849838)
		(end 177.903632 -277.849838)
		(stroke
			(width 0.1016)
			(type default)
		)
		(fill no)
		(layer "In6.Cu")
	)
	(gr_circle
		(center 177.649886 -313.949842)
		(end 177.903886 -313.949842)
		(stroke
			(width 0.1016)
			(type default)
		)
		(fill no)
		(layer "In6.Cu")
	)
	(gr_circle
		(center 177.649886 -312.999882)
		(end 177.903886 -312.999882)
		(stroke
			(width 0.1016)
			(type default)
		)
		(fill no)
		(layer "In6.Cu")
	)
	(gr_circle
		(center 178.599846 -312.049922)
		(end 178.853846 -312.049922)
		(stroke
			(width 0.1016)
			(type default)
		)
		(fill no)
		(layer "In6.Cu")
	)
	(gr_circle
		(center 178.599846 -311.099962)
		(end 178.853846 -311.099962)
		(stroke
			(width 0.1016)
			(type default)
		)
		(fill no)
		(layer "In6.Cu")
	)
	(gr_circle
		(center 178.599846 -280.699464)
		(end 178.853846 -280.699464)
		(stroke
			(width 0.1016)
			(type default)
		)
		(fill no)
		(layer "In6.Cu")
	)
	(gr_circle
		(center 178.599846 -279.749504)
		(end 178.853846 -279.749504)
		(stroke
			(width 0.1016)
			(type default)
		)
		(fill no)
		(layer "In6.Cu")
	)
	(gr_circle
		(center 179.549806 -278.799798)
		(end 179.803806 -278.799798)
		(stroke
			(width 0.1016)
			(type default)
		)
		(fill no)
		(layer "In6.Cu")
	)
	(gr_circle
		(center 179.549806 -277.849838)
		(end 179.803806 -277.849838)
		(stroke
			(width 0.1016)
			(type default)
		)
		(fill no)
		(layer "In6.Cu")
	)
	(gr_circle
		(center 179.55006 -313.949842)
		(end 179.80406 -313.949842)
		(stroke
			(width 0.1016)
			(type default)
		)
		(fill no)
		(layer "In6.Cu")
	)
	(gr_circle
		(center 179.55006 -312.999882)
		(end 179.80406 -312.999882)
		(stroke
			(width 0.1016)
			(type default)
		)
		(fill no)
		(layer "In6.Cu")
	)
	(gr_circle
		(center 180.50002 -312.049922)
		(end 180.75402 -312.049922)
		(stroke
			(width 0.1016)
			(type default)
		)
		(fill no)
		(layer "In6.Cu")
	)
	(gr_circle
		(center 180.50002 -311.099962)
		(end 180.75402 -311.099962)
		(stroke
			(width 0.1016)
			(type default)
		)
		(fill no)
		(layer "In6.Cu")
	)
	(gr_circle
		(center 180.50002 -280.699464)
		(end 180.75402 -280.699464)
		(stroke
			(width 0.1016)
			(type default)
		)
		(fill no)
		(layer "In6.Cu")
	)
	(gr_circle
		(center 180.50002 -279.749504)
		(end 180.75402 -279.749504)
		(stroke
			(width 0.1016)
			(type default)
		)
		(fill no)
		(layer "In6.Cu")
	)
	(gr_circle
		(center 181.449726 -278.799798)
		(end 181.703726 -278.799798)
		(stroke
			(width 0.1016)
			(type default)
		)
		(fill no)
		(layer "In6.Cu")
	)
	(gr_circle
		(center 181.449726 -277.849838)
		(end 181.703726 -277.849838)
		(stroke
			(width 0.1016)
			(type default)
		)
		(fill no)
		(layer "In6.Cu")
	)
	(gr_circle
		(center 181.44998 -313.949842)
		(end 181.70398 -313.949842)
		(stroke
			(width 0.1016)
			(type default)
		)
		(fill no)
		(layer "In6.Cu")
	)
	(gr_circle
		(center 181.44998 -312.999882)
		(end 181.70398 -312.999882)
		(stroke
			(width 0.1016)
			(type default)
		)
		(fill no)
		(layer "In6.Cu")
	)
	(gr_circle
		(center 182.39994 -316.799722)
		(end 182.65394 -316.799722)
		(stroke
			(width 0.1016)
			(type default)
		)
		(fill no)
		(layer "In6.Cu")
	)
	(gr_circle
		(center 182.39994 -315.849762)
		(end 182.65394 -315.849762)
		(stroke
			(width 0.1016)
			(type default)
		)
		(fill no)
		(layer "In6.Cu")
	)
	(gr_circle
		(center 182.39994 -312.049922)
		(end 182.65394 -312.049922)
		(stroke
			(width 0.1016)
			(type default)
		)
		(fill no)
		(layer "In6.Cu")
	)
	(gr_circle
		(center 182.39994 -311.099962)
		(end 182.65394 -311.099962)
		(stroke
			(width 0.1016)
			(type default)
		)
		(fill no)
		(layer "In6.Cu")
	)
	(gr_circle
		(center 182.39994 -280.699464)
		(end 182.65394 -280.699464)
		(stroke
			(width 0.1016)
			(type default)
		)
		(fill no)
		(layer "In6.Cu")
	)
	(gr_circle
		(center 182.39994 -279.749504)
		(end 182.65394 -279.749504)
		(stroke
			(width 0.1016)
			(type default)
		)
		(fill no)
		(layer "In6.Cu")
	)
	(gr_circle
		(center 183.349646 -278.799798)
		(end 183.603646 -278.799798)
		(stroke
			(width 0.1016)
			(type default)
		)
		(fill no)
		(layer "In6.Cu")
	)
	(gr_circle
		(center 183.349646 -277.849838)
		(end 183.603646 -277.849838)
		(stroke
			(width 0.1016)
			(type default)
		)
		(fill no)
		(layer "In6.Cu")
	)
	(gr_circle
		(center 183.3499 -318.699896)
		(end 183.6039 -318.699896)
		(stroke
			(width 0.1016)
			(type default)
		)
		(fill no)
		(layer "In6.Cu")
	)
	(gr_circle
		(center 183.3499 -317.749936)
		(end 183.6039 -317.749936)
		(stroke
			(width 0.1016)
			(type default)
		)
		(fill no)
		(layer "In6.Cu")
	)
	(gr_circle
		(center 183.3499 -313.949842)
		(end 183.6039 -313.949842)
		(stroke
			(width 0.1016)
			(type default)
		)
		(fill no)
		(layer "In6.Cu")
	)
	(gr_circle
		(center 183.3499 -312.999882)
		(end 183.6039 -312.999882)
		(stroke
			(width 0.1016)
			(type default)
		)
		(fill no)
		(layer "In6.Cu")
	)
	(gr_circle
		(center 184.29986 -316.799722)
		(end 184.55386 -316.799722)
		(stroke
			(width 0.1016)
			(type default)
		)
		(fill no)
		(layer "In6.Cu")
	)
	(gr_circle
		(center 184.29986 -315.849762)
		(end 184.55386 -315.849762)
		(stroke
			(width 0.1016)
			(type default)
		)
		(fill no)
		(layer "In6.Cu")
	)
	(gr_circle
		(center 184.29986 -312.049922)
		(end 184.55386 -312.049922)
		(stroke
			(width 0.1016)
			(type default)
		)
		(fill no)
		(layer "In6.Cu")
	)
	(gr_circle
		(center 184.29986 -311.099962)
		(end 184.55386 -311.099962)
		(stroke
			(width 0.1016)
			(type default)
		)
		(fill no)
		(layer "In6.Cu")
	)
	(gr_circle
		(center 184.29986 -280.699464)
		(end 184.55386 -280.699464)
		(stroke
			(width 0.1016)
			(type default)
		)
		(fill no)
		(layer "In6.Cu")
	)
	(gr_circle
		(center 184.29986 -279.749504)
		(end 184.55386 -279.749504)
		(stroke
			(width 0.1016)
			(type default)
		)
		(fill no)
		(layer "In6.Cu")
	)
	(gr_circle
		(center 185.24982 -278.799798)
		(end 185.50382 -278.799798)
		(stroke
			(width 0.1016)
			(type default)
		)
		(fill no)
		(layer "In6.Cu")
	)
	(gr_circle
		(center 185.24982 -277.849838)
		(end 185.50382 -277.849838)
		(stroke
			(width 0.1016)
			(type default)
		)
		(fill no)
		(layer "In6.Cu")
	)
	(gr_circle
		(center 185.250074 -318.699896)
		(end 185.504074 -318.699896)
		(stroke
			(width 0.1016)
			(type default)
		)
		(fill no)
		(layer "In6.Cu")
	)
	(gr_circle
		(center 185.250074 -317.749936)
		(end 185.504074 -317.749936)
		(stroke
			(width 0.1016)
			(type default)
		)
		(fill no)
		(layer "In6.Cu")
	)
	(gr_circle
		(center 185.250074 -313.949842)
		(end 185.504074 -313.949842)
		(stroke
			(width 0.1016)
			(type default)
		)
		(fill no)
		(layer "In6.Cu")
	)
	(gr_circle
		(center 185.250074 -312.999882)
		(end 185.504074 -312.999882)
		(stroke
			(width 0.1016)
			(type default)
		)
		(fill no)
		(layer "In6.Cu")
	)
	(gr_circle
		(center 186.200034 -316.799722)
		(end 186.454034 -316.799722)
		(stroke
			(width 0.1016)
			(type default)
		)
		(fill no)
		(layer "In6.Cu")
	)
	(gr_circle
		(center 186.200034 -315.849762)
		(end 186.454034 -315.849762)
		(stroke
			(width 0.1016)
			(type default)
		)
		(fill no)
		(layer "In6.Cu")
	)
	(gr_circle
		(center 186.200034 -312.049922)
		(end 186.454034 -312.049922)
		(stroke
			(width 0.1016)
			(type default)
		)
		(fill no)
		(layer "In6.Cu")
	)
	(gr_circle
		(center 186.200034 -311.099962)
		(end 186.454034 -311.099962)
		(stroke
			(width 0.1016)
			(type default)
		)
		(fill no)
		(layer "In6.Cu")
	)
	(gr_circle
		(center 186.200034 -280.699464)
		(end 186.454034 -280.699464)
		(stroke
			(width 0.1016)
			(type default)
		)
		(fill no)
		(layer "In6.Cu")
	)
	(gr_circle
		(center 186.200034 -279.749504)
		(end 186.454034 -279.749504)
		(stroke
			(width 0.1016)
			(type default)
		)
		(fill no)
		(layer "In6.Cu")
	)
	(gr_circle
		(center 187.14974 -278.799798)
		(end 187.40374 -278.799798)
		(stroke
			(width 0.1016)
			(type default)
		)
		(fill no)
		(layer "In6.Cu")
	)
	(gr_circle
		(center 187.14974 -277.849838)
		(end 187.40374 -277.849838)
		(stroke
			(width 0.1016)
			(type default)
		)
		(fill no)
		(layer "In6.Cu")
	)
	(gr_circle
		(center 187.149994 -318.699896)
		(end 187.403994 -318.699896)
		(stroke
			(width 0.1016)
			(type default)
		)
		(fill no)
		(layer "In6.Cu")
	)
	(gr_circle
		(center 187.149994 -317.749936)
		(end 187.403994 -317.749936)
		(stroke
			(width 0.1016)
			(type default)
		)
		(fill no)
		(layer "In6.Cu")
	)
	(gr_circle
		(center 187.149994 -313.949842)
		(end 187.403994 -313.949842)
		(stroke
			(width 0.1016)
			(type default)
		)
		(fill no)
		(layer "In6.Cu")
	)
	(gr_circle
		(center 187.149994 -312.999882)
		(end 187.403994 -312.999882)
		(stroke
			(width 0.1016)
			(type default)
		)
		(fill no)
		(layer "In6.Cu")
	)
	(gr_circle
		(center 188.099954 -316.799722)
		(end 188.353954 -316.799722)
		(stroke
			(width 0.1016)
			(type default)
		)
		(fill no)
		(layer "In6.Cu")
	)
	(gr_circle
		(center 188.099954 -315.849762)
		(end 188.353954 -315.849762)
		(stroke
			(width 0.1016)
			(type default)
		)
		(fill no)
		(layer "In6.Cu")
	)
	(gr_circle
		(center 188.099954 -312.049922)
		(end 188.353954 -312.049922)
		(stroke
			(width 0.1016)
			(type default)
		)
		(fill no)
		(layer "In6.Cu")
	)
	(gr_circle
		(center 188.099954 -311.099962)
		(end 188.353954 -311.099962)
		(stroke
			(width 0.1016)
			(type default)
		)
		(fill no)
		(layer "In6.Cu")
	)
	(gr_circle
		(center 188.099954 -280.699464)
		(end 188.353954 -280.699464)
		(stroke
			(width 0.1016)
			(type default)
		)
		(fill no)
		(layer "In6.Cu")
	)
	(gr_circle
		(center 188.099954 -279.749504)
		(end 188.353954 -279.749504)
		(stroke
			(width 0.1016)
			(type default)
		)
		(fill no)
		(layer "In6.Cu")
	)
	(gr_circle
		(center 189.04966 -278.799798)
		(end 189.30366 -278.799798)
		(stroke
			(width 0.1016)
			(type default)
		)
		(fill no)
		(layer "In6.Cu")
	)
	(gr_circle
		(center 189.04966 -277.849838)
		(end 189.30366 -277.849838)
		(stroke
			(width 0.1016)
			(type default)
		)
		(fill no)
		(layer "In6.Cu")
	)
	(gr_circle
		(center 189.049914 -318.699896)
		(end 189.303914 -318.699896)
		(stroke
			(width 0.1016)
			(type default)
		)
		(fill no)
		(layer "In6.Cu")
	)
	(gr_circle
		(center 189.049914 -317.749936)
		(end 189.303914 -317.749936)
		(stroke
			(width 0.1016)
			(type default)
		)
		(fill no)
		(layer "In6.Cu")
	)
	(gr_circle
		(center 189.049914 -313.949842)
		(end 189.303914 -313.949842)
		(stroke
			(width 0.1016)
			(type default)
		)
		(fill no)
		(layer "In6.Cu")
	)
	(gr_circle
		(center 189.049914 -312.999882)
		(end 189.303914 -312.999882)
		(stroke
			(width 0.1016)
			(type default)
		)
		(fill no)
		(layer "In6.Cu")
	)
	(gr_circle
		(center 189.999874 -312.049922)
		(end 190.253874 -312.049922)
		(stroke
			(width 0.1016)
			(type default)
		)
		(fill no)
		(layer "In6.Cu")
	)
	(gr_circle
		(center 189.999874 -311.099962)
		(end 190.253874 -311.099962)
		(stroke
			(width 0.1016)
			(type default)
		)
		(fill no)
		(layer "In6.Cu")
	)
	(gr_circle
		(center 189.999874 -280.699464)
		(end 190.253874 -280.699464)
		(stroke
			(width 0.1016)
			(type default)
		)
		(fill no)
		(layer "In6.Cu")
	)
	(gr_circle
		(center 189.999874 -279.749504)
		(end 190.253874 -279.749504)
		(stroke
			(width 0.1016)
			(type default)
		)
		(fill no)
		(layer "In6.Cu")
	)
	(gr_circle
		(center 190.949834 -278.799798)
		(end 191.203834 -278.799798)
		(stroke
			(width 0.1016)
			(type default)
		)
		(fill no)
		(layer "In6.Cu")
	)
	(gr_circle
		(center 190.949834 -277.849838)
		(end 191.203834 -277.849838)
		(stroke
			(width 0.1016)
			(type default)
		)
		(fill no)
		(layer "In6.Cu")
	)
	(gr_circle
		(center 190.950088 -313.949842)
		(end 191.204088 -313.949842)
		(stroke
			(width 0.1016)
			(type default)
		)
		(fill no)
		(layer "In6.Cu")
	)
	(gr_circle
		(center 190.950088 -312.999882)
		(end 191.204088 -312.999882)
		(stroke
			(width 0.1016)
			(type default)
		)
		(fill no)
		(layer "In6.Cu")
	)
	(gr_circle
		(center 190.950088 -308.249828)
		(end 191.204088 -308.249828)
		(stroke
			(width 0.1016)
			(type default)
		)
		(fill no)
		(layer "In6.Cu")
	)
	(gr_circle
		(center 190.950088 -306.349908)
		(end 191.204088 -306.349908)
		(stroke
			(width 0.1016)
			(type default)
		)
		(fill no)
		(layer "In6.Cu")
	)
	(gr_circle
		(center 190.950088 -304.449734)
		(end 191.204088 -304.449734)
		(stroke
			(width 0.1016)
			(type default)
		)
		(fill no)
		(layer "In6.Cu")
	)
	(gr_circle
		(center 190.950088 -287.349946)
		(end 191.204088 -287.349946)
		(stroke
			(width 0.1016)
			(type default)
		)
		(fill no)
		(layer "In6.Cu")
	)
	(gr_circle
		(center 190.950088 -285.449772)
		(end 191.204088 -285.449772)
		(stroke
			(width 0.1016)
			(type default)
		)
		(fill no)
		(layer "In6.Cu")
	)
	(gr_circle
		(center 190.950088 -283.549852)
		(end 191.204088 -283.549852)
		(stroke
			(width 0.1016)
			(type default)
		)
		(fill no)
		(layer "In6.Cu")
	)
	(gr_circle
		(center 191.900048 -312.049922)
		(end 192.154048 -312.049922)
		(stroke
			(width 0.1016)
			(type default)
		)
		(fill no)
		(layer "In6.Cu")
	)
	(gr_circle
		(center 191.900048 -311.099962)
		(end 192.154048 -311.099962)
		(stroke
			(width 0.1016)
			(type default)
		)
		(fill no)
		(layer "In6.Cu")
	)
	(gr_circle
		(center 191.900048 -308.249828)
		(end 192.154048 -308.249828)
		(stroke
			(width 0.1016)
			(type default)
		)
		(fill no)
		(layer "In6.Cu")
	)
	(gr_circle
		(center 191.900048 -306.349908)
		(end 192.154048 -306.349908)
		(stroke
			(width 0.1016)
			(type default)
		)
		(fill no)
		(layer "In6.Cu")
	)
	(gr_circle
		(center 191.900048 -304.449734)
		(end 192.154048 -304.449734)
		(stroke
			(width 0.1016)
			(type default)
		)
		(fill no)
		(layer "In6.Cu")
	)
	(gr_circle
		(center 191.900048 -287.349946)
		(end 192.154048 -287.349946)
		(stroke
			(width 0.1016)
			(type default)
		)
		(fill no)
		(layer "In6.Cu")
	)
	(gr_circle
		(center 191.900048 -285.449772)
		(end 192.154048 -285.449772)
		(stroke
			(width 0.1016)
			(type default)
		)
		(fill no)
		(layer "In6.Cu")
	)
	(gr_circle
		(center 191.900048 -283.549852)
		(end 192.154048 -283.549852)
		(stroke
			(width 0.1016)
			(type default)
		)
		(fill no)
		(layer "In6.Cu")
	)
	(gr_circle
		(center 191.900048 -280.699464)
		(end 192.154048 -280.699464)
		(stroke
			(width 0.1016)
			(type default)
		)
		(fill no)
		(layer "In6.Cu")
	)
	(gr_circle
		(center 191.900048 -279.749504)
		(end 192.154048 -279.749504)
		(stroke
			(width 0.1016)
			(type default)
		)
		(fill no)
		(layer "In6.Cu")
	)
	(gr_circle
		(center 192.849754 -278.799798)
		(end 193.103754 -278.799798)
		(stroke
			(width 0.1016)
			(type default)
		)
		(fill no)
		(layer "In6.Cu")
	)
	(gr_circle
		(center 192.849754 -277.849838)
		(end 193.103754 -277.849838)
		(stroke
			(width 0.1016)
			(type default)
		)
		(fill no)
		(layer "In6.Cu")
	)
	(gr_circle
		(center 192.850008 -313.949842)
		(end 193.104008 -313.949842)
		(stroke
			(width 0.1016)
			(type default)
		)
		(fill no)
		(layer "In6.Cu")
	)
	(gr_circle
		(center 192.850008 -312.999882)
		(end 193.104008 -312.999882)
		(stroke
			(width 0.1016)
			(type default)
		)
		(fill no)
		(layer "In6.Cu")
	)
	(gr_circle
		(center 192.850008 -309.199788)
		(end 193.104008 -309.199788)
		(stroke
			(width 0.1016)
			(type default)
		)
		(fill no)
		(layer "In6.Cu")
	)
	(gr_circle
		(center 192.850008 -307.299868)
		(end 193.104008 -307.299868)
		(stroke
			(width 0.1016)
			(type default)
		)
		(fill no)
		(layer "In6.Cu")
	)
	(gr_circle
		(center 192.850008 -305.399948)
		(end 193.104008 -305.399948)
		(stroke
			(width 0.1016)
			(type default)
		)
		(fill no)
		(layer "In6.Cu")
	)
	(gr_circle
		(center 192.850008 -288.299906)
		(end 193.104008 -288.299906)
		(stroke
			(width 0.1016)
			(type default)
		)
		(fill no)
		(layer "In6.Cu")
	)
	(gr_circle
		(center 192.850008 -286.399986)
		(end 193.104008 -286.399986)
		(stroke
			(width 0.1016)
			(type default)
		)
		(fill no)
		(layer "In6.Cu")
	)
	(gr_circle
		(center 192.850008 -284.499812)
		(end 193.104008 -284.499812)
		(stroke
			(width 0.1016)
			(type default)
		)
		(fill no)
		(layer "In6.Cu")
	)
	(gr_circle
		(center 192.850008 -282.599892)
		(end 193.104008 -282.599892)
		(stroke
			(width 0.1016)
			(type default)
		)
		(fill no)
		(layer "In6.Cu")
	)
	(gr_circle
		(center 193.799968 -312.049922)
		(end 194.053968 -312.049922)
		(stroke
			(width 0.1016)
			(type default)
		)
		(fill no)
		(layer "In6.Cu")
	)
	(gr_circle
		(center 193.799968 -311.099962)
		(end 194.053968 -311.099962)
		(stroke
			(width 0.1016)
			(type default)
		)
		(fill no)
		(layer "In6.Cu")
	)
	(gr_circle
		(center 193.799968 -309.199788)
		(end 194.053968 -309.199788)
		(stroke
			(width 0.1016)
			(type default)
		)
		(fill no)
		(layer "In6.Cu")
	)
	(gr_circle
		(center 193.799968 -307.299868)
		(end 194.053968 -307.299868)
		(stroke
			(width 0.1016)
			(type default)
		)
		(fill no)
		(layer "In6.Cu")
	)
	(gr_circle
		(center 193.799968 -305.399948)
		(end 194.053968 -305.399948)
		(stroke
			(width 0.1016)
			(type default)
		)
		(fill no)
		(layer "In6.Cu")
	)
	(gr_circle
		(center 193.799968 -288.299906)
		(end 194.053968 -288.299906)
		(stroke
			(width 0.1016)
			(type default)
		)
		(fill no)
		(layer "In6.Cu")
	)
	(gr_circle
		(center 193.799968 -286.399986)
		(end 194.053968 -286.399986)
		(stroke
			(width 0.1016)
			(type default)
		)
		(fill no)
		(layer "In6.Cu")
	)
	(gr_circle
		(center 193.799968 -284.499812)
		(end 194.053968 -284.499812)
		(stroke
			(width 0.1016)
			(type default)
		)
		(fill no)
		(layer "In6.Cu")
	)
	(gr_circle
		(center 193.799968 -282.599892)
		(end 194.053968 -282.599892)
		(stroke
			(width 0.1016)
			(type default)
		)
		(fill no)
		(layer "In6.Cu")
	)
	(gr_circle
		(center 193.799968 -280.699464)
		(end 194.053968 -280.699464)
		(stroke
			(width 0.1016)
			(type default)
		)
		(fill no)
		(layer "In6.Cu")
	)
	(gr_circle
		(center 193.799968 -279.749504)
		(end 194.053968 -279.749504)
		(stroke
			(width 0.1016)
			(type default)
		)
		(fill no)
		(layer "In6.Cu")
	)
	(gr_circle
		(center 194.749674 -278.799798)
		(end 195.003674 -278.799798)
		(stroke
			(width 0.1016)
			(type default)
		)
		(fill no)
		(layer "In6.Cu")
	)
	(gr_circle
		(center 194.749674 -277.849838)
		(end 195.003674 -277.849838)
		(stroke
			(width 0.1016)
			(type default)
		)
		(fill no)
		(layer "In6.Cu")
	)
	(gr_circle
		(center 194.749928 -313.949842)
		(end 195.003928 -313.949842)
		(stroke
			(width 0.1016)
			(type default)
		)
		(fill no)
		(layer "In6.Cu")
	)
	(gr_circle
		(center 194.749928 -312.999882)
		(end 195.003928 -312.999882)
		(stroke
			(width 0.1016)
			(type default)
		)
		(fill no)
		(layer "In6.Cu")
	)
	(gr_circle
		(center 195.699888 -312.049922)
		(end 195.953888 -312.049922)
		(stroke
			(width 0.1016)
			(type default)
		)
		(fill no)
		(layer "In6.Cu")
	)
	(gr_circle
		(center 195.699888 -311.099962)
		(end 195.953888 -311.099962)
		(stroke
			(width 0.1016)
			(type default)
		)
		(fill no)
		(layer "In6.Cu")
	)
	(gr_circle
		(center 195.699888 -280.699718)
		(end 195.953888 -280.699718)
		(stroke
			(width 0.1016)
			(type default)
		)
		(fill no)
		(layer "In6.Cu")
	)
	(gr_circle
		(center 195.699888 -279.749758)
		(end 195.953888 -279.749758)
		(stroke
			(width 0.1016)
			(type default)
		)
		(fill no)
		(layer "In6.Cu")
	)
	(gr_circle
		(center 196.649848 -313.949842)
		(end 196.903848 -313.949842)
		(stroke
			(width 0.1016)
			(type default)
		)
		(fill no)
		(layer "In6.Cu")
	)
	(gr_circle
		(center 196.649848 -312.999882)
		(end 196.903848 -312.999882)
		(stroke
			(width 0.1016)
			(type default)
		)
		(fill no)
		(layer "In6.Cu")
	)
	(gr_circle
		(center 196.649848 -278.799798)
		(end 196.903848 -278.799798)
		(stroke
			(width 0.1016)
			(type default)
		)
		(fill no)
		(layer "In6.Cu")
	)
	(gr_circle
		(center 196.649848 -277.849838)
		(end 196.903848 -277.849838)
		(stroke
			(width 0.1016)
			(type default)
		)
		(fill no)
		(layer "In6.Cu")
	)
	(gr_circle
		(center 197.600062 -314.899802)
		(end 197.854062 -314.899802)
		(stroke
			(width 0.1016)
			(type default)
		)
		(fill no)
		(layer "In6.Cu")
	)
	(gr_circle
		(center 197.600062 -312.049922)
		(end 197.854062 -312.049922)
		(stroke
			(width 0.1016)
			(type default)
		)
		(fill no)
		(layer "In6.Cu")
	)
	(gr_circle
		(center 197.600062 -279.749758)
		(end 197.854062 -279.749758)
		(stroke
			(width 0.1016)
			(type default)
		)
		(fill no)
		(layer "In6.Cu")
	)
	(gr_circle
		(center 197.600062 -276.899878)
		(end 197.854062 -276.899878)
		(stroke
			(width 0.1016)
			(type default)
		)
		(fill no)
		(layer "In6.Cu")
	)
	(gr_circle
		(center 198.550022 -314.899802)
		(end 198.804022 -314.899802)
		(stroke
			(width 0.1016)
			(type default)
		)
		(fill no)
		(layer "In6.Cu")
	)
	(gr_circle
		(center 198.550022 -312.049922)
		(end 198.804022 -312.049922)
		(stroke
			(width 0.1016)
			(type default)
		)
		(fill no)
		(layer "In6.Cu")
	)
	(gr_circle
		(center 198.550022 -279.749758)
		(end 198.804022 -279.749758)
		(stroke
			(width 0.1016)
			(type default)
		)
		(fill no)
		(layer "In6.Cu")
	)
	(gr_circle
		(center 198.550022 -276.899878)
		(end 198.804022 -276.899878)
		(stroke
			(width 0.1016)
			(type default)
		)
		(fill no)
		(layer "In6.Cu")
	)
	(gr_circle
		(center 269.049754 -314.899802)
		(end 269.303754 -314.899802)
		(stroke
			(width 0.1016)
			(type default)
		)
		(fill no)
		(layer "In6.Cu")
	)
	(gr_circle
		(center 269.049754 -312.049922)
		(end 269.303754 -312.049922)
		(stroke
			(width 0.1016)
			(type default)
		)
		(fill no)
		(layer "In6.Cu")
	)
	(gr_circle
		(center 269.999714 -314.899802)
		(end 270.253714 -314.899802)
		(stroke
			(width 0.1016)
			(type default)
		)
		(fill no)
		(layer "In6.Cu")
	)
	(gr_circle
		(center 269.999714 -312.049922)
		(end 270.253714 -312.049922)
		(stroke
			(width 0.1016)
			(type default)
		)
		(fill no)
		(layer "In6.Cu")
	)
	(gr_circle
		(center 270.949928 -313.949842)
		(end 271.203928 -313.949842)
		(stroke
			(width 0.1016)
			(type default)
		)
		(fill no)
		(layer "In6.Cu")
	)
	(gr_circle
		(center 270.949928 -312.999882)
		(end 271.203928 -312.999882)
		(stroke
			(width 0.1016)
			(type default)
		)
		(fill no)
		(layer "In6.Cu")
	)
	(gr_circle
		(center 271.899888 -312.049922)
		(end 272.153888 -312.049922)
		(stroke
			(width 0.1016)
			(type default)
		)
		(fill no)
		(layer "In6.Cu")
	)
	(gr_circle
		(center 271.899888 -311.099962)
		(end 272.153888 -311.099962)
		(stroke
			(width 0.1016)
			(type default)
		)
		(fill no)
		(layer "In6.Cu")
	)
	(gr_circle
		(center 272.849848 -313.949842)
		(end 273.103848 -313.949842)
		(stroke
			(width 0.1016)
			(type default)
		)
		(fill no)
		(layer "In6.Cu")
	)
	(gr_circle
		(center 272.849848 -312.999882)
		(end 273.103848 -312.999882)
		(stroke
			(width 0.1016)
			(type default)
		)
		(fill no)
		(layer "In6.Cu")
	)
	(gr_circle
		(center 273.799808 -312.049922)
		(end 274.053808 -312.049922)
		(stroke
			(width 0.1016)
			(type default)
		)
		(fill no)
		(layer "In6.Cu")
	)
	(gr_circle
		(center 273.799808 -311.099962)
		(end 274.053808 -311.099962)
		(stroke
			(width 0.1016)
			(type default)
		)
		(fill no)
		(layer "In6.Cu")
	)
	(gr_circle
		(center 273.799808 -309.199788)
		(end 274.053808 -309.199788)
		(stroke
			(width 0.1016)
			(type default)
		)
		(fill no)
		(layer "In6.Cu")
	)
	(gr_circle
		(center 273.799808 -307.299868)
		(end 274.053808 -307.299868)
		(stroke
			(width 0.1016)
			(type default)
		)
		(fill no)
		(layer "In6.Cu")
	)
	(gr_circle
		(center 273.799808 -305.399948)
		(end 274.053808 -305.399948)
		(stroke
			(width 0.1016)
			(type default)
		)
		(fill no)
		(layer "In6.Cu")
	)
	(gr_circle
		(center 273.799808 -303.499774)
		(end 274.053808 -303.499774)
		(stroke
			(width 0.1016)
			(type default)
		)
		(fill no)
		(layer "In6.Cu")
	)
	(gr_circle
		(center 273.799808 -301.599854)
		(end 274.053808 -301.599854)
		(stroke
			(width 0.1016)
			(type default)
		)
		(fill no)
		(layer "In6.Cu")
	)
	(gr_circle
		(center 274.749768 -313.949842)
		(end 275.003768 -313.949842)
		(stroke
			(width 0.1016)
			(type default)
		)
		(fill no)
		(layer "In6.Cu")
	)
	(gr_circle
		(center 274.749768 -312.999882)
		(end 275.003768 -312.999882)
		(stroke
			(width 0.1016)
			(type default)
		)
		(fill no)
		(layer "In6.Cu")
	)
	(gr_circle
		(center 274.749768 -309.199788)
		(end 275.003768 -309.199788)
		(stroke
			(width 0.1016)
			(type default)
		)
		(fill no)
		(layer "In6.Cu")
	)
	(gr_circle
		(center 274.749768 -307.299868)
		(end 275.003768 -307.299868)
		(stroke
			(width 0.1016)
			(type default)
		)
		(fill no)
		(layer "In6.Cu")
	)
	(gr_circle
		(center 274.749768 -305.399948)
		(end 275.003768 -305.399948)
		(stroke
			(width 0.1016)
			(type default)
		)
		(fill no)
		(layer "In6.Cu")
	)
	(gr_circle
		(center 274.749768 -303.499774)
		(end 275.003768 -303.499774)
		(stroke
			(width 0.1016)
			(type default)
		)
		(fill no)
		(layer "In6.Cu")
	)
	(gr_circle
		(center 274.749768 -301.599854)
		(end 275.003768 -301.599854)
		(stroke
			(width 0.1016)
			(type default)
		)
		(fill no)
		(layer "In6.Cu")
	)
	(gr_circle
		(center 275.699728 -312.049922)
		(end 275.953728 -312.049922)
		(stroke
			(width 0.1016)
			(type default)
		)
		(fill no)
		(layer "In6.Cu")
	)
	(gr_circle
		(center 275.699728 -311.099962)
		(end 275.953728 -311.099962)
		(stroke
			(width 0.1016)
			(type default)
		)
		(fill no)
		(layer "In6.Cu")
	)
	(gr_circle
		(center 275.699728 -308.249828)
		(end 275.953728 -308.249828)
		(stroke
			(width 0.1016)
			(type default)
		)
		(fill no)
		(layer "In6.Cu")
	)
	(gr_circle
		(center 275.699728 -306.349908)
		(end 275.953728 -306.349908)
		(stroke
			(width 0.1016)
			(type default)
		)
		(fill no)
		(layer "In6.Cu")
	)
	(gr_circle
		(center 275.699728 -304.449734)
		(end 275.953728 -304.449734)
		(stroke
			(width 0.1016)
			(type default)
		)
		(fill no)
		(layer "In6.Cu")
	)
	(gr_circle
		(center 275.699728 -302.549814)
		(end 275.953728 -302.549814)
		(stroke
			(width 0.1016)
			(type default)
		)
		(fill no)
		(layer "In6.Cu")
	)
	(gr_circle
		(center 276.649688 -313.949842)
		(end 276.903688 -313.949842)
		(stroke
			(width 0.1016)
			(type default)
		)
		(fill no)
		(layer "In6.Cu")
	)
	(gr_circle
		(center 276.649688 -312.999882)
		(end 276.903688 -312.999882)
		(stroke
			(width 0.1016)
			(type default)
		)
		(fill no)
		(layer "In6.Cu")
	)
	(gr_circle
		(center 276.649688 -308.249828)
		(end 276.903688 -308.249828)
		(stroke
			(width 0.1016)
			(type default)
		)
		(fill no)
		(layer "In6.Cu")
	)
	(gr_circle
		(center 276.649688 -306.349908)
		(end 276.903688 -306.349908)
		(stroke
			(width 0.1016)
			(type default)
		)
		(fill no)
		(layer "In6.Cu")
	)
	(gr_circle
		(center 276.649688 -304.449734)
		(end 276.903688 -304.449734)
		(stroke
			(width 0.1016)
			(type default)
		)
		(fill no)
		(layer "In6.Cu")
	)
	(gr_circle
		(center 276.649688 -302.549814)
		(end 276.903688 -302.549814)
		(stroke
			(width 0.1016)
			(type default)
		)
		(fill no)
		(layer "In6.Cu")
	)
	(gr_circle
		(center 276.649688 -278.799798)
		(end 276.903688 -278.799798)
		(stroke
			(width 0.1016)
			(type default)
		)
		(fill no)
		(layer "In6.Cu")
	)
	(gr_circle
		(center 276.649688 -277.849838)
		(end 276.903688 -277.849838)
		(stroke
			(width 0.1016)
			(type default)
		)
		(fill no)
		(layer "In6.Cu")
	)
	(gr_circle
		(center 276.649688 -274.049744)
		(end 276.903688 -274.049744)
		(stroke
			(width 0.1016)
			(type default)
		)
		(fill no)
		(layer "In6.Cu")
	)
	(gr_circle
		(center 276.649688 -273.099784)
		(end 276.903688 -273.099784)
		(stroke
			(width 0.1016)
			(type default)
		)
		(fill no)
		(layer "In6.Cu")
	)
	(gr_circle
		(center 277.599902 -312.049922)
		(end 277.853902 -312.049922)
		(stroke
			(width 0.1016)
			(type default)
		)
		(fill no)
		(layer "In6.Cu")
	)
	(gr_circle
		(center 277.599902 -311.099962)
		(end 277.853902 -311.099962)
		(stroke
			(width 0.1016)
			(type default)
		)
		(fill no)
		(layer "In6.Cu")
	)
	(gr_circle
		(center 277.599902 -280.699464)
		(end 277.853902 -280.699464)
		(stroke
			(width 0.1016)
			(type default)
		)
		(fill no)
		(layer "In6.Cu")
	)
	(gr_circle
		(center 277.599902 -279.749504)
		(end 277.853902 -279.749504)
		(stroke
			(width 0.1016)
			(type default)
		)
		(fill no)
		(layer "In6.Cu")
	)
	(gr_circle
		(center 277.599902 -275.949918)
		(end 277.853902 -275.949918)
		(stroke
			(width 0.1016)
			(type default)
		)
		(fill no)
		(layer "In6.Cu")
	)
	(gr_circle
		(center 277.599902 -274.999958)
		(end 277.853902 -274.999958)
		(stroke
			(width 0.1016)
			(type default)
		)
		(fill no)
		(layer "In6.Cu")
	)
	(gr_circle
		(center 278.549862 -313.949842)
		(end 278.803862 -313.949842)
		(stroke
			(width 0.1016)
			(type default)
		)
		(fill no)
		(layer "In6.Cu")
	)
	(gr_circle
		(center 278.549862 -312.999882)
		(end 278.803862 -312.999882)
		(stroke
			(width 0.1016)
			(type default)
		)
		(fill no)
		(layer "In6.Cu")
	)
	(gr_circle
		(center 278.549862 -278.799798)
		(end 278.803862 -278.799798)
		(stroke
			(width 0.1016)
			(type default)
		)
		(fill no)
		(layer "In6.Cu")
	)
	(gr_circle
		(center 278.549862 -277.849838)
		(end 278.803862 -277.849838)
		(stroke
			(width 0.1016)
			(type default)
		)
		(fill no)
		(layer "In6.Cu")
	)
	(gr_circle
		(center 278.549862 -274.049744)
		(end 278.803862 -274.049744)
		(stroke
			(width 0.1016)
			(type default)
		)
		(fill no)
		(layer "In6.Cu")
	)
	(gr_circle
		(center 278.549862 -273.099784)
		(end 278.803862 -273.099784)
		(stroke
			(width 0.1016)
			(type default)
		)
		(fill no)
		(layer "In6.Cu")
	)
	(gr_circle
		(center 279.499822 -312.049922)
		(end 279.753822 -312.049922)
		(stroke
			(width 0.1016)
			(type default)
		)
		(fill no)
		(layer "In6.Cu")
	)
	(gr_circle
		(center 279.499822 -311.099962)
		(end 279.753822 -311.099962)
		(stroke
			(width 0.1016)
			(type default)
		)
		(fill no)
		(layer "In6.Cu")
	)
	(gr_circle
		(center 279.499822 -280.699464)
		(end 279.753822 -280.699464)
		(stroke
			(width 0.1016)
			(type default)
		)
		(fill no)
		(layer "In6.Cu")
	)
	(gr_circle
		(center 279.499822 -279.749504)
		(end 279.753822 -279.749504)
		(stroke
			(width 0.1016)
			(type default)
		)
		(fill no)
		(layer "In6.Cu")
	)
	(gr_circle
		(center 279.499822 -275.949918)
		(end 279.753822 -275.949918)
		(stroke
			(width 0.1016)
			(type default)
		)
		(fill no)
		(layer "In6.Cu")
	)
	(gr_circle
		(center 279.499822 -274.999958)
		(end 279.753822 -274.999958)
		(stroke
			(width 0.1016)
			(type default)
		)
		(fill no)
		(layer "In6.Cu")
	)
	(gr_circle
		(center 280.449782 -313.949842)
		(end 280.703782 -313.949842)
		(stroke
			(width 0.1016)
			(type default)
		)
		(fill no)
		(layer "In6.Cu")
	)
	(gr_circle
		(center 280.449782 -312.999882)
		(end 280.703782 -312.999882)
		(stroke
			(width 0.1016)
			(type default)
		)
		(fill no)
		(layer "In6.Cu")
	)
	(gr_circle
		(center 280.449782 -278.799798)
		(end 280.703782 -278.799798)
		(stroke
			(width 0.1016)
			(type default)
		)
		(fill no)
		(layer "In6.Cu")
	)
	(gr_circle
		(center 280.449782 -277.849838)
		(end 280.703782 -277.849838)
		(stroke
			(width 0.1016)
			(type default)
		)
		(fill no)
		(layer "In6.Cu")
	)
	(gr_circle
		(center 280.449782 -274.049744)
		(end 280.703782 -274.049744)
		(stroke
			(width 0.1016)
			(type default)
		)
		(fill no)
		(layer "In6.Cu")
	)
	(gr_circle
		(center 280.449782 -273.099784)
		(end 280.703782 -273.099784)
		(stroke
			(width 0.1016)
			(type default)
		)
		(fill no)
		(layer "In6.Cu")
	)
	(gr_circle
		(center 281.399742 -312.049922)
		(end 281.653742 -312.049922)
		(stroke
			(width 0.1016)
			(type default)
		)
		(fill no)
		(layer "In6.Cu")
	)
	(gr_circle
		(center 281.399742 -311.099962)
		(end 281.653742 -311.099962)
		(stroke
			(width 0.1016)
			(type default)
		)
		(fill no)
		(layer "In6.Cu")
	)
	(gr_circle
		(center 281.399742 -280.699464)
		(end 281.653742 -280.699464)
		(stroke
			(width 0.1016)
			(type default)
		)
		(fill no)
		(layer "In6.Cu")
	)
	(gr_circle
		(center 281.399742 -279.749504)
		(end 281.653742 -279.749504)
		(stroke
			(width 0.1016)
			(type default)
		)
		(fill no)
		(layer "In6.Cu")
	)
	(gr_circle
		(center 281.399742 -275.949918)
		(end 281.653742 -275.949918)
		(stroke
			(width 0.1016)
			(type default)
		)
		(fill no)
		(layer "In6.Cu")
	)
	(gr_circle
		(center 281.399742 -274.999958)
		(end 281.653742 -274.999958)
		(stroke
			(width 0.1016)
			(type default)
		)
		(fill no)
		(layer "In6.Cu")
	)
	(gr_circle
		(center 282.349702 -313.949842)
		(end 282.603702 -313.949842)
		(stroke
			(width 0.1016)
			(type default)
		)
		(fill no)
		(layer "In6.Cu")
	)
	(gr_circle
		(center 282.349702 -312.999882)
		(end 282.603702 -312.999882)
		(stroke
			(width 0.1016)
			(type default)
		)
		(fill no)
		(layer "In6.Cu")
	)
	(gr_circle
		(center 282.349702 -278.799798)
		(end 282.603702 -278.799798)
		(stroke
			(width 0.1016)
			(type default)
		)
		(fill no)
		(layer "In6.Cu")
	)
	(gr_circle
		(center 282.349702 -277.849838)
		(end 282.603702 -277.849838)
		(stroke
			(width 0.1016)
			(type default)
		)
		(fill no)
		(layer "In6.Cu")
	)
	(gr_circle
		(center 282.349702 -274.049744)
		(end 282.603702 -274.049744)
		(stroke
			(width 0.1016)
			(type default)
		)
		(fill no)
		(layer "In6.Cu")
	)
	(gr_circle
		(center 282.349702 -273.099784)
		(end 282.603702 -273.099784)
		(stroke
			(width 0.1016)
			(type default)
		)
		(fill no)
		(layer "In6.Cu")
	)
	(gr_circle
		(center 283.299916 -316.799722)
		(end 283.553916 -316.799722)
		(stroke
			(width 0.1016)
			(type default)
		)
		(fill no)
		(layer "In6.Cu")
	)
	(gr_circle
		(center 283.299916 -315.849762)
		(end 283.553916 -315.849762)
		(stroke
			(width 0.1016)
			(type default)
		)
		(fill no)
		(layer "In6.Cu")
	)
	(gr_circle
		(center 283.299916 -312.049922)
		(end 283.553916 -312.049922)
		(stroke
			(width 0.1016)
			(type default)
		)
		(fill no)
		(layer "In6.Cu")
	)
	(gr_circle
		(center 283.299916 -311.099962)
		(end 283.553916 -311.099962)
		(stroke
			(width 0.1016)
			(type default)
		)
		(fill no)
		(layer "In6.Cu")
	)
	(gr_circle
		(center 283.299916 -280.699464)
		(end 283.553916 -280.699464)
		(stroke
			(width 0.1016)
			(type default)
		)
		(fill no)
		(layer "In6.Cu")
	)
	(gr_circle
		(center 283.299916 -279.749504)
		(end 283.553916 -279.749504)
		(stroke
			(width 0.1016)
			(type default)
		)
		(fill no)
		(layer "In6.Cu")
	)
	(gr_circle
		(center 283.299916 -275.949918)
		(end 283.553916 -275.949918)
		(stroke
			(width 0.1016)
			(type default)
		)
		(fill no)
		(layer "In6.Cu")
	)
	(gr_circle
		(center 283.299916 -274.999958)
		(end 283.553916 -274.999958)
		(stroke
			(width 0.1016)
			(type default)
		)
		(fill no)
		(layer "In6.Cu")
	)
	(gr_circle
		(center 284.249876 -318.699896)
		(end 284.503876 -318.699896)
		(stroke
			(width 0.1016)
			(type default)
		)
		(fill no)
		(layer "In6.Cu")
	)
	(gr_circle
		(center 284.249876 -317.749936)
		(end 284.503876 -317.749936)
		(stroke
			(width 0.1016)
			(type default)
		)
		(fill no)
		(layer "In6.Cu")
	)
	(gr_circle
		(center 284.249876 -313.949842)
		(end 284.503876 -313.949842)
		(stroke
			(width 0.1016)
			(type default)
		)
		(fill no)
		(layer "In6.Cu")
	)
	(gr_circle
		(center 284.249876 -312.999882)
		(end 284.503876 -312.999882)
		(stroke
			(width 0.1016)
			(type default)
		)
		(fill no)
		(layer "In6.Cu")
	)
	(gr_circle
		(center 284.249876 -278.799798)
		(end 284.503876 -278.799798)
		(stroke
			(width 0.1016)
			(type default)
		)
		(fill no)
		(layer "In6.Cu")
	)
	(gr_circle
		(center 284.249876 -277.849838)
		(end 284.503876 -277.849838)
		(stroke
			(width 0.1016)
			(type default)
		)
		(fill no)
		(layer "In6.Cu")
	)
	(gr_circle
		(center 284.249876 -274.049744)
		(end 284.503876 -274.049744)
		(stroke
			(width 0.1016)
			(type default)
		)
		(fill no)
		(layer "In6.Cu")
	)
	(gr_circle
		(center 284.249876 -273.099784)
		(end 284.503876 -273.099784)
		(stroke
			(width 0.1016)
			(type default)
		)
		(fill no)
		(layer "In6.Cu")
	)
	(gr_circle
		(center 285.199836 -316.799722)
		(end 285.453836 -316.799722)
		(stroke
			(width 0.1016)
			(type default)
		)
		(fill no)
		(layer "In6.Cu")
	)
	(gr_circle
		(center 285.199836 -315.849762)
		(end 285.453836 -315.849762)
		(stroke
			(width 0.1016)
			(type default)
		)
		(fill no)
		(layer "In6.Cu")
	)
	(gr_circle
		(center 285.199836 -312.049922)
		(end 285.453836 -312.049922)
		(stroke
			(width 0.1016)
			(type default)
		)
		(fill no)
		(layer "In6.Cu")
	)
	(gr_circle
		(center 285.199836 -311.099962)
		(end 285.453836 -311.099962)
		(stroke
			(width 0.1016)
			(type default)
		)
		(fill no)
		(layer "In6.Cu")
	)
	(gr_circle
		(center 285.199836 -280.699464)
		(end 285.453836 -280.699464)
		(stroke
			(width 0.1016)
			(type default)
		)
		(fill no)
		(layer "In6.Cu")
	)
	(gr_circle
		(center 285.199836 -279.749504)
		(end 285.453836 -279.749504)
		(stroke
			(width 0.1016)
			(type default)
		)
		(fill no)
		(layer "In6.Cu")
	)
	(gr_circle
		(center 285.199836 -275.949918)
		(end 285.453836 -275.949918)
		(stroke
			(width 0.1016)
			(type default)
		)
		(fill no)
		(layer "In6.Cu")
	)
	(gr_circle
		(center 285.199836 -274.999958)
		(end 285.453836 -274.999958)
		(stroke
			(width 0.1016)
			(type default)
		)
		(fill no)
		(layer "In6.Cu")
	)
	(gr_circle
		(center 286.149796 -318.699896)
		(end 286.403796 -318.699896)
		(stroke
			(width 0.1016)
			(type default)
		)
		(fill no)
		(layer "In6.Cu")
	)
	(gr_circle
		(center 286.149796 -317.749936)
		(end 286.403796 -317.749936)
		(stroke
			(width 0.1016)
			(type default)
		)
		(fill no)
		(layer "In6.Cu")
	)
	(gr_circle
		(center 286.149796 -313.949842)
		(end 286.403796 -313.949842)
		(stroke
			(width 0.1016)
			(type default)
		)
		(fill no)
		(layer "In6.Cu")
	)
	(gr_circle
		(center 286.149796 -312.999882)
		(end 286.403796 -312.999882)
		(stroke
			(width 0.1016)
			(type default)
		)
		(fill no)
		(layer "In6.Cu")
	)
	(gr_circle
		(center 286.149796 -278.799798)
		(end 286.403796 -278.799798)
		(stroke
			(width 0.1016)
			(type default)
		)
		(fill no)
		(layer "In6.Cu")
	)
	(gr_circle
		(center 286.149796 -277.849838)
		(end 286.403796 -277.849838)
		(stroke
			(width 0.1016)
			(type default)
		)
		(fill no)
		(layer "In6.Cu")
	)
	(gr_circle
		(center 286.149796 -274.049744)
		(end 286.403796 -274.049744)
		(stroke
			(width 0.1016)
			(type default)
		)
		(fill no)
		(layer "In6.Cu")
	)
	(gr_circle
		(center 286.149796 -273.099784)
		(end 286.403796 -273.099784)
		(stroke
			(width 0.1016)
			(type default)
		)
		(fill no)
		(layer "In6.Cu")
	)
	(gr_circle
		(center 287.099756 -316.799722)
		(end 287.353756 -316.799722)
		(stroke
			(width 0.1016)
			(type default)
		)
		(fill no)
		(layer "In6.Cu")
	)
	(gr_circle
		(center 287.099756 -315.849762)
		(end 287.353756 -315.849762)
		(stroke
			(width 0.1016)
			(type default)
		)
		(fill no)
		(layer "In6.Cu")
	)
	(gr_circle
		(center 287.099756 -312.049922)
		(end 287.353756 -312.049922)
		(stroke
			(width 0.1016)
			(type default)
		)
		(fill no)
		(layer "In6.Cu")
	)
	(gr_circle
		(center 287.099756 -311.099962)
		(end 287.353756 -311.099962)
		(stroke
			(width 0.1016)
			(type default)
		)
		(fill no)
		(layer "In6.Cu")
	)
	(gr_circle
		(center 287.099756 -280.699464)
		(end 287.353756 -280.699464)
		(stroke
			(width 0.1016)
			(type default)
		)
		(fill no)
		(layer "In6.Cu")
	)
	(gr_circle
		(center 287.099756 -279.749504)
		(end 287.353756 -279.749504)
		(stroke
			(width 0.1016)
			(type default)
		)
		(fill no)
		(layer "In6.Cu")
	)
	(gr_circle
		(center 287.099756 -275.949918)
		(end 287.353756 -275.949918)
		(stroke
			(width 0.1016)
			(type default)
		)
		(fill no)
		(layer "In6.Cu")
	)
	(gr_circle
		(center 287.099756 -274.999958)
		(end 287.353756 -274.999958)
		(stroke
			(width 0.1016)
			(type default)
		)
		(fill no)
		(layer "In6.Cu")
	)
	(gr_circle
		(center 288.049716 -318.699896)
		(end 288.303716 -318.699896)
		(stroke
			(width 0.1016)
			(type default)
		)
		(fill no)
		(layer "In6.Cu")
	)
	(gr_circle
		(center 288.049716 -317.749936)
		(end 288.303716 -317.749936)
		(stroke
			(width 0.1016)
			(type default)
		)
		(fill no)
		(layer "In6.Cu")
	)
	(gr_circle
		(center 288.049716 -313.949842)
		(end 288.303716 -313.949842)
		(stroke
			(width 0.1016)
			(type default)
		)
		(fill no)
		(layer "In6.Cu")
	)
	(gr_circle
		(center 288.049716 -312.999882)
		(end 288.303716 -312.999882)
		(stroke
			(width 0.1016)
			(type default)
		)
		(fill no)
		(layer "In6.Cu")
	)
	(gr_circle
		(center 288.049716 -278.799798)
		(end 288.303716 -278.799798)
		(stroke
			(width 0.1016)
			(type default)
		)
		(fill no)
		(layer "In6.Cu")
	)
	(gr_circle
		(center 288.049716 -277.849838)
		(end 288.303716 -277.849838)
		(stroke
			(width 0.1016)
			(type default)
		)
		(fill no)
		(layer "In6.Cu")
	)
	(gr_circle
		(center 288.049716 -274.049744)
		(end 288.303716 -274.049744)
		(stroke
			(width 0.1016)
			(type default)
		)
		(fill no)
		(layer "In6.Cu")
	)
	(gr_circle
		(center 288.049716 -273.099784)
		(end 288.303716 -273.099784)
		(stroke
			(width 0.1016)
			(type default)
		)
		(fill no)
		(layer "In6.Cu")
	)
	(gr_circle
		(center 288.999676 -280.699464)
		(end 289.253676 -280.699464)
		(stroke
			(width 0.1016)
			(type default)
		)
		(fill no)
		(layer "In6.Cu")
	)
	(gr_circle
		(center 288.999676 -279.749504)
		(end 289.253676 -279.749504)
		(stroke
			(width 0.1016)
			(type default)
		)
		(fill no)
		(layer "In6.Cu")
	)
	(gr_circle
		(center 288.99993 -316.799722)
		(end 289.25393 -316.799722)
		(stroke
			(width 0.1016)
			(type default)
		)
		(fill no)
		(layer "In6.Cu")
	)
	(gr_circle
		(center 288.99993 -315.849762)
		(end 289.25393 -315.849762)
		(stroke
			(width 0.1016)
			(type default)
		)
		(fill no)
		(layer "In6.Cu")
	)
	(gr_circle
		(center 288.99993 -312.049922)
		(end 289.25393 -312.049922)
		(stroke
			(width 0.1016)
			(type default)
		)
		(fill no)
		(layer "In6.Cu")
	)
	(gr_circle
		(center 288.99993 -311.099962)
		(end 289.25393 -311.099962)
		(stroke
			(width 0.1016)
			(type default)
		)
		(fill no)
		(layer "In6.Cu")
	)
	(gr_circle
		(center 288.99993 -275.949918)
		(end 289.25393 -275.949918)
		(stroke
			(width 0.1016)
			(type default)
		)
		(fill no)
		(layer "In6.Cu")
	)
	(gr_circle
		(center 288.99993 -274.999958)
		(end 289.25393 -274.999958)
		(stroke
			(width 0.1016)
			(type default)
		)
		(fill no)
		(layer "In6.Cu")
	)
	(gr_circle
		(center 289.94989 -318.699896)
		(end 290.20389 -318.699896)
		(stroke
			(width 0.1016)
			(type default)
		)
		(fill no)
		(layer "In6.Cu")
	)
	(gr_circle
		(center 289.94989 -317.749936)
		(end 290.20389 -317.749936)
		(stroke
			(width 0.1016)
			(type default)
		)
		(fill no)
		(layer "In6.Cu")
	)
	(gr_circle
		(center 289.94989 -313.949842)
		(end 290.20389 -313.949842)
		(stroke
			(width 0.1016)
			(type default)
		)
		(fill no)
		(layer "In6.Cu")
	)
	(gr_circle
		(center 289.94989 -312.999882)
		(end 290.20389 -312.999882)
		(stroke
			(width 0.1016)
			(type default)
		)
		(fill no)
		(layer "In6.Cu")
	)
	(gr_circle
		(center 289.94989 -278.799798)
		(end 290.20389 -278.799798)
		(stroke
			(width 0.1016)
			(type default)
		)
		(fill no)
		(layer "In6.Cu")
	)
	(gr_circle
		(center 289.94989 -277.849838)
		(end 290.20389 -277.849838)
		(stroke
			(width 0.1016)
			(type default)
		)
		(fill no)
		(layer "In6.Cu")
	)
	(gr_circle
		(center 289.94989 -274.049744)
		(end 290.20389 -274.049744)
		(stroke
			(width 0.1016)
			(type default)
		)
		(fill no)
		(layer "In6.Cu")
	)
	(gr_circle
		(center 289.94989 -273.099784)
		(end 290.20389 -273.099784)
		(stroke
			(width 0.1016)
			(type default)
		)
		(fill no)
		(layer "In6.Cu")
	)
	(gr_circle
		(center 290.89985 -316.799722)
		(end 291.15385 -316.799722)
		(stroke
			(width 0.1016)
			(type default)
		)
		(fill no)
		(layer "In6.Cu")
	)
	(gr_circle
		(center 290.89985 -315.849762)
		(end 291.15385 -315.849762)
		(stroke
			(width 0.1016)
			(type default)
		)
		(fill no)
		(layer "In6.Cu")
	)
	(gr_circle
		(center 290.89985 -312.049922)
		(end 291.15385 -312.049922)
		(stroke
			(width 0.1016)
			(type default)
		)
		(fill no)
		(layer "In6.Cu")
	)
	(gr_circle
		(center 290.89985 -311.099962)
		(end 291.15385 -311.099962)
		(stroke
			(width 0.1016)
			(type default)
		)
		(fill no)
		(layer "In6.Cu")
	)
	(gr_circle
		(center 290.89985 -280.699464)
		(end 291.15385 -280.699464)
		(stroke
			(width 0.1016)
			(type default)
		)
		(fill no)
		(layer "In6.Cu")
	)
	(gr_circle
		(center 290.89985 -279.749504)
		(end 291.15385 -279.749504)
		(stroke
			(width 0.1016)
			(type default)
		)
		(fill no)
		(layer "In6.Cu")
	)
	(gr_circle
		(center 290.89985 -275.949918)
		(end 291.15385 -275.949918)
		(stroke
			(width 0.1016)
			(type default)
		)
		(fill no)
		(layer "In6.Cu")
	)
	(gr_circle
		(center 290.89985 -274.999958)
		(end 291.15385 -274.999958)
		(stroke
			(width 0.1016)
			(type default)
		)
		(fill no)
		(layer "In6.Cu")
	)
	(gr_circle
		(center 291.849556 -278.799798)
		(end 292.103556 -278.799798)
		(stroke
			(width 0.1016)
			(type default)
		)
		(fill no)
		(layer "In6.Cu")
	)
	(gr_circle
		(center 291.849556 -277.849838)
		(end 292.103556 -277.849838)
		(stroke
			(width 0.1016)
			(type default)
		)
		(fill no)
		(layer "In6.Cu")
	)
	(gr_circle
		(center 291.84981 -318.699896)
		(end 292.10381 -318.699896)
		(stroke
			(width 0.1016)
			(type default)
		)
		(fill no)
		(layer "In6.Cu")
	)
	(gr_circle
		(center 291.84981 -317.749936)
		(end 292.10381 -317.749936)
		(stroke
			(width 0.1016)
			(type default)
		)
		(fill no)
		(layer "In6.Cu")
	)
	(gr_circle
		(center 291.84981 -313.949842)
		(end 292.10381 -313.949842)
		(stroke
			(width 0.1016)
			(type default)
		)
		(fill no)
		(layer "In6.Cu")
	)
	(gr_circle
		(center 291.84981 -312.999882)
		(end 292.10381 -312.999882)
		(stroke
			(width 0.1016)
			(type default)
		)
		(fill no)
		(layer "In6.Cu")
	)
	(gr_circle
		(center 292.79977 -316.799722)
		(end 293.05377 -316.799722)
		(stroke
			(width 0.1016)
			(type default)
		)
		(fill no)
		(layer "In6.Cu")
	)
	(gr_circle
		(center 292.79977 -315.849762)
		(end 293.05377 -315.849762)
		(stroke
			(width 0.1016)
			(type default)
		)
		(fill no)
		(layer "In6.Cu")
	)
	(gr_circle
		(center 292.79977 -312.049922)
		(end 293.05377 -312.049922)
		(stroke
			(width 0.1016)
			(type default)
		)
		(fill no)
		(layer "In6.Cu")
	)
	(gr_circle
		(center 292.79977 -311.099962)
		(end 293.05377 -311.099962)
		(stroke
			(width 0.1016)
			(type default)
		)
		(fill no)
		(layer "In6.Cu")
	)
	(gr_circle
		(center 292.79977 -280.699464)
		(end 293.05377 -280.699464)
		(stroke
			(width 0.1016)
			(type default)
		)
		(fill no)
		(layer "In6.Cu")
	)
	(gr_circle
		(center 292.79977 -279.749504)
		(end 293.05377 -279.749504)
		(stroke
			(width 0.1016)
			(type default)
		)
		(fill no)
		(layer "In6.Cu")
	)
	(gr_circle
		(center 293.749476 -278.799798)
		(end 294.003476 -278.799798)
		(stroke
			(width 0.1016)
			(type default)
		)
		(fill no)
		(layer "In6.Cu")
	)
	(gr_circle
		(center 293.749476 -277.849838)
		(end 294.003476 -277.849838)
		(stroke
			(width 0.1016)
			(type default)
		)
		(fill no)
		(layer "In6.Cu")
	)
	(gr_circle
		(center 293.74973 -318.699896)
		(end 294.00373 -318.699896)
		(stroke
			(width 0.1016)
			(type default)
		)
		(fill no)
		(layer "In6.Cu")
	)
	(gr_circle
		(center 293.74973 -317.749936)
		(end 294.00373 -317.749936)
		(stroke
			(width 0.1016)
			(type default)
		)
		(fill no)
		(layer "In6.Cu")
	)
	(gr_circle
		(center 293.74973 -313.949842)
		(end 294.00373 -313.949842)
		(stroke
			(width 0.1016)
			(type default)
		)
		(fill no)
		(layer "In6.Cu")
	)
	(gr_circle
		(center 293.74973 -312.999882)
		(end 294.00373 -312.999882)
		(stroke
			(width 0.1016)
			(type default)
		)
		(fill no)
		(layer "In6.Cu")
	)
	(gr_circle
		(center 294.69969 -316.799722)
		(end 294.95369 -316.799722)
		(stroke
			(width 0.1016)
			(type default)
		)
		(fill no)
		(layer "In6.Cu")
	)
	(gr_circle
		(center 294.69969 -315.849762)
		(end 294.95369 -315.849762)
		(stroke
			(width 0.1016)
			(type default)
		)
		(fill no)
		(layer "In6.Cu")
	)
	(gr_circle
		(center 294.69969 -312.049922)
		(end 294.95369 -312.049922)
		(stroke
			(width 0.1016)
			(type default)
		)
		(fill no)
		(layer "In6.Cu")
	)
	(gr_circle
		(center 294.69969 -311.099962)
		(end 294.95369 -311.099962)
		(stroke
			(width 0.1016)
			(type default)
		)
		(fill no)
		(layer "In6.Cu")
	)
	(gr_circle
		(center 294.69969 -280.699464)
		(end 294.95369 -280.699464)
		(stroke
			(width 0.1016)
			(type default)
		)
		(fill no)
		(layer "In6.Cu")
	)
	(gr_circle
		(center 294.69969 -279.749504)
		(end 294.95369 -279.749504)
		(stroke
			(width 0.1016)
			(type default)
		)
		(fill no)
		(layer "In6.Cu")
	)
	(gr_circle
		(center 295.64965 -278.799798)
		(end 295.90365 -278.799798)
		(stroke
			(width 0.1016)
			(type default)
		)
		(fill no)
		(layer "In6.Cu")
	)
	(gr_circle
		(center 295.64965 -277.849838)
		(end 295.90365 -277.849838)
		(stroke
			(width 0.1016)
			(type default)
		)
		(fill no)
		(layer "In6.Cu")
	)
	(gr_circle
		(center 295.649904 -318.699896)
		(end 295.903904 -318.699896)
		(stroke
			(width 0.1016)
			(type default)
		)
		(fill no)
		(layer "In6.Cu")
	)
	(gr_circle
		(center 295.649904 -317.749936)
		(end 295.903904 -317.749936)
		(stroke
			(width 0.1016)
			(type default)
		)
		(fill no)
		(layer "In6.Cu")
	)
	(gr_circle
		(center 295.649904 -313.949842)
		(end 295.903904 -313.949842)
		(stroke
			(width 0.1016)
			(type default)
		)
		(fill no)
		(layer "In6.Cu")
	)
	(gr_circle
		(center 295.649904 -312.999882)
		(end 295.903904 -312.999882)
		(stroke
			(width 0.1016)
			(type default)
		)
		(fill no)
		(layer "In6.Cu")
	)
	(gr_circle
		(center 296.599864 -316.799722)
		(end 296.853864 -316.799722)
		(stroke
			(width 0.1016)
			(type default)
		)
		(fill no)
		(layer "In6.Cu")
	)
	(gr_circle
		(center 296.599864 -315.849762)
		(end 296.853864 -315.849762)
		(stroke
			(width 0.1016)
			(type default)
		)
		(fill no)
		(layer "In6.Cu")
	)
	(gr_circle
		(center 296.599864 -312.049922)
		(end 296.853864 -312.049922)
		(stroke
			(width 0.1016)
			(type default)
		)
		(fill no)
		(layer "In6.Cu")
	)
	(gr_circle
		(center 296.599864 -311.099962)
		(end 296.853864 -311.099962)
		(stroke
			(width 0.1016)
			(type default)
		)
		(fill no)
		(layer "In6.Cu")
	)
	(gr_circle
		(center 296.599864 -280.699464)
		(end 296.853864 -280.699464)
		(stroke
			(width 0.1016)
			(type default)
		)
		(fill no)
		(layer "In6.Cu")
	)
	(gr_circle
		(center 296.599864 -279.749504)
		(end 296.853864 -279.749504)
		(stroke
			(width 0.1016)
			(type default)
		)
		(fill no)
		(layer "In6.Cu")
	)
	(gr_circle
		(center 297.54957 -278.799798)
		(end 297.80357 -278.799798)
		(stroke
			(width 0.1016)
			(type default)
		)
		(fill no)
		(layer "In6.Cu")
	)
	(gr_circle
		(center 297.54957 -277.849838)
		(end 297.80357 -277.849838)
		(stroke
			(width 0.1016)
			(type default)
		)
		(fill no)
		(layer "In6.Cu")
	)
	(gr_circle
		(center 297.549824 -318.699896)
		(end 297.803824 -318.699896)
		(stroke
			(width 0.1016)
			(type default)
		)
		(fill no)
		(layer "In6.Cu")
	)
	(gr_circle
		(center 297.549824 -317.749936)
		(end 297.803824 -317.749936)
		(stroke
			(width 0.1016)
			(type default)
		)
		(fill no)
		(layer "In6.Cu")
	)
	(gr_circle
		(center 297.549824 -313.949842)
		(end 297.803824 -313.949842)
		(stroke
			(width 0.1016)
			(type default)
		)
		(fill no)
		(layer "In6.Cu")
	)
	(gr_circle
		(center 297.549824 -312.999882)
		(end 297.803824 -312.999882)
		(stroke
			(width 0.1016)
			(type default)
		)
		(fill no)
		(layer "In6.Cu")
	)
	(gr_circle
		(center 298.499784 -312.049922)
		(end 298.753784 -312.049922)
		(stroke
			(width 0.1016)
			(type default)
		)
		(fill no)
		(layer "In6.Cu")
	)
	(gr_circle
		(center 298.499784 -311.099962)
		(end 298.753784 -311.099962)
		(stroke
			(width 0.1016)
			(type default)
		)
		(fill no)
		(layer "In6.Cu")
	)
	(gr_circle
		(center 298.499784 -280.699464)
		(end 298.753784 -280.699464)
		(stroke
			(width 0.1016)
			(type default)
		)
		(fill no)
		(layer "In6.Cu")
	)
	(gr_circle
		(center 298.499784 -279.749504)
		(end 298.753784 -279.749504)
		(stroke
			(width 0.1016)
			(type default)
		)
		(fill no)
		(layer "In6.Cu")
	)
	(gr_circle
		(center 299.44949 -278.799798)
		(end 299.70349 -278.799798)
		(stroke
			(width 0.1016)
			(type default)
		)
		(fill no)
		(layer "In6.Cu")
	)
	(gr_circle
		(center 299.44949 -277.849838)
		(end 299.70349 -277.849838)
		(stroke
			(width 0.1016)
			(type default)
		)
		(fill no)
		(layer "In6.Cu")
	)
	(gr_circle
		(center 299.449744 -313.949842)
		(end 299.703744 -313.949842)
		(stroke
			(width 0.1016)
			(type default)
		)
		(fill no)
		(layer "In6.Cu")
	)
	(gr_circle
		(center 299.449744 -312.999882)
		(end 299.703744 -312.999882)
		(stroke
			(width 0.1016)
			(type default)
		)
		(fill no)
		(layer "In6.Cu")
	)
	(gr_circle
		(center 300.399704 -312.049922)
		(end 300.653704 -312.049922)
		(stroke
			(width 0.1016)
			(type default)
		)
		(fill no)
		(layer "In6.Cu")
	)
	(gr_circle
		(center 300.399704 -311.099962)
		(end 300.653704 -311.099962)
		(stroke
			(width 0.1016)
			(type default)
		)
		(fill no)
		(layer "In6.Cu")
	)
	(gr_circle
		(center 300.399704 -280.699464)
		(end 300.653704 -280.699464)
		(stroke
			(width 0.1016)
			(type default)
		)
		(fill no)
		(layer "In6.Cu")
	)
	(gr_circle
		(center 300.399704 -279.749504)
		(end 300.653704 -279.749504)
		(stroke
			(width 0.1016)
			(type default)
		)
		(fill no)
		(layer "In6.Cu")
	)
	(gr_circle
		(center 301.349664 -278.799798)
		(end 301.603664 -278.799798)
		(stroke
			(width 0.1016)
			(type default)
		)
		(fill no)
		(layer "In6.Cu")
	)
	(gr_circle
		(center 301.349664 -277.849838)
		(end 301.603664 -277.849838)
		(stroke
			(width 0.1016)
			(type default)
		)
		(fill no)
		(layer "In6.Cu")
	)
	(gr_circle
		(center 301.349918 -313.949842)
		(end 301.603918 -313.949842)
		(stroke
			(width 0.1016)
			(type default)
		)
		(fill no)
		(layer "In6.Cu")
	)
	(gr_circle
		(center 301.349918 -312.999882)
		(end 301.603918 -312.999882)
		(stroke
			(width 0.1016)
			(type default)
		)
		(fill no)
		(layer "In6.Cu")
	)
	(gr_circle
		(center 302.299878 -312.049922)
		(end 302.553878 -312.049922)
		(stroke
			(width 0.1016)
			(type default)
		)
		(fill no)
		(layer "In6.Cu")
	)
	(gr_circle
		(center 302.299878 -311.099962)
		(end 302.553878 -311.099962)
		(stroke
			(width 0.1016)
			(type default)
		)
		(fill no)
		(layer "In6.Cu")
	)
	(gr_circle
		(center 302.299878 -280.699464)
		(end 302.553878 -280.699464)
		(stroke
			(width 0.1016)
			(type default)
		)
		(fill no)
		(layer "In6.Cu")
	)
	(gr_circle
		(center 302.299878 -279.749504)
		(end 302.553878 -279.749504)
		(stroke
			(width 0.1016)
			(type default)
		)
		(fill no)
		(layer "In6.Cu")
	)
	(gr_circle
		(center 303.249584 -278.799798)
		(end 303.503584 -278.799798)
		(stroke
			(width 0.1016)
			(type default)
		)
		(fill no)
		(layer "In6.Cu")
	)
	(gr_circle
		(center 303.249584 -277.849838)
		(end 303.503584 -277.849838)
		(stroke
			(width 0.1016)
			(type default)
		)
		(fill no)
		(layer "In6.Cu")
	)
	(gr_circle
		(center 303.249838 -313.949842)
		(end 303.503838 -313.949842)
		(stroke
			(width 0.1016)
			(type default)
		)
		(fill no)
		(layer "In6.Cu")
	)
	(gr_circle
		(center 303.249838 -312.999882)
		(end 303.503838 -312.999882)
		(stroke
			(width 0.1016)
			(type default)
		)
		(fill no)
		(layer "In6.Cu")
	)
	(gr_circle
		(center 304.199798 -312.049922)
		(end 304.453798 -312.049922)
		(stroke
			(width 0.1016)
			(type default)
		)
		(fill no)
		(layer "In6.Cu")
	)
	(gr_circle
		(center 304.199798 -311.099962)
		(end 304.453798 -311.099962)
		(stroke
			(width 0.1016)
			(type default)
		)
		(fill no)
		(layer "In6.Cu")
	)
	(gr_circle
		(center 304.199798 -280.699464)
		(end 304.453798 -280.699464)
		(stroke
			(width 0.1016)
			(type default)
		)
		(fill no)
		(layer "In6.Cu")
	)
	(gr_circle
		(center 304.199798 -279.749504)
		(end 304.453798 -279.749504)
		(stroke
			(width 0.1016)
			(type default)
		)
		(fill no)
		(layer "In6.Cu")
	)
	(gr_circle
		(center 305.149504 -278.799798)
		(end 305.403504 -278.799798)
		(stroke
			(width 0.1016)
			(type default)
		)
		(fill no)
		(layer "In6.Cu")
	)
	(gr_circle
		(center 305.149504 -277.849838)
		(end 305.403504 -277.849838)
		(stroke
			(width 0.1016)
			(type default)
		)
		(fill no)
		(layer "In6.Cu")
	)
	(gr_circle
		(center 305.149758 -313.949842)
		(end 305.403758 -313.949842)
		(stroke
			(width 0.1016)
			(type default)
		)
		(fill no)
		(layer "In6.Cu")
	)
	(gr_circle
		(center 305.149758 -312.999882)
		(end 305.403758 -312.999882)
		(stroke
			(width 0.1016)
			(type default)
		)
		(fill no)
		(layer "In6.Cu")
	)
	(gr_circle
		(center 306.099718 -316.799722)
		(end 306.353718 -316.799722)
		(stroke
			(width 0.1016)
			(type default)
		)
		(fill no)
		(layer "In6.Cu")
	)
	(gr_circle
		(center 306.099718 -315.849762)
		(end 306.353718 -315.849762)
		(stroke
			(width 0.1016)
			(type default)
		)
		(fill no)
		(layer "In6.Cu")
	)
	(gr_circle
		(center 306.099718 -312.049922)
		(end 306.353718 -312.049922)
		(stroke
			(width 0.1016)
			(type default)
		)
		(fill no)
		(layer "In6.Cu")
	)
	(gr_circle
		(center 306.099718 -311.099962)
		(end 306.353718 -311.099962)
		(stroke
			(width 0.1016)
			(type default)
		)
		(fill no)
		(layer "In6.Cu")
	)
	(gr_circle
		(center 306.099718 -280.699464)
		(end 306.353718 -280.699464)
		(stroke
			(width 0.1016)
			(type default)
		)
		(fill no)
		(layer "In6.Cu")
	)
	(gr_circle
		(center 306.099718 -279.749504)
		(end 306.353718 -279.749504)
		(stroke
			(width 0.1016)
			(type default)
		)
		(fill no)
		(layer "In6.Cu")
	)
	(gr_circle
		(center 307.049678 -278.799798)
		(end 307.303678 -278.799798)
		(stroke
			(width 0.1016)
			(type default)
		)
		(fill no)
		(layer "In6.Cu")
	)
	(gr_circle
		(center 307.049678 -277.849838)
		(end 307.303678 -277.849838)
		(stroke
			(width 0.1016)
			(type default)
		)
		(fill no)
		(layer "In6.Cu")
	)
	(gr_circle
		(center 307.049932 -318.699896)
		(end 307.303932 -318.699896)
		(stroke
			(width 0.1016)
			(type default)
		)
		(fill no)
		(layer "In6.Cu")
	)
	(gr_circle
		(center 307.049932 -317.749936)
		(end 307.303932 -317.749936)
		(stroke
			(width 0.1016)
			(type default)
		)
		(fill no)
		(layer "In6.Cu")
	)
	(gr_circle
		(center 307.049932 -313.949842)
		(end 307.303932 -313.949842)
		(stroke
			(width 0.1016)
			(type default)
		)
		(fill no)
		(layer "In6.Cu")
	)
	(gr_circle
		(center 307.049932 -312.999882)
		(end 307.303932 -312.999882)
		(stroke
			(width 0.1016)
			(type default)
		)
		(fill no)
		(layer "In6.Cu")
	)
	(gr_circle
		(center 307.049932 -308.249828)
		(end 307.303932 -308.249828)
		(stroke
			(width 0.1016)
			(type default)
		)
		(fill no)
		(layer "In6.Cu")
	)
	(gr_circle
		(center 307.049932 -306.349908)
		(end 307.303932 -306.349908)
		(stroke
			(width 0.1016)
			(type default)
		)
		(fill no)
		(layer "In6.Cu")
	)
	(gr_circle
		(center 307.049932 -304.449734)
		(end 307.303932 -304.449734)
		(stroke
			(width 0.1016)
			(type default)
		)
		(fill no)
		(layer "In6.Cu")
	)
	(gr_circle
		(center 307.049932 -287.349946)
		(end 307.303932 -287.349946)
		(stroke
			(width 0.1016)
			(type default)
		)
		(fill no)
		(layer "In6.Cu")
	)
	(gr_circle
		(center 307.049932 -285.449772)
		(end 307.303932 -285.449772)
		(stroke
			(width 0.1016)
			(type default)
		)
		(fill no)
		(layer "In6.Cu")
	)
	(gr_circle
		(center 307.049932 -283.549852)
		(end 307.303932 -283.549852)
		(stroke
			(width 0.1016)
			(type default)
		)
		(fill no)
		(layer "In6.Cu")
	)
	(gr_circle
		(center 307.999892 -316.799722)
		(end 308.253892 -316.799722)
		(stroke
			(width 0.1016)
			(type default)
		)
		(fill no)
		(layer "In6.Cu")
	)
	(gr_circle
		(center 307.999892 -315.849762)
		(end 308.253892 -315.849762)
		(stroke
			(width 0.1016)
			(type default)
		)
		(fill no)
		(layer "In6.Cu")
	)
	(gr_circle
		(center 307.999892 -312.049922)
		(end 308.253892 -312.049922)
		(stroke
			(width 0.1016)
			(type default)
		)
		(fill no)
		(layer "In6.Cu")
	)
	(gr_circle
		(center 307.999892 -311.099962)
		(end 308.253892 -311.099962)
		(stroke
			(width 0.1016)
			(type default)
		)
		(fill no)
		(layer "In6.Cu")
	)
	(gr_circle
		(center 307.999892 -308.249828)
		(end 308.253892 -308.249828)
		(stroke
			(width 0.1016)
			(type default)
		)
		(fill no)
		(layer "In6.Cu")
	)
	(gr_circle
		(center 307.999892 -306.349908)
		(end 308.253892 -306.349908)
		(stroke
			(width 0.1016)
			(type default)
		)
		(fill no)
		(layer "In6.Cu")
	)
	(gr_circle
		(center 307.999892 -304.449734)
		(end 308.253892 -304.449734)
		(stroke
			(width 0.1016)
			(type default)
		)
		(fill no)
		(layer "In6.Cu")
	)
	(gr_circle
		(center 307.999892 -287.349946)
		(end 308.253892 -287.349946)
		(stroke
			(width 0.1016)
			(type default)
		)
		(fill no)
		(layer "In6.Cu")
	)
	(gr_circle
		(center 307.999892 -285.449772)
		(end 308.253892 -285.449772)
		(stroke
			(width 0.1016)
			(type default)
		)
		(fill no)
		(layer "In6.Cu")
	)
	(gr_circle
		(center 307.999892 -283.549852)
		(end 308.253892 -283.549852)
		(stroke
			(width 0.1016)
			(type default)
		)
		(fill no)
		(layer "In6.Cu")
	)
	(gr_circle
		(center 307.999892 -280.699464)
		(end 308.253892 -280.699464)
		(stroke
			(width 0.1016)
			(type default)
		)
		(fill no)
		(layer "In6.Cu")
	)
	(gr_circle
		(center 307.999892 -279.749504)
		(end 308.253892 -279.749504)
		(stroke
			(width 0.1016)
			(type default)
		)
		(fill no)
		(layer "In6.Cu")
	)
	(gr_circle
		(center 308.949598 -278.799798)
		(end 309.203598 -278.799798)
		(stroke
			(width 0.1016)
			(type default)
		)
		(fill no)
		(layer "In6.Cu")
	)
	(gr_circle
		(center 308.949598 -277.849838)
		(end 309.203598 -277.849838)
		(stroke
			(width 0.1016)
			(type default)
		)
		(fill no)
		(layer "In6.Cu")
	)
	(gr_circle
		(center 308.949852 -318.699896)
		(end 309.203852 -318.699896)
		(stroke
			(width 0.1016)
			(type default)
		)
		(fill no)
		(layer "In6.Cu")
	)
	(gr_circle
		(center 308.949852 -317.749936)
		(end 309.203852 -317.749936)
		(stroke
			(width 0.1016)
			(type default)
		)
		(fill no)
		(layer "In6.Cu")
	)
	(gr_circle
		(center 308.949852 -313.949842)
		(end 309.203852 -313.949842)
		(stroke
			(width 0.1016)
			(type default)
		)
		(fill no)
		(layer "In6.Cu")
	)
	(gr_circle
		(center 308.949852 -312.999882)
		(end 309.203852 -312.999882)
		(stroke
			(width 0.1016)
			(type default)
		)
		(fill no)
		(layer "In6.Cu")
	)
	(gr_circle
		(center 308.949852 -309.199788)
		(end 309.203852 -309.199788)
		(stroke
			(width 0.1016)
			(type default)
		)
		(fill no)
		(layer "In6.Cu")
	)
	(gr_circle
		(center 308.949852 -307.299868)
		(end 309.203852 -307.299868)
		(stroke
			(width 0.1016)
			(type default)
		)
		(fill no)
		(layer "In6.Cu")
	)
	(gr_circle
		(center 308.949852 -305.399948)
		(end 309.203852 -305.399948)
		(stroke
			(width 0.1016)
			(type default)
		)
		(fill no)
		(layer "In6.Cu")
	)
	(gr_circle
		(center 308.949852 -288.299906)
		(end 309.203852 -288.299906)
		(stroke
			(width 0.1016)
			(type default)
		)
		(fill no)
		(layer "In6.Cu")
	)
	(gr_circle
		(center 308.949852 -286.399986)
		(end 309.203852 -286.399986)
		(stroke
			(width 0.1016)
			(type default)
		)
		(fill no)
		(layer "In6.Cu")
	)
	(gr_circle
		(center 308.949852 -284.499812)
		(end 309.203852 -284.499812)
		(stroke
			(width 0.1016)
			(type default)
		)
		(fill no)
		(layer "In6.Cu")
	)
	(gr_circle
		(center 308.949852 -282.599892)
		(end 309.203852 -282.599892)
		(stroke
			(width 0.1016)
			(type default)
		)
		(fill no)
		(layer "In6.Cu")
	)
	(gr_circle
		(center 309.899812 -316.799722)
		(end 310.153812 -316.799722)
		(stroke
			(width 0.1016)
			(type default)
		)
		(fill no)
		(layer "In6.Cu")
	)
	(gr_circle
		(center 309.899812 -315.849762)
		(end 310.153812 -315.849762)
		(stroke
			(width 0.1016)
			(type default)
		)
		(fill no)
		(layer "In6.Cu")
	)
	(gr_circle
		(center 309.899812 -312.049922)
		(end 310.153812 -312.049922)
		(stroke
			(width 0.1016)
			(type default)
		)
		(fill no)
		(layer "In6.Cu")
	)
	(gr_circle
		(center 309.899812 -311.099962)
		(end 310.153812 -311.099962)
		(stroke
			(width 0.1016)
			(type default)
		)
		(fill no)
		(layer "In6.Cu")
	)
	(gr_circle
		(center 309.899812 -309.199788)
		(end 310.153812 -309.199788)
		(stroke
			(width 0.1016)
			(type default)
		)
		(fill no)
		(layer "In6.Cu")
	)
	(gr_circle
		(center 309.899812 -307.299868)
		(end 310.153812 -307.299868)
		(stroke
			(width 0.1016)
			(type default)
		)
		(fill no)
		(layer "In6.Cu")
	)
	(gr_circle
		(center 309.899812 -305.399948)
		(end 310.153812 -305.399948)
		(stroke
			(width 0.1016)
			(type default)
		)
		(fill no)
		(layer "In6.Cu")
	)
	(gr_circle
		(center 309.899812 -288.299906)
		(end 310.153812 -288.299906)
		(stroke
			(width 0.1016)
			(type default)
		)
		(fill no)
		(layer "In6.Cu")
	)
	(gr_circle
		(center 309.899812 -286.399986)
		(end 310.153812 -286.399986)
		(stroke
			(width 0.1016)
			(type default)
		)
		(fill no)
		(layer "In6.Cu")
	)
	(gr_circle
		(center 309.899812 -284.499812)
		(end 310.153812 -284.499812)
		(stroke
			(width 0.1016)
			(type default)
		)
		(fill no)
		(layer "In6.Cu")
	)
	(gr_circle
		(center 309.899812 -282.599892)
		(end 310.153812 -282.599892)
		(stroke
			(width 0.1016)
			(type default)
		)
		(fill no)
		(layer "In6.Cu")
	)
	(gr_circle
		(center 309.899812 -280.699464)
		(end 310.153812 -280.699464)
		(stroke
			(width 0.1016)
			(type default)
		)
		(fill no)
		(layer "In6.Cu")
	)
	(gr_circle
		(center 309.899812 -279.749504)
		(end 310.153812 -279.749504)
		(stroke
			(width 0.1016)
			(type default)
		)
		(fill no)
		(layer "In6.Cu")
	)
	(gr_circle
		(center 310.849518 -278.799798)
		(end 311.103518 -278.799798)
		(stroke
			(width 0.1016)
			(type default)
		)
		(fill no)
		(layer "In6.Cu")
	)
	(gr_circle
		(center 310.849518 -277.849838)
		(end 311.103518 -277.849838)
		(stroke
			(width 0.1016)
			(type default)
		)
		(fill no)
		(layer "In6.Cu")
	)
	(gr_circle
		(center 310.849772 -318.699896)
		(end 311.103772 -318.699896)
		(stroke
			(width 0.1016)
			(type default)
		)
		(fill no)
		(layer "In6.Cu")
	)
	(gr_circle
		(center 310.849772 -317.749936)
		(end 311.103772 -317.749936)
		(stroke
			(width 0.1016)
			(type default)
		)
		(fill no)
		(layer "In6.Cu")
	)
	(gr_circle
		(center 310.849772 -313.949842)
		(end 311.103772 -313.949842)
		(stroke
			(width 0.1016)
			(type default)
		)
		(fill no)
		(layer "In6.Cu")
	)
	(gr_circle
		(center 310.849772 -312.999882)
		(end 311.103772 -312.999882)
		(stroke
			(width 0.1016)
			(type default)
		)
		(fill no)
		(layer "In6.Cu")
	)
	(gr_circle
		(center 311.799732 -316.799722)
		(end 312.053732 -316.799722)
		(stroke
			(width 0.1016)
			(type default)
		)
		(fill no)
		(layer "In6.Cu")
	)
	(gr_circle
		(center 311.799732 -315.849762)
		(end 312.053732 -315.849762)
		(stroke
			(width 0.1016)
			(type default)
		)
		(fill no)
		(layer "In6.Cu")
	)
	(gr_circle
		(center 311.799732 -312.049922)
		(end 312.053732 -312.049922)
		(stroke
			(width 0.1016)
			(type default)
		)
		(fill no)
		(layer "In6.Cu")
	)
	(gr_circle
		(center 311.799732 -311.099962)
		(end 312.053732 -311.099962)
		(stroke
			(width 0.1016)
			(type default)
		)
		(fill no)
		(layer "In6.Cu")
	)
	(gr_circle
		(center 311.799732 -309.199788)
		(end 312.053732 -309.199788)
		(stroke
			(width 0.1016)
			(type default)
		)
		(fill no)
		(layer "In6.Cu")
	)
	(gr_circle
		(center 311.799732 -307.299868)
		(end 312.053732 -307.299868)
		(stroke
			(width 0.1016)
			(type default)
		)
		(fill no)
		(layer "In6.Cu")
	)
	(gr_circle
		(center 311.799732 -305.399948)
		(end 312.053732 -305.399948)
		(stroke
			(width 0.1016)
			(type default)
		)
		(fill no)
		(layer "In6.Cu")
	)
	(gr_circle
		(center 311.799732 -280.699718)
		(end 312.053732 -280.699718)
		(stroke
			(width 0.1016)
			(type default)
		)
		(fill no)
		(layer "In6.Cu")
	)
	(gr_circle
		(center 311.799732 -279.749758)
		(end 312.053732 -279.749758)
		(stroke
			(width 0.1016)
			(type default)
		)
		(fill no)
		(layer "In6.Cu")
	)
	(gr_circle
		(center 312.749692 -318.699896)
		(end 313.003692 -318.699896)
		(stroke
			(width 0.1016)
			(type default)
		)
		(fill no)
		(layer "In6.Cu")
	)
	(gr_circle
		(center 312.749692 -317.749936)
		(end 313.003692 -317.749936)
		(stroke
			(width 0.1016)
			(type default)
		)
		(fill no)
		(layer "In6.Cu")
	)
	(gr_circle
		(center 312.749692 -313.949842)
		(end 313.003692 -313.949842)
		(stroke
			(width 0.1016)
			(type default)
		)
		(fill no)
		(layer "In6.Cu")
	)
	(gr_circle
		(center 312.749692 -312.999882)
		(end 313.003692 -312.999882)
		(stroke
			(width 0.1016)
			(type default)
		)
		(fill no)
		(layer "In6.Cu")
	)
	(gr_circle
		(center 312.749692 -309.199788)
		(end 313.003692 -309.199788)
		(stroke
			(width 0.1016)
			(type default)
		)
		(fill no)
		(layer "In6.Cu")
	)
	(gr_circle
		(center 312.749692 -307.299868)
		(end 313.003692 -307.299868)
		(stroke
			(width 0.1016)
			(type default)
		)
		(fill no)
		(layer "In6.Cu")
	)
	(gr_circle
		(center 312.749692 -305.399948)
		(end 313.003692 -305.399948)
		(stroke
			(width 0.1016)
			(type default)
		)
		(fill no)
		(layer "In6.Cu")
	)
	(gr_circle
		(center 312.749692 -278.799798)
		(end 313.003692 -278.799798)
		(stroke
			(width 0.1016)
			(type default)
		)
		(fill no)
		(layer "In6.Cu")
	)
	(gr_circle
		(center 312.749692 -277.849838)
		(end 313.003692 -277.849838)
		(stroke
			(width 0.1016)
			(type default)
		)
		(fill no)
		(layer "In6.Cu")
	)
	(gr_circle
		(center 313.699906 -316.799722)
		(end 313.953906 -316.799722)
		(stroke
			(width 0.1016)
			(type default)
		)
		(fill no)
		(layer "In6.Cu")
	)
	(gr_circle
		(center 313.699906 -314.899802)
		(end 313.953906 -314.899802)
		(stroke
			(width 0.1016)
			(type default)
		)
		(fill no)
		(layer "In6.Cu")
	)
	(gr_circle
		(center 313.699906 -312.049922)
		(end 313.953906 -312.049922)
		(stroke
			(width 0.1016)
			(type default)
		)
		(fill no)
		(layer "In6.Cu")
	)
	(gr_circle
		(center 313.699906 -310.149748)
		(end 313.953906 -310.149748)
		(stroke
			(width 0.1016)
			(type default)
		)
		(fill no)
		(layer "In6.Cu")
	)
	(gr_circle
		(center 313.699906 -308.249828)
		(end 313.953906 -308.249828)
		(stroke
			(width 0.1016)
			(type default)
		)
		(fill no)
		(layer "In6.Cu")
	)
	(gr_circle
		(center 313.699906 -306.349908)
		(end 313.953906 -306.349908)
		(stroke
			(width 0.1016)
			(type default)
		)
		(fill no)
		(layer "In6.Cu")
	)
	(gr_circle
		(center 313.699906 -304.449734)
		(end 313.953906 -304.449734)
		(stroke
			(width 0.1016)
			(type default)
		)
		(fill no)
		(layer "In6.Cu")
	)
	(gr_circle
		(center 313.699906 -279.749758)
		(end 313.953906 -279.749758)
		(stroke
			(width 0.1016)
			(type default)
		)
		(fill no)
		(layer "In6.Cu")
	)
	(gr_circle
		(center 313.699906 -276.899878)
		(end 313.953906 -276.899878)
		(stroke
			(width 0.1016)
			(type default)
		)
		(fill no)
		(layer "In6.Cu")
	)
	(gr_circle
		(center 314.649866 -316.799722)
		(end 314.903866 -316.799722)
		(stroke
			(width 0.1016)
			(type default)
		)
		(fill no)
		(layer "In6.Cu")
	)
	(gr_circle
		(center 314.649866 -314.899802)
		(end 314.903866 -314.899802)
		(stroke
			(width 0.1016)
			(type default)
		)
		(fill no)
		(layer "In6.Cu")
	)
	(gr_circle
		(center 314.649866 -312.049922)
		(end 314.903866 -312.049922)
		(stroke
			(width 0.1016)
			(type default)
		)
		(fill no)
		(layer "In6.Cu")
	)
	(gr_circle
		(center 314.649866 -310.149748)
		(end 314.903866 -310.149748)
		(stroke
			(width 0.1016)
			(type default)
		)
		(fill no)
		(layer "In6.Cu")
	)
	(gr_circle
		(center 314.649866 -308.249828)
		(end 314.903866 -308.249828)
		(stroke
			(width 0.1016)
			(type default)
		)
		(fill no)
		(layer "In6.Cu")
	)
	(gr_circle
		(center 314.649866 -306.349908)
		(end 314.903866 -306.349908)
		(stroke
			(width 0.1016)
			(type default)
		)
		(fill no)
		(layer "In6.Cu")
	)
	(gr_circle
		(center 314.649866 -304.449734)
		(end 314.903866 -304.449734)
		(stroke
			(width 0.1016)
			(type default)
		)
		(fill no)
		(layer "In6.Cu")
	)
	(gr_circle
		(center 314.649866 -279.749758)
		(end 314.903866 -279.749758)
		(stroke
			(width 0.1016)
			(type default)
		)
		(fill no)
		(layer "In6.Cu")
	)
	(gr_circle
		(center 314.649866 -276.899878)
		(end 314.903866 -276.899878)
		(stroke
			(width 0.1016)
			(type default)
		)
		(fill no)
		(layer "In6.Cu")
	)
	(gr_circle
		(center 385.149852 -316.799722)
		(end 385.403852 -316.799722)
		(stroke
			(width 0.1016)
			(type default)
		)
		(fill no)
		(layer "In6.Cu")
	)
	(gr_circle
		(center 385.149852 -314.899802)
		(end 385.403852 -314.899802)
		(stroke
			(width 0.1016)
			(type default)
		)
		(fill no)
		(layer "In6.Cu")
	)
	(gr_circle
		(center 385.149852 -312.049922)
		(end 385.403852 -312.049922)
		(stroke
			(width 0.1016)
			(type default)
		)
		(fill no)
		(layer "In6.Cu")
	)
	(gr_circle
		(center 385.149852 -310.149748)
		(end 385.403852 -310.149748)
		(stroke
			(width 0.1016)
			(type default)
		)
		(fill no)
		(layer "In6.Cu")
	)
	(gr_circle
		(center 385.149852 -308.249828)
		(end 385.403852 -308.249828)
		(stroke
			(width 0.1016)
			(type default)
		)
		(fill no)
		(layer "In6.Cu")
	)
	(gr_circle
		(center 385.149852 -306.349908)
		(end 385.403852 -306.349908)
		(stroke
			(width 0.1016)
			(type default)
		)
		(fill no)
		(layer "In6.Cu")
	)
	(gr_circle
		(center 385.149852 -304.449734)
		(end 385.403852 -304.449734)
		(stroke
			(width 0.1016)
			(type default)
		)
		(fill no)
		(layer "In6.Cu")
	)
	(gr_circle
		(center 385.149852 -302.549814)
		(end 385.403852 -302.549814)
		(stroke
			(width 0.1016)
			(type default)
		)
		(fill no)
		(layer "In6.Cu")
	)
	(gr_circle
		(center 386.099812 -316.799722)
		(end 386.353812 -316.799722)
		(stroke
			(width 0.1016)
			(type default)
		)
		(fill no)
		(layer "In6.Cu")
	)
	(gr_circle
		(center 386.099812 -314.899802)
		(end 386.353812 -314.899802)
		(stroke
			(width 0.1016)
			(type default)
		)
		(fill no)
		(layer "In6.Cu")
	)
	(gr_circle
		(center 386.099812 -312.049922)
		(end 386.353812 -312.049922)
		(stroke
			(width 0.1016)
			(type default)
		)
		(fill no)
		(layer "In6.Cu")
	)
	(gr_circle
		(center 386.099812 -310.149748)
		(end 386.353812 -310.149748)
		(stroke
			(width 0.1016)
			(type default)
		)
		(fill no)
		(layer "In6.Cu")
	)
	(gr_circle
		(center 386.099812 -308.249828)
		(end 386.353812 -308.249828)
		(stroke
			(width 0.1016)
			(type default)
		)
		(fill no)
		(layer "In6.Cu")
	)
	(gr_circle
		(center 386.099812 -306.349908)
		(end 386.353812 -306.349908)
		(stroke
			(width 0.1016)
			(type default)
		)
		(fill no)
		(layer "In6.Cu")
	)
	(gr_circle
		(center 386.099812 -304.449734)
		(end 386.353812 -304.449734)
		(stroke
			(width 0.1016)
			(type default)
		)
		(fill no)
		(layer "In6.Cu")
	)
	(gr_circle
		(center 386.099812 -302.549814)
		(end 386.353812 -302.549814)
		(stroke
			(width 0.1016)
			(type default)
		)
		(fill no)
		(layer "In6.Cu")
	)
	(gr_circle
		(center 387.050026 -318.699896)
		(end 387.304026 -318.699896)
		(stroke
			(width 0.1016)
			(type default)
		)
		(fill no)
		(layer "In6.Cu")
	)
	(gr_circle
		(center 387.050026 -317.749936)
		(end 387.304026 -317.749936)
		(stroke
			(width 0.1016)
			(type default)
		)
		(fill no)
		(layer "In6.Cu")
	)
	(gr_circle
		(center 387.050026 -313.949842)
		(end 387.304026 -313.949842)
		(stroke
			(width 0.1016)
			(type default)
		)
		(fill no)
		(layer "In6.Cu")
	)
	(gr_circle
		(center 387.050026 -312.999882)
		(end 387.304026 -312.999882)
		(stroke
			(width 0.1016)
			(type default)
		)
		(fill no)
		(layer "In6.Cu")
	)
	(gr_circle
		(center 387.050026 -309.199788)
		(end 387.304026 -309.199788)
		(stroke
			(width 0.1016)
			(type default)
		)
		(fill no)
		(layer "In6.Cu")
	)
	(gr_circle
		(center 387.050026 -307.299868)
		(end 387.304026 -307.299868)
		(stroke
			(width 0.1016)
			(type default)
		)
		(fill no)
		(layer "In6.Cu")
	)
	(gr_circle
		(center 387.050026 -305.399948)
		(end 387.304026 -305.399948)
		(stroke
			(width 0.1016)
			(type default)
		)
		(fill no)
		(layer "In6.Cu")
	)
	(gr_circle
		(center 387.050026 -303.499774)
		(end 387.304026 -303.499774)
		(stroke
			(width 0.1016)
			(type default)
		)
		(fill no)
		(layer "In6.Cu")
	)
	(gr_circle
		(center 387.050026 -301.599854)
		(end 387.304026 -301.599854)
		(stroke
			(width 0.1016)
			(type default)
		)
		(fill no)
		(layer "In6.Cu")
	)
	(gr_circle
		(center 387.999986 -316.799722)
		(end 388.253986 -316.799722)
		(stroke
			(width 0.1016)
			(type default)
		)
		(fill no)
		(layer "In6.Cu")
	)
	(gr_circle
		(center 387.999986 -315.849762)
		(end 388.253986 -315.849762)
		(stroke
			(width 0.1016)
			(type default)
		)
		(fill no)
		(layer "In6.Cu")
	)
	(gr_circle
		(center 387.999986 -312.049922)
		(end 388.253986 -312.049922)
		(stroke
			(width 0.1016)
			(type default)
		)
		(fill no)
		(layer "In6.Cu")
	)
	(gr_circle
		(center 387.999986 -311.099962)
		(end 388.253986 -311.099962)
		(stroke
			(width 0.1016)
			(type default)
		)
		(fill no)
		(layer "In6.Cu")
	)
	(gr_circle
		(center 387.999986 -309.199788)
		(end 388.253986 -309.199788)
		(stroke
			(width 0.1016)
			(type default)
		)
		(fill no)
		(layer "In6.Cu")
	)
	(gr_circle
		(center 387.999986 -307.299868)
		(end 388.253986 -307.299868)
		(stroke
			(width 0.1016)
			(type default)
		)
		(fill no)
		(layer "In6.Cu")
	)
	(gr_circle
		(center 387.999986 -305.399948)
		(end 388.253986 -305.399948)
		(stroke
			(width 0.1016)
			(type default)
		)
		(fill no)
		(layer "In6.Cu")
	)
	(gr_circle
		(center 387.999986 -303.499774)
		(end 388.253986 -303.499774)
		(stroke
			(width 0.1016)
			(type default)
		)
		(fill no)
		(layer "In6.Cu")
	)
	(gr_circle
		(center 387.999986 -301.599854)
		(end 388.253986 -301.599854)
		(stroke
			(width 0.1016)
			(type default)
		)
		(fill no)
		(layer "In6.Cu")
	)
	(gr_circle
		(center 388.949946 -318.699896)
		(end 389.203946 -318.699896)
		(stroke
			(width 0.1016)
			(type default)
		)
		(fill no)
		(layer "In6.Cu")
	)
	(gr_circle
		(center 388.949946 -317.749936)
		(end 389.203946 -317.749936)
		(stroke
			(width 0.1016)
			(type default)
		)
		(fill no)
		(layer "In6.Cu")
	)
	(gr_circle
		(center 388.949946 -313.949842)
		(end 389.203946 -313.949842)
		(stroke
			(width 0.1016)
			(type default)
		)
		(fill no)
		(layer "In6.Cu")
	)
	(gr_circle
		(center 388.949946 -312.999882)
		(end 389.203946 -312.999882)
		(stroke
			(width 0.1016)
			(type default)
		)
		(fill no)
		(layer "In6.Cu")
	)
	(gr_circle
		(center 389.899906 -316.799722)
		(end 390.153906 -316.799722)
		(stroke
			(width 0.1016)
			(type default)
		)
		(fill no)
		(layer "In6.Cu")
	)
	(gr_circle
		(center 389.899906 -315.849762)
		(end 390.153906 -315.849762)
		(stroke
			(width 0.1016)
			(type default)
		)
		(fill no)
		(layer "In6.Cu")
	)
	(gr_circle
		(center 389.899906 -312.049922)
		(end 390.153906 -312.049922)
		(stroke
			(width 0.1016)
			(type default)
		)
		(fill no)
		(layer "In6.Cu")
	)
	(gr_circle
		(center 389.899906 -311.099962)
		(end 390.153906 -311.099962)
		(stroke
			(width 0.1016)
			(type default)
		)
		(fill no)
		(layer "In6.Cu")
	)
	(gr_circle
		(center 389.899906 -309.199788)
		(end 390.153906 -309.199788)
		(stroke
			(width 0.1016)
			(type default)
		)
		(fill no)
		(layer "In6.Cu")
	)
	(gr_circle
		(center 389.899906 -307.299868)
		(end 390.153906 -307.299868)
		(stroke
			(width 0.1016)
			(type default)
		)
		(fill no)
		(layer "In6.Cu")
	)
	(gr_circle
		(center 389.899906 -305.399948)
		(end 390.153906 -305.399948)
		(stroke
			(width 0.1016)
			(type default)
		)
		(fill no)
		(layer "In6.Cu")
	)
	(gr_circle
		(center 389.899906 -303.499774)
		(end 390.153906 -303.499774)
		(stroke
			(width 0.1016)
			(type default)
		)
		(fill no)
		(layer "In6.Cu")
	)
	(gr_circle
		(center 389.899906 -301.599854)
		(end 390.153906 -301.599854)
		(stroke
			(width 0.1016)
			(type default)
		)
		(fill no)
		(layer "In6.Cu")
	)
	(gr_circle
		(center 390.849866 -318.699896)
		(end 391.103866 -318.699896)
		(stroke
			(width 0.1016)
			(type default)
		)
		(fill no)
		(layer "In6.Cu")
	)
	(gr_circle
		(center 390.849866 -317.749936)
		(end 391.103866 -317.749936)
		(stroke
			(width 0.1016)
			(type default)
		)
		(fill no)
		(layer "In6.Cu")
	)
	(gr_circle
		(center 390.849866 -313.949842)
		(end 391.103866 -313.949842)
		(stroke
			(width 0.1016)
			(type default)
		)
		(fill no)
		(layer "In6.Cu")
	)
	(gr_circle
		(center 390.849866 -312.999882)
		(end 391.103866 -312.999882)
		(stroke
			(width 0.1016)
			(type default)
		)
		(fill no)
		(layer "In6.Cu")
	)
	(gr_circle
		(center 390.849866 -309.199788)
		(end 391.103866 -309.199788)
		(stroke
			(width 0.1016)
			(type default)
		)
		(fill no)
		(layer "In6.Cu")
	)
	(gr_circle
		(center 390.849866 -307.299868)
		(end 391.103866 -307.299868)
		(stroke
			(width 0.1016)
			(type default)
		)
		(fill no)
		(layer "In6.Cu")
	)
	(gr_circle
		(center 390.849866 -305.399948)
		(end 391.103866 -305.399948)
		(stroke
			(width 0.1016)
			(type default)
		)
		(fill no)
		(layer "In6.Cu")
	)
	(gr_circle
		(center 390.849866 -303.499774)
		(end 391.103866 -303.499774)
		(stroke
			(width 0.1016)
			(type default)
		)
		(fill no)
		(layer "In6.Cu")
	)
	(gr_circle
		(center 390.849866 -301.599854)
		(end 391.103866 -301.599854)
		(stroke
			(width 0.1016)
			(type default)
		)
		(fill no)
		(layer "In6.Cu")
	)
	(gr_circle
		(center 391.799826 -316.799722)
		(end 392.053826 -316.799722)
		(stroke
			(width 0.1016)
			(type default)
		)
		(fill no)
		(layer "In6.Cu")
	)
	(gr_circle
		(center 391.799826 -315.849762)
		(end 392.053826 -315.849762)
		(stroke
			(width 0.1016)
			(type default)
		)
		(fill no)
		(layer "In6.Cu")
	)
	(gr_circle
		(center 391.799826 -312.049922)
		(end 392.053826 -312.049922)
		(stroke
			(width 0.1016)
			(type default)
		)
		(fill no)
		(layer "In6.Cu")
	)
	(gr_circle
		(center 391.799826 -311.099962)
		(end 392.053826 -311.099962)
		(stroke
			(width 0.1016)
			(type default)
		)
		(fill no)
		(layer "In6.Cu")
	)
	(gr_circle
		(center 391.799826 -308.249828)
		(end 392.053826 -308.249828)
		(stroke
			(width 0.1016)
			(type default)
		)
		(fill no)
		(layer "In6.Cu")
	)
	(gr_circle
		(center 391.799826 -306.349908)
		(end 392.053826 -306.349908)
		(stroke
			(width 0.1016)
			(type default)
		)
		(fill no)
		(layer "In6.Cu")
	)
	(gr_circle
		(center 391.799826 -304.449734)
		(end 392.053826 -304.449734)
		(stroke
			(width 0.1016)
			(type default)
		)
		(fill no)
		(layer "In6.Cu")
	)
	(gr_circle
		(center 391.799826 -302.549814)
		(end 392.053826 -302.549814)
		(stroke
			(width 0.1016)
			(type default)
		)
		(fill no)
		(layer "In6.Cu")
	)
	(gr_circle
		(center 392.749786 -318.699896)
		(end 393.003786 -318.699896)
		(stroke
			(width 0.1016)
			(type default)
		)
		(fill no)
		(layer "In6.Cu")
	)
	(gr_circle
		(center 392.749786 -317.749936)
		(end 393.003786 -317.749936)
		(stroke
			(width 0.1016)
			(type default)
		)
		(fill no)
		(layer "In6.Cu")
	)
	(gr_circle
		(center 392.749786 -313.949842)
		(end 393.003786 -313.949842)
		(stroke
			(width 0.1016)
			(type default)
		)
		(fill no)
		(layer "In6.Cu")
	)
	(gr_circle
		(center 392.749786 -312.999882)
		(end 393.003786 -312.999882)
		(stroke
			(width 0.1016)
			(type default)
		)
		(fill no)
		(layer "In6.Cu")
	)
	(gr_circle
		(center 392.749786 -308.249828)
		(end 393.003786 -308.249828)
		(stroke
			(width 0.1016)
			(type default)
		)
		(fill no)
		(layer "In6.Cu")
	)
	(gr_circle
		(center 392.749786 -306.349908)
		(end 393.003786 -306.349908)
		(stroke
			(width 0.1016)
			(type default)
		)
		(fill no)
		(layer "In6.Cu")
	)
	(gr_circle
		(center 392.749786 -304.449734)
		(end 393.003786 -304.449734)
		(stroke
			(width 0.1016)
			(type default)
		)
		(fill no)
		(layer "In6.Cu")
	)
	(gr_circle
		(center 392.749786 -302.549814)
		(end 393.003786 -302.549814)
		(stroke
			(width 0.1016)
			(type default)
		)
		(fill no)
		(layer "In6.Cu")
	)
	(gr_circle
		(center 392.749786 -278.799798)
		(end 393.003786 -278.799798)
		(stroke
			(width 0.1016)
			(type default)
		)
		(fill no)
		(layer "In6.Cu")
	)
	(gr_circle
		(center 392.749786 -277.849838)
		(end 393.003786 -277.849838)
		(stroke
			(width 0.1016)
			(type default)
		)
		(fill no)
		(layer "In6.Cu")
	)
	(gr_circle
		(center 392.749786 -274.049744)
		(end 393.003786 -274.049744)
		(stroke
			(width 0.1016)
			(type default)
		)
		(fill no)
		(layer "In6.Cu")
	)
	(gr_circle
		(center 392.749786 -273.099784)
		(end 393.003786 -273.099784)
		(stroke
			(width 0.1016)
			(type default)
		)
		(fill no)
		(layer "In6.Cu")
	)
	(gr_circle
		(center 393.7 -316.799722)
		(end 393.954 -316.799722)
		(stroke
			(width 0.1016)
			(type default)
		)
		(fill no)
		(layer "In6.Cu")
	)
	(gr_circle
		(center 393.7 -315.849762)
		(end 393.954 -315.849762)
		(stroke
			(width 0.1016)
			(type default)
		)
		(fill no)
		(layer "In6.Cu")
	)
	(gr_circle
		(center 393.7 -312.049922)
		(end 393.954 -312.049922)
		(stroke
			(width 0.1016)
			(type default)
		)
		(fill no)
		(layer "In6.Cu")
	)
	(gr_circle
		(center 393.7 -311.099962)
		(end 393.954 -311.099962)
		(stroke
			(width 0.1016)
			(type default)
		)
		(fill no)
		(layer "In6.Cu")
	)
	(gr_circle
		(center 393.7 -280.699464)
		(end 393.954 -280.699464)
		(stroke
			(width 0.1016)
			(type default)
		)
		(fill no)
		(layer "In6.Cu")
	)
	(gr_circle
		(center 393.7 -279.749504)
		(end 393.954 -279.749504)
		(stroke
			(width 0.1016)
			(type default)
		)
		(fill no)
		(layer "In6.Cu")
	)
	(gr_circle
		(center 393.7 -275.949918)
		(end 393.954 -275.949918)
		(stroke
			(width 0.1016)
			(type default)
		)
		(fill no)
		(layer "In6.Cu")
	)
	(gr_circle
		(center 393.7 -274.999958)
		(end 393.954 -274.999958)
		(stroke
			(width 0.1016)
			(type default)
		)
		(fill no)
		(layer "In6.Cu")
	)
	(gr_circle
		(center 394.64996 -318.699896)
		(end 394.90396 -318.699896)
		(stroke
			(width 0.1016)
			(type default)
		)
		(fill no)
		(layer "In6.Cu")
	)
	(gr_circle
		(center 394.64996 -317.749936)
		(end 394.90396 -317.749936)
		(stroke
			(width 0.1016)
			(type default)
		)
		(fill no)
		(layer "In6.Cu")
	)
	(gr_circle
		(center 394.64996 -313.949842)
		(end 394.90396 -313.949842)
		(stroke
			(width 0.1016)
			(type default)
		)
		(fill no)
		(layer "In6.Cu")
	)
	(gr_circle
		(center 394.64996 -312.999882)
		(end 394.90396 -312.999882)
		(stroke
			(width 0.1016)
			(type default)
		)
		(fill no)
		(layer "In6.Cu")
	)
	(gr_circle
		(center 394.64996 -278.799798)
		(end 394.90396 -278.799798)
		(stroke
			(width 0.1016)
			(type default)
		)
		(fill no)
		(layer "In6.Cu")
	)
	(gr_circle
		(center 394.64996 -277.849838)
		(end 394.90396 -277.849838)
		(stroke
			(width 0.1016)
			(type default)
		)
		(fill no)
		(layer "In6.Cu")
	)
	(gr_circle
		(center 394.64996 -274.049744)
		(end 394.90396 -274.049744)
		(stroke
			(width 0.1016)
			(type default)
		)
		(fill no)
		(layer "In6.Cu")
	)
	(gr_circle
		(center 394.64996 -273.099784)
		(end 394.90396 -273.099784)
		(stroke
			(width 0.1016)
			(type default)
		)
		(fill no)
		(layer "In6.Cu")
	)
	(gr_circle
		(center 395.59992 -316.799722)
		(end 395.85392 -316.799722)
		(stroke
			(width 0.1016)
			(type default)
		)
		(fill no)
		(layer "In6.Cu")
	)
	(gr_circle
		(center 395.59992 -315.849762)
		(end 395.85392 -315.849762)
		(stroke
			(width 0.1016)
			(type default)
		)
		(fill no)
		(layer "In6.Cu")
	)
	(gr_circle
		(center 395.59992 -312.049922)
		(end 395.85392 -312.049922)
		(stroke
			(width 0.1016)
			(type default)
		)
		(fill no)
		(layer "In6.Cu")
	)
	(gr_circle
		(center 395.59992 -311.099962)
		(end 395.85392 -311.099962)
		(stroke
			(width 0.1016)
			(type default)
		)
		(fill no)
		(layer "In6.Cu")
	)
	(gr_circle
		(center 395.59992 -280.699464)
		(end 395.85392 -280.699464)
		(stroke
			(width 0.1016)
			(type default)
		)
		(fill no)
		(layer "In6.Cu")
	)
	(gr_circle
		(center 395.59992 -279.749504)
		(end 395.85392 -279.749504)
		(stroke
			(width 0.1016)
			(type default)
		)
		(fill no)
		(layer "In6.Cu")
	)
	(gr_circle
		(center 395.59992 -275.949918)
		(end 395.85392 -275.949918)
		(stroke
			(width 0.1016)
			(type default)
		)
		(fill no)
		(layer "In6.Cu")
	)
	(gr_circle
		(center 395.59992 -274.999958)
		(end 395.85392 -274.999958)
		(stroke
			(width 0.1016)
			(type default)
		)
		(fill no)
		(layer "In6.Cu")
	)
	(gr_circle
		(center 396.54988 -318.699896)
		(end 396.80388 -318.699896)
		(stroke
			(width 0.1016)
			(type default)
		)
		(fill no)
		(layer "In6.Cu")
	)
	(gr_circle
		(center 396.54988 -317.749936)
		(end 396.80388 -317.749936)
		(stroke
			(width 0.1016)
			(type default)
		)
		(fill no)
		(layer "In6.Cu")
	)
	(gr_circle
		(center 396.54988 -313.949842)
		(end 396.80388 -313.949842)
		(stroke
			(width 0.1016)
			(type default)
		)
		(fill no)
		(layer "In6.Cu")
	)
	(gr_circle
		(center 396.54988 -312.999882)
		(end 396.80388 -312.999882)
		(stroke
			(width 0.1016)
			(type default)
		)
		(fill no)
		(layer "In6.Cu")
	)
	(gr_circle
		(center 396.54988 -278.799798)
		(end 396.80388 -278.799798)
		(stroke
			(width 0.1016)
			(type default)
		)
		(fill no)
		(layer "In6.Cu")
	)
	(gr_circle
		(center 396.54988 -277.849838)
		(end 396.80388 -277.849838)
		(stroke
			(width 0.1016)
			(type default)
		)
		(fill no)
		(layer "In6.Cu")
	)
	(gr_circle
		(center 396.54988 -274.049744)
		(end 396.80388 -274.049744)
		(stroke
			(width 0.1016)
			(type default)
		)
		(fill no)
		(layer "In6.Cu")
	)
	(gr_circle
		(center 396.54988 -273.099784)
		(end 396.80388 -273.099784)
		(stroke
			(width 0.1016)
			(type default)
		)
		(fill no)
		(layer "In6.Cu")
	)
	(gr_circle
		(center 397.49984 -316.799722)
		(end 397.75384 -316.799722)
		(stroke
			(width 0.1016)
			(type default)
		)
		(fill no)
		(layer "In6.Cu")
	)
	(gr_circle
		(center 397.49984 -315.849762)
		(end 397.75384 -315.849762)
		(stroke
			(width 0.1016)
			(type default)
		)
		(fill no)
		(layer "In6.Cu")
	)
	(gr_circle
		(center 397.49984 -312.049922)
		(end 397.75384 -312.049922)
		(stroke
			(width 0.1016)
			(type default)
		)
		(fill no)
		(layer "In6.Cu")
	)
	(gr_circle
		(center 397.49984 -311.099962)
		(end 397.75384 -311.099962)
		(stroke
			(width 0.1016)
			(type default)
		)
		(fill no)
		(layer "In6.Cu")
	)
	(gr_circle
		(center 397.49984 -280.699464)
		(end 397.75384 -280.699464)
		(stroke
			(width 0.1016)
			(type default)
		)
		(fill no)
		(layer "In6.Cu")
	)
	(gr_circle
		(center 397.49984 -279.749504)
		(end 397.75384 -279.749504)
		(stroke
			(width 0.1016)
			(type default)
		)
		(fill no)
		(layer "In6.Cu")
	)
	(gr_circle
		(center 397.49984 -275.949918)
		(end 397.75384 -275.949918)
		(stroke
			(width 0.1016)
			(type default)
		)
		(fill no)
		(layer "In6.Cu")
	)
	(gr_circle
		(center 397.49984 -274.999958)
		(end 397.75384 -274.999958)
		(stroke
			(width 0.1016)
			(type default)
		)
		(fill no)
		(layer "In6.Cu")
	)
	(gr_circle
		(center 398.4498 -318.699896)
		(end 398.7038 -318.699896)
		(stroke
			(width 0.1016)
			(type default)
		)
		(fill no)
		(layer "In6.Cu")
	)
	(gr_circle
		(center 398.4498 -317.749936)
		(end 398.7038 -317.749936)
		(stroke
			(width 0.1016)
			(type default)
		)
		(fill no)
		(layer "In6.Cu")
	)
	(gr_circle
		(center 398.4498 -313.949842)
		(end 398.7038 -313.949842)
		(stroke
			(width 0.1016)
			(type default)
		)
		(fill no)
		(layer "In6.Cu")
	)
	(gr_circle
		(center 398.4498 -312.999882)
		(end 398.7038 -312.999882)
		(stroke
			(width 0.1016)
			(type default)
		)
		(fill no)
		(layer "In6.Cu")
	)
	(gr_circle
		(center 398.4498 -278.799798)
		(end 398.7038 -278.799798)
		(stroke
			(width 0.1016)
			(type default)
		)
		(fill no)
		(layer "In6.Cu")
	)
	(gr_circle
		(center 398.4498 -277.849838)
		(end 398.7038 -277.849838)
		(stroke
			(width 0.1016)
			(type default)
		)
		(fill no)
		(layer "In6.Cu")
	)
	(gr_circle
		(center 398.4498 -274.049744)
		(end 398.7038 -274.049744)
		(stroke
			(width 0.1016)
			(type default)
		)
		(fill no)
		(layer "In6.Cu")
	)
	(gr_circle
		(center 398.4498 -273.099784)
		(end 398.7038 -273.099784)
		(stroke
			(width 0.1016)
			(type default)
		)
		(fill no)
		(layer "In6.Cu")
	)
	(gr_circle
		(center 399.400014 -312.049922)
		(end 399.654014 -312.049922)
		(stroke
			(width 0.1016)
			(type default)
		)
		(fill no)
		(layer "In6.Cu")
	)
	(gr_circle
		(center 399.400014 -311.099962)
		(end 399.654014 -311.099962)
		(stroke
			(width 0.1016)
			(type default)
		)
		(fill no)
		(layer "In6.Cu")
	)
	(gr_circle
		(center 399.400014 -280.699464)
		(end 399.654014 -280.699464)
		(stroke
			(width 0.1016)
			(type default)
		)
		(fill no)
		(layer "In6.Cu")
	)
	(gr_circle
		(center 399.400014 -279.749504)
		(end 399.654014 -279.749504)
		(stroke
			(width 0.1016)
			(type default)
		)
		(fill no)
		(layer "In6.Cu")
	)
	(gr_circle
		(center 399.400014 -275.949918)
		(end 399.654014 -275.949918)
		(stroke
			(width 0.1016)
			(type default)
		)
		(fill no)
		(layer "In6.Cu")
	)
	(gr_circle
		(center 399.400014 -274.999958)
		(end 399.654014 -274.999958)
		(stroke
			(width 0.1016)
			(type default)
		)
		(fill no)
		(layer "In6.Cu")
	)
	(gr_circle
		(center 400.349974 -313.949842)
		(end 400.603974 -313.949842)
		(stroke
			(width 0.1016)
			(type default)
		)
		(fill no)
		(layer "In6.Cu")
	)
	(gr_circle
		(center 400.349974 -312.999882)
		(end 400.603974 -312.999882)
		(stroke
			(width 0.1016)
			(type default)
		)
		(fill no)
		(layer "In6.Cu")
	)
	(gr_circle
		(center 400.349974 -278.799798)
		(end 400.603974 -278.799798)
		(stroke
			(width 0.1016)
			(type default)
		)
		(fill no)
		(layer "In6.Cu")
	)
	(gr_circle
		(center 400.349974 -277.849838)
		(end 400.603974 -277.849838)
		(stroke
			(width 0.1016)
			(type default)
		)
		(fill no)
		(layer "In6.Cu")
	)
	(gr_circle
		(center 400.349974 -274.049744)
		(end 400.603974 -274.049744)
		(stroke
			(width 0.1016)
			(type default)
		)
		(fill no)
		(layer "In6.Cu")
	)
	(gr_circle
		(center 400.349974 -273.099784)
		(end 400.603974 -273.099784)
		(stroke
			(width 0.1016)
			(type default)
		)
		(fill no)
		(layer "In6.Cu")
	)
	(gr_circle
		(center 401.299934 -312.049922)
		(end 401.553934 -312.049922)
		(stroke
			(width 0.1016)
			(type default)
		)
		(fill no)
		(layer "In6.Cu")
	)
	(gr_circle
		(center 401.299934 -311.099962)
		(end 401.553934 -311.099962)
		(stroke
			(width 0.1016)
			(type default)
		)
		(fill no)
		(layer "In6.Cu")
	)
	(gr_circle
		(center 401.299934 -280.699464)
		(end 401.553934 -280.699464)
		(stroke
			(width 0.1016)
			(type default)
		)
		(fill no)
		(layer "In6.Cu")
	)
	(gr_circle
		(center 401.299934 -279.749504)
		(end 401.553934 -279.749504)
		(stroke
			(width 0.1016)
			(type default)
		)
		(fill no)
		(layer "In6.Cu")
	)
	(gr_circle
		(center 401.299934 -275.949918)
		(end 401.553934 -275.949918)
		(stroke
			(width 0.1016)
			(type default)
		)
		(fill no)
		(layer "In6.Cu")
	)
	(gr_circle
		(center 401.299934 -274.999958)
		(end 401.553934 -274.999958)
		(stroke
			(width 0.1016)
			(type default)
		)
		(fill no)
		(layer "In6.Cu")
	)
	(gr_circle
		(center 402.249894 -313.949842)
		(end 402.503894 -313.949842)
		(stroke
			(width 0.1016)
			(type default)
		)
		(fill no)
		(layer "In6.Cu")
	)
	(gr_circle
		(center 402.249894 -312.999882)
		(end 402.503894 -312.999882)
		(stroke
			(width 0.1016)
			(type default)
		)
		(fill no)
		(layer "In6.Cu")
	)
	(gr_circle
		(center 402.249894 -278.799798)
		(end 402.503894 -278.799798)
		(stroke
			(width 0.1016)
			(type default)
		)
		(fill no)
		(layer "In6.Cu")
	)
	(gr_circle
		(center 402.249894 -277.849838)
		(end 402.503894 -277.849838)
		(stroke
			(width 0.1016)
			(type default)
		)
		(fill no)
		(layer "In6.Cu")
	)
	(gr_circle
		(center 402.249894 -274.049744)
		(end 402.503894 -274.049744)
		(stroke
			(width 0.1016)
			(type default)
		)
		(fill no)
		(layer "In6.Cu")
	)
	(gr_circle
		(center 402.249894 -273.099784)
		(end 402.503894 -273.099784)
		(stroke
			(width 0.1016)
			(type default)
		)
		(fill no)
		(layer "In6.Cu")
	)
	(gr_circle
		(center 403.199854 -312.049922)
		(end 403.453854 -312.049922)
		(stroke
			(width 0.1016)
			(type default)
		)
		(fill no)
		(layer "In6.Cu")
	)
	(gr_circle
		(center 403.199854 -311.099962)
		(end 403.453854 -311.099962)
		(stroke
			(width 0.1016)
			(type default)
		)
		(fill no)
		(layer "In6.Cu")
	)
	(gr_circle
		(center 403.199854 -280.699464)
		(end 403.453854 -280.699464)
		(stroke
			(width 0.1016)
			(type default)
		)
		(fill no)
		(layer "In6.Cu")
	)
	(gr_circle
		(center 403.199854 -279.749504)
		(end 403.453854 -279.749504)
		(stroke
			(width 0.1016)
			(type default)
		)
		(fill no)
		(layer "In6.Cu")
	)
	(gr_circle
		(center 403.199854 -275.949918)
		(end 403.453854 -275.949918)
		(stroke
			(width 0.1016)
			(type default)
		)
		(fill no)
		(layer "In6.Cu")
	)
	(gr_circle
		(center 403.199854 -274.999958)
		(end 403.453854 -274.999958)
		(stroke
			(width 0.1016)
			(type default)
		)
		(fill no)
		(layer "In6.Cu")
	)
	(gr_circle
		(center 404.149814 -313.949842)
		(end 404.403814 -313.949842)
		(stroke
			(width 0.1016)
			(type default)
		)
		(fill no)
		(layer "In6.Cu")
	)
	(gr_circle
		(center 404.149814 -312.999882)
		(end 404.403814 -312.999882)
		(stroke
			(width 0.1016)
			(type default)
		)
		(fill no)
		(layer "In6.Cu")
	)
	(gr_circle
		(center 404.149814 -278.799798)
		(end 404.403814 -278.799798)
		(stroke
			(width 0.1016)
			(type default)
		)
		(fill no)
		(layer "In6.Cu")
	)
	(gr_circle
		(center 404.149814 -277.849838)
		(end 404.403814 -277.849838)
		(stroke
			(width 0.1016)
			(type default)
		)
		(fill no)
		(layer "In6.Cu")
	)
	(gr_circle
		(center 404.149814 -274.049744)
		(end 404.403814 -274.049744)
		(stroke
			(width 0.1016)
			(type default)
		)
		(fill no)
		(layer "In6.Cu")
	)
	(gr_circle
		(center 404.149814 -273.099784)
		(end 404.403814 -273.099784)
		(stroke
			(width 0.1016)
			(type default)
		)
		(fill no)
		(layer "In6.Cu")
	)
	(gr_circle
		(center 405.099774 -280.699464)
		(end 405.353774 -280.699464)
		(stroke
			(width 0.1016)
			(type default)
		)
		(fill no)
		(layer "In6.Cu")
	)
	(gr_circle
		(center 405.099774 -279.749504)
		(end 405.353774 -279.749504)
		(stroke
			(width 0.1016)
			(type default)
		)
		(fill no)
		(layer "In6.Cu")
	)
	(gr_circle
		(center 405.100028 -312.049922)
		(end 405.354028 -312.049922)
		(stroke
			(width 0.1016)
			(type default)
		)
		(fill no)
		(layer "In6.Cu")
	)
	(gr_circle
		(center 405.100028 -311.099962)
		(end 405.354028 -311.099962)
		(stroke
			(width 0.1016)
			(type default)
		)
		(fill no)
		(layer "In6.Cu")
	)
	(gr_circle
		(center 405.100028 -275.949918)
		(end 405.354028 -275.949918)
		(stroke
			(width 0.1016)
			(type default)
		)
		(fill no)
		(layer "In6.Cu")
	)
	(gr_circle
		(center 405.100028 -274.999958)
		(end 405.354028 -274.999958)
		(stroke
			(width 0.1016)
			(type default)
		)
		(fill no)
		(layer "In6.Cu")
	)
	(gr_circle
		(center 406.049988 -313.949842)
		(end 406.303988 -313.949842)
		(stroke
			(width 0.1016)
			(type default)
		)
		(fill no)
		(layer "In6.Cu")
	)
	(gr_circle
		(center 406.049988 -312.999882)
		(end 406.303988 -312.999882)
		(stroke
			(width 0.1016)
			(type default)
		)
		(fill no)
		(layer "In6.Cu")
	)
	(gr_circle
		(center 406.049988 -278.799798)
		(end 406.303988 -278.799798)
		(stroke
			(width 0.1016)
			(type default)
		)
		(fill no)
		(layer "In6.Cu")
	)
	(gr_circle
		(center 406.049988 -277.849838)
		(end 406.303988 -277.849838)
		(stroke
			(width 0.1016)
			(type default)
		)
		(fill no)
		(layer "In6.Cu")
	)
	(gr_circle
		(center 406.049988 -274.049744)
		(end 406.303988 -274.049744)
		(stroke
			(width 0.1016)
			(type default)
		)
		(fill no)
		(layer "In6.Cu")
	)
	(gr_circle
		(center 406.049988 -273.099784)
		(end 406.303988 -273.099784)
		(stroke
			(width 0.1016)
			(type default)
		)
		(fill no)
		(layer "In6.Cu")
	)
	(gr_circle
		(center 406.999948 -312.049922)
		(end 407.253948 -312.049922)
		(stroke
			(width 0.1016)
			(type default)
		)
		(fill no)
		(layer "In6.Cu")
	)
	(gr_circle
		(center 406.999948 -311.099962)
		(end 407.253948 -311.099962)
		(stroke
			(width 0.1016)
			(type default)
		)
		(fill no)
		(layer "In6.Cu")
	)
	(gr_circle
		(center 406.999948 -280.699464)
		(end 407.253948 -280.699464)
		(stroke
			(width 0.1016)
			(type default)
		)
		(fill no)
		(layer "In6.Cu")
	)
	(gr_circle
		(center 406.999948 -279.749504)
		(end 407.253948 -279.749504)
		(stroke
			(width 0.1016)
			(type default)
		)
		(fill no)
		(layer "In6.Cu")
	)
	(gr_circle
		(center 406.999948 -275.949918)
		(end 407.253948 -275.949918)
		(stroke
			(width 0.1016)
			(type default)
		)
		(fill no)
		(layer "In6.Cu")
	)
	(gr_circle
		(center 406.999948 -274.999958)
		(end 407.253948 -274.999958)
		(stroke
			(width 0.1016)
			(type default)
		)
		(fill no)
		(layer "In6.Cu")
	)
	(gr_circle
		(center 407.949654 -278.799798)
		(end 408.203654 -278.799798)
		(stroke
			(width 0.1016)
			(type default)
		)
		(fill no)
		(layer "In6.Cu")
	)
	(gr_circle
		(center 407.949654 -277.849838)
		(end 408.203654 -277.849838)
		(stroke
			(width 0.1016)
			(type default)
		)
		(fill no)
		(layer "In6.Cu")
	)
	(gr_circle
		(center 407.949908 -313.949842)
		(end 408.203908 -313.949842)
		(stroke
			(width 0.1016)
			(type default)
		)
		(fill no)
		(layer "In6.Cu")
	)
	(gr_circle
		(center 407.949908 -312.999882)
		(end 408.203908 -312.999882)
		(stroke
			(width 0.1016)
			(type default)
		)
		(fill no)
		(layer "In6.Cu")
	)
	(gr_circle
		(center 408.899868 -312.049922)
		(end 409.153868 -312.049922)
		(stroke
			(width 0.1016)
			(type default)
		)
		(fill no)
		(layer "In6.Cu")
	)
	(gr_circle
		(center 408.899868 -311.099962)
		(end 409.153868 -311.099962)
		(stroke
			(width 0.1016)
			(type default)
		)
		(fill no)
		(layer "In6.Cu")
	)
	(gr_circle
		(center 408.899868 -280.699464)
		(end 409.153868 -280.699464)
		(stroke
			(width 0.1016)
			(type default)
		)
		(fill no)
		(layer "In6.Cu")
	)
	(gr_circle
		(center 408.899868 -279.749504)
		(end 409.153868 -279.749504)
		(stroke
			(width 0.1016)
			(type default)
		)
		(fill no)
		(layer "In6.Cu")
	)
	(gr_circle
		(center 409.849574 -278.799798)
		(end 410.103574 -278.799798)
		(stroke
			(width 0.1016)
			(type default)
		)
		(fill no)
		(layer "In6.Cu")
	)
	(gr_circle
		(center 409.849574 -277.849838)
		(end 410.103574 -277.849838)
		(stroke
			(width 0.1016)
			(type default)
		)
		(fill no)
		(layer "In6.Cu")
	)
	(gr_circle
		(center 409.849828 -313.949842)
		(end 410.103828 -313.949842)
		(stroke
			(width 0.1016)
			(type default)
		)
		(fill no)
		(layer "In6.Cu")
	)
	(gr_circle
		(center 409.849828 -312.999882)
		(end 410.103828 -312.999882)
		(stroke
			(width 0.1016)
			(type default)
		)
		(fill no)
		(layer "In6.Cu")
	)
	(gr_circle
		(center 410.799788 -312.049922)
		(end 411.053788 -312.049922)
		(stroke
			(width 0.1016)
			(type default)
		)
		(fill no)
		(layer "In6.Cu")
	)
	(gr_circle
		(center 410.799788 -311.099962)
		(end 411.053788 -311.099962)
		(stroke
			(width 0.1016)
			(type default)
		)
		(fill no)
		(layer "In6.Cu")
	)
	(gr_circle
		(center 410.799788 -280.699464)
		(end 411.053788 -280.699464)
		(stroke
			(width 0.1016)
			(type default)
		)
		(fill no)
		(layer "In6.Cu")
	)
	(gr_circle
		(center 410.799788 -279.749504)
		(end 411.053788 -279.749504)
		(stroke
			(width 0.1016)
			(type default)
		)
		(fill no)
		(layer "In6.Cu")
	)
	(gr_circle
		(center 411.749748 -278.799798)
		(end 412.003748 -278.799798)
		(stroke
			(width 0.1016)
			(type default)
		)
		(fill no)
		(layer "In6.Cu")
	)
	(gr_circle
		(center 411.749748 -277.849838)
		(end 412.003748 -277.849838)
		(stroke
			(width 0.1016)
			(type default)
		)
		(fill no)
		(layer "In6.Cu")
	)
	(gr_circle
		(center 411.750002 -313.949842)
		(end 412.004002 -313.949842)
		(stroke
			(width 0.1016)
			(type default)
		)
		(fill no)
		(layer "In6.Cu")
	)
	(gr_circle
		(center 411.750002 -312.999882)
		(end 412.004002 -312.999882)
		(stroke
			(width 0.1016)
			(type default)
		)
		(fill no)
		(layer "In6.Cu")
	)
	(gr_circle
		(center 412.699962 -312.049922)
		(end 412.953962 -312.049922)
		(stroke
			(width 0.1016)
			(type default)
		)
		(fill no)
		(layer "In6.Cu")
	)
	(gr_circle
		(center 412.699962 -311.099962)
		(end 412.953962 -311.099962)
		(stroke
			(width 0.1016)
			(type default)
		)
		(fill no)
		(layer "In6.Cu")
	)
	(gr_circle
		(center 412.699962 -280.699464)
		(end 412.953962 -280.699464)
		(stroke
			(width 0.1016)
			(type default)
		)
		(fill no)
		(layer "In6.Cu")
	)
	(gr_circle
		(center 412.699962 -279.749504)
		(end 412.953962 -279.749504)
		(stroke
			(width 0.1016)
			(type default)
		)
		(fill no)
		(layer "In6.Cu")
	)
	(gr_circle
		(center 413.649668 -278.799798)
		(end 413.903668 -278.799798)
		(stroke
			(width 0.1016)
			(type default)
		)
		(fill no)
		(layer "In6.Cu")
	)
	(gr_circle
		(center 413.649668 -277.849838)
		(end 413.903668 -277.849838)
		(stroke
			(width 0.1016)
			(type default)
		)
		(fill no)
		(layer "In6.Cu")
	)
	(gr_circle
		(center 413.649922 -313.949842)
		(end 413.903922 -313.949842)
		(stroke
			(width 0.1016)
			(type default)
		)
		(fill no)
		(layer "In6.Cu")
	)
	(gr_circle
		(center 413.649922 -312.999882)
		(end 413.903922 -312.999882)
		(stroke
			(width 0.1016)
			(type default)
		)
		(fill no)
		(layer "In6.Cu")
	)
	(gr_circle
		(center 414.599882 -316.799722)
		(end 414.853882 -316.799722)
		(stroke
			(width 0.1016)
			(type default)
		)
		(fill no)
		(layer "In6.Cu")
	)
	(gr_circle
		(center 414.599882 -315.849762)
		(end 414.853882 -315.849762)
		(stroke
			(width 0.1016)
			(type default)
		)
		(fill no)
		(layer "In6.Cu")
	)
	(gr_circle
		(center 414.599882 -312.049922)
		(end 414.853882 -312.049922)
		(stroke
			(width 0.1016)
			(type default)
		)
		(fill no)
		(layer "In6.Cu")
	)
	(gr_circle
		(center 414.599882 -311.099962)
		(end 414.853882 -311.099962)
		(stroke
			(width 0.1016)
			(type default)
		)
		(fill no)
		(layer "In6.Cu")
	)
	(gr_circle
		(center 414.599882 -280.699464)
		(end 414.853882 -280.699464)
		(stroke
			(width 0.1016)
			(type default)
		)
		(fill no)
		(layer "In6.Cu")
	)
	(gr_circle
		(center 414.599882 -279.749504)
		(end 414.853882 -279.749504)
		(stroke
			(width 0.1016)
			(type default)
		)
		(fill no)
		(layer "In6.Cu")
	)
	(gr_circle
		(center 415.549588 -278.799798)
		(end 415.803588 -278.799798)
		(stroke
			(width 0.1016)
			(type default)
		)
		(fill no)
		(layer "In6.Cu")
	)
	(gr_circle
		(center 415.549588 -277.849838)
		(end 415.803588 -277.849838)
		(stroke
			(width 0.1016)
			(type default)
		)
		(fill no)
		(layer "In6.Cu")
	)
	(gr_circle
		(center 415.549842 -318.699896)
		(end 415.803842 -318.699896)
		(stroke
			(width 0.1016)
			(type default)
		)
		(fill no)
		(layer "In6.Cu")
	)
	(gr_circle
		(center 415.549842 -317.749936)
		(end 415.803842 -317.749936)
		(stroke
			(width 0.1016)
			(type default)
		)
		(fill no)
		(layer "In6.Cu")
	)
	(gr_circle
		(center 415.549842 -313.949842)
		(end 415.803842 -313.949842)
		(stroke
			(width 0.1016)
			(type default)
		)
		(fill no)
		(layer "In6.Cu")
	)
	(gr_circle
		(center 415.549842 -312.999882)
		(end 415.803842 -312.999882)
		(stroke
			(width 0.1016)
			(type default)
		)
		(fill no)
		(layer "In6.Cu")
	)
	(gr_circle
		(center 416.499802 -316.799722)
		(end 416.753802 -316.799722)
		(stroke
			(width 0.1016)
			(type default)
		)
		(fill no)
		(layer "In6.Cu")
	)
	(gr_circle
		(center 416.499802 -315.849762)
		(end 416.753802 -315.849762)
		(stroke
			(width 0.1016)
			(type default)
		)
		(fill no)
		(layer "In6.Cu")
	)
	(gr_circle
		(center 416.499802 -312.049922)
		(end 416.753802 -312.049922)
		(stroke
			(width 0.1016)
			(type default)
		)
		(fill no)
		(layer "In6.Cu")
	)
	(gr_circle
		(center 416.499802 -311.099962)
		(end 416.753802 -311.099962)
		(stroke
			(width 0.1016)
			(type default)
		)
		(fill no)
		(layer "In6.Cu")
	)
	(gr_circle
		(center 416.499802 -280.699464)
		(end 416.753802 -280.699464)
		(stroke
			(width 0.1016)
			(type default)
		)
		(fill no)
		(layer "In6.Cu")
	)
	(gr_circle
		(center 416.499802 -279.749504)
		(end 416.753802 -279.749504)
		(stroke
			(width 0.1016)
			(type default)
		)
		(fill no)
		(layer "In6.Cu")
	)
	(gr_circle
		(center 417.449762 -278.799798)
		(end 417.703762 -278.799798)
		(stroke
			(width 0.1016)
			(type default)
		)
		(fill no)
		(layer "In6.Cu")
	)
	(gr_circle
		(center 417.449762 -277.849838)
		(end 417.703762 -277.849838)
		(stroke
			(width 0.1016)
			(type default)
		)
		(fill no)
		(layer "In6.Cu")
	)
	(gr_circle
		(center 417.450016 -318.699896)
		(end 417.704016 -318.699896)
		(stroke
			(width 0.1016)
			(type default)
		)
		(fill no)
		(layer "In6.Cu")
	)
	(gr_circle
		(center 417.450016 -317.749936)
		(end 417.704016 -317.749936)
		(stroke
			(width 0.1016)
			(type default)
		)
		(fill no)
		(layer "In6.Cu")
	)
	(gr_circle
		(center 417.450016 -313.949842)
		(end 417.704016 -313.949842)
		(stroke
			(width 0.1016)
			(type default)
		)
		(fill no)
		(layer "In6.Cu")
	)
	(gr_circle
		(center 417.450016 -312.999882)
		(end 417.704016 -312.999882)
		(stroke
			(width 0.1016)
			(type default)
		)
		(fill no)
		(layer "In6.Cu")
	)
	(gr_circle
		(center 418.399976 -316.799722)
		(end 418.653976 -316.799722)
		(stroke
			(width 0.1016)
			(type default)
		)
		(fill no)
		(layer "In6.Cu")
	)
	(gr_circle
		(center 418.399976 -315.849762)
		(end 418.653976 -315.849762)
		(stroke
			(width 0.1016)
			(type default)
		)
		(fill no)
		(layer "In6.Cu")
	)
	(gr_circle
		(center 418.399976 -312.049922)
		(end 418.653976 -312.049922)
		(stroke
			(width 0.1016)
			(type default)
		)
		(fill no)
		(layer "In6.Cu")
	)
	(gr_circle
		(center 418.399976 -311.099962)
		(end 418.653976 -311.099962)
		(stroke
			(width 0.1016)
			(type default)
		)
		(fill no)
		(layer "In6.Cu")
	)
	(gr_circle
		(center 418.399976 -280.699464)
		(end 418.653976 -280.699464)
		(stroke
			(width 0.1016)
			(type default)
		)
		(fill no)
		(layer "In6.Cu")
	)
	(gr_circle
		(center 418.399976 -279.749504)
		(end 418.653976 -279.749504)
		(stroke
			(width 0.1016)
			(type default)
		)
		(fill no)
		(layer "In6.Cu")
	)
	(gr_circle
		(center 419.349682 -278.799798)
		(end 419.603682 -278.799798)
		(stroke
			(width 0.1016)
			(type default)
		)
		(fill no)
		(layer "In6.Cu")
	)
	(gr_circle
		(center 419.349682 -277.849838)
		(end 419.603682 -277.849838)
		(stroke
			(width 0.1016)
			(type default)
		)
		(fill no)
		(layer "In6.Cu")
	)
	(gr_circle
		(center 419.349936 -318.699896)
		(end 419.603936 -318.699896)
		(stroke
			(width 0.1016)
			(type default)
		)
		(fill no)
		(layer "In6.Cu")
	)
	(gr_circle
		(center 419.349936 -317.749936)
		(end 419.603936 -317.749936)
		(stroke
			(width 0.1016)
			(type default)
		)
		(fill no)
		(layer "In6.Cu")
	)
	(gr_circle
		(center 419.349936 -313.949842)
		(end 419.603936 -313.949842)
		(stroke
			(width 0.1016)
			(type default)
		)
		(fill no)
		(layer "In6.Cu")
	)
	(gr_circle
		(center 419.349936 -312.999882)
		(end 419.603936 -312.999882)
		(stroke
			(width 0.1016)
			(type default)
		)
		(fill no)
		(layer "In6.Cu")
	)
	(gr_circle
		(center 420.299896 -316.799722)
		(end 420.553896 -316.799722)
		(stroke
			(width 0.1016)
			(type default)
		)
		(fill no)
		(layer "In6.Cu")
	)
	(gr_circle
		(center 420.299896 -315.849762)
		(end 420.553896 -315.849762)
		(stroke
			(width 0.1016)
			(type default)
		)
		(fill no)
		(layer "In6.Cu")
	)
	(gr_circle
		(center 420.299896 -312.049922)
		(end 420.553896 -312.049922)
		(stroke
			(width 0.1016)
			(type default)
		)
		(fill no)
		(layer "In6.Cu")
	)
	(gr_circle
		(center 420.299896 -311.099962)
		(end 420.553896 -311.099962)
		(stroke
			(width 0.1016)
			(type default)
		)
		(fill no)
		(layer "In6.Cu")
	)
	(gr_circle
		(center 420.299896 -280.699464)
		(end 420.553896 -280.699464)
		(stroke
			(width 0.1016)
			(type default)
		)
		(fill no)
		(layer "In6.Cu")
	)
	(gr_circle
		(center 420.299896 -279.749504)
		(end 420.553896 -279.749504)
		(stroke
			(width 0.1016)
			(type default)
		)
		(fill no)
		(layer "In6.Cu")
	)
	(gr_circle
		(center 421.249602 -278.799798)
		(end 421.503602 -278.799798)
		(stroke
			(width 0.1016)
			(type default)
		)
		(fill no)
		(layer "In6.Cu")
	)
	(gr_circle
		(center 421.249602 -277.849838)
		(end 421.503602 -277.849838)
		(stroke
			(width 0.1016)
			(type default)
		)
		(fill no)
		(layer "In6.Cu")
	)
	(gr_circle
		(center 421.249856 -318.699896)
		(end 421.503856 -318.699896)
		(stroke
			(width 0.1016)
			(type default)
		)
		(fill no)
		(layer "In6.Cu")
	)
	(gr_circle
		(center 421.249856 -317.749936)
		(end 421.503856 -317.749936)
		(stroke
			(width 0.1016)
			(type default)
		)
		(fill no)
		(layer "In6.Cu")
	)
	(gr_circle
		(center 421.249856 -313.949842)
		(end 421.503856 -313.949842)
		(stroke
			(width 0.1016)
			(type default)
		)
		(fill no)
		(layer "In6.Cu")
	)
	(gr_circle
		(center 421.249856 -312.999882)
		(end 421.503856 -312.999882)
		(stroke
			(width 0.1016)
			(type default)
		)
		(fill no)
		(layer "In6.Cu")
	)
	(gr_circle
		(center 422.199816 -312.049922)
		(end 422.453816 -312.049922)
		(stroke
			(width 0.1016)
			(type default)
		)
		(fill no)
		(layer "In6.Cu")
	)
	(gr_circle
		(center 422.199816 -311.099962)
		(end 422.453816 -311.099962)
		(stroke
			(width 0.1016)
			(type default)
		)
		(fill no)
		(layer "In6.Cu")
	)
	(gr_circle
		(center 422.199816 -280.699464)
		(end 422.453816 -280.699464)
		(stroke
			(width 0.1016)
			(type default)
		)
		(fill no)
		(layer "In6.Cu")
	)
	(gr_circle
		(center 422.199816 -279.749504)
		(end 422.453816 -279.749504)
		(stroke
			(width 0.1016)
			(type default)
		)
		(fill no)
		(layer "In6.Cu")
	)
	(gr_circle
		(center 423.149776 -278.799798)
		(end 423.403776 -278.799798)
		(stroke
			(width 0.1016)
			(type default)
		)
		(fill no)
		(layer "In6.Cu")
	)
	(gr_circle
		(center 423.149776 -277.849838)
		(end 423.403776 -277.849838)
		(stroke
			(width 0.1016)
			(type default)
		)
		(fill no)
		(layer "In6.Cu")
	)
	(gr_circle
		(center 423.15003 -313.949842)
		(end 423.40403 -313.949842)
		(stroke
			(width 0.1016)
			(type default)
		)
		(fill no)
		(layer "In6.Cu")
	)
	(gr_circle
		(center 423.15003 -312.999882)
		(end 423.40403 -312.999882)
		(stroke
			(width 0.1016)
			(type default)
		)
		(fill no)
		(layer "In6.Cu")
	)
	(gr_circle
		(center 423.15003 -308.249828)
		(end 423.40403 -308.249828)
		(stroke
			(width 0.1016)
			(type default)
		)
		(fill no)
		(layer "In6.Cu")
	)
	(gr_circle
		(center 423.15003 -306.349908)
		(end 423.40403 -306.349908)
		(stroke
			(width 0.1016)
			(type default)
		)
		(fill no)
		(layer "In6.Cu")
	)
	(gr_circle
		(center 423.15003 -304.449734)
		(end 423.40403 -304.449734)
		(stroke
			(width 0.1016)
			(type default)
		)
		(fill no)
		(layer "In6.Cu")
	)
	(gr_circle
		(center 423.15003 -287.349946)
		(end 423.40403 -287.349946)
		(stroke
			(width 0.1016)
			(type default)
		)
		(fill no)
		(layer "In6.Cu")
	)
	(gr_circle
		(center 423.15003 -285.449772)
		(end 423.40403 -285.449772)
		(stroke
			(width 0.1016)
			(type default)
		)
		(fill no)
		(layer "In6.Cu")
	)
	(gr_circle
		(center 423.15003 -283.549852)
		(end 423.40403 -283.549852)
		(stroke
			(width 0.1016)
			(type default)
		)
		(fill no)
		(layer "In6.Cu")
	)
	(gr_circle
		(center 424.09999 -312.049922)
		(end 424.35399 -312.049922)
		(stroke
			(width 0.1016)
			(type default)
		)
		(fill no)
		(layer "In6.Cu")
	)
	(gr_circle
		(center 424.09999 -311.099962)
		(end 424.35399 -311.099962)
		(stroke
			(width 0.1016)
			(type default)
		)
		(fill no)
		(layer "In6.Cu")
	)
	(gr_circle
		(center 424.09999 -308.249828)
		(end 424.35399 -308.249828)
		(stroke
			(width 0.1016)
			(type default)
		)
		(fill no)
		(layer "In6.Cu")
	)
	(gr_circle
		(center 424.09999 -306.349908)
		(end 424.35399 -306.349908)
		(stroke
			(width 0.1016)
			(type default)
		)
		(fill no)
		(layer "In6.Cu")
	)
	(gr_circle
		(center 424.09999 -304.449734)
		(end 424.35399 -304.449734)
		(stroke
			(width 0.1016)
			(type default)
		)
		(fill no)
		(layer "In6.Cu")
	)
	(gr_circle
		(center 424.09999 -287.349946)
		(end 424.35399 -287.349946)
		(stroke
			(width 0.1016)
			(type default)
		)
		(fill no)
		(layer "In6.Cu")
	)
	(gr_circle
		(center 424.09999 -285.449772)
		(end 424.35399 -285.449772)
		(stroke
			(width 0.1016)
			(type default)
		)
		(fill no)
		(layer "In6.Cu")
	)
	(gr_circle
		(center 424.09999 -283.549852)
		(end 424.35399 -283.549852)
		(stroke
			(width 0.1016)
			(type default)
		)
		(fill no)
		(layer "In6.Cu")
	)
	(gr_circle
		(center 424.09999 -280.699464)
		(end 424.35399 -280.699464)
		(stroke
			(width 0.1016)
			(type default)
		)
		(fill no)
		(layer "In6.Cu")
	)
	(gr_circle
		(center 424.09999 -279.749504)
		(end 424.35399 -279.749504)
		(stroke
			(width 0.1016)
			(type default)
		)
		(fill no)
		(layer "In6.Cu")
	)
	(gr_circle
		(center 425.049696 -278.799798)
		(end 425.303696 -278.799798)
		(stroke
			(width 0.1016)
			(type default)
		)
		(fill no)
		(layer "In6.Cu")
	)
	(gr_circle
		(center 425.049696 -277.849838)
		(end 425.303696 -277.849838)
		(stroke
			(width 0.1016)
			(type default)
		)
		(fill no)
		(layer "In6.Cu")
	)
	(gr_circle
		(center 425.04995 -313.949842)
		(end 425.30395 -313.949842)
		(stroke
			(width 0.1016)
			(type default)
		)
		(fill no)
		(layer "In6.Cu")
	)
	(gr_circle
		(center 425.04995 -312.999882)
		(end 425.30395 -312.999882)
		(stroke
			(width 0.1016)
			(type default)
		)
		(fill no)
		(layer "In6.Cu")
	)
	(gr_circle
		(center 425.04995 -309.199788)
		(end 425.30395 -309.199788)
		(stroke
			(width 0.1016)
			(type default)
		)
		(fill no)
		(layer "In6.Cu")
	)
	(gr_circle
		(center 425.04995 -307.299868)
		(end 425.30395 -307.299868)
		(stroke
			(width 0.1016)
			(type default)
		)
		(fill no)
		(layer "In6.Cu")
	)
	(gr_circle
		(center 425.04995 -305.399948)
		(end 425.30395 -305.399948)
		(stroke
			(width 0.1016)
			(type default)
		)
		(fill no)
		(layer "In6.Cu")
	)
	(gr_circle
		(center 425.04995 -288.299906)
		(end 425.30395 -288.299906)
		(stroke
			(width 0.1016)
			(type default)
		)
		(fill no)
		(layer "In6.Cu")
	)
	(gr_circle
		(center 425.04995 -286.399986)
		(end 425.30395 -286.399986)
		(stroke
			(width 0.1016)
			(type default)
		)
		(fill no)
		(layer "In6.Cu")
	)
	(gr_circle
		(center 425.04995 -284.499812)
		(end 425.30395 -284.499812)
		(stroke
			(width 0.1016)
			(type default)
		)
		(fill no)
		(layer "In6.Cu")
	)
	(gr_circle
		(center 425.04995 -282.599892)
		(end 425.30395 -282.599892)
		(stroke
			(width 0.1016)
			(type default)
		)
		(fill no)
		(layer "In6.Cu")
	)
	(gr_circle
		(center 425.99991 -312.049922)
		(end 426.25391 -312.049922)
		(stroke
			(width 0.1016)
			(type default)
		)
		(fill no)
		(layer "In6.Cu")
	)
	(gr_circle
		(center 425.99991 -311.099962)
		(end 426.25391 -311.099962)
		(stroke
			(width 0.1016)
			(type default)
		)
		(fill no)
		(layer "In6.Cu")
	)
	(gr_circle
		(center 425.99991 -309.199788)
		(end 426.25391 -309.199788)
		(stroke
			(width 0.1016)
			(type default)
		)
		(fill no)
		(layer "In6.Cu")
	)
	(gr_circle
		(center 425.99991 -307.299868)
		(end 426.25391 -307.299868)
		(stroke
			(width 0.1016)
			(type default)
		)
		(fill no)
		(layer "In6.Cu")
	)
	(gr_circle
		(center 425.99991 -305.399948)
		(end 426.25391 -305.399948)
		(stroke
			(width 0.1016)
			(type default)
		)
		(fill no)
		(layer "In6.Cu")
	)
	(gr_circle
		(center 425.99991 -288.299906)
		(end 426.25391 -288.299906)
		(stroke
			(width 0.1016)
			(type default)
		)
		(fill no)
		(layer "In6.Cu")
	)
	(gr_circle
		(center 425.99991 -286.399986)
		(end 426.25391 -286.399986)
		(stroke
			(width 0.1016)
			(type default)
		)
		(fill no)
		(layer "In6.Cu")
	)
	(gr_circle
		(center 425.99991 -284.499812)
		(end 426.25391 -284.499812)
		(stroke
			(width 0.1016)
			(type default)
		)
		(fill no)
		(layer "In6.Cu")
	)
	(gr_circle
		(center 425.99991 -282.599892)
		(end 426.25391 -282.599892)
		(stroke
			(width 0.1016)
			(type default)
		)
		(fill no)
		(layer "In6.Cu")
	)
	(gr_circle
		(center 425.99991 -280.699464)
		(end 426.25391 -280.699464)
		(stroke
			(width 0.1016)
			(type default)
		)
		(fill no)
		(layer "In6.Cu")
	)
	(gr_circle
		(center 425.99991 -279.749504)
		(end 426.25391 -279.749504)
		(stroke
			(width 0.1016)
			(type default)
		)
		(fill no)
		(layer "In6.Cu")
	)
	(gr_circle
		(center 426.949616 -278.799798)
		(end 427.203616 -278.799798)
		(stroke
			(width 0.1016)
			(type default)
		)
		(fill no)
		(layer "In6.Cu")
	)
	(gr_circle
		(center 426.949616 -277.849838)
		(end 427.203616 -277.849838)
		(stroke
			(width 0.1016)
			(type default)
		)
		(fill no)
		(layer "In6.Cu")
	)
	(gr_circle
		(center 426.94987 -313.949842)
		(end 427.20387 -313.949842)
		(stroke
			(width 0.1016)
			(type default)
		)
		(fill no)
		(layer "In6.Cu")
	)
	(gr_circle
		(center 426.94987 -312.999882)
		(end 427.20387 -312.999882)
		(stroke
			(width 0.1016)
			(type default)
		)
		(fill no)
		(layer "In6.Cu")
	)
	(gr_circle
		(center 427.89983 -312.049922)
		(end 428.15383 -312.049922)
		(stroke
			(width 0.1016)
			(type default)
		)
		(fill no)
		(layer "In6.Cu")
	)
	(gr_circle
		(center 427.89983 -311.099962)
		(end 428.15383 -311.099962)
		(stroke
			(width 0.1016)
			(type default)
		)
		(fill no)
		(layer "In6.Cu")
	)
	(gr_circle
		(center 427.89983 -280.699718)
		(end 428.15383 -280.699718)
		(stroke
			(width 0.1016)
			(type default)
		)
		(fill no)
		(layer "In6.Cu")
	)
	(gr_circle
		(center 427.89983 -279.749758)
		(end 428.15383 -279.749758)
		(stroke
			(width 0.1016)
			(type default)
		)
		(fill no)
		(layer "In6.Cu")
	)
	(gr_circle
		(center 428.84979 -313.949842)
		(end 429.10379 -313.949842)
		(stroke
			(width 0.1016)
			(type default)
		)
		(fill no)
		(layer "In6.Cu")
	)
	(gr_circle
		(center 428.84979 -312.999882)
		(end 429.10379 -312.999882)
		(stroke
			(width 0.1016)
			(type default)
		)
		(fill no)
		(layer "In6.Cu")
	)
	(gr_circle
		(center 428.84979 -278.799798)
		(end 429.10379 -278.799798)
		(stroke
			(width 0.1016)
			(type default)
		)
		(fill no)
		(layer "In6.Cu")
	)
	(gr_circle
		(center 428.84979 -277.849838)
		(end 429.10379 -277.849838)
		(stroke
			(width 0.1016)
			(type default)
		)
		(fill no)
		(layer "In6.Cu")
	)
	(gr_circle
		(center 429.800004 -314.899802)
		(end 430.054004 -314.899802)
		(stroke
			(width 0.1016)
			(type default)
		)
		(fill no)
		(layer "In6.Cu")
	)
	(gr_circle
		(center 429.800004 -312.049922)
		(end 430.054004 -312.049922)
		(stroke
			(width 0.1016)
			(type default)
		)
		(fill no)
		(layer "In6.Cu")
	)
	(gr_circle
		(center 429.800004 -279.749758)
		(end 430.054004 -279.749758)
		(stroke
			(width 0.1016)
			(type default)
		)
		(fill no)
		(layer "In6.Cu")
	)
	(gr_circle
		(center 429.800004 -276.899878)
		(end 430.054004 -276.899878)
		(stroke
			(width 0.1016)
			(type default)
		)
		(fill no)
		(layer "In6.Cu")
	)
	(gr_circle
		(center 430.749964 -314.899802)
		(end 431.003964 -314.899802)
		(stroke
			(width 0.1016)
			(type default)
		)
		(fill no)
		(layer "In6.Cu")
	)
	(gr_circle
		(center 430.749964 -312.049922)
		(end 431.003964 -312.049922)
		(stroke
			(width 0.1016)
			(type default)
		)
		(fill no)
		(layer "In6.Cu")
	)
	(gr_circle
		(center 430.749964 -279.749758)
		(end 431.003964 -279.749758)
		(stroke
			(width 0.1016)
			(type default)
		)
		(fill no)
		(layer "In6.Cu")
	)
	(gr_circle
		(center 430.749964 -276.899878)
		(end 431.003964 -276.899878)
		(stroke
			(width 0.1016)
			(type default)
		)
		(fill no)
		(layer "In6.Cu")
	)
	(gr_poly
		(pts
			(xy 19.570446 -210.367372) (xy 19.570446 -207.446372) (xy 19.316446 -207.192372) (xy 17.284446 -207.192372)
			(xy 17.030446 -207.446372) (xy 17.030446 -210.621372) (xy 17.157446 -210.748372) (xy 19.189446 -210.748372)
		)
		(stroke
			(width 0)
			(type solid)
		)
		(fill yes)
		(layer "In7.Cu")
		(net "P1V8_PLL0_PEX0")
	)
	(gr_poly
		(pts
			(xy 150.902162 -239.345978) (xy 150.902162 -236.424978) (xy 150.648162 -236.170978) (xy 148.616162 -236.170978)
			(xy 148.362162 -236.424978) (xy 148.362162 -239.599978) (xy 148.489162 -239.726978) (xy 150.521162 -239.726978)
		)
		(stroke
			(width 0)
			(type solid)
		)
		(fill yes)
		(layer "In7.Cu")
		(net "P1V8_PLL0_PEX1")
	)
	(gr_poly
		(pts
			(xy 459.832202 -246.42064) (xy 459.832202 -243.49964) (xy 459.578202 -243.24564) (xy 457.546202 -243.24564)
			(xy 457.292202 -243.49964) (xy 457.292202 -246.67464) (xy 457.419202 -246.80164) (xy 459.451202 -246.80164)
		)
		(stroke
			(width 0)
			(type solid)
		)
		(fill yes)
		(layer "In7.Cu")
		(net "P1V8_PLL0_PEX3")
	)
	(gr_poly
		(pts
			(arc
				(start 233.09834 -279.883108)
				(mid 232.79354 -279.883108)
				(end 233.09834 -279.883108)
			)
		)
		(stroke
			(width 0)
			(type solid)
		)
		(fill yes)
		(layer "In7.Cu")
		(net "GND")
	)
	(gr_poly
		(pts
			(arc
				(start 249.348498 -279.883108)
				(mid 249.043698 -279.883108)
				(end 249.348498 -279.883108)
			)
		)
		(stroke
			(width 0)
			(type solid)
		)
		(fill yes)
		(layer "In7.Cu")
		(net "GND")
	)
	(gr_poly
		(pts
			(arc
				(start 86.097364 -140.934694)
				(mid 85.7885 -140.934694)
				(end 86.097364 -140.934694)
			)
		)
		(stroke
			(width 0)
			(type solid)
		)
		(fill yes)
		(layer "In7.Cu")
		(net "GND")
	)
	(gr_poly
		(pts
			(arc
				(start 95.024448 -131.560316)
				(mid 94.715584 -131.560316)
				(end 95.024448 -131.560316)
			)
		)
		(stroke
			(width 0)
			(type solid)
		)
		(fill yes)
		(layer "In7.Cu")
		(net "GND")
	)
	(gr_poly
		(pts
			(arc
				(start 105.564178 -77.969364)
				(mid 105.255314 -77.969364)
				(end 105.564178 -77.969364)
			)
		)
		(stroke
			(width 0)
			(type solid)
		)
		(fill yes)
		(layer "In7.Cu")
		(net "GND")
	)
	(gr_poly
		(pts
			(arc
				(start 106.823002 -77.969364)
				(mid 106.514138 -77.969364)
				(end 106.823002 -77.969364)
			)
		)
		(stroke
			(width 0)
			(type solid)
		)
		(fill yes)
		(layer "In7.Cu")
		(net "GND")
	)
	(gr_poly
		(pts
			(arc
				(start 107.564174 -78.731364)
				(mid 107.25531 -78.731364)
				(end 107.564174 -78.731364)
			)
		)
		(stroke
			(width 0)
			(type solid)
		)
		(fill yes)
		(layer "In7.Cu")
		(net "GND")
	)
	(gr_poly
		(pts
			(arc
				(start 108.822998 -78.731364)
				(mid 108.514134 -78.731364)
				(end 108.822998 -78.731364)
			)
		)
		(stroke
			(width 0)
			(type solid)
		)
		(fill yes)
		(layer "In7.Cu")
		(net "GND")
	)
	(gr_poly
		(pts
			(arc
				(start 109.563916 -93.424502)
				(mid 109.255052 -93.424502)
				(end 109.563916 -93.424502)
			)
		)
		(stroke
			(width 0)
			(type solid)
		)
		(fill yes)
		(layer "In7.Cu")
		(net "GND")
	)
	(gr_poly
		(pts
			(arc
				(start 109.56417 -77.969364)
				(mid 109.255306 -77.969364)
				(end 109.56417 -77.969364)
			)
		)
		(stroke
			(width 0)
			(type solid)
		)
		(fill yes)
		(layer "In7.Cu")
		(net "GND")
	)
	(gr_poly
		(pts
			(arc
				(start 110.82274 -93.424502)
				(mid 110.513876 -93.424502)
				(end 110.82274 -93.424502)
			)
		)
		(stroke
			(width 0)
			(type solid)
		)
		(fill yes)
		(layer "In7.Cu")
		(net "GND")
	)
	(gr_poly
		(pts
			(arc
				(start 110.822994 -77.969364)
				(mid 110.51413 -77.969364)
				(end 110.822994 -77.969364)
			)
		)
		(stroke
			(width 0)
			(type solid)
		)
		(fill yes)
		(layer "In7.Cu")
		(net "GND")
	)
	(gr_poly
		(pts
			(arc
				(start 116.601748 -87.556594)
				(mid 116.292884 -87.556594)
				(end 116.601748 -87.556594)
			)
		)
		(stroke
			(width 0)
			(type solid)
		)
		(fill yes)
		(layer "In7.Cu")
		(net "GND")
	)
	(gr_poly
		(pts
			(arc
				(start 116.601748 -86.29777)
				(mid 116.292884 -86.29777)
				(end 116.601748 -86.29777)
			)
		)
		(stroke
			(width 0)
			(type solid)
		)
		(fill yes)
		(layer "In7.Cu")
		(net "GND")
	)
	(gr_poly
		(pts
			(arc
				(start 116.601748 -83.556602)
				(mid 116.292884 -83.556602)
				(end 116.601748 -83.556602)
			)
		)
		(stroke
			(width 0)
			(type solid)
		)
		(fill yes)
		(layer "In7.Cu")
		(net "GND")
	)
	(gr_poly
		(pts
			(arc
				(start 116.601748 -82.297778)
				(mid 116.292884 -82.297778)
				(end 116.601748 -82.297778)
			)
		)
		(stroke
			(width 0)
			(type solid)
		)
		(fill yes)
		(layer "In7.Cu")
		(net "GND")
	)
	(gr_poly
		(pts
			(arc
				(start 117.363748 -89.55659)
				(mid 117.054884 -89.55659)
				(end 117.363748 -89.55659)
			)
		)
		(stroke
			(width 0)
			(type solid)
		)
		(fill yes)
		(layer "In7.Cu")
		(net "GND")
	)
	(gr_poly
		(pts
			(arc
				(start 117.363748 -88.297766)
				(mid 117.054884 -88.297766)
				(end 117.363748 -88.297766)
			)
		)
		(stroke
			(width 0)
			(type solid)
		)
		(fill yes)
		(layer "In7.Cu")
		(net "GND")
	)
	(gr_poly
		(pts
			(arc
				(start 117.363748 -85.556598)
				(mid 117.054884 -85.556598)
				(end 117.363748 -85.556598)
			)
		)
		(stroke
			(width 0)
			(type solid)
		)
		(fill yes)
		(layer "In7.Cu")
		(net "GND")
	)
	(gr_poly
		(pts
			(arc
				(start 117.363748 -84.297774)
				(mid 117.054884 -84.297774)
				(end 117.363748 -84.297774)
			)
		)
		(stroke
			(width 0)
			(type solid)
		)
		(fill yes)
		(layer "In7.Cu")
		(net "GND")
	)
	(gr_poly
		(pts
			(arc
				(start 122.8979 -93.086174)
				(mid 122.589036 -93.086174)
				(end 122.8979 -93.086174)
			)
		)
		(stroke
			(width 0)
			(type solid)
		)
		(fill yes)
		(layer "In7.Cu")
		(net "GND")
	)
	(gr_poly
		(pts
			(arc
				(start 122.973846 -96.597724)
				(mid 122.664982 -96.597724)
				(end 122.973846 -96.597724)
			)
		)
		(stroke
			(width 0)
			(type solid)
		)
		(fill yes)
		(layer "In7.Cu")
		(net "GND")
	)
	(gr_poly
		(pts
			(arc
				(start 122.984768 -95.46336)
				(mid 122.675904 -95.46336)
				(end 122.984768 -95.46336)
			)
		)
		(stroke
			(width 0)
			(type solid)
		)
		(fill yes)
		(layer "In7.Cu")
		(net "GND")
	)
	(gr_poly
		(pts
			(arc
				(start 123.023376 -94.301564)
				(mid 122.714512 -94.301564)
				(end 123.023376 -94.301564)
			)
		)
		(stroke
			(width 0)
			(type solid)
		)
		(fill yes)
		(layer "In7.Cu")
		(net "GND")
	)
	(gr_poly
		(pts
			(arc
				(start 137.732008 -98.817938)
				(mid 137.423144 -98.817938)
				(end 137.732008 -98.817938)
			)
		)
		(stroke
			(width 0)
			(type solid)
		)
		(fill yes)
		(layer "In7.Cu")
		(net "GND")
	)
	(gr_poly
		(pts
			(arc
				(start 140.802106 -98.675698)
				(mid 140.493242 -98.675698)
				(end 140.802106 -98.675698)
			)
		)
		(stroke
			(width 0)
			(type solid)
		)
		(fill yes)
		(layer "In7.Cu")
		(net "GND")
	)
	(gr_poly
		(pts
			(arc
				(start 145.095468 -95.365062)
				(mid 144.786604 -95.365062)
				(end 145.095468 -95.365062)
			)
		)
		(stroke
			(width 0)
			(type solid)
		)
		(fill yes)
		(layer "In7.Cu")
		(net "GND")
	)
	(gr_poly
		(pts
			(arc
				(start 147.85213 -85.515704)
				(mid 147.543266 -85.515704)
				(end 147.85213 -85.515704)
			)
		)
		(stroke
			(width 0)
			(type solid)
		)
		(fill yes)
		(layer "In7.Cu")
		(net "GND")
	)
	(gr_poly
		(pts
			(arc
				(start 150.059644 -78.67904)
				(mid 149.75078 -78.67904)
				(end 150.059644 -78.67904)
			)
		)
		(stroke
			(width 0)
			(type solid)
		)
		(fill yes)
		(layer "In7.Cu")
		(net "GND")
	)
	(gr_poly
		(pts
			(arc
				(start 174.40148 -86.30793)
				(mid 174.092616 -86.30793)
				(end 174.40148 -86.30793)
			)
		)
		(stroke
			(width 0)
			(type solid)
		)
		(fill yes)
		(layer "In7.Cu")
		(net "GND")
	)
	(gr_poly
		(pts
			(arc
				(start 222.720916 -76.899516)
				(mid 222.412052 -76.899516)
				(end 222.720916 -76.899516)
			)
		)
		(stroke
			(width 0)
			(type solid)
		)
		(fill yes)
		(layer "In7.Cu")
		(net "GND")
	)
	(gr_poly
		(pts
			(arc
				(start 241.82197 -376.463306)
				(mid 241.841493 -376.459405)
				(end 241.858038 -376.44832)
			)
			(arc
				(start 242.310666 -375.995692)
				(mid 242.321777 -375.979158)
				(end 242.325652 -375.959624)
			)
			(arc
				(start 242.325652 -368.584988)
				(mid 242.321751 -368.565465)
				(end 242.310666 -368.54892)
			)
			(arc
				(start 242.213638 -368.451892)
				(mid 242.197104 -368.440781)
				(end 242.17757 -368.436906)
			)
			(arc
				(start 236.311948 -368.436906)
				(mid 236.292425 -368.440807)
				(end 236.27588 -368.451892)
			)
			(arc
				(start 236.087666 -368.640106)
				(mid 236.076555 -368.65664)
				(end 236.07268 -368.676174)
			)
			(arc
				(start 236.07268 -376.18035)
				(mid 236.076581 -376.199873)
				(end 236.087666 -376.216418)
			)
			(arc
				(start 236.319568 -376.44832)
				(mid 236.336102 -376.459431)
				(end 236.355636 -376.463306)
			)
		)
		(stroke
			(width 0)
			(type solid)
		)
		(fill yes)
		(layer "In7.Cu")
		(net "P12V_STBY_R1")
	)
	(gr_poly
		(pts
			(arc
				(start 252.431042 -397.963136)
				(mid 252.450565 -397.959235)
				(end 252.46711 -397.94815)
			)
			(arc
				(start 252.932438 -397.482822)
				(mid 252.943549 -397.466288)
				(end 252.947424 -397.446754)
			)
			(arc
				(start 252.947424 -392.961114)
				(mid 252.943523 -392.941591)
				(end 252.932438 -392.925046)
			)
			(arc
				(start 252.451362 -392.44397)
				(mid 252.434828 -392.432859)
				(end 252.415294 -392.428984)
			)
			(arc
				(start 245.184422 -392.428984)
				(mid 245.164899 -392.432885)
				(end 245.148354 -392.44397)
			)
			(arc
				(start 244.746526 -392.845798)
				(mid 244.735415 -392.862332)
				(end 244.73154 -392.881866)
			)
			(arc
				(start 244.73154 -397.594328)
				(mid 244.735441 -397.613851)
				(end 244.746526 -397.630396)
			)
			(arc
				(start 245.06428 -397.94815)
				(mid 245.080814 -397.959261)
				(end 245.100348 -397.963136)
			)
		)
		(stroke
			(width 0)
			(type solid)
		)
		(fill yes)
		(layer "In7.Cu")
		(net "P12V_STBY_FUSE")
	)
	(gr_poly
		(pts
			(arc
				(start 261.653274 -355.276658)
				(mid 261.672797 -355.272757)
				(end 261.689342 -355.261672)
			)
			(arc
				(start 262.021574 -354.92944)
				(mid 262.032685 -354.912906)
				(end 262.03656 -354.893372)
			)
			(arc
				(start 262.03656 -351.882456)
				(mid 262.032659 -351.862933)
				(end 262.021574 -351.846388)
			)
			(arc
				(start 261.861046 -351.68586)
				(mid 261.844512 -351.674749)
				(end 261.824978 -351.670874)
			)
			(arc
				(start 256.266442 -351.670874)
				(mid 256.246919 -351.674775)
				(end 256.230374 -351.68586)
			)
			(arc
				(start 256.076196 -351.840038)
				(mid 256.065085 -351.856572)
				(end 256.06121 -351.876106)
			)
			(arc
				(start 256.06121 -354.912168)
				(mid 256.065111 -354.931691)
				(end 256.076196 -354.948236)
			)
			(arc
				(start 256.389632 -355.261672)
				(mid 256.406166 -355.272783)
				(end 256.4257 -355.276658)
			)
		)
		(stroke
			(width 0)
			(type solid)
		)
		(fill yes)
		(layer "In7.Cu")
		(net "GND")
	)
	(gr_poly
		(pts
			(arc
				(start 110.042706 -259.201412)
				(mid 110.05877 -259.198805)
				(end 110.073186 -259.191252)
			)
			(xy 110.078774 -259.186426) (xy 110.20425 -259.06095)
			(arc
				(start 110.209076 -259.055362)
				(mid 110.216629 -259.040946)
				(end 110.219236 -259.024882)
			)
			(arc
				(start 110.219236 -257.932428)
				(mid 110.216629 -257.916364)
				(end 110.209076 -257.901948)
			)
			(xy 110.20425 -257.89636) (xy 110.141004 -257.833114)
			(arc
				(start 110.135416 -257.828288)
				(mid 110.121 -257.820735)
				(end 110.104936 -257.818128)
			)
			(arc
				(start 108.398564 -257.818128)
				(mid 108.3825 -257.820735)
				(end 108.368084 -257.828288)
			)
			(xy 108.362496 -257.833114) (xy 108.205778 -257.989832)
			(arc
				(start 108.200952 -257.99542)
				(mid 108.193399 -258.009836)
				(end 108.190792 -258.0259)
			)
			(arc
				(start 108.190792 -259.05587)
				(mid 108.193399 -259.071934)
				(end 108.200952 -259.08635)
			)
			(xy 108.205778 -259.091938) (xy 108.300266 -259.186426)
			(arc
				(start 108.305854 -259.191252)
				(mid 108.32027 -259.198805)
				(end 108.336334 -259.201412)
			)
		)
		(stroke
			(width 0)
			(type solid)
		)
		(fill yes)
		(layer "In7.Cu")
		(net "P5V_AUX")
	)
	(gr_poly
		(pts
			(arc
				(start 241.286792 -169.595292)
				(mid 241.306315 -169.591391)
				(end 241.32286 -169.580306)
			)
			(arc
				(start 241.483642 -169.419524)
				(mid 241.494753 -169.40299)
				(end 241.498628 -169.383456)
			)
			(arc
				(start 241.498628 -164.488622)
				(mid 241.494727 -164.469099)
				(end 241.483642 -164.452554)
			)
			(arc
				(start 240.50498 -163.473892)
				(mid 240.433211 -163.366432)
				(end 240.407952 -163.239704)
			)
			(arc
				(start 240.407952 -160.542224)
				(mid 240.393073 -160.506303)
				(end 240.357152 -160.491424)
			)
			(arc
				(start 239.266476 -160.491424)
				(mid 239.246953 -160.495325)
				(end 239.230408 -160.50641)
			)
			(xy 239.078516 -160.658302) (xy 239.07115 -160.665414) (xy 239.06353 -160.68421)
			(arc
				(start 239.06353 -169.3926)
				(mid 239.067431 -169.412123)
				(end 239.078516 -169.428668)
			)
			(arc
				(start 239.230154 -169.580306)
				(mid 239.246688 -169.591417)
				(end 239.266222 -169.595292)
			)
		)
		(stroke
			(width 0)
			(type solid)
		)
		(fill yes)
		(layer "In7.Cu")
		(net "P5V_AUX")
	)
	(gr_poly
		(pts
			(arc
				(start 122.497088 -138.014456)
				(mid 122.575536 -137.987892)
				(end 122.65787 -137.978896)
			)
			(arc
				(start 122.65787 -137.978896)
				(mid 122.684861 -137.979852)
				(end 122.711718 -137.982706)
			)
			(xy 122.722894 -137.98423) (xy 122.743722 -137.978134)
			(arc
				(start 122.81027 -137.920476)
				(mid 122.82319 -137.903201)
				(end 122.827796 -137.882122)
			)
			(arc
				(start 122.827796 -136.174734)
				(mid 122.822986 -136.153157)
				(end 122.809508 -136.135618)
			)
			(xy 122.740928 -136.078468) (xy 122.719084 -136.072626)
			(arc
				(start 122.708162 -136.074658)
				(mid 122.674389 -136.079212)
				(end 122.640344 -136.080754)
			)
			(arc
				(start 122.640344 -136.080754)
				(mid 122.565481 -136.073286)
				(end 122.493532 -136.05129)
			)
			(xy 122.48134 -136.04621) (xy 122.456448 -136.04875)
			(arc
				(start 122.375422 -136.102852)
				(mid 122.358879 -136.121114)
				(end 122.352816 -136.145016)
			)
			(arc
				(start 122.352816 -137.922254)
				(mid 122.358967 -137.94674)
				(end 122.376184 -137.96518)
			)
			(xy 122.459496 -138.018266) (xy 122.48515 -138.020044)
		)
		(stroke
			(width 0)
			(type solid)
		)
		(fill yes)
		(layer "In7.Cu")
		(net "GND")
	)
	(gr_poly
		(pts
			(xy 122.040396 -146.471132)
			(arc
				(start 122.81281 -145.698718)
				(mid 122.823872 -145.682301)
				(end 122.827796 -145.662904)
			)
			(arc
				(start 122.827796 -139.854686)
				(mid 122.823212 -139.833597)
				(end 122.81027 -139.816332)
			)
			(xy 122.743722 -139.758674) (xy 122.722894 -139.752578)
			(arc
				(start 122.711718 -139.754102)
				(mid 122.684862 -139.756965)
				(end 122.65787 -139.757912)
			)
			(arc
				(start 122.65787 -139.757912)
				(mid 122.575536 -139.748916)
				(end 122.497088 -139.722352)
			)
			(xy 122.48515 -139.716764) (xy 122.459496 -139.718542)
			(arc
				(start 122.376184 -139.771628)
				(mid 122.35903 -139.790103)
				(end 122.352816 -139.814554)
			)
			(arc
				(start 122.352816 -145.745962)
				(mid 122.327531 -145.87299)
				(end 122.255534 -145.980658)
			)
			(arc
				(start 121.97969 -146.256502)
				(mid 121.968628 -146.272919)
				(end 121.964704 -146.292316)
			)
			(arc
				(start 121.964704 -146.424142)
				(mid 121.973306 -146.452426)
				(end 121.9962 -146.471132)
			)
			(xy 122.010678 -146.476974)
		)
		(stroke
			(width 0)
			(type solid)
		)
		(fill yes)
		(layer "In7.Cu")
		(net "GND")
	)
	(gr_poly
		(pts
			(arc
				(start 265.756136 -366.15497)
				(mid 265.775659 -366.151069)
				(end 265.792204 -366.139984)
			)
			(arc
				(start 265.910314 -366.021874)
				(mid 265.921425 -366.00534)
				(end 265.9253 -365.985806)
			)
			(arc
				(start 265.9253 -361.73791)
				(mid 265.921399 -361.718387)
				(end 265.910314 -361.701842)
			)
			(xy 261.521956 -357.313484) (xy 261.509002 -357.313484)
			(arc
				(start 261.105142 -356.909624)
				(mid 261.088608 -356.898513)
				(end 261.069074 -356.894638)
			)
			(arc
				(start 255.655318 -356.894638)
				(mid 255.635931 -356.898588)
				(end 255.619504 -356.909624)
			)
			(arc
				(start 255.563116 -356.966012)
				(mid 255.546553 -356.976986)
				(end 255.527048 -356.980744)
			)
			(arc
				(start 252.340872 -356.980744)
				(mid 252.321485 -356.984694)
				(end 252.305058 -356.99573)
			)
			(arc
				(start 249.53976 -359.761028)
				(mid 249.523226 -359.772139)
				(end 249.503692 -359.776014)
			)
			(arc
				(start 238.600488 -359.776014)
				(mid 238.580965 -359.779915)
				(end 238.56442 -359.791)
			)
			(arc
				(start 236.869478 -361.485942)
				(mid 236.858367 -361.502476)
				(end 236.854492 -361.52201)
			)
			(arc
				(start 236.854492 -365.783876)
				(mid 236.858393 -365.803399)
				(end 236.869478 -365.819944)
			)
			(arc
				(start 237.189518 -366.139984)
				(mid 237.206052 -366.151095)
				(end 237.225586 -366.15497)
			)
		)
		(stroke
			(width 0)
			(type solid)
		)
		(fill yes)
		(layer "In7.Cu")
		(net "P12V_AUX")
	)
	(gr_poly
		(pts
			(xy 121.988834 -134.48792) (xy 122.2883 -134.188454) (xy 122.295158 -134.161784)
			(arc
				(start 122.291348 -134.148322)
				(mid 122.280126 -134.095891)
				(end 122.276362 -134.042404)
			)
			(arc
				(start 122.276362 -134.042404)
				(mid 122.388103 -133.772637)
				(end 122.65787 -133.660896)
			)
			(arc
				(start 122.65787 -133.660896)
				(mid 122.684861 -133.661852)
				(end 122.711718 -133.664706)
			)
			(xy 122.722894 -133.66623) (xy 122.743722 -133.660134)
			(arc
				(start 122.81027 -133.602476)
				(mid 122.82319 -133.585201)
				(end 122.827796 -133.564122)
			)
			(arc
				(start 122.827796 -118.319296)
				(mid 122.823846 -118.299909)
				(end 122.81281 -118.283482)
			)
			(arc
				(start 122.389392 -117.85981)
				(mid 122.363363 -117.846)
				(end 122.33402 -117.848888)
			)
			(xy 122.319542 -117.854984) (xy 122.302524 -117.88013)
			(arc
				(start 122.302524 -121.46788)
				(mid 122.277356 -121.594879)
				(end 122.205496 -121.702576)
			)
			(arc
				(start 121.928128 -121.979944)
				(mid 121.917202 -121.99639)
				(end 121.913396 -122.015758)
			)
			(arc
				(start 121.913396 -134.44093)
				(mid 121.921835 -134.469225)
				(end 121.944638 -134.48792)
			)
			(xy 121.959116 -134.493762)
		)
		(stroke
			(width 0)
			(type solid)
		)
		(fill yes)
		(layer "In7.Cu")
		(net "GND")
	)
	(gr_poly
		(pts
			(arc
				(start 132.2832 -179.03444)
				(mid 132.325377 -179.027631)
				(end 132.368036 -179.025296)
			)
			(arc
				(start 132.368036 -179.025296)
				(mid 132.410693 -179.027645)
				(end 132.452872 -179.03444)
			)
			(xy 132.457952 -179.035456)
			(arc
				(start 133.987286 -179.035456)
				(mid 134.006809 -179.031555)
				(end 134.023354 -179.02047)
			)
			(arc
				(start 134.097268 -178.946556)
				(mid 134.108379 -178.930022)
				(end 134.112254 -178.910488)
			)
			(arc
				(start 134.112254 -176.398428)
				(mid 134.108353 -176.378905)
				(end 134.097268 -176.36236)
			)
			(arc
				(start 134.003796 -176.268888)
				(mid 133.987262 -176.257777)
				(end 133.967728 -176.253902)
			)
			(arc
				(start 131.460748 -176.253902)
				(mid 131.441225 -176.257803)
				(end 131.42468 -176.268888)
			)
			(arc
				(start 131.335018 -176.35855)
				(mid 131.323907 -176.375084)
				(end 131.320032 -176.394618)
			)
			(xy 131.320032 -176.597056)
			(arc
				(start 131.322318 -176.604168)
				(mid 131.339848 -176.722278)
				(end 131.322318 -176.840388)
			)
			(xy 131.320032 -176.8475) (xy 131.320032 -178.0032)
			(arc
				(start 131.322826 -178.011074)
				(mid 131.339356 -178.076198)
				(end 131.344924 -178.143154)
			)
			(arc
				(start 131.344924 -178.143154)
				(mid 131.339336 -178.210107)
				(end 131.322826 -178.275234)
			)
			(xy 131.320032 -178.283108)
			(arc
				(start 131.320032 -178.682396)
				(mid 131.323933 -178.701919)
				(end 131.335018 -178.718464)
			)
			(arc
				(start 131.637024 -179.02047)
				(mid 131.653558 -179.031581)
				(end 131.673092 -179.035456)
			)
			(xy 132.27812 -179.035456)
		)
		(stroke
			(width 0)
			(type solid)
		)
		(fill yes)
		(layer "In7.Cu")
		(net "GND")
	)
	(gr_poly
		(pts
			(xy 332.375002 -206.149194) (xy 332.375002 -205.929484) (xy 332.375002 -203.230226)
			(arc
				(start 331.90815 -202.763374)
				(mid 331.891704 -202.752448)
				(end 331.872336 -202.748642)
			)
			(arc
				(start 330.349606 -202.748642)
				(mid 330.328029 -202.753452)
				(end 330.31049 -202.76693)
			)
			(xy 330.25334 -202.836018) (xy 330.247752 -202.857608)
			(arc
				(start 330.249784 -202.869038)
				(mid 330.254724 -202.90419)
				(end 330.256388 -202.93965)
			)
			(arc
				(start 330.256388 -202.93965)
				(mid 330.144647 -203.209417)
				(end 329.87488 -203.321158)
			)
			(arc
				(start 329.87488 -203.321158)
				(mid 329.73071 -203.292869)
				(end 329.607926 -203.212192)
			)
			(xy 329.274932 -203.212192) (xy 329.022964 -203.46416) (xy 329.022964 -205.931008) (xy 329.219052 -206.127096)
			(arc
				(start 330.464922 -206.127096)
				(mid 330.482353 -206.124012)
				(end 330.497688 -206.115158)
			)
			(arc
				(start 330.497688 -206.115158)
				(mid 330.612677 -206.048492)
				(end 330.74356 -206.025242)
			)
			(arc
				(start 330.74356 -206.025242)
				(mid 330.874474 -206.048407)
				(end 330.989432 -206.115158)
			)
			(arc
				(start 330.989432 -206.115158)
				(mid 331.004756 -206.124042)
				(end 331.022198 -206.127096)
			)
			(xy 331.168756 -206.127096) (xy 331.21727 -206.17561) (xy 331.21727 -206.420466) (xy 331.346556 -206.549752)
			(xy 331.974444 -206.549752)
		)
		(stroke
			(width 0)
			(type solid)
		)
		(fill yes)
		(layer "In7.Cu")
		(net "GND")
	)
	(gr_poly
		(pts
			(arc
				(start 263.911588 -377.748546)
				(mid 263.945184 -377.735851)
				(end 263.96188 -377.704096)
			)
			(arc
				(start 263.96188 -377.704096)
				(mid 264.777335 -375.057413)
				(end 266.446 -372.847108)
			)
			(arc
				(start 266.446 -372.847108)
				(mid 266.458064 -372.830145)
				(end 266.462256 -372.80977)
			)
			(arc
				(start 266.462256 -368.750596)
				(mid 266.458306 -368.731209)
				(end 266.44727 -368.714782)
			)
			(arc
				(start 266.291568 -368.55908)
				(mid 266.275034 -368.547969)
				(end 266.2555 -368.544094)
			)
			(xy 243.539264 -368.544094) (xy 243.533676 -368.538506)
			(arc
				(start 242.778534 -368.538506)
				(mid 242.759011 -368.542407)
				(end 242.742466 -368.553492)
			)
			(arc
				(start 242.620038 -368.67592)
				(mid 242.608927 -368.692454)
				(end 242.605052 -368.711988)
			)
			(arc
				(start 242.605052 -376.015758)
				(mid 242.608953 -376.035281)
				(end 242.620038 -376.051826)
			)
			(arc
				(start 242.930426 -376.362214)
				(mid 242.94696 -376.373325)
				(end 242.966494 -376.3772)
			)
			(arc
				(start 249.280426 -376.3772)
				(mid 249.299949 -376.381101)
				(end 249.316494 -376.392186)
			)
			(arc
				(start 250.657868 -377.73356)
				(mid 250.674402 -377.744671)
				(end 250.693936 -377.748546)
			)
		)
		(stroke
			(width 0)
			(type solid)
		)
		(fill yes)
		(layer "In7.Cu")
		(net "P12V_STBY_R2")
	)
	(gr_poly
		(pts
			(arc
				(start 108.51134 -337.046062)
				(mid 108.519982 -337.045278)
				(end 108.528358 -337.043014)
			)
			(xy 109.456474 -336.711036) (xy 109.474 -336.690716)
			(arc
				(start 109.47654 -336.677254)
				(mid 109.60818 -336.455068)
				(end 109.85119 -336.367628)
			)
			(arc
				(start 109.851444 -336.367628)
				(mid 109.981123 -336.390436)
				(end 110.095284 -336.45602)
			)
			(xy 110.105698 -336.464656) (xy 110.132368 -336.469228) (xy 110.193328 -336.447384) (xy 110.197646 -336.445606)
			(arc
				(start 110.236762 -336.427572)
				(mid 110.258313 -336.408784)
				(end 110.266226 -336.381344)
			)
			(arc
				(start 110.266226 -333.862426)
				(mid 110.262325 -333.842903)
				(end 110.25124 -333.826358)
			)
			(arc
				(start 110.164372 -333.73949)
				(mid 110.145941 -333.727633)
				(end 110.12424 -333.724758)
			)
			(xy 110.035594 -333.732124) (xy 110.01629 -333.743046)
			(arc
				(start 110.009686 -333.752444)
				(mid 109.87367 -333.870265)
				(end 109.69879 -333.912718)
			)
			(arc
				(start 109.69879 -333.912718)
				(mid 109.439182 -333.810767)
				(end 109.318298 -333.559404)
			)
			(arc
				(start 109.318298 -333.559404)
				(mid 109.313438 -333.541255)
				(end 109.302296 -333.52613)
			)
			(arc
				(start 109.25175 -333.47914)
				(mid 109.235664 -333.468938)
				(end 109.216952 -333.465424)
			)
			(arc
				(start 109.016292 -333.465424)
				(mid 108.996769 -333.469325)
				(end 108.980224 -333.48041)
			)
			(xy 107.542076 -334.918558) (xy 107.53471 -334.92567) (xy 107.52709 -334.944466)
			(arc
				(start 107.52709 -336.255106)
				(mid 107.530991 -336.274629)
				(end 107.542076 -336.291174)
			)
			(arc
				(start 108.281978 -337.031076)
				(mid 108.298512 -337.042187)
				(end 108.318046 -337.046062)
			)
		)
		(stroke
			(width 0)
			(type solid)
		)
		(fill yes)
		(layer "In7.Cu")
		(net "P3V3_CLK_BUFFER_9ZXL0451E_VZX3P3A")
	)
	(gr_poly
		(pts
			(arc
				(start 331.22108 -263.931146)
				(mid 331.240603 -263.927245)
				(end 331.257148 -263.91616)
			)
			(arc
				(start 331.523848 -263.64946)
				(mid 331.534528 -263.6336)
				(end 331.53858 -263.614916)
			)
			(arc
				(start 331.539342 -263.58469)
				(mid 331.536499 -263.566886)
				(end 331.527658 -263.551162)
			)
			(arc
				(start 331.527658 -263.551162)
				(mid 331.462782 -263.437238)
				(end 331.440282 -263.308084)
			)
			(arc
				(start 331.440282 -263.308084)
				(mid 331.552023 -263.038317)
				(end 331.82179 -262.926576)
			)
			(arc
				(start 331.82179 -262.926576)
				(mid 331.959615 -262.952342)
				(end 332.078838 -263.026144)
			)
			(xy 332.093824 -263.03986) (xy 332.13421 -263.039098)
			(arc
				(start 333.439262 -261.734046)
				(mid 333.455796 -261.722935)
				(end 333.47533 -261.71906)
			)
			(arc
				(start 341.517732 -261.71906)
				(mid 341.537255 -261.715159)
				(end 341.5538 -261.704074)
			)
			(arc
				(start 341.744046 -261.513828)
				(mid 341.755157 -261.497294)
				(end 341.759032 -261.47776)
			)
			(arc
				(start 341.759032 -259.60705)
				(mid 341.755131 -259.587527)
				(end 341.744046 -259.570982)
			)
			(arc
				(start 341.413084 -259.240274)
				(mid 341.39655 -259.229163)
				(end 341.377016 -259.225288)
			)
			(arc
				(start 333.13878 -259.225288)
				(mid 333.102859 -259.240167)
				(end 333.08798 -259.276088)
			)
			(arc
				(start 333.08798 -259.457698)
				(mid 333.062695 -259.584726)
				(end 332.990698 -259.692394)
			)
			(arc
				(start 331.336396 -261.346696)
				(mid 331.228702 -261.418562)
				(end 331.1017 -261.443724)
			)
			(arc
				(start 330.532486 -261.443724)
				(mid 330.513099 -261.447674)
				(end 330.496672 -261.45871)
			)
			(arc
				(start 330.090272 -261.86511)
				(mid 330.073738 -261.876221)
				(end 330.054204 -261.880096)
			)
			(arc
				(start 327.48982 -261.880096)
				(mid 327.453899 -261.894975)
				(end 327.43902 -261.930896)
			)
			(arc
				(start 327.43902 -262.46836)
				(mid 327.415765 -262.585182)
				(end 327.349612 -262.68426)
			)
			(arc
				(start 326.189086 -263.844532)
				(mid 326.175276 -263.870561)
				(end 326.178164 -263.899904)
			)
			(xy 326.184006 -263.914128) (xy 326.209406 -263.931146)
		)
		(stroke
			(width 0)
			(type solid)
		)
		(fill yes)
		(layer "In7.Cu")
		(net "P5V_AUX")
	)
	(gr_poly
		(pts
			(xy 107.165902 -348.63659) (xy 107.175972 -348.636166) (xy 107.194575 -348.62845) (xy 107.20197 -348.621604)
			(xy 107.351068 -348.472506) (xy 107.357919 -348.465109) (xy 107.36566 -348.446511) (xy 107.366054 -348.436438)
			(xy 107.366054 -346.28709) (xy 107.36648 -346.277022) (xy 107.374203 -346.258425) (xy 107.38104 -346.251022)
			(xy 107.61091 -346.021152) (xy 107.618306 -346.014301) (xy 107.636905 -346.006562) (xy 107.646978 -346.006166)
			(xy 108.687616 -346.006166) (xy 108.697684 -346.005739) (xy 108.716281 -345.998017) (xy 108.723684 -345.99118)
			(xy 108.953554 -345.76131) (xy 108.960407 -345.753914) (xy 108.968152 -345.735316) (xy 108.96854 -345.725242)
			(xy 108.96854 -344.186256) (xy 108.968107 -344.176191) (xy 108.960375 -344.157604) (xy 108.953554 -344.150188)
			(xy 108.702094 -343.898728) (xy 108.694696 -343.89188) (xy 108.676098 -343.884143) (xy 108.666026 -343.883742)
			(xy 105.957624 -343.883742) (xy 105.947561 -343.88418) (xy 105.928981 -343.891919) (xy 105.921556 -343.898728)
			(xy 105.489502 -344.330782) (xy 105.482668 -344.338185) (xy 105.474964 -344.356783) (xy 105.474516 -344.36685)
			(xy 105.474516 -345.228926) (xy 105.613452 -345.228926) (xy 105.617523 -345.173304) (xy 105.629649 -345.118867)
			(xy 105.649572 -345.066776) (xy 105.676868 -345.018141) (xy 105.710954 -344.973998) (xy 105.751103 -344.935289)
			(xy 105.796461 -344.902838) (xy 105.846061 -344.877337) (xy 105.898845 -344.85933) (xy 105.953688 -344.8492)
			(xy 106.009422 -344.847163) (xy 106.064859 -344.853263) (xy 106.118816 -344.867369) (xy 106.170145 -344.889181)
			(xy 106.217751 -344.918235) (xy 106.260619 -344.95391) (xy 106.297836 -344.995447) (xy 106.328609 -345.04196)
			(xy 106.352281 -345.092457) (xy 106.368349 -345.145864) (xy 106.376469 -345.20104) (xy 106.376978 -345.228926)
			(xy 106.376469 -345.256812) (xy 106.368349 -345.311988) (xy 106.352281 -345.365395) (xy 106.328609 -345.415892)
			(xy 106.297836 -345.462405) (xy 106.260619 -345.503942) (xy 106.217751 -345.539617) (xy 106.170145 -345.568671)
			(xy 106.118816 -345.590483) (xy 106.064859 -345.604589) (xy 106.009422 -345.610689) (xy 105.953688 -345.608652)
			(xy 105.898845 -345.598522) (xy 105.846061 -345.580515) (xy 105.796461 -345.555014) (xy 105.751103 -345.522563)
			(xy 105.710954 -345.483854) (xy 105.676868 -345.439711) (xy 105.649572 -345.391076) (xy 105.629649 -345.338985)
			(xy 105.617523 -345.284548) (xy 105.613452 -345.228926) (xy 105.474516 -345.228926) (xy 105.474516 -345.479624)
			(xy 105.474944 -345.489692) (xy 105.482666 -345.508289) (xy 105.489502 -345.515692) (xy 106.00817 -346.03436)
			(xy 106.01501 -346.04176) (xy 106.022727 -346.060359) (xy 106.023156 -346.070428) (xy 106.023156 -348.23146)
			(xy 106.026712 -348.24035) (xy 106.035012 -348.262561) (xy 106.046668 -348.308524) (xy 106.052523 -348.355579)
			(xy 106.052874 -348.379288) (xy 106.052591 -348.400225) (xy 106.04801 -348.441849) (xy 106.04373 -348.462346)
			(xy 106.040936 -348.475046) (xy 106.048048 -348.499938) (xy 106.169714 -348.621604) (xy 106.177114 -348.628448)
			(xy 106.195711 -348.636176) (xy 106.205782 -348.63659)
		)
		(stroke
			(width 0)
			(type solid)
		)
		(fill yes)
		(layer "In7.Cu")
		(net "P3V3_CLK_BUFFER_9ZXL0451E_S3_VZX3P3A")
	)
	(gr_poly
		(pts
			(xy 42.390314 -13.820648) (xy 42.390314 -13.401548) (xy 42.34688 -13.358114)
			(arc
				(start 34.964878 -13.358114)
				(mid 33.898562 -12.916432)
				(end 33.45688 -11.850116)
			)
			(arc
				(start 33.45688 -1.999996)
				(mid 33.019884 -0.944996)
				(end 31.964884 -0.508)
			)
			(arc
				(start 19.964908 -0.508)
				(mid 18.909908 -0.944996)
				(end 18.472912 -1.999996)
			)
			(xy 18.472912 -11.631422) (xy 18.980404 -11.631422)
			(arc
				(start 18.980404 -1.999996)
				(mid 19.268759 -1.303847)
				(end 19.964908 -1.015492)
			)
			(arc
				(start 31.964884 -1.015492)
				(mid 32.661033 -1.303847)
				(end 32.949388 -1.999996)
			)
			(arc
				(start 32.949388 -11.850116)
				(mid 33.539801 -13.275118)
				(end 34.964878 -13.865352)
			)
			(xy 42.34561 -13.865352)
		)
		(stroke
			(width 0)
			(type solid)
		)
		(fill yes)
		(layer "In7.Cu")
		(net "GND")
	)
	(gr_poly
		(pts
			(xy 68.431156 -13.728954) (xy 68.431156 -13.494512) (xy 68.294758 -13.358114)
			(arc
				(start 60.96508 -13.358114)
				(mid 59.898764 -12.916432)
				(end 59.457082 -11.850116)
			)
			(arc
				(start 59.457082 -1.999996)
				(mid 59.020086 -0.944996)
				(end 57.965086 -0.508)
			)
			(arc
				(start 45.96511 -0.508)
				(mid 44.91011 -0.944996)
				(end 44.473114 -1.999996)
			)
			(xy 44.473114 -11.726418) (xy 44.980352 -11.726418)
			(arc
				(start 44.980352 -1.999996)
				(mid 45.268617 -1.303936)
				(end 45.964602 -1.015492)
			)
			(arc
				(start 57.965086 -1.015492)
				(mid 58.661325 -1.303831)
				(end 58.949844 -1.999996)
			)
			(arc
				(start 58.949844 -11.850116)
				(mid 59.540093 -13.275103)
				(end 60.96508 -13.865352)
			)
			(xy 68.294758 -13.865352)
		)
		(stroke
			(width 0)
			(type solid)
		)
		(fill yes)
		(layer "In7.Cu")
		(net "GND")
	)
	(gr_poly
		(pts
			(xy 94.285816 -13.833856) (xy 94.285816 -13.444728) (xy 94.199202 -13.358114)
			(arc
				(start 86.965028 -13.358114)
				(mid 85.898712 -12.916432)
				(end 85.45703 -11.850116)
			)
			(arc
				(start 85.45703 -1.999996)
				(mid 85.020034 -0.944996)
				(end 83.965034 -0.508)
			)
			(arc
				(start 71.965058 -0.508)
				(mid 70.910058 -0.944996)
				(end 70.473062 -1.999996)
			)
			(xy 70.473062 -11.716004) (xy 70.9803 -11.716004)
			(arc
				(start 70.9803 -1.999996)
				(mid 71.268565 -1.303936)
				(end 71.96455 -1.015492)
			)
			(arc
				(start 83.965034 -1.015492)
				(mid 84.661273 -1.303831)
				(end 84.949792 -1.999996)
			)
			(arc
				(start 84.949792 -11.850116)
				(mid 85.540041 -13.275103)
				(end 86.965028 -13.865352)
			)
			(xy 94.25432 -13.865352)
		)
		(stroke
			(width 0)
			(type solid)
		)
		(fill yes)
		(layer "In7.Cu")
		(net "GND")
	)
	(gr_poly
		(pts
			(xy 132.291582 -13.80998) (xy 132.291582 -13.413486) (xy 132.23621 -13.358114)
			(arc
				(start 125.065028 -13.358114)
				(mid 123.998712 -12.916432)
				(end 123.55703 -11.850116)
			)
			(arc
				(start 123.55703 -1.999996)
				(mid 123.120034 -0.944996)
				(end 122.065034 -0.508)
			)
			(arc
				(start 97.965006 -0.508)
				(mid 96.910006 -0.944996)
				(end 96.47301 -1.999996)
			)
			(xy 96.47301 -11.72464) (xy 96.980248 -11.72464)
			(arc
				(start 96.980248 -1.999996)
				(mid 97.268513 -1.303936)
				(end 97.964498 -1.015492)
			)
			(arc
				(start 122.065034 -1.015492)
				(mid 122.761273 -1.303831)
				(end 123.049792 -1.999996)
			)
			(arc
				(start 123.049792 -11.850116)
				(mid 123.640041 -13.275103)
				(end 125.065028 -13.865352)
			)
			(xy 132.23621 -13.865352)
		)
		(stroke
			(width 0)
			(type solid)
		)
		(fill yes)
		(layer "In7.Cu")
		(net "GND")
	)
	(gr_poly
		(pts
			(xy 158.365444 -13.805662) (xy 158.365444 -13.417804) (xy 158.305754 -13.358114)
			(arc
				(start 151.064976 -13.358114)
				(mid 149.99866 -12.916432)
				(end 149.556978 -11.850116)
			)
			(arc
				(start 149.556978 -1.999996)
				(mid 149.119982 -0.944996)
				(end 148.064982 -0.508)
			)
			(arc
				(start 136.065006 -0.508)
				(mid 135.010006 -0.944996)
				(end 134.57301 -1.999996)
			)
			(xy 134.57301 -11.817604) (xy 135.080248 -11.817604)
			(arc
				(start 135.080248 -1.999996)
				(mid 135.368513 -1.303936)
				(end 136.064498 -1.015492)
			)
			(arc
				(start 148.064982 -1.015492)
				(mid 148.761221 -1.303831)
				(end 149.04974 -1.999996)
			)
			(arc
				(start 149.04974 -11.850116)
				(mid 149.639989 -13.275103)
				(end 151.064976 -13.865352)
			)
			(xy 158.305754 -13.865352)
		)
		(stroke
			(width 0)
			(type solid)
		)
		(fill yes)
		(layer "In7.Cu")
		(net "GND")
	)
	(gr_poly
		(pts
			(xy 184.389268 -13.77569) (xy 184.389268 -13.447776) (xy 184.299606 -13.358114)
			(arc
				(start 177.064924 -13.358114)
				(mid 175.998608 -12.916432)
				(end 175.556926 -11.850116)
			)
			(arc
				(start 175.556926 -1.999996)
				(mid 175.11993 -0.944996)
				(end 174.06493 -0.508)
			)
			(arc
				(start 162.064954 -0.508)
				(mid 161.009954 -0.944996)
				(end 160.572958 -1.999996)
			)
			(xy 160.572958 -11.62304) (xy 161.080196 -11.62304)
			(arc
				(start 161.080196 -1.999996)
				(mid 161.368461 -1.303936)
				(end 162.064446 -1.015492)
			)
			(arc
				(start 174.06493 -1.015492)
				(mid 174.761169 -1.303831)
				(end 175.049688 -1.999996)
			)
			(arc
				(start 175.049688 -11.850116)
				(mid 175.639937 -13.275103)
				(end 177.064924 -13.865352)
			)
			(xy 184.299606 -13.865352)
		)
		(stroke
			(width 0)
			(type solid)
		)
		(fill yes)
		(layer "In7.Cu")
		(net "GND")
	)
	(gr_poly
		(pts
			(xy 210.250024 -13.829284) (xy 210.250024 -13.394182) (xy 210.213956 -13.358114)
			(arc
				(start 203.064872 -13.358114)
				(mid 201.998721 -12.916342)
				(end 201.556874 -11.850116)
			)
			(arc
				(start 201.556874 -1.999996)
				(mid 201.119878 -0.944996)
				(end 200.064878 -0.508)
			)
			(arc
				(start 188.064902 -0.508)
				(mid 187.009902 -0.944996)
				(end 186.572906 -1.999996)
			)
			(xy 186.572906 -11.750294) (xy 187.080144 -11.750294)
			(arc
				(start 187.080144 -1.999996)
				(mid 187.368409 -1.303936)
				(end 188.064394 -1.015492)
			)
			(arc
				(start 200.064878 -1.015492)
				(mid 200.761117 -1.303831)
				(end 201.049636 -1.999996)
			)
			(arc
				(start 201.049636 -11.850116)
				(mid 201.63987 -13.275193)
				(end 203.064872 -13.865352)
			)
			(xy 210.213956 -13.865352)
		)
		(stroke
			(width 0)
			(type solid)
		)
		(fill yes)
		(layer "In7.Cu")
		(net "GND")
	)
	(gr_poly
		(pts
			(xy 300.515782 -13.7541) (xy 300.515782 -13.469366) (xy 300.40453 -13.358114)
			(arc
				(start 293.165022 -13.358114)
				(mid 292.098706 -12.916432)
				(end 291.657024 -11.850116)
			)
			(arc
				(start 291.657024 -1.999996)
				(mid 291.220028 -0.944996)
				(end 290.165028 -0.508)
			)
			(arc
				(start 278.165052 -0.508)
				(mid 277.110052 -0.944996)
				(end 276.673056 -1.999996)
			)
			(xy 276.673056 -11.825732) (xy 277.180548 -11.825732)
			(arc
				(start 277.180548 -1.999996)
				(mid 277.468903 -1.303847)
				(end 278.165052 -1.015492)
			)
			(arc
				(start 290.165028 -1.015492)
				(mid 290.861177 -1.303847)
				(end 291.149532 -1.999996)
			)
			(arc
				(start 291.149532 -11.850116)
				(mid 291.739945 -13.275118)
				(end 293.165022 -13.865352)
			)
			(xy 300.40453 -13.865352)
		)
		(stroke
			(width 0)
			(type solid)
		)
		(fill yes)
		(layer "In7.Cu")
		(net "GND")
	)
	(gr_poly
		(pts
			(xy 442.67882 -13.82903) (xy 442.67882 -13.394436) (xy 442.642498 -13.358114)
			(arc
				(start 435.265068 -13.358114)
				(mid 434.198752 -12.916432)
				(end 433.75707 -11.850116)
			)
			(arc
				(start 433.75707 -1.999996)
				(mid 433.320074 -0.944996)
				(end 432.265074 -0.508)
			)
			(arc
				(start 420.265098 -0.508)
				(mid 419.210098 -0.944996)
				(end 418.773102 -1.999996)
			)
			(xy 418.773102 -11.73734) (xy 419.28034 -11.73734)
			(arc
				(start 419.28034 -1.999996)
				(mid 419.568605 -1.303936)
				(end 420.26459 -1.015492)
			)
			(arc
				(start 432.265074 -1.015492)
				(mid 432.961313 -1.303831)
				(end 433.249832 -1.999996)
			)
			(arc
				(start 433.249832 -11.850116)
				(mid 433.840081 -13.275103)
				(end 435.265068 -13.865352)
			)
			(xy 442.642498 -13.865352)
		)
		(stroke
			(width 0)
			(type solid)
		)
		(fill yes)
		(layer "In7.Cu")
		(net "GND")
	)
	(gr_poly
		(pts
			(xy 248.61139 -13.829538) (xy 248.61139 -13.393928) (xy 248.575576 -13.358114)
			(arc
				(start 241.164872 -13.358114)
				(mid 240.098721 -12.916342)
				(end 239.656874 -11.850116)
			)
			(arc
				(start 239.656874 -1.999996)
				(mid 239.219878 -0.944996)
				(end 238.164878 -0.508)
			)
			(arc
				(start 214.065104 -0.508)
				(mid 213.010104 -0.944996)
				(end 212.573108 -1.999996)
			)
			(xy 212.573108 -11.851132) (xy 212.571584 -11.91895) (xy 213.07933 -11.91895) (xy 213.0806 -11.850116)
			(arc
				(start 213.0806 -1.999996)
				(mid 213.368955 -1.303847)
				(end 214.065104 -1.015492)
			)
			(arc
				(start 238.164878 -1.015492)
				(mid 238.861117 -1.303831)
				(end 239.149636 -1.999996)
			)
			(arc
				(start 239.149636 -11.850116)
				(mid 239.73987 -13.275193)
				(end 241.164872 -13.865352)
			)
			(xy 248.575576 -13.865352)
		)
		(stroke
			(width 0)
			(type solid)
		)
		(fill yes)
		(layer "In7.Cu")
		(net "GND")
	)
	(gr_poly
		(pts
			(xy 274.599654 -13.810742) (xy 274.599654 -13.412724) (xy 274.545044 -13.358114)
			(arc
				(start 267.165074 -13.358114)
				(mid 266.098758 -12.916432)
				(end 265.657076 -11.850116)
			)
			(arc
				(start 265.657076 -1.999996)
				(mid 265.22008 -0.944996)
				(end 264.16508 -0.508)
			)
			(arc
				(start 252.165104 -0.508)
				(mid 251.110104 -0.944996)
				(end 250.673108 -1.999996)
			)
			(xy 250.673108 -11.850116) (xy 250.673108 -11.851386) (xy 251.1806 -11.851386) (xy 251.1806 -11.850116)
			(arc
				(start 251.1806 -1.999996)
				(mid 251.468955 -1.303847)
				(end 252.165104 -1.015492)
			)
			(arc
				(start 264.16508 -1.015492)
				(mid 264.861229 -1.303847)
				(end 265.149584 -1.999996)
			)
			(arc
				(start 265.149584 -11.850116)
				(mid 265.739997 -13.275118)
				(end 267.165074 -13.865352)
			)
			(xy 274.545044 -13.865352)
		)
		(stroke
			(width 0)
			(type solid)
		)
		(fill yes)
		(layer "In7.Cu")
		(net "GND")
	)
	(gr_poly
		(pts
			(xy 239.563402 -205.590394) (xy 239.62106 -205.52918) (xy 239.628172 -205.509876) (xy 239.627664 -205.499208)
			(arc
				(start 239.627156 -205.47711)
				(mid 239.730323 -205.216199)
				(end 239.984026 -205.096364)
			)
			(xy 239.993932 -205.095856) (xy 240.011204 -205.087728)
			(arc
				(start 240.065306 -205.029816)
				(mid 240.075639 -205.013757)
				(end 240.079276 -204.995018)
			)
			(arc
				(start 240.079276 -201.549)
				(mid 240.109253 -201.364019)
				(end 240.196116 -201.197972)
			)
			(arc
				(start 240.196116 -201.197972)
				(mid 240.203669 -201.183556)
				(end 240.206276 -201.167492)
			)
			(xy 240.206276 -200.2536)
			(arc
				(start 240.206276 -200.24344)
				(mid 240.191397 -200.207519)
				(end 240.155476 -200.19264)
			)
			(arc
				(start 239.886236 -200.19264)
				(mid 239.862297 -200.198634)
				(end 239.844072 -200.215246)
			)
			(xy 239.78997 -200.296018) (xy 239.78743 -200.321164)
			(arc
				(start 239.792256 -200.333102)
				(mid 239.813879 -200.404451)
				(end 239.821212 -200.478644)
			)
			(arc
				(start 239.821212 -200.478644)
				(mid 239.709471 -200.748411)
				(end 239.439704 -200.860152)
			)
			(arc
				(start 239.439704 -200.860152)
				(mid 239.210883 -200.783976)
				(end 239.073436 -200.585832)
			)
			(xy 239.069626 -200.572624) (xy 239.050576 -200.554082)
			(arc
				(start 238.952786 -200.52919)
				(mid 238.926768 -200.529354)
				(end 238.904272 -200.542398)
			)
			(arc
				(start 237.352586 -202.094084)
				(mid 237.341475 -202.110618)
				(end 237.3376 -202.130152)
			)
			(arc
				(start 237.3376 -202.513438)
				(mid 237.338149 -202.521148)
				(end 237.339886 -202.528678)
			)
			(xy 237.346744 -202.550014)
			(arc
				(start 237.350554 -202.55611)
				(mid 237.414454 -202.767438)
				(end 237.350554 -202.978766)
			)
			(xy 237.346744 -202.984862)
			(arc
				(start 237.339886 -203.006198)
				(mid 237.338174 -203.013732)
				(end 237.3376 -203.021438)
			)
			(arc
				(start 237.3376 -205.017878)
				(mid 237.341501 -205.037401)
				(end 237.352586 -205.053946)
			)
			(arc
				(start 237.788704 -205.490318)
				(mid 237.811564 -205.503586)
				(end 237.83798 -205.503526)
			)
			(xy 237.842806 -205.502002) (xy 237.94339 -205.463902) (xy 237.960916 -205.440026)
			(arc
				(start 237.961932 -205.42504)
				(mid 238.081662 -205.171157)
				(end 238.342678 -205.067916)
			)
			(arc
				(start 238.342678 -205.067916)
				(mid 238.612445 -205.179657)
				(end 238.724186 -205.449424)
			)
			(arc
				(start 238.724186 -205.449424)
				(mid 238.72355 -205.471432)
				(end 238.721646 -205.493366)
			)
			(xy 238.720376 -205.504034) (xy 238.72698 -205.524862)
			(arc
				(start 238.77524 -205.578964)
				(mid 238.792386 -205.591334)
				(end 238.813086 -205.595728)
			)
			(xy 239.557306 -205.595728)
		)
		(stroke
			(width 0)
			(type solid)
		)
		(fill yes)
		(layer "In7.Cu")
		(net "GND")
	)
	(gr_poly
		(pts
			(xy 416.458146 -13.816076) (xy 416.458146 -13.40739) (xy 416.40887 -13.358114)
			(arc
				(start 409.26512 -13.358114)
				(mid 408.198804 -12.916432)
				(end 407.757122 -11.850116)
			)
			(arc
				(start 407.757122 -1.999996)
				(mid 407.320126 -0.944996)
				(end 406.265126 -0.508)
			)
			(arc
				(start 394.264896 -0.508)
				(mid 393.209896 -0.944996)
				(end 392.7729 -1.999996)
			)
			(arc
				(start 392.7729 -11.850116)
				(mid 392.702216 -12.306469)
				(end 392.496802 -12.720066)
			)
			(xy 392.496802 -12.748514) (xy 392.499088 -12.7508)
			(arc
				(start 393.067794 -12.7508)
				(mid 393.226496 -12.312827)
				(end 393.280392 -11.850116)
			)
			(arc
				(start 393.280392 -1.999996)
				(mid 393.568747 -1.303847)
				(end 394.264896 -1.015492)
			)
			(arc
				(start 406.265126 -1.015492)
				(mid 406.961365 -1.303831)
				(end 407.249884 -1.999996)
			)
			(arc
				(start 407.249884 -11.850116)
				(mid 407.840133 -13.275103)
				(end 409.26512 -13.865352)
			)
			(xy 416.40887 -13.865352)
		)
		(stroke
			(width 0)
			(type solid)
		)
		(fill yes)
		(layer "In7.Cu")
		(net "GND")
	)
	(gr_poly
		(pts
			(xy 364.71606 -13.770102) (xy 364.71606 -13.453364) (xy 364.62081 -13.358114)
			(arc
				(start 357.26497 -13.358114)
				(mid 356.198654 -12.916432)
				(end 355.756972 -11.850116)
			)
			(arc
				(start 355.756972 -1.999996)
				(mid 355.319976 -0.944996)
				(end 354.264976 -0.508)
			)
			(arc
				(start 330.164948 -0.508)
				(mid 329.109948 -0.944996)
				(end 328.672952 -1.999996)
			)
			(arc
				(start 328.672952 -11.850116)
				(mid 328.570197 -12.397292)
				(end 328.27595 -12.869926)
			)
			(xy 328.27595 -12.876784) (xy 328.28738 -12.888214) (xy 328.885042 -12.888214)
			(arc
				(start 328.90333 -12.869926)
				(mid 329.10994 -12.378512)
				(end 329.180444 -11.850116)
			)
			(arc
				(start 329.180444 -1.999996)
				(mid 329.468799 -1.303847)
				(end 330.164948 -1.015492)
			)
			(arc
				(start 354.264976 -1.015492)
				(mid 354.961125 -1.303847)
				(end 355.24948 -1.999996)
			)
			(arc
				(start 355.24948 -11.850116)
				(mid 355.839893 -13.275118)
				(end 357.26497 -13.865352)
			)
			(xy 364.62081 -13.865352)
		)
		(stroke
			(width 0)
			(type solid)
		)
		(fill yes)
		(layer "In7.Cu")
		(net "GND")
	)
	(gr_poly
		(pts
			(xy 390.499092 -13.810996) (xy 390.499092 -13.41247) (xy 390.444736 -13.358114)
			(arc
				(start 383.264918 -13.358114)
				(mid 382.198602 -12.916432)
				(end 381.75692 -11.850116)
			)
			(arc
				(start 381.75692 -1.999996)
				(mid 381.319924 -0.944996)
				(end 380.264924 -0.508)
			)
			(arc
				(start 368.264948 -0.508)
				(mid 367.209948 -0.944996)
				(end 366.772952 -1.999996)
			)
			(arc
				(start 366.772952 -11.850116)
				(mid 366.670132 -12.397459)
				(end 366.375696 -12.87018)
			)
			(xy 366.375696 -12.899644) (xy 366.434878 -12.958826) (xy 366.914684 -12.958826)
			(arc
				(start 367.00333 -12.87018)
				(mid 367.209881 -12.378884)
				(end 367.280444 -11.850624)
			)
			(arc
				(start 367.280444 -1.999996)
				(mid 367.568799 -1.303847)
				(end 368.264948 -1.015492)
			)
			(arc
				(start 380.264924 -1.015492)
				(mid 380.961073 -1.303847)
				(end 381.249428 -1.999996)
			)
			(arc
				(start 381.249428 -11.850116)
				(mid 381.839841 -13.275118)
				(end 383.264918 -13.865352)
			)
			(xy 390.444736 -13.865352)
		)
		(stroke
			(width 0)
			(type solid)
		)
		(fill yes)
		(layer "In7.Cu")
		(net "GND")
	)
	(gr_poly
		(pts
			(xy 326.45985 -13.852906) (xy 326.45985 -13.37945) (xy 326.438514 -13.358114)
			(arc
				(start 319.16497 -13.358114)
				(mid 318.098654 -12.916432)
				(end 317.656972 -11.850116)
			)
			(arc
				(start 317.656972 -1.999996)
				(mid 317.219976 -0.944996)
				(end 316.164976 -0.508)
			)
			(arc
				(start 304.165 -0.508)
				(mid 303.11 -0.944996)
				(end 302.673004 -1.999996)
			)
			(arc
				(start 302.673004 -11.850116)
				(mid 302.577528 -12.378214)
				(end 302.30318 -12.839446)
			)
			(xy 302.30318 -12.884912) (xy 302.304196 -12.885928) (xy 302.874426 -12.885928)
			(arc
				(start 302.920908 -12.839446)
				(mid 303.114524 -12.361527)
				(end 303.180496 -11.850116)
			)
			(arc
				(start 303.180496 -1.999996)
				(mid 303.468851 -1.303847)
				(end 304.165 -1.015492)
			)
			(arc
				(start 316.164976 -1.015492)
				(mid 316.861125 -1.303847)
				(end 317.14948 -1.999996)
			)
			(arc
				(start 317.14948 -11.850116)
				(mid 317.739893 -13.275118)
				(end 319.16497 -13.865352)
			)
			(xy 326.438514 -13.865352) (xy 326.447404 -13.865352)
		)
		(stroke
			(width 0)
			(type solid)
		)
		(fill yes)
		(layer "In7.Cu")
		(net "GND")
	)
	(gr_poly
		(pts
			(arc
				(start 113.337594 -97.298002)
				(mid 113.364572 -97.311989)
				(end 113.394744 -97.308162)
			)
			(xy 113.495836 -97.261934) (xy 113.512092 -97.234502) (xy 113.510822 -97.218754)
			(arc
				(start 113.509806 -97.190814)
				(mid 113.546562 -97.027372)
				(end 113.64976 -96.895412)
			)
			(xy 113.658904 -96.888046) (xy 113.66881 -96.86671) (xy 113.66627 -96.763078) (xy 113.655602 -96.742504)
			(arc
				(start 113.646204 -96.735392)
				(mid 113.562712 -96.64982)
				(end 113.509806 -96.542606)
			)
			(xy 113.507774 -96.536764) (xy 113.501424 -96.526096)
			(arc
				(start 112.058704 -95.083376)
				(mid 111.986838 -94.975682)
				(end 111.961676 -94.84868)
			)
			(arc
				(start 111.961676 -94.227142)
				(mid 111.957726 -94.207755)
				(end 111.94669 -94.191328)
			)
			(arc
				(start 111.040672 -93.28531)
				(mid 111.024255 -93.274248)
				(end 111.004858 -93.270324)
			)
			(arc
				(start 107.265978 -93.270324)
				(mid 107.245027 -93.274961)
				(end 107.227878 -93.28785)
			)
			(xy 107.17022 -93.353636) (xy 107.16387 -93.374464)
			(arc
				(start 107.165394 -93.38564)
				(mid 107.167882 -93.410858)
				(end 107.168696 -93.436186)
			)
			(arc
				(start 107.168696 -93.436186)
				(mid 106.787188 -93.817694)
				(end 106.40568 -93.436186)
			)
			(arc
				(start 106.40568 -93.436186)
				(mid 106.406488 -93.410858)
				(end 106.408982 -93.38564)
			)
			(xy 106.410506 -93.374464) (xy 106.404156 -93.353636)
			(arc
				(start 106.346498 -93.28785)
				(mid 106.329339 -93.274983)
				(end 106.308398 -93.270324)
			)
			(arc
				(start 105.830624 -93.270324)
				(mid 105.703625 -93.245156)
				(end 105.595928 -93.173296)
			)
			(arc
				(start 104.644952 -92.22232)
				(mid 104.573086 -92.114626)
				(end 104.547924 -91.987624)
			)
			(arc
				(start 104.547924 -91.05265)
				(mid 104.539322 -91.024366)
				(end 104.516428 -91.00566)
			)
			(xy 104.50195 -90.999818) (xy 104.472232 -91.00566)
			(arc
				(start 104.17556 -91.302332)
				(mid 104.164634 -91.318778)
				(end 104.160828 -91.338146)
			)
			(arc
				(start 104.160828 -93.073728)
				(mid 104.164661 -93.093085)
				(end 104.17556 -93.109542)
			)
			(arc
				(start 104.281224 -93.21546)
				(mid 104.298968 -93.2269)
				(end 104.319832 -93.230192)
			)
			(xy 104.406192 -93.22562) (xy 104.425242 -93.215968)
			(arc
				(start 104.4321 -93.207332)
				(mid 104.56443 -93.103026)
				(end 104.728772 -93.065854)
			)
			(arc
				(start 104.728772 -93.065854)
				(mid 104.998539 -93.177595)
				(end 105.11028 -93.447362)
			)
			(arc
				(start 105.11028 -93.447362)
				(mid 105.073098 -93.611699)
				(end 104.968802 -93.744034)
			)
			(xy 104.960166 -93.750892) (xy 104.950514 -93.769942)
			(arc
				(start 104.945942 -93.856302)
				(mid 104.949189 -93.877183)
				(end 104.960674 -93.89491)
			)
			(arc
				(start 105.414064 -94.348046)
				(mid 105.430481 -94.359108)
				(end 105.449878 -94.363032)
			)
			(arc
				(start 109.085634 -94.363032)
				(mid 109.109339 -94.357028)
				(end 109.127544 -94.34068)
			)
			(xy 109.182154 -94.260924) (xy 109.184948 -94.23654)
			(arc
				(start 109.180376 -94.224602)
				(mid 109.157139 -94.142987)
				(end 109.149388 -94.058486)
			)
			(arc
				(start 109.149388 -94.058486)
				(mid 109.283432 -93.734748)
				(end 109.607096 -93.600524)
			)
			(arc
				(start 110.470696 -93.600524)
				(mid 110.794434 -93.734673)
				(end 110.928404 -94.058486)
			)
			(arc
				(start 110.928404 -94.058486)
				(mid 110.863556 -94.293667)
				(end 110.687104 -94.462092)
			)
			(xy 110.676436 -94.46768) (xy 110.662466 -94.487492)
			(arc
				(start 110.64875 -94.579948)
				(mid 110.650822 -94.603387)
				(end 110.663228 -94.623382)
			)
		)
		(stroke
			(width 0)
			(type solid)
		)
		(fill yes)
		(layer "In7.Cu")
		(net "GND")
	)
	(gr_poly
		(pts
			(xy 382.470406 -270.89989) (xy 382.469904 -270.80457) (xy 382.461867 -270.614099) (xy 382.445808 -270.424136)
			(xy 382.421755 -270.23502) (xy 382.38975 -270.047085) (xy 382.349852 -269.860667) (xy 382.30213 -269.676096)
			(xy 382.24667 -269.493701) (xy 382.18357 -269.313806) (xy 382.112943 -269.136732) (xy 382.034913 -268.962792)
			(xy 381.94962 -268.792296) (xy 381.857215 -268.625547) (xy 381.757863 -268.462843) (xy 381.65174 -268.304471)
			(xy 381.539035 -268.150713) (xy 381.419949 -268.001844) (xy 381.294692 -267.858127) (xy 381.163488 -267.719819)
			(xy 381.026571 -267.587164) (xy 380.884182 -267.460399) (xy 380.736577 -267.33975) (xy 380.584016 -267.225431)
			(xy 380.426772 -267.117644) (xy 380.265123 -267.016582) (xy 380.099358 -266.922425) (xy 379.929771 -266.835339)
			(xy 379.756663 -266.75548) (xy 379.580343 -266.68299) (xy 379.401124 -266.617997) (xy 379.219324 -266.560617)
			(xy 379.035266 -266.510952) (xy 378.849279 -266.469091) (xy 378.661692 -266.435107) (xy 378.472839 -266.409062)
			(xy 378.283056 -266.391001) (xy 378.092681 -266.380956) (xy 377.902051 -266.378947) (xy 377.711506 -266.384975)
			(xy 377.521385 -266.399031) (xy 377.332025 -266.421089) (xy 377.143764 -266.45111) (xy 376.956935 -266.489041)
			(xy 376.771871 -266.534814) (xy 376.588902 -266.588348) (xy 376.408352 -266.649548) (xy 376.230543 -266.718305)
			(xy 376.05579 -266.794497) (xy 375.884404 -266.877988) (xy 375.716691 -266.96863) (xy 375.552948 -267.066261)
			(xy 375.393466 -267.170708) (xy 375.238529 -267.281786) (xy 375.088413 -267.399297) (xy 374.943383 -267.523031)
			(xy 374.803699 -267.65277) (xy 374.669609 -267.788281) (xy 374.54135 -267.929325) (xy 374.419151 -268.075651)
			(xy 374.30323 -268.226998) (xy 374.193791 -268.383097) (xy 374.091031 -268.543671) (xy 373.995131 -268.708435)
			(xy 373.906263 -268.877094) (xy 373.824583 -269.04935) (xy 373.750238 -269.224897) (xy 373.68336 -269.403421)
			(xy 373.624066 -269.584606) (xy 373.572464 -269.76813) (xy 373.528644 -269.953665) (xy 373.492685 -270.140884)
			(xy 373.46465 -270.329451) (xy 373.444589 -270.519033) (xy 373.432539 -270.709292) (xy 373.42852 -270.89989)
			(xy 375.182393 -270.89989) (xy 375.186382 -270.75135) (xy 375.198339 -270.603237) (xy 375.218229 -270.45598)
			(xy 375.245994 -270.310004) (xy 375.281555 -270.165727) (xy 375.324809 -270.023568) (xy 375.375631 -269.883935)
			(xy 375.433875 -269.747232) (xy 375.499373 -269.613852) (xy 375.571936 -269.48418) (xy 375.651354 -269.35859)
			(xy 375.737399 -269.237443) (xy 375.829823 -269.12109) (xy 375.928359 -269.009866) (xy 376.032723 -268.904091)
			(xy 376.142615 -268.804071) (xy 376.257716 -268.710093) (xy 376.377696 -268.622429) (xy 376.502209 -268.541332)
			(xy 376.630895 -268.467035) (xy 376.763384 -268.399753) (xy 376.899293 -268.339679) (xy 377.038231 -268.286987)
			(xy 377.179797 -268.241828) (xy 377.323583 -268.204333) (xy 377.469174 -268.174611) (xy 377.61615 -268.152746)
			(xy 377.764089 -268.138802) (xy 377.912562 -268.132818) (xy 378.061143 -268.134813) (xy 378.209402 -268.144781)
			(xy 378.356913 -268.162692) (xy 378.503249 -268.188495) (xy 378.64799 -268.222115) (xy 378.790717 -268.263457)
			(xy 378.93102 -268.3124) (xy 379.068493 -268.368803) (xy 379.20274 -268.432504) (xy 379.333375 -268.50332)
			(xy 379.46002 -268.581045) (xy 379.58231 -268.665456) (xy 379.699893 -268.756309) (xy 379.81243 -268.853343)
			(xy 379.919597 -268.956278) (xy 380.021084 -269.064817) (xy 380.116598 -269.178646) (xy 380.205865 -269.297439)
			(xy 380.288626 -269.420851) (xy 380.364644 -269.548529) (xy 380.433699 -269.680102) (xy 380.495592 -269.815193)
			(xy 380.550145 -269.95341) (xy 380.5972 -270.094357) (xy 380.636622 -270.237627) (xy 380.668296 -270.382806)
			(xy 380.692132 -270.529475) (xy 380.708061 -270.677213) (xy 380.716037 -270.825593) (xy 380.716536 -270.89989)
			(xy 380.716037 -270.974187) (xy 380.708061 -271.122567) (xy 380.692132 -271.270305) (xy 380.668296 -271.416974)
			(xy 380.636622 -271.562153) (xy 380.5972 -271.705423) (xy 380.550145 -271.84637) (xy 380.495592 -271.984587)
			(xy 380.433699 -272.119678) (xy 380.364644 -272.251251) (xy 380.288626 -272.378929) (xy 380.205865 -272.502341)
			(xy 380.116598 -272.621134) (xy 380.021084 -272.734963) (xy 379.919597 -272.843502) (xy 379.81243 -272.946437)
			(xy 379.699893 -273.043471) (xy 379.58231 -273.134324) (xy 379.46002 -273.218735) (xy 379.333375 -273.29646)
			(xy 379.20274 -273.367276) (xy 379.068493 -273.430977) (xy 378.93102 -273.48738) (xy 378.790717 -273.536323)
			(xy 378.64799 -273.577665) (xy 378.503249 -273.611285) (xy 378.356913 -273.637088) (xy 378.209402 -273.654999)
			(xy 378.061143 -273.664967) (xy 377.912562 -273.666962) (xy 377.764089 -273.660978) (xy 377.61615 -273.647034)
			(xy 377.469174 -273.625169) (xy 377.323583 -273.595447) (xy 377.179797 -273.557952) (xy 377.038231 -273.512793)
			(xy 376.899293 -273.460101) (xy 376.763384 -273.400027) (xy 376.630895 -273.332745) (xy 376.502209 -273.258448)
			(xy 376.377696 -273.177351) (xy 376.257716 -273.089687) (xy 376.142615 -272.995709) (xy 376.032723 -272.895689)
			(xy 375.928359 -272.789914) (xy 375.829823 -272.67869) (xy 375.737399 -272.562337) (xy 375.651354 -272.44119)
			(xy 375.571936 -272.3156) (xy 375.499373 -272.185928) (xy 375.433875 -272.052548) (xy 375.375631 -271.915845)
			(xy 375.324809 -271.776212) (xy 375.281555 -271.634053) (xy 375.245994 -271.489776) (xy 375.218229 -271.3438)
			(xy 375.198339 -271.196543) (xy 375.186382 -271.04843) (xy 375.182393 -270.89989) (xy 373.42852 -270.89989)
			(xy 373.432539 -271.090488) (xy 373.444589 -271.280747) (xy 373.46465 -271.470329) (xy 373.492685 -271.658896)
			(xy 373.528644 -271.846115) (xy 373.572464 -272.03165) (xy 373.624066 -272.215174) (xy 373.68336 -272.396359)
			(xy 373.750238 -272.574883) (xy 373.824583 -272.75043) (xy 373.906263 -272.922686) (xy 373.995131 -273.091345)
			(xy 374.091031 -273.256109) (xy 374.193791 -273.416683) (xy 374.30323 -273.572782) (xy 374.419151 -273.724129)
			(xy 374.54135 -273.870455) (xy 374.669609 -274.011499) (xy 374.803699 -274.14701) (xy 374.943383 -274.276749)
			(xy 375.088413 -274.400483) (xy 375.238529 -274.517994) (xy 375.393466 -274.629072) (xy 375.552948 -274.733519)
			(xy 375.716691 -274.83115) (xy 375.884404 -274.921792) (xy 376.05579 -275.005283) (xy 376.230543 -275.081475)
			(xy 376.408352 -275.150232) (xy 376.588902 -275.211432) (xy 376.771871 -275.264966) (xy 376.956935 -275.310739)
			(xy 377.143764 -275.34867) (xy 377.332025 -275.378691) (xy 377.521385 -275.400749) (xy 377.711506 -275.414805)
			(xy 377.902051 -275.420833) (xy 378.092681 -275.418824) (xy 378.283056 -275.408779) (xy 378.472839 -275.390718)
			(xy 378.661692 -275.364673) (xy 378.849279 -275.330689) (xy 379.035266 -275.288828) (xy 379.219324 -275.239163)
			(xy 379.401124 -275.181783) (xy 379.580343 -275.11679) (xy 379.756663 -275.0443) (xy 379.929771 -274.964441)
			(xy 380.099358 -274.877355) (xy 380.265123 -274.783198) (xy 380.426772 -274.682136) (xy 380.584016 -274.574349)
			(xy 380.736577 -274.46003) (xy 380.884182 -274.339381) (xy 381.026571 -274.212616) (xy 381.163488 -274.079961)
			(xy 381.294692 -273.941653) (xy 381.419949 -273.797936) (xy 381.539035 -273.649067) (xy 381.65174 -273.495309)
			(xy 381.757863 -273.336937) (xy 381.857215 -273.174233) (xy 381.94962 -273.007484) (xy 382.034913 -272.836988)
			(xy 382.112943 -272.663048) (xy 382.18357 -272.485974) (xy 382.24667 -272.306079) (xy 382.30213 -272.123684)
			(xy 382.349852 -271.939113) (xy 382.38975 -271.752695) (xy 382.421755 -271.56476) (xy 382.445808 -271.375644)
			(xy 382.461867 -271.185681) (xy 382.469904 -270.99521)
		)
		(stroke
			(width 0)
			(type solid)
		)
		(fill yes)
		(layer "In7.Cu")
		(net "GND")
	)
	(gr_poly
		(pts
			(arc
				(start 235.636562 -413.132016)
				(mid 235.656085 -413.128115)
				(end 235.67263 -413.11703)
			)
			(arc
				(start 236.812328 -411.977332)
				(mid 236.823439 -411.960798)
				(end 236.827314 -411.941264)
			)
			(arc
				(start 236.827314 -402.776436)
				(mid 236.831215 -402.756913)
				(end 236.8423 -402.740368)
			)
			(arc
				(start 238.886238 -400.69643)
				(mid 238.902772 -400.685319)
				(end 238.922306 -400.681444)
			)
			(arc
				(start 242.916964 -400.681444)
				(mid 242.936487 -400.677543)
				(end 242.953032 -400.666458)
			)
			(arc
				(start 243.86286 -399.75663)
				(mid 243.873971 -399.740096)
				(end 243.877846 -399.720562)
			)
			(arc
				(start 243.877846 -392.486896)
				(mid 243.881747 -392.467373)
				(end 243.892832 -392.450828)
			)
			(xy 243.896388 -392.447272)
			(arc
				(start 243.896388 -391.97026)
				(mid 243.900289 -391.950737)
				(end 243.911374 -391.934192)
			)
			(arc
				(start 245.02999 -390.815576)
				(mid 245.046524 -390.804465)
				(end 245.066058 -390.80059)
			)
			(arc
				(start 259.092954 -390.80059)
				(mid 259.112477 -390.796689)
				(end 259.129022 -390.785604)
			)
			(arc
				(start 262.060944 -387.853682)
				(mid 262.072055 -387.837148)
				(end 262.07593 -387.817614)
			)
			(arc
				(start 262.07593 -379.165866)
				(mid 262.072029 -379.146343)
				(end 262.060944 -379.129798)
			)
			(arc
				(start 261.987538 -379.056392)
				(mid 261.971004 -379.045281)
				(end 261.95147 -379.041406)
			)
			(xy 243.1415 -379.041406) (xy 243.140484 -379.042422)
			(arc
				(start 240.581688 -379.042422)
				(mid 240.562165 -379.046323)
				(end 240.54562 -379.057408)
			)
			(arc
				(start 239.903 -379.700028)
				(mid 239.886466 -379.711139)
				(end 239.866932 -379.715014)
			)
			(arc
				(start 237.06963 -379.715014)
				(mid 237.050107 -379.711113)
				(end 237.033562 -379.700028)
			)
			(arc
				(start 232.94086 -375.607326)
				(mid 232.929749 -375.590792)
				(end 232.925874 -375.571258)
			)
			(arc
				(start 232.925874 -372.098062)
				(mid 232.921973 -372.078539)
				(end 232.910888 -372.061994)
			)
			(arc
				(start 232.189274 -371.34038)
				(mid 232.178163 -371.323846)
				(end 232.174288 -371.304312)
			)
			(arc
				(start 232.174288 -371.057424)
				(mid 232.170387 -371.037901)
				(end 232.159302 -371.021356)
			)
			(xy 232.119932 -370.981986) (xy 232.118408 -370.981986)
			(arc
				(start 232.015284 -370.878862)
				(mid 232.004173 -370.862328)
				(end 232.000298 -370.842794)
			)
			(arc
				(start 232.000298 -367.379758)
				(mid 231.996397 -367.360235)
				(end 231.985312 -367.34369)
			)
			(arc
				(start 231.905048 -367.263426)
				(mid 231.888514 -367.252315)
				(end 231.86898 -367.24844)
			)
			(arc
				(start 228.707696 -367.24844)
				(mid 228.688173 -367.252341)
				(end 228.671628 -367.263426)
			)
			(arc
				(start 228.614478 -367.320576)
				(mid 228.603367 -367.33711)
				(end 228.599492 -367.356644)
			)
			(arc
				(start 228.599492 -370.828062)
				(mid 228.595591 -370.847585)
				(end 228.584506 -370.86413)
			)
			(arc
				(start 228.431344 -371.017292)
				(mid 228.420233 -371.033826)
				(end 228.416358 -371.05336)
			)
			(arc
				(start 228.416358 -371.446552)
				(mid 228.412457 -371.466075)
				(end 228.401372 -371.48262)
			)
			(arc
				(start 227.137722 -372.74627)
				(mid 227.126611 -372.762804)
				(end 227.122736 -372.782338)
			)
			(arc
				(start 227.122736 -374.248426)
				(mid 227.118835 -374.267949)
				(end 227.10775 -374.284494)
			)
			(arc
				(start 225.693224 -375.69902)
				(mid 225.67669 -375.710131)
				(end 225.657156 -375.714006)
			)
			(arc
				(start 223.582484 -375.714006)
				(mid 223.562961 -375.710105)
				(end 223.546416 -375.69902)
			)
			(arc
				(start 221.539816 -373.69242)
				(mid 221.528705 -373.675886)
				(end 221.52483 -373.656352)
			)
			(arc
				(start 221.52483 -371.070124)
				(mid 221.520929 -371.050601)
				(end 221.509844 -371.034056)
			)
			(arc
				(start 221.337632 -370.861844)
				(mid 221.326521 -370.84531)
				(end 221.322646 -370.825776)
			)
			(arc
				(start 221.322646 -367.359692)
				(mid 221.318745 -367.340169)
				(end 221.30766 -367.323624)
			)
			(arc
				(start 221.24416 -367.260124)
				(mid 221.227626 -367.249013)
				(end 221.208092 -367.245138)
			)
			(arc
				(start 218.078304 -367.245138)
				(mid 218.058781 -367.249039)
				(end 218.042236 -367.260124)
			)
			(arc
				(start 217.916506 -367.385854)
				(mid 217.905395 -367.402388)
				(end 217.90152 -367.421922)
			)
			(arc
				(start 217.90152 -370.80063)
				(mid 217.897619 -370.820153)
				(end 217.886534 -370.836698)
			)
			(arc
				(start 216.72931 -371.993922)
				(mid 216.712776 -372.005033)
				(end 216.693242 -372.008908)
			)
			(arc
				(start 210.338924 -372.008908)
				(mid 210.319401 -372.005007)
				(end 210.302856 -371.993922)
			)
			(arc
				(start 210.054698 -371.745764)
				(mid 210.043587 -371.72923)
				(end 210.039712 -371.709696)
			)
			(arc
				(start 210.039712 -371.274086)
				(mid 210.035811 -371.254563)
				(end 210.024726 -371.238018)
			)
			(arc
				(start 209.986626 -371.199918)
				(mid 209.970063 -371.188944)
				(end 209.950558 -371.185186)
			)
			(arc
				(start 209.475324 -371.185186)
				(mid 209.455801 -371.181285)
				(end 209.439256 -371.1702)
			)
			(arc
				(start 208.832196 -370.56314)
				(mid 208.821085 -370.546606)
				(end 208.81721 -370.527072)
			)
			(arc
				(start 208.81721 -370.46027)
				(mid 208.813309 -370.440747)
				(end 208.802224 -370.424202)
			)
			(xy 208.795366 -370.417344)
			(arc
				(start 208.220056 -370.417344)
				(mid 208.200533 -370.413443)
				(end 208.183988 -370.402358)
			)
			(arc
				(start 208.098898 -370.317268)
				(mid 208.087787 -370.300734)
				(end 208.083912 -370.2812)
			)
			(arc
				(start 208.083912 -367.384584)
				(mid 208.080011 -367.365061)
				(end 208.068926 -367.348516)
			)
			(arc
				(start 207.996028 -367.275618)
				(mid 207.979494 -367.264507)
				(end 207.95996 -367.260632)
			)
			(arc
				(start 204.786484 -367.260632)
				(mid 204.766961 -367.264533)
				(end 204.750416 -367.275618)
			)
			(arc
				(start 204.68082 -367.345214)
				(mid 204.669709 -367.361748)
				(end 204.665834 -367.381282)
			)
			(arc
				(start 204.665834 -370.837714)
				(mid 204.669735 -370.857237)
				(end 204.68082 -370.873782)
			)
			(arc
				(start 204.794104 -370.987066)
				(mid 204.805215 -371.0036)
				(end 204.80909 -371.023134)
			)
			(arc
				(start 204.80909 -372.841012)
				(mid 204.815471 -372.865662)
				(end 204.832966 -372.884192)
			)
			(xy 204.917548 -372.93677) (xy 204.94371 -372.93804)
			(arc
				(start 204.955648 -372.932198)
				(mid 205.037716 -372.902845)
				(end 205.124304 -372.892828)
			)
			(arc
				(start 205.124304 -372.892828)
				(mid 205.505812 -373.274336)
				(end 205.124304 -373.655844)
			)
			(arc
				(start 205.124304 -373.655844)
				(mid 205.037702 -373.645885)
				(end 204.955648 -373.616474)
			)
			(xy 204.94371 -373.610632) (xy 204.917548 -373.611902)
			(arc
				(start 204.832966 -373.66448)
				(mid 204.815396 -373.682968)
				(end 204.80909 -373.70766)
			)
			(arc
				(start 204.80909 -374.498616)
				(mid 204.812991 -374.518139)
				(end 204.824076 -374.534684)
			)
			(arc
				(start 204.905102 -374.61571)
				(mid 204.916213 -374.632244)
				(end 204.920088 -374.651778)
			)
			(arc
				(start 204.920088 -387.060948)
				(mid 204.923989 -387.080471)
				(end 204.935074 -387.097016)
			)
			(arc
				(start 207.491838 -389.65378)
				(mid 207.502949 -389.670314)
				(end 207.506824 -389.689848)
			)
			(arc
				(start 207.506824 -411.710124)
				(mid 207.510725 -411.729647)
				(end 207.52181 -411.746192)
			)
			(arc
				(start 208.892648 -413.11703)
				(mid 208.909182 -413.128141)
				(end 208.928716 -413.132016)
			)
		)
		(stroke
			(width 0)
			(type solid)
		)
		(fill yes)
		(layer "In7.Cu")
		(net "P12V_STBY")
	)
	(gr_poly
		(pts
			(xy 127.237236 -183.07431) (xy 127.246849 -183.073903) (xy 127.264741 -183.066867) (xy 127.272034 -183.060594)
			(xy 127.329946 -183.006492) (xy 127.338074 -182.98922) (xy 127.338582 -182.979568) (xy 127.340854 -182.952302)
			(xy 127.35222 -182.898782) (xy 127.371114 -182.847435) (xy 127.397148 -182.799313) (xy 127.429789 -182.755402)
			(xy 127.468366 -182.716604) (xy 127.51209 -182.683713) (xy 127.560063 -182.657405) (xy 127.611301 -182.638218)
			(xy 127.664755 -182.626546) (xy 127.719328 -182.622629) (xy 127.773901 -182.626546) (xy 127.827355 -182.638218)
			(xy 127.878593 -182.657405) (xy 127.926566 -182.683713) (xy 127.97029 -182.716604) (xy 128.008867 -182.755402)
			(xy 128.041508 -182.799313) (xy 128.067542 -182.847435) (xy 128.086436 -182.898782) (xy 128.097802 -182.952302)
			(xy 128.100074 -182.979568) (xy 128.100582 -182.98922) (xy 128.10871 -183.006492) (xy 128.166622 -183.060594)
			(xy 128.173915 -183.066871) (xy 128.191805 -183.073913) (xy 128.20142 -183.07431) (xy 131.567936 -183.07431)
			(xy 131.578004 -183.073881) (xy 131.5966 -183.066158) (xy 131.604004 -183.059324) (xy 131.844542 -182.818786)
			(xy 131.851393 -182.81139) (xy 131.859131 -182.792791) (xy 131.859528 -182.782718) (xy 131.859528 -181.627272)
			(xy 131.859101 -181.617203) (xy 131.851382 -181.598604) (xy 131.844542 -181.591204) (xy 127.86233 -177.608992)
			(xy 127.854307 -177.601831) (xy 127.834222 -177.594215) (xy 127.823468 -177.59426) (xy 127.736854 -177.59934)
			(xy 127.71755 -177.6095) (xy 127.710692 -177.618136) (xy 127.692497 -177.640401) (xy 127.650554 -177.679729)
			(xy 127.603186 -177.712321) (xy 127.551466 -177.73744) (xy 127.496563 -177.754517) (xy 127.43972 -177.763167)
			(xy 127.410972 -177.763678) (xy 127.38603 -177.76327) (xy 127.336572 -177.756765) (xy 127.288384 -177.743868)
			(xy 127.265176 -177.734722) (xy 127.254254 -177.73015) (xy 127.23114 -177.731674) (xy 127.14097 -177.78222)
			(xy 127.127762 -177.80127) (xy 127.125984 -177.812954) (xy 127.121345 -177.839572) (xy 127.105546 -177.891241)
			(xy 127.082614 -177.940164) (xy 127.053009 -177.985362) (xy 127.017322 -178.02593) (xy 126.976268 -178.061056)
			(xy 126.930668 -178.090038) (xy 126.881435 -178.112296) (xy 126.829554 -178.127385) (xy 126.776063 -178.135001)
			(xy 126.749048 -178.135534) (xy 126.721791 -178.135074) (xy 126.667831 -178.127322) (xy 126.615524 -178.111969)
			(xy 126.565934 -178.089328) (xy 126.520072 -178.059859) (xy 126.478871 -178.024163) (xy 126.443169 -177.982966)
			(xy 126.413695 -177.937108) (xy 126.391047 -177.887521) (xy 126.375688 -177.835216) (xy 126.367929 -177.781257)
			(xy 126.367929 -177.726743) (xy 126.375688 -177.672784) (xy 126.391047 -177.620479) (xy 126.413695 -177.570892)
			(xy 126.443169 -177.525034) (xy 126.478871 -177.483837) (xy 126.520072 -177.448141) (xy 126.565934 -177.418672)
			(xy 126.615524 -177.396031) (xy 126.667831 -177.380678) (xy 126.721791 -177.372926) (xy 126.749048 -177.372518)
			(xy 126.77399 -177.372927) (xy 126.823447 -177.379435) (xy 126.871633 -177.392334) (xy 126.894844 -177.401474)
			(xy 126.905766 -177.406046) (xy 126.92888 -177.404522) (xy 127.01905 -177.353976) (xy 127.032258 -177.334926)
			(xy 127.034036 -177.323242) (xy 127.038674 -177.296622) (xy 127.054472 -177.244948) (xy 127.077403 -177.19602)
			(xy 127.107007 -177.150816) (xy 127.142693 -177.110242) (xy 127.183746 -177.075108) (xy 127.229345 -177.046117)
			(xy 127.278578 -177.02385) (xy 127.330461 -177.008752) (xy 127.383955 -177.001124) (xy 127.410972 -177.000662)
			(xy 127.438079 -177.001118) (xy 127.49175 -177.008768) (xy 127.517906 -177.015902) (xy 127.52959 -177.019458)
			(xy 127.552958 -177.01514) (xy 127.627634 -176.959006) (xy 127.63674 -176.951404) (xy 127.647332 -176.930212)
			(xy 127.647954 -176.918366) (xy 127.647954 -171.388024) (xy 127.647516 -171.377961) (xy 127.639777 -171.359381)
			(xy 127.632968 -171.351956) (xy 127.431038 -171.150026) (xy 127.423637 -171.143187) (xy 127.405039 -171.135471)
			(xy 127.39497 -171.13504) (xy 125.311916 -171.13504) (xy 125.301854 -171.13548) (xy 125.283275 -171.14322)
			(xy 125.275848 -171.150026) (xy 124.533152 -171.892722) (xy 124.526304 -171.900119) (xy 124.518569 -171.918718)
			(xy 124.518166 -171.92879) (xy 124.518166 -179.203096) (xy 126.797562 -179.203096) (xy 126.798048 -179.175845)
			(xy 126.805804 -179.121897) (xy 126.821159 -179.069602) (xy 126.843801 -179.020025) (xy 126.873267 -178.974175)
			(xy 126.908958 -178.932984) (xy 126.950149 -178.897293) (xy 126.995999 -178.867827) (xy 127.045576 -178.845185)
			(xy 127.097871 -178.82983) (xy 127.151819 -178.822074) (xy 127.206321 -178.822074) (xy 127.260269 -178.82983)
			(xy 127.312564 -178.845185) (xy 127.362141 -178.867827) (xy 127.407991 -178.897293) (xy 127.449182 -178.932984)
			(xy 127.484873 -178.974175) (xy 127.514339 -179.020025) (xy 127.536981 -179.069602) (xy 127.552336 -179.121897)
			(xy 127.560092 -179.175845) (xy 127.560578 -179.203096) (xy 127.56005 -179.230697) (xy 127.55212 -179.285327)
			(xy 127.536395 -179.338242) (xy 127.513204 -179.388336) (xy 127.483033 -179.434564) (xy 127.446511 -179.475957)
			(xy 127.404403 -179.511652) (xy 127.381254 -179.526692) (xy 127.369055 -179.534986) (xy 127.349584 -179.557122)
			(xy 127.337247 -179.583899) (xy 127.333072 -179.613083) (xy 127.337409 -179.642244) (xy 127.349894 -179.668952)
			(xy 127.369488 -179.69098) (xy 127.381762 -179.699158) (xy 127.405094 -179.714179) (xy 127.447593 -179.749855)
			(xy 127.484474 -179.791313) (xy 127.514959 -179.837676) (xy 127.538406 -179.887967) (xy 127.554319 -179.941124)
			(xy 127.562363 -179.996026) (xy 127.562864 -180.02377) (xy 127.562378 -180.051021) (xy 127.554622 -180.104969)
			(xy 127.539267 -180.157264) (xy 127.516625 -180.206841) (xy 127.487159 -180.252691) (xy 127.451468 -180.293882)
			(xy 127.410277 -180.329573) (xy 127.364427 -180.359039) (xy 127.31485 -180.381681) (xy 127.262555 -180.397036)
			(xy 127.208607 -180.404792) (xy 127.154105 -180.404792) (xy 127.100157 -180.397036) (xy 127.047862 -180.381681)
			(xy 126.998285 -180.359039) (xy 126.952435 -180.329573) (xy 126.911244 -180.293882) (xy 126.875553 -180.252691)
			(xy 126.846087 -180.206841) (xy 126.823445 -180.157264) (xy 126.80809 -180.104969) (xy 126.800334 -180.051021)
			(xy 126.799848 -180.02377) (xy 126.800337 -179.996167) (xy 126.808273 -179.941535) (xy 126.824004 -179.888619)
			(xy 126.8472 -179.838524) (xy 126.877378 -179.792297) (xy 126.913906 -179.750905) (xy 126.95602 -179.715212)
			(xy 126.979172 -179.700174) (xy 126.991411 -179.69193) (xy 127.010898 -179.669787) (xy 127.023244 -179.642998)
			(xy 127.027418 -179.613799) (xy 127.023071 -179.584624) (xy 127.010568 -179.557909) (xy 126.99095 -179.535882)
			(xy 126.978664 -179.527708) (xy 126.955323 -179.512701) (xy 126.912823 -179.477023) (xy 126.875941 -179.435564)
			(xy 126.845456 -179.389199) (xy 126.822011 -179.338905) (xy 126.8061 -179.285745) (xy 126.798061 -179.230841)
			(xy 126.797562 -179.203096) (xy 124.518166 -179.203096) (xy 124.518166 -181.275736) (xy 124.518597 -181.285802)
			(xy 124.526328 -181.304391) (xy 124.533152 -181.311804) (xy 124.996956 -181.775608) (xy 127.458976 -181.775608)
			(xy 127.463047 -181.719986) (xy 127.475173 -181.665549) (xy 127.495096 -181.613458) (xy 127.522392 -181.564823)
			(xy 127.556478 -181.52068) (xy 127.596627 -181.481971) (xy 127.641985 -181.44952) (xy 127.691585 -181.424019)
			(xy 127.744369 -181.406012) (xy 127.799212 -181.395882) (xy 127.854946 -181.393845) (xy 127.910383 -181.399945)
			(xy 127.96434 -181.414051) (xy 128.015669 -181.435863) (xy 128.063275 -181.464917) (xy 128.106143 -181.500592)
			(xy 128.14336 -181.542129) (xy 128.174133 -181.588642) (xy 128.197805 -181.639139) (xy 128.213873 -181.692546)
			(xy 128.221993 -181.747722) (xy 128.222502 -181.775608) (xy 128.221993 -181.803494) (xy 128.213873 -181.85867)
			(xy 128.197805 -181.912077) (xy 128.174133 -181.962574) (xy 128.14336 -182.009087) (xy 128.106143 -182.050624)
			(xy 128.063275 -182.086299) (xy 128.015669 -182.115353) (xy 127.96434 -182.137165) (xy 127.910383 -182.151271)
			(xy 127.854946 -182.157371) (xy 127.799212 -182.155334) (xy 127.744369 -182.145204) (xy 127.691585 -182.127197)
			(xy 127.641985 -182.101696) (xy 127.596627 -182.069245) (xy 127.556478 -182.030536) (xy 127.522392 -181.986393)
			(xy 127.495096 -181.937758) (xy 127.475173 -181.885667) (xy 127.463047 -181.83123) (xy 127.458976 -181.775608)
			(xy 124.996956 -181.775608) (xy 126.280672 -183.059324) (xy 126.288071 -183.066167) (xy 126.30667 -183.073887)
			(xy 126.31674 -183.07431)
		)
		(stroke
			(width 0)
			(type solid)
		)
		(fill yes)
		(layer "In7.Cu")
		(net "P3V3_DB2000QL_FB_VDD")
	)
	(gr_poly
		(pts
			(xy 252.526292 -293.755826) (xy 252.536363 -293.755405) (xy 252.554972 -293.747696) (xy 252.56236 -293.74084)
			(xy 252.966982 -293.336218) (xy 252.973817 -293.328816) (xy 252.981525 -293.310217) (xy 252.981968 -293.30015)
			(xy 252.981968 -257.763772) (xy 252.981539 -257.753705) (xy 252.973814 -257.735111) (xy 252.966982 -257.727704)
			(xy 252.503178 -257.2639) (xy 252.495778 -257.257057) (xy 252.47718 -257.249331) (xy 252.46711 -257.248914)
			(xy 251.522992 -257.248914) (xy 251.510803 -257.249673) (xy 251.48917 -257.260931) (xy 251.48159 -257.270504)
			(xy 251.426726 -257.34899) (xy 251.423424 -257.373628) (xy 251.427742 -257.385312) (xy 251.438366 -257.416706)
			(xy 251.449854 -257.481972) (xy 251.450602 -257.515106) (xy 251.450602 -257.515614) (xy 251.4501 -257.543414)
			(xy 251.442036 -257.598425) (xy 251.42608 -257.651686) (xy 251.402569 -257.70207) (xy 251.372001 -257.748512)
			(xy 251.335021 -257.790031) (xy 251.292412 -257.825749) (xy 251.268992 -257.840734) (xy 251.258324 -257.847084)
			(xy 251.245624 -257.867912) (xy 251.238004 -257.974846) (xy 251.247656 -257.997452) (xy 251.257054 -258.005326)
			(xy 251.278177 -258.023525) (xy 251.315392 -258.06504) (xy 251.346162 -258.111534) (xy 251.369832 -258.162015)
			(xy 251.385896 -258.215405) (xy 251.394012 -258.270565) (xy 251.394468 -258.298442) (xy 251.394034 -258.324313)
			(xy 251.387038 -258.375581) (xy 251.37318 -258.425434) (xy 251.352713 -258.472957) (xy 251.326014 -258.517279)
			(xy 251.293571 -258.557588) (xy 251.25598 -258.593145) (xy 251.23521 -258.608576) (xy 251.225747 -258.616144)
			(xy 251.214616 -258.637628) (xy 251.213874 -258.649724) (xy 251.213874 -258.732528) (xy 251.214607 -258.744625)
			(xy 251.22574 -258.766114) (xy 251.23521 -258.773676) (xy 251.255991 -258.789096) (xy 251.293596 -258.824644)
			(xy 251.326048 -258.864951) (xy 251.352752 -258.909275) (xy 251.373218 -258.956803) (xy 251.387069 -259.006662)
			(xy 251.394051 -259.057936) (xy 251.394468 -259.08381) (xy 251.393982 -259.111061) (xy 251.386226 -259.165009)
			(xy 251.370871 -259.217304) (xy 251.348229 -259.266881) (xy 251.318763 -259.312731) (xy 251.283072 -259.353922)
			(xy 251.241881 -259.389613) (xy 251.196031 -259.419079) (xy 251.146454 -259.441721) (xy 251.094159 -259.457076)
			(xy 251.040211 -259.464832) (xy 250.985709 -259.464832) (xy 250.931761 -259.457076) (xy 250.879466 -259.441721)
			(xy 250.829889 -259.419079) (xy 250.784039 -259.389613) (xy 250.742848 -259.353922) (xy 250.707157 -259.312731)
			(xy 250.677691 -259.266881) (xy 250.655049 -259.217304) (xy 250.639694 -259.165009) (xy 250.631938 -259.111061)
			(xy 250.631452 -259.08381) (xy 250.631889 -259.05794) (xy 250.638891 -259.006677) (xy 250.652755 -258.956829)
			(xy 250.673226 -258.909311) (xy 250.699929 -258.864995) (xy 250.732374 -258.824692) (xy 250.769967 -258.789142)
			(xy 250.79071 -258.773676) (xy 250.800179 -258.766109) (xy 250.811327 -258.744626) (xy 250.812046 -258.732528)
			(xy 250.812046 -258.649724) (xy 250.811304 -258.637631) (xy 250.800162 -258.616157) (xy 250.79071 -258.608576)
			(xy 250.76993 -258.593156) (xy 250.732328 -258.557607) (xy 250.699879 -258.5173) (xy 250.673179 -258.472975)
			(xy 250.652718 -258.425447) (xy 250.638872 -258.375588) (xy 250.631896 -258.324315) (xy 250.631452 -258.298442)
			(xy 250.631958 -258.270644) (xy 250.640028 -258.215638) (xy 250.65599 -258.162384) (xy 250.679506 -258.112007)
			(xy 250.710079 -258.065573) (xy 250.747062 -258.024063) (xy 250.789674 -257.988356) (xy 250.813062 -257.973322)
			(xy 250.82373 -257.966972) (xy 250.83643 -257.946144) (xy 250.84405 -257.83921) (xy 250.834398 -257.816604)
			(xy 250.825 -257.80873) (xy 250.803877 -257.790532) (xy 250.766662 -257.749017) (xy 250.735892 -257.702523)
			(xy 250.712224 -257.652042) (xy 250.696164 -257.598652) (xy 250.688054 -257.543491) (xy 250.687586 -257.515614)
			(xy 250.687586 -257.515106) (xy 250.688315 -257.48197) (xy 250.699804 -257.416701) (xy 250.710446 -257.385312)
			(xy 250.714764 -257.373628) (xy 250.711462 -257.34899) (xy 250.656598 -257.270504) (xy 250.649019 -257.260927)
			(xy 250.627388 -257.24967) (xy 250.615196 -257.248914) (xy 235.500418 -257.248914) (xy 235.490355 -257.249352)
			(xy 235.471773 -257.257089) (xy 235.46435 -257.2639) (xy 234.782868 -257.945382) (xy 234.776027 -257.952782)
			(xy 234.768312 -257.971381) (xy 234.767882 -257.98145) (xy 234.767882 -260.087872) (xy 250.630942 -260.087872)
			(xy 250.635013 -260.03225) (xy 250.647139 -259.977813) (xy 250.667062 -259.925722) (xy 250.694358 -259.877087)
			(xy 250.728444 -259.832944) (xy 250.768593 -259.794235) (xy 250.813951 -259.761784) (xy 250.863551 -259.736283)
			(xy 250.916335 -259.718276) (xy 250.971178 -259.708146) (xy 251.026912 -259.706109) (xy 251.082349 -259.712209)
			(xy 251.136306 -259.726315) (xy 251.187635 -259.748127) (xy 251.235241 -259.777181) (xy 251.278109 -259.812856)
			(xy 251.315326 -259.854393) (xy 251.346099 -259.900906) (xy 251.369771 -259.951403) (xy 251.385839 -260.00481)
			(xy 251.393959 -260.059986) (xy 251.394468 -260.087872) (xy 251.393959 -260.115758) (xy 251.385839 -260.170934)
			(xy 251.369771 -260.224341) (xy 251.346099 -260.274838) (xy 251.315326 -260.321351) (xy 251.278109 -260.362888)
			(xy 251.235241 -260.398563) (xy 251.187635 -260.427617) (xy 251.136306 -260.449429) (xy 251.082349 -260.463535)
			(xy 251.026912 -260.469635) (xy 250.971178 -260.467598) (xy 250.916335 -260.457468) (xy 250.863551 -260.439461)
			(xy 250.813951 -260.41396) (xy 250.768593 -260.381509) (xy 250.728444 -260.3428) (xy 250.694358 -260.298657)
			(xy 250.667062 -260.250022) (xy 250.647139 -260.197931) (xy 250.635013 -260.143494) (xy 250.630942 -260.087872)
			(xy 234.767882 -260.087872) (xy 234.767882 -268.764766) (xy 234.768317 -268.774831) (xy 234.776046 -268.79342)
			(xy 234.782868 -268.800834) (xy 235.18749 -269.205456) (xy 235.194886 -269.212309) (xy 235.213484 -269.220054)
			(xy 235.223558 -269.220442) (xy 247.982486 -269.220442) (xy 247.992548 -269.220882) (xy 248.011126 -269.228623)
			(xy 248.018554 -269.235428) (xy 248.937018 -270.153892) (xy 248.943874 -270.161286) (xy 248.951625 -270.179885)
			(xy 248.952004 -270.18996) (xy 248.952004 -272.39976) (xy 248.952438 -272.409825) (xy 248.960168 -272.428413)
			(xy 248.96699 -272.435828) (xy 250.5964 -274.065238) (xy 250.60324 -274.072639) (xy 250.610961 -274.091237)
			(xy 250.611386 -274.101306) (xy 250.611386 -274.84959) (xy 250.610964 -274.859661) (xy 250.603251 -274.878266)
			(xy 250.5964 -274.885658) (xy 249.668538 -275.81352) (xy 249.66169 -275.820918) (xy 249.653957 -275.839516)
			(xy 249.653552 -275.849588) (xy 249.653552 -278.811482) (xy 250.95403 -278.811482) (xy 250.958103 -278.755823)
			(xy 250.970238 -278.70135) (xy 250.990174 -278.649224) (xy 251.017488 -278.600556) (xy 251.051596 -278.556384)
			(xy 251.091773 -278.517649) (xy 251.137161 -278.485177) (xy 251.186793 -278.459659) (xy 251.239613 -278.44164)
			(xy 251.294492 -278.431503) (xy 251.350263 -278.429465) (xy 251.405737 -278.435568) (xy 251.45973 -278.449684)
			(xy 251.511093 -278.471511) (xy 251.558731 -278.500584) (xy 251.601627 -278.536283) (xy 251.638869 -278.577847)
			(xy 251.669663 -278.624391) (xy 251.693351 -278.674922) (xy 251.709429 -278.728364) (xy 251.717555 -278.783578)
			(xy 251.718064 -278.811482) (xy 251.717555 -278.839386) (xy 251.709429 -278.8946) (xy 251.693351 -278.948042)
			(xy 251.669663 -278.998573) (xy 251.638869 -279.045117) (xy 251.601627 -279.086681) (xy 251.558731 -279.12238)
			(xy 251.511093 -279.151453) (xy 251.45973 -279.17328) (xy 251.405737 -279.187396) (xy 251.350263 -279.193499)
			(xy 251.294492 -279.191461) (xy 251.239613 -279.181324) (xy 251.186793 -279.163305) (xy 251.137161 -279.137787)
			(xy 251.091773 -279.105315) (xy 251.051596 -279.06658) (xy 251.017488 -279.022408) (xy 250.990174 -278.97374)
			(xy 250.970238 -278.921614) (xy 250.958103 -278.867141) (xy 250.95403 -278.811482) (xy 249.653552 -278.811482)
			(xy 249.653552 -280.706322) (xy 249.653123 -280.716389) (xy 249.645398 -280.734983) (xy 249.638566 -280.74239)
			(xy 248.927366 -281.45359) (xy 248.920511 -281.460985) (xy 248.912762 -281.479583) (xy 248.91238 -281.489658)
			(xy 248.91238 -281.55011) (xy 250.225558 -281.55011) (xy 250.229631 -281.494451) (xy 250.241766 -281.439978)
			(xy 250.261702 -281.387852) (xy 250.289016 -281.339184) (xy 250.323124 -281.295012) (xy 250.363301 -281.256277)
			(xy 250.408689 -281.223805) (xy 250.458321 -281.198287) (xy 250.511141 -281.180268) (xy 250.56602 -281.170131)
			(xy 250.621791 -281.168093) (xy 250.677265 -281.174196) (xy 250.731258 -281.188312) (xy 250.782621 -281.210139)
			(xy 250.830259 -281.239212) (xy 250.873155 -281.274911) (xy 250.910397 -281.316475) (xy 250.941191 -281.363019)
			(xy 250.964879 -281.41355) (xy 250.980957 -281.466992) (xy 250.989083 -281.522206) (xy 250.989592 -281.55011)
			(xy 250.989083 -281.578014) (xy 250.980957 -281.633228) (xy 250.964879 -281.68667) (xy 250.941191 -281.737201)
			(xy 250.910397 -281.783745) (xy 250.873155 -281.825309) (xy 250.830259 -281.861008) (xy 250.782621 -281.890081)
			(xy 250.731258 -281.911908) (xy 250.677265 -281.926024) (xy 250.621791 -281.932127) (xy 250.56602 -281.930089)
			(xy 250.511141 -281.919952) (xy 250.458321 -281.901933) (xy 250.408689 -281.876415) (xy 250.363301 -281.843943)
			(xy 250.323124 -281.805208) (xy 250.289016 -281.761036) (xy 250.261702 -281.712368) (xy 250.241766 -281.660242)
			(xy 250.229631 -281.605769) (xy 250.225558 -281.55011) (xy 248.91238 -281.55011) (xy 248.91238 -292.589204)
			(xy 248.912803 -292.599274) (xy 248.920516 -292.61788) (xy 248.927366 -292.625272) (xy 250.042934 -293.74084)
			(xy 250.050332 -293.747688) (xy 250.06893 -293.755419) (xy 250.079002 -293.755826)
		)
		(stroke
			(width 0)
			(type solid)
		)
		(fill yes)
		(layer "In7.Cu")
		(net "P1V25_SERDES_VDDPLL_PEX2")
	)
	(gr_poly
		(pts
			(xy 117.59692 -291.667946) (xy 117.605677 -291.666732) (xy 117.621656 -291.659199) (xy 117.628162 -291.653214)
			(xy 117.737382 -291.543994) (xy 117.743424 -291.537528) (xy 117.750959 -291.521527) (xy 117.752114 -291.512752)
			(xy 117.752368 -291.510212) (xy 117.752368 -284.710378) (xy 117.745764 -284.693106) (xy 117.73916 -284.685994)
			(xy 117.738144 -284.684724) (xy 117.73662 -284.682946) (xy 117.731286 -284.677612) (xy 117.440964 -284.387036)
			(xy 117.420692 -284.366118) (xy 117.385198 -284.319929) (xy 117.356033 -284.269505) (xy 117.333694 -284.215707)
			(xy 117.318565 -284.159454) (xy 117.310903 -284.101709) (xy 117.310408 -284.072584) (xy 117.310877 -284.043567)
			(xy 117.31842 -283.986024) (xy 117.333377 -283.92995) (xy 117.355493 -283.876295) (xy 117.384394 -283.825968)
			(xy 117.419589 -283.779823) (xy 117.439694 -283.758894) (xy 117.439948 -283.75864) (xy 117.446043 -283.75213)
			(xy 117.453609 -283.735996) (xy 117.45468 -283.727144) (xy 117.45468 -283.726636) (xy 117.456712 -283.69641)
			(xy 117.456712 -283.695902) (xy 117.457474 -283.688028) (xy 117.452902 -283.67101) (xy 117.44706 -283.662374)
			(xy 117.444266 -283.658564) (xy 117.442234 -283.65577) (xy 117.43563 -283.646118) (xy 117.420964 -283.622744)
			(xy 117.397788 -283.572669) (xy 117.382064 -283.519778) (xy 117.37412 -283.465173) (xy 117.373654 -283.437584)
			(xy 117.373654 -283.431488) (xy 117.374416 -283.417772) (xy 117.376116 -283.392747) (xy 117.385265 -283.34343)
			(xy 117.400797 -283.295738) (xy 117.422446 -283.250492) (xy 117.449837 -283.208473) (xy 117.465856 -283.189172)
			(xy 117.471864 -283.181445) (xy 117.478066 -283.162899) (xy 117.476878 -283.14338) (xy 117.468472 -283.125723)
			(xy 117.45407 -283.112494) (xy 117.435765 -283.105615) (xy 117.425978 -283.105352) (xy 116.552472 -283.105352)
			(xy 116.52085 -283.104847) (xy 116.458144 -283.096621) (xy 116.397047 -283.080287) (xy 116.338602 -283.056124)
			(xy 116.283808 -283.024545) (xy 116.2336 -282.986089) (xy 116.210842 -282.964128) (xy 115.709192 -282.462224)
			(xy 115.701783 -282.455539) (xy 115.683347 -282.447956) (xy 115.673378 -282.447492) (xy 114.036094 -282.447492)
			(xy 114.004462 -282.446975) (xy 113.94174 -282.438719) (xy 113.880631 -282.42235) (xy 113.82218 -282.398148)
			(xy 113.767387 -282.366525) (xy 113.717188 -282.328024) (xy 113.694464 -282.306014) (xy 112.539526 -281.150822)
			(xy 112.532178 -281.144021) (xy 112.513715 -281.136312) (xy 112.503712 -281.135836) (xy 111.95431 -281.135836)
			(xy 111.941639 -281.136577) (xy 111.919373 -281.148697) (xy 111.911892 -281.15895) (xy 111.858298 -281.240992)
			(xy 111.856012 -281.266392) (xy 111.861346 -281.27833) (xy 111.871467 -281.302537) (xy 111.88572 -281.353032)
			(xy 111.892911 -281.405004) (xy 111.89335 -281.431238) (xy 111.892882 -281.458536) (xy 111.885096 -281.512576)
			(xy 111.86969 -281.564954) (xy 111.846977 -281.614602) (xy 111.81742 -281.660507) (xy 111.799878 -281.681428)
			(xy 111.793528 -281.688794) (xy 111.787178 -281.706574) (xy 111.790734 -281.795982) (xy 111.798354 -281.813254)
			(xy 111.805212 -281.820112) (xy 111.826321 -281.84176) (xy 111.862112 -281.890489) (xy 111.889772 -281.944252)
			(xy 111.908609 -282.001704) (xy 111.918152 -282.061408) (xy 111.91875 -282.091638) (xy 111.918263 -282.119278)
			(xy 111.910288 -282.173979) (xy 111.894497 -282.226955) (xy 111.87122 -282.277095) (xy 111.840947 -282.323348)
			(xy 111.822992 -282.344368) (xy 111.81461 -282.35402) (xy 111.808768 -282.378404) (xy 111.835946 -282.484576)
			(xy 111.852964 -282.503118) (xy 111.864902 -282.507436) (xy 111.892309 -282.517775) (xy 111.943825 -282.545652)
			(xy 111.99047 -282.581082) (xy 112.031147 -282.62323) (xy 112.064897 -282.671105) (xy 112.090926 -282.723578)
			(xy 112.108623 -282.779416) (xy 112.117569 -282.837304) (xy 112.11814 -282.866592) (xy 112.117591 -282.893855)
			(xy 112.447747 -282.893855) (xy 112.447747 -282.839345) (xy 112.455505 -282.78539) (xy 112.470863 -282.733089)
			(xy 112.493509 -282.683505) (xy 112.52298 -282.63765) (xy 112.558678 -282.596455) (xy 112.599876 -282.560761)
			(xy 112.645734 -282.531293) (xy 112.695319 -282.508652) (xy 112.747622 -282.493299) (xy 112.801577 -282.485545)
			(xy 112.828832 -282.485084) (xy 112.856204 -282.485511) (xy 112.910385 -282.493335) (xy 112.96289 -282.508832)
			(xy 113.012636 -282.531683) (xy 113.0586 -282.561418) (xy 113.07953 -282.579064) (xy 113.086642 -282.58516)
			(xy 113.10366 -282.59151) (xy 113.189004 -282.59151) (xy 113.206022 -282.58516) (xy 113.213134 -282.579064)
			(xy 113.234076 -282.561437) (xy 113.280046 -282.531724) (xy 113.329791 -282.508887) (xy 113.38229 -282.493393)
			(xy 113.436464 -282.48556) (xy 113.463832 -282.485084) (xy 113.491081 -282.485588) (xy 113.545024 -282.493348)
			(xy 113.597314 -282.508706) (xy 113.646886 -282.531348) (xy 113.692732 -282.560815) (xy 113.733917 -282.596505)
			(xy 113.769605 -282.637694) (xy 113.799067 -282.683542) (xy 113.821706 -282.733116) (xy 113.837059 -282.785407)
			(xy 113.844814 -282.839351) (xy 113.844814 -282.893849) (xy 113.837059 -282.947793) (xy 113.821706 -283.000084)
			(xy 113.799067 -283.049658) (xy 113.769605 -283.095506) (xy 113.733917 -283.136695) (xy 113.692732 -283.172385)
			(xy 113.646886 -283.201852) (xy 113.597314 -283.224494) (xy 113.545024 -283.239852) (xy 113.491081 -283.247612)
			(xy 113.463832 -283.2481) (xy 113.436462 -283.247615) (xy 113.382284 -283.239802) (xy 113.329781 -283.224317)
			(xy 113.280034 -283.20148) (xy 113.234066 -283.171759) (xy 113.213134 -283.15412) (xy 113.206022 -283.148024)
			(xy 113.189004 -283.141674) (xy 113.10366 -283.141674) (xy 113.086642 -283.148024) (xy 113.07953 -283.15412)
			(xy 113.0586 -283.171762) (xy 113.012626 -283.201472) (xy 112.962878 -283.224308) (xy 112.910377 -283.239798)
			(xy 112.856201 -283.247626) (xy 112.828832 -283.2481) (xy 112.801577 -283.247655) (xy 112.747622 -283.239901)
			(xy 112.695319 -283.224548) (xy 112.645734 -283.201907) (xy 112.599876 -283.172439) (xy 112.558678 -283.136745)
			(xy 112.52298 -283.09555) (xy 112.493509 -283.049695) (xy 112.470863 -283.000111) (xy 112.455505 -282.94781)
			(xy 112.447747 -282.893855) (xy 112.117591 -282.893855) (xy 112.117539 -282.896428) (xy 112.108222 -282.955371)
			(xy 112.099598 -282.98394) (xy 112.096296 -282.994354) (xy 112.098582 -283.015944) (xy 112.14862 -283.100526)
			(xy 112.1664 -283.112972) (xy 112.177068 -283.115004) (xy 112.202871 -283.120406) (xy 112.252785 -283.13737)
			(xy 112.299888 -283.161044) (xy 112.343283 -283.190979) (xy 112.382143 -283.226602) (xy 112.415729 -283.267237)
			(xy 112.4434 -283.312109) (xy 112.46463 -283.360363) (xy 112.479014 -283.41108) (xy 112.486278 -283.463295)
			(xy 112.486694 -283.489654) (xy 112.486128 -283.519779) (xy 112.476663 -283.579282) (xy 112.457959 -283.636556)
			(xy 112.430483 -283.690177) (xy 112.394918 -283.738812) (xy 112.373918 -283.760418) (xy 112.366552 -283.76753)
			(xy 112.358932 -283.786326) (xy 112.358932 -283.878782) (xy 112.366552 -283.897578) (xy 112.373918 -283.90469)
			(xy 112.394896 -283.926315) (xy 112.430453 -283.974949) (xy 112.457925 -284.028567) (xy 112.476631 -284.085835)
			(xy 112.486105 -284.145331) (xy 112.486694 -284.175454) (xy 112.486208 -284.202705) (xy 112.478452 -284.256653)
			(xy 112.463097 -284.308948) (xy 112.440455 -284.358525) (xy 112.410989 -284.404375) (xy 112.375298 -284.445566)
			(xy 112.334107 -284.481257) (xy 112.288257 -284.510723) (xy 112.23868 -284.533365) (xy 112.186385 -284.54872)
			(xy 112.132437 -284.556476) (xy 112.077935 -284.556476) (xy 112.023987 -284.54872) (xy 111.971692 -284.533365)
			(xy 111.922115 -284.510723) (xy 111.876265 -284.481257) (xy 111.835074 -284.445566) (xy 111.799383 -284.404375)
			(xy 111.769917 -284.358525) (xy 111.747275 -284.308948) (xy 111.73192 -284.256653) (xy 111.724164 -284.202705)
			(xy 111.723678 -284.175454) (xy 111.724243 -284.145329) (xy 111.733709 -284.085827) (xy 111.752415 -284.028554)
			(xy 111.779894 -283.974935) (xy 111.815463 -283.926305) (xy 111.836454 -283.90469) (xy 111.84382 -283.897578)
			(xy 111.85144 -283.878782) (xy 111.85144 -283.786326) (xy 111.84382 -283.76753) (xy 111.836454 -283.760418)
			(xy 111.815477 -283.738793) (xy 111.779922 -283.690158) (xy 111.75245 -283.63654) (xy 111.733745 -283.579272)
			(xy 111.72427 -283.519777) (xy 111.723678 -283.489654) (xy 111.724275 -283.459817) (xy 111.733586 -283.400873)
			(xy 111.74222 -283.372306) (xy 111.745522 -283.361892) (xy 111.743236 -283.340302) (xy 111.693198 -283.25572)
			(xy 111.675418 -283.243274) (xy 111.66475 -283.241242) (xy 111.636901 -283.235368) (xy 111.583216 -283.216467)
			(xy 111.532939 -283.189795) (xy 111.487185 -283.155945) (xy 111.446971 -283.115669) (xy 111.413192 -283.069863)
			(xy 111.386597 -283.019544) (xy 111.367778 -282.965831) (xy 111.361982 -282.937966) (xy 111.359442 -282.925774)
			(xy 111.343694 -282.905962) (xy 111.243618 -282.862528) (xy 111.218472 -282.86456) (xy 111.207804 -282.871164)
			(xy 111.184811 -282.885157) (xy 111.135732 -282.907254) (xy 111.084039 -282.922249) (xy 111.030754 -282.929846)
			(xy 111.003842 -282.930346) (xy 110.985824 -282.930111) (xy 110.94995 -282.926674) (xy 110.932214 -282.923488)
			(xy 110.922816 -282.92171) (xy 110.903766 -282.92552) (xy 110.828582 -282.973272) (xy 110.817152 -282.98902)
			(xy 110.814866 -282.998418) (xy 110.807482 -283.025468) (xy 110.785868 -283.077205) (xy 110.756912 -283.12522)
			(xy 110.721238 -283.168478) (xy 110.679616 -283.206048) (xy 110.632941 -283.237118) (xy 110.582221 -283.261021)
			(xy 110.528547 -283.27724) (xy 110.473077 -283.285426) (xy 110.445042 -283.285946) (xy 110.417786 -283.285486)
			(xy 110.363829 -283.277734) (xy 110.311523 -283.262382) (xy 110.261936 -283.239743) (xy 110.216074 -283.210276)
			(xy 110.174874 -283.174583) (xy 110.139172 -283.13339) (xy 110.109696 -283.087535) (xy 110.087046 -283.037952)
			(xy 110.071683 -282.98565) (xy 110.06392 -282.931694) (xy 110.063534 -282.904438) (xy 110.065058 -282.86964)
			(xy 110.066582 -282.853638) (xy 110.05058 -282.825952) (xy 109.949488 -282.778454) (xy 109.939856 -282.774544)
			(xy 109.919096 -282.773978) (xy 109.899794 -282.781641) (xy 109.892084 -282.788614) (xy 109.74451 -282.936442)
			(xy 109.736459 -282.945369) (xy 109.728911 -282.96816) (xy 109.730032 -282.98013) (xy 109.744764 -283.073348)
			(xy 109.758734 -283.092906) (xy 109.769656 -283.098494) (xy 109.795724 -283.112561) (xy 109.843547 -283.147509)
			(xy 109.885396 -283.189426) (xy 109.920266 -283.237305) (xy 109.947319 -283.289997) (xy 109.965907 -283.346237)
			(xy 109.975582 -283.404673) (xy 109.976412 -283.434282) (xy 109.976412 -283.437838) (xy 109.975881 -283.467266)
			(xy 109.966877 -283.525428) (xy 109.949056 -283.58152) (xy 109.922842 -283.634214) (xy 109.906308 -283.658564)
			(xy 109.9058 -283.659072) (xy 109.905292 -283.659834) (xy 109.90326 -283.662628) (xy 109.898942 -283.671264)
			(xy 109.896482 -283.67659) (xy 109.893792 -283.688006) (xy 109.893608 -283.69387) (xy 109.893608 -283.698188)
			(xy 109.896148 -283.727398) (xy 109.897159 -283.736289) (xy 109.904567 -283.752564) (xy 109.910626 -283.759148)
			(xy 109.91723 -283.765752) (xy 110.351316 -284.200092) (xy 110.371588 -284.22101) (xy 110.40708 -284.267199)
			(xy 110.436244 -284.317624) (xy 110.458579 -284.371422) (xy 110.473706 -284.427674) (xy 110.481365 -284.485419)
			(xy 110.481872 -284.514544) (xy 110.481872 -291.507926) (xy 110.482126 -291.512752) (xy 110.483345 -291.521507)
			(xy 110.490881 -291.537482) (xy 110.496858 -291.543994) (xy 110.606078 -291.653214) (xy 110.612539 -291.659267)
			(xy 110.628539 -291.666821) (xy 110.63732 -291.667946) (xy 110.63986 -291.6682) (xy 117.592094 -291.6682)
		)
		(stroke
			(width 0)
			(type solid)
		)
		(fill yes)
		(layer "In7.Cu")
		(net "GND")
	)
	(gr_poly
		(pts
			(xy 126.112016 -291.667946)
			(arc
				(start 126.236222 -291.54374)
				(mid 126.247284 -291.527323)
				(end 126.251208 -291.507926)
			)
			(arc
				(start 126.251208 -287.803082)
				(mid 126.247258 -287.783695)
				(end 126.236222 -287.767268)
			)
			(xy 125.69825 -287.229296) (xy 125.686566 -287.222692)
			(arc
				(start 125.679708 -287.220914)
				(mid 125.438396 -287.06279)
				(end 125.344936 -286.789876)
			)
			(arc
				(start 125.344936 -286.789876)
				(mid 125.475276 -286.475208)
				(end 125.789944 -286.344868)
			)
			(arc
				(start 125.887988 -286.344868)
				(mid 125.972592 -286.353034)
				(end 126.054104 -286.377126)
			)
			(xy 126.066042 -286.381952) (xy 126.090934 -286.379412)
			(arc
				(start 126.171198 -286.325056)
				(mid 126.187741 -286.306794)
				(end 126.193804 -286.282892)
			)
			(arc
				(start 126.193804 -286.215074)
				(mid 126.189854 -286.195687)
				(end 126.178818 -286.17926)
			)
			(arc
				(start 124.632466 -284.633162)
				(mid 124.527735 -284.476421)
				(end 124.490988 -284.291532)
			)
			(arc
				(start 124.490988 -282.866338)
				(mid 124.487155 -282.846981)
				(end 124.476256 -282.830524)
			)
			(arc
				(start 124.320046 -282.674314)
				(mid 124.303629 -282.663252)
				(end 124.284232 -282.659328)
			)
			(arc
				(start 122.433842 -282.659328)
				(mid 122.411854 -282.664333)
				(end 122.394218 -282.678378)
			)
			(xy 122.337322 -282.749498) (xy 122.332242 -282.77185)
			(arc
				(start 122.334782 -282.78328)
				(mid 122.341652 -282.824684)
				(end 122.343926 -282.866592)
			)
			(arc
				(start 122.343926 -282.866592)
				(mid 122.232185 -283.136359)
				(end 121.962418 -283.2481)
			)
			(arc
				(start 121.962418 -283.2481)
				(mid 121.828556 -283.223827)
				(end 121.71172 -283.15412)
			)
			(xy 121.704608 -283.148024) (xy 121.68759 -283.141674) (xy 121.602246 -283.141674) (xy 121.585228 -283.148024)
			(arc
				(start 121.578116 -283.15412)
				(mid 121.46129 -283.223853)
				(end 121.327418 -283.2481)
			)
			(arc
				(start 121.327418 -283.2481)
				(mid 120.94591 -282.866592)
				(end 121.327418 -282.485084)
			)
			(arc
				(start 121.327418 -282.485084)
				(mid 121.46128 -282.509357)
				(end 121.578116 -282.579064)
			)
			(xy 121.585228 -282.58516) (xy 121.602246 -282.59151) (xy 121.68759 -282.59151) (xy 121.704608 -282.58516)
			(arc
				(start 121.71172 -282.579064)
				(mid 121.758707 -282.544)
				(end 121.810526 -282.51658)
			)
			(xy 121.82221 -282.5115) (xy 121.837704 -282.491942)
			(arc
				(start 121.855738 -282.396946)
				(mid 121.854363 -282.372605)
				(end 121.841768 -282.351734)
			)
			(arc
				(start 120.688862 -281.198574)
				(mid 120.672445 -281.187512)
				(end 120.653048 -281.183588)
			)
			(arc
				(start 120.47093 -281.183588)
				(mid 120.448035 -281.189168)
				(end 120.430036 -281.204416)
			)
			(xy 120.37441 -281.280616) (xy 120.370346 -281.304238)
			(arc
				(start 120.374156 -281.315922)
				(mid 120.387473 -281.372897)
				(end 120.391936 -281.431238)
			)
			(arc
				(start 120.391936 -281.431238)
				(mid 120.367802 -281.564776)
				(end 120.298464 -281.681428)
			)
			(xy 120.292114 -281.688794) (xy 120.285764 -281.706574) (xy 120.28932 -281.795982) (xy 120.29694 -281.813254)
			(arc
				(start 120.303798 -281.820112)
				(mid 120.387795 -281.944488)
				(end 120.417336 -282.091638)
			)
			(arc
				(start 120.417336 -282.091638)
				(mid 120.3926 -282.226775)
				(end 120.321578 -282.344368)
			)
			(xy 120.313196 -282.35402) (xy 120.307354 -282.378404) (xy 120.334532 -282.484576) (xy 120.35155 -282.503118)
			(arc
				(start 120.363488 -282.507436)
				(mid 120.547074 -282.646853)
				(end 120.616726 -282.866592)
			)
			(arc
				(start 120.616726 -282.866592)
				(mid 120.612034 -282.925988)
				(end 120.598184 -282.98394)
			)
			(xy 120.594882 -282.994354) (xy 120.597168 -283.015944) (xy 120.647206 -283.100526) (xy 120.664986 -283.112972)
			(arc
				(start 120.675654 -283.115004)
				(mid 120.89784 -283.246644)
				(end 120.98528 -283.489654)
			)
			(arc
				(start 120.98528 -283.489654)
				(mid 120.955964 -283.636314)
				(end 120.872504 -283.760418)
			)
			(xy 120.865138 -283.76753) (xy 120.857518 -283.786326) (xy 120.857518 -283.878782) (xy 120.865138 -283.897578)
			(arc
				(start 120.872504 -283.90469)
				(mid 120.955942 -284.028803)
				(end 120.98528 -284.175454)
			)
			(arc
				(start 120.98528 -284.175454)
				(mid 120.603772 -284.556962)
				(end 120.222264 -284.175454)
			)
			(arc
				(start 120.222264 -284.175454)
				(mid 120.25158 -284.028794)
				(end 120.33504 -283.90469)
			)
			(xy 120.342406 -283.897578) (xy 120.350026 -283.878782) (xy 120.350026 -283.786326) (xy 120.342406 -283.76753)
			(arc
				(start 120.33504 -283.760418)
				(mid 120.251602 -283.636305)
				(end 120.222264 -283.489654)
			)
			(arc
				(start 120.222264 -283.489654)
				(mid 120.226956 -283.430258)
				(end 120.240806 -283.372306)
			)
			(xy 120.244108 -283.361892) (xy 120.241822 -283.340302) (xy 120.191784 -283.25572) (xy 120.174004 -283.243274)
			(arc
				(start 120.163336 -283.241242)
				(mid 119.965292 -283.136165)
				(end 119.860568 -282.937966)
			)
			(xy 119.858028 -282.925774) (xy 119.84228 -282.905962) (xy 119.742204 -282.862528) (xy 119.717058 -282.86456)
			(arc
				(start 119.70639 -282.871164)
				(mid 119.608606 -282.9152)
				(end 119.502428 -282.930346)
			)
			(arc
				(start 119.502428 -282.930346)
				(mid 119.466454 -282.928598)
				(end 119.4308 -282.923488)
			)
			(xy 119.421402 -282.92171) (xy 119.402352 -282.92552) (xy 119.327168 -282.973272) (xy 119.315738 -282.98902)
			(arc
				(start 119.313452 -282.998418)
				(mid 119.177873 -283.205655)
				(end 118.943628 -283.285946)
			)
			(arc
				(start 118.943628 -283.285946)
				(mid 118.673861 -283.174205)
				(end 118.56212 -282.904438)
			)
			(arc
				(start 118.56212 -282.904438)
				(mid 118.597404 -282.744197)
				(end 118.69674 -282.613608)
			)
			(arc
				(start 118.69674 -282.613608)
				(mid 118.710069 -282.596174)
				(end 118.714774 -282.574746)
			)
			(arc
				(start 118.714774 -282.49753)
				(mid 118.71004 -282.476115)
				(end 118.69674 -282.458668)
			)
			(arc
				(start 118.69674 -282.458668)
				(mid 118.637392 -282.395335)
				(end 118.59387 -282.320238)
			)
			(xy 118.58879 -282.308808) (xy 118.569232 -282.29306)
			(arc
				(start 118.474236 -282.275026)
				(mid 118.449884 -282.276397)
				(end 118.429024 -282.288996)
			)
			(xy 117.754146 -282.964128)
			(arc
				(start 117.748304 -282.969716)
				(mid 117.735878 -283.023783)
				(end 117.780308 -283.056838)
			)
			(arc
				(start 117.780308 -283.056838)
				(mid 118.032749 -283.175528)
				(end 118.136924 -283.434282)
			)
			(arc
				(start 118.136924 -283.437838)
				(mid 118.119005 -283.553639)
				(end 118.06682 -283.658564)
			)
			(xy 118.066312 -283.659072) (xy 118.065804 -283.659834) (xy 118.063772 -283.662628)
			(arc
				(start 118.059454 -283.671264)
				(mid 118.055489 -283.682259)
				(end 118.05412 -283.69387)
			)
			(xy 118.05412 -283.698188)
			(arc
				(start 118.05666 -283.727398)
				(mid 118.061063 -283.74457)
				(end 118.071138 -283.759148)
			)
			(xy 118.077742 -283.765752)
			(arc
				(start 118.511828 -284.200092)
				(mid 118.608364 -284.344335)
				(end 118.642384 -284.514544)
			)
			(xy 118.642384 -291.507926)
			(arc
				(start 118.642638 -291.512752)
				(mid 118.647289 -291.529648)
				(end 118.65737 -291.543994)
			)
			(xy 118.65864 -291.545264)
			(arc
				(start 118.76659 -291.653468)
				(mid 118.783036 -291.664394)
				(end 118.802404 -291.6682)
			)
			(xy 126.111508 -291.6682)
		)
		(stroke
			(width 0)
			(type solid)
		)
		(fill yes)
		(layer "In7.Cu")
		(net "GND")
	)
	(gr_poly
		(pts
			(xy 31.867856 -257.250692) (xy 31.877921 -257.250258) (xy 31.89651 -257.242529) (xy 31.903924 -257.235706)
			(xy 32.910526 -256.229104) (xy 32.917926 -256.222261) (xy 32.936524 -256.214536) (xy 32.946594 -256.214118)
			(xy 34.312606 -256.214118) (xy 34.321593 -256.213774) (xy 34.338459 -256.207565) (xy 34.35212 -256.195888)
			(xy 34.356802 -256.18821) (xy 34.370439 -256.165038) (xy 34.403219 -256.122419) (xy 34.441656 -256.084822)
			(xy 34.484988 -256.052991) (xy 34.532358 -256.027556) (xy 34.582828 -256.009019) (xy 34.6354 -255.997748)
			(xy 34.689034 -255.993967) (xy 34.742668 -255.997748) (xy 34.79524 -256.009019) (xy 34.84571 -256.027556)
			(xy 34.89308 -256.052991) (xy 34.936412 -256.084822) (xy 34.974849 -256.122419) (xy 35.007629 -256.165038)
			(xy 35.021266 -256.18821) (xy 35.025985 -256.195856) (xy 35.039651 -256.207503) (xy 35.056486 -256.213749)
			(xy 35.065462 -256.214118) (xy 41.154096 -256.214118) (xy 41.164167 -256.213696) (xy 41.182774 -256.205985)
			(xy 41.190164 -256.199132) (xy 41.583102 -255.806194) (xy 41.589947 -255.798795) (xy 41.597679 -255.780197)
			(xy 41.598088 -255.770126) (xy 41.598088 -252.20168) (xy 41.597834 -252.196854) (xy 40.29329 -238.297466)
			(xy 40.292782 -238.292894) (xy 39.03345 -231.64292) (xy 39.031806 -231.63549) (xy 39.024698 -231.622043)
			(xy 39.01948 -231.616504) (xy 37.960808 -230.557832) (xy 37.953411 -230.550981) (xy 37.934813 -230.543239)
			(xy 37.92474 -230.542846) (xy 31.366968 -230.542846) (xy 31.356901 -230.543276) (xy 31.33831 -230.551004)
			(xy 31.3309 -230.557832) (xy 29.020262 -232.86847) (xy 29.01342 -232.875869) (xy 29.005701 -232.894468)
			(xy 29.005276 -232.904538) (xy 29.005276 -250.792742) (xy 29.005744 -250.802413) (xy 29.012991 -250.82035)
			(xy 29.026363 -250.83433) (xy 29.034994 -250.838716) (xy 29.13253 -250.883674) (xy 29.16174 -250.879356)
			(xy 29.17317 -250.86945) (xy 29.194063 -250.852093) (xy 29.239831 -250.822844) (xy 29.289282 -250.800376)
			(xy 29.341418 -250.785143) (xy 29.395186 -250.777452) (xy 29.422344 -250.776994) (xy 29.449593 -250.777483)
			(xy 29.503536 -250.785244) (xy 29.555825 -250.800603) (xy 29.605396 -250.823247) (xy 29.651241 -250.852714)
			(xy 29.692426 -250.888405) (xy 29.728112 -250.929594) (xy 29.757574 -250.975442) (xy 29.780212 -251.025016)
			(xy 29.795565 -251.077307) (xy 29.80332 -251.131251) (xy 29.80332 -251.158502) (xy 30.056326 -251.158502)
			(xy 30.060397 -251.10288) (xy 30.072523 -251.048443) (xy 30.092446 -250.996352) (xy 30.119742 -250.947717)
			(xy 30.153828 -250.903574) (xy 30.193977 -250.864865) (xy 30.239335 -250.832414) (xy 30.288935 -250.806913)
			(xy 30.341719 -250.788906) (xy 30.396562 -250.778776) (xy 30.452296 -250.776739) (xy 30.507733 -250.782839)
			(xy 30.56169 -250.796945) (xy 30.613019 -250.818757) (xy 30.660625 -250.847811) (xy 30.703493 -250.883486)
			(xy 30.74071 -250.925023) (xy 30.771483 -250.971536) (xy 30.795155 -251.022033) (xy 30.811223 -251.07544)
			(xy 30.819343 -251.130616) (xy 30.819852 -251.158502) (xy 31.072326 -251.158502) (xy 31.076397 -251.10288)
			(xy 31.088523 -251.048443) (xy 31.108446 -250.996352) (xy 31.135742 -250.947717) (xy 31.169828 -250.903574)
			(xy 31.209977 -250.864865) (xy 31.255335 -250.832414) (xy 31.304935 -250.806913) (xy 31.357719 -250.788906)
			(xy 31.412562 -250.778776) (xy 31.468296 -250.776739) (xy 31.523733 -250.782839) (xy 31.57769 -250.796945)
			(xy 31.629019 -250.818757) (xy 31.676625 -250.847811) (xy 31.719493 -250.883486) (xy 31.75671 -250.925023)
			(xy 31.787483 -250.971536) (xy 31.811155 -251.022033) (xy 31.827223 -251.07544) (xy 31.835343 -251.130616)
			(xy 31.835852 -251.158502) (xy 32.088326 -251.158502) (xy 32.092397 -251.10288) (xy 32.104523 -251.048443)
			(xy 32.124446 -250.996352) (xy 32.151742 -250.947717) (xy 32.185828 -250.903574) (xy 32.225977 -250.864865)
			(xy 32.271335 -250.832414) (xy 32.320935 -250.806913) (xy 32.373719 -250.788906) (xy 32.428562 -250.778776)
			(xy 32.484296 -250.776739) (xy 32.539733 -250.782839) (xy 32.59369 -250.796945) (xy 32.645019 -250.818757)
			(xy 32.692625 -250.847811) (xy 32.735493 -250.883486) (xy 32.77271 -250.925023) (xy 32.803483 -250.971536)
			(xy 32.827155 -251.022033) (xy 32.843223 -251.07544) (xy 32.851343 -251.130616) (xy 32.851852 -251.158502)
			(xy 33.104326 -251.158502) (xy 33.108397 -251.10288) (xy 33.120523 -251.048443) (xy 33.140446 -250.996352)
			(xy 33.167742 -250.947717) (xy 33.201828 -250.903574) (xy 33.241977 -250.864865) (xy 33.287335 -250.832414)
			(xy 33.336935 -250.806913) (xy 33.389719 -250.788906) (xy 33.444562 -250.778776) (xy 33.500296 -250.776739)
			(xy 33.555733 -250.782839) (xy 33.60969 -250.796945) (xy 33.661019 -250.818757) (xy 33.708625 -250.847811)
			(xy 33.751493 -250.883486) (xy 33.78871 -250.925023) (xy 33.819483 -250.971536) (xy 33.843155 -251.022033)
			(xy 33.859223 -251.07544) (xy 33.867343 -251.130616) (xy 33.867852 -251.158502) (xy 34.120326 -251.158502)
			(xy 34.124397 -251.10288) (xy 34.136523 -251.048443) (xy 34.156446 -250.996352) (xy 34.183742 -250.947717)
			(xy 34.217828 -250.903574) (xy 34.257977 -250.864865) (xy 34.303335 -250.832414) (xy 34.352935 -250.806913)
			(xy 34.405719 -250.788906) (xy 34.460562 -250.778776) (xy 34.516296 -250.776739) (xy 34.571733 -250.782839)
			(xy 34.62569 -250.796945) (xy 34.677019 -250.818757) (xy 34.724625 -250.847811) (xy 34.767493 -250.883486)
			(xy 34.80471 -250.925023) (xy 34.835483 -250.971536) (xy 34.859155 -251.022033) (xy 34.875223 -251.07544)
			(xy 34.883343 -251.130616) (xy 34.883852 -251.158502) (xy 35.136326 -251.158502) (xy 35.140397 -251.10288)
			(xy 35.152523 -251.048443) (xy 35.172446 -250.996352) (xy 35.199742 -250.947717) (xy 35.233828 -250.903574)
			(xy 35.273977 -250.864865) (xy 35.319335 -250.832414) (xy 35.368935 -250.806913) (xy 35.421719 -250.788906)
			(xy 35.476562 -250.778776) (xy 35.532296 -250.776739) (xy 35.587733 -250.782839) (xy 35.64169 -250.796945)
			(xy 35.693019 -250.818757) (xy 35.740625 -250.847811) (xy 35.783493 -250.883486) (xy 35.82071 -250.925023)
			(xy 35.851483 -250.971536) (xy 35.875155 -251.022033) (xy 35.891223 -251.07544) (xy 35.899343 -251.130616)
			(xy 35.899852 -251.158502) (xy 36.152326 -251.158502) (xy 36.156397 -251.10288) (xy 36.168523 -251.048443)
			(xy 36.188446 -250.996352) (xy 36.215742 -250.947717) (xy 36.249828 -250.903574) (xy 36.289977 -250.864865)
			(xy 36.335335 -250.832414) (xy 36.384935 -250.806913) (xy 36.437719 -250.788906) (xy 36.492562 -250.778776)
			(xy 36.548296 -250.776739) (xy 36.603733 -250.782839) (xy 36.65769 -250.796945) (xy 36.709019 -250.818757)
			(xy 36.756625 -250.847811) (xy 36.799493 -250.883486) (xy 36.83671 -250.925023) (xy 36.867483 -250.971536)
			(xy 36.891155 -251.022033) (xy 36.907223 -251.07544) (xy 36.915343 -251.130616) (xy 36.915852 -251.158502)
			(xy 37.168326 -251.158502) (xy 37.172397 -251.10288) (xy 37.184523 -251.048443) (xy 37.204446 -250.996352)
			(xy 37.231742 -250.947717) (xy 37.265828 -250.903574) (xy 37.305977 -250.864865) (xy 37.351335 -250.832414)
			(xy 37.400935 -250.806913) (xy 37.453719 -250.788906) (xy 37.508562 -250.778776) (xy 37.564296 -250.776739)
			(xy 37.619733 -250.782839) (xy 37.67369 -250.796945) (xy 37.725019 -250.818757) (xy 37.772625 -250.847811)
			(xy 37.815493 -250.883486) (xy 37.85271 -250.925023) (xy 37.883483 -250.971536) (xy 37.907155 -251.022033)
			(xy 37.923223 -251.07544) (xy 37.931343 -251.130616) (xy 37.931852 -251.158502) (xy 38.184326 -251.158502)
			(xy 38.188397 -251.10288) (xy 38.200523 -251.048443) (xy 38.220446 -250.996352) (xy 38.247742 -250.947717)
			(xy 38.281828 -250.903574) (xy 38.321977 -250.864865) (xy 38.367335 -250.832414) (xy 38.416935 -250.806913)
			(xy 38.469719 -250.788906) (xy 38.524562 -250.778776) (xy 38.580296 -250.776739) (xy 38.635733 -250.782839)
			(xy 38.68969 -250.796945) (xy 38.741019 -250.818757) (xy 38.788625 -250.847811) (xy 38.831493 -250.883486)
			(xy 38.86871 -250.925023) (xy 38.899483 -250.971536) (xy 38.923155 -251.022033) (xy 38.939223 -251.07544)
			(xy 38.947343 -251.130616) (xy 38.947852 -251.158502) (xy 40.216326 -251.158502) (xy 40.220397 -251.10288)
			(xy 40.232523 -251.048443) (xy 40.252446 -250.996352) (xy 40.279742 -250.947717) (xy 40.313828 -250.903574)
			(xy 40.353977 -250.864865) (xy 40.399335 -250.832414) (xy 40.448935 -250.806913) (xy 40.501719 -250.788906)
			(xy 40.556562 -250.778776) (xy 40.612296 -250.776739) (xy 40.667733 -250.782839) (xy 40.72169 -250.796945)
			(xy 40.773019 -250.818757) (xy 40.820625 -250.847811) (xy 40.863493 -250.883486) (xy 40.90071 -250.925023)
			(xy 40.931483 -250.971536) (xy 40.955155 -251.022033) (xy 40.971223 -251.07544) (xy 40.979343 -251.130616)
			(xy 40.979852 -251.158502) (xy 40.979343 -251.186388) (xy 40.971223 -251.241564) (xy 40.955155 -251.294971)
			(xy 40.931483 -251.345468) (xy 40.90071 -251.391981) (xy 40.863493 -251.433518) (xy 40.820625 -251.469193)
			(xy 40.773019 -251.498247) (xy 40.72169 -251.520059) (xy 40.667733 -251.534165) (xy 40.612296 -251.540265)
			(xy 40.556562 -251.538228) (xy 40.501719 -251.528098) (xy 40.448935 -251.510091) (xy 40.399335 -251.48459)
			(xy 40.353977 -251.452139) (xy 40.313828 -251.41343) (xy 40.279742 -251.369287) (xy 40.252446 -251.320652)
			(xy 40.232523 -251.268561) (xy 40.220397 -251.214124) (xy 40.216326 -251.158502) (xy 38.947852 -251.158502)
			(xy 38.947343 -251.186388) (xy 38.939223 -251.241564) (xy 38.923155 -251.294971) (xy 38.899483 -251.345468)
			(xy 38.86871 -251.391981) (xy 38.831493 -251.433518) (xy 38.788625 -251.469193) (xy 38.741019 -251.498247)
			(xy 38.68969 -251.520059) (xy 38.635733 -251.534165) (xy 38.580296 -251.540265) (xy 38.524562 -251.538228)
			(xy 38.469719 -251.528098) (xy 38.416935 -251.510091) (xy 38.367335 -251.48459) (xy 38.321977 -251.452139)
			(xy 38.281828 -251.41343) (xy 38.247742 -251.369287) (xy 38.220446 -251.320652) (xy 38.200523 -251.268561)
			(xy 38.188397 -251.214124) (xy 38.184326 -251.158502) (xy 37.931852 -251.158502) (xy 37.931343 -251.186388)
			(xy 37.923223 -251.241564) (xy 37.907155 -251.294971) (xy 37.883483 -251.345468) (xy 37.85271 -251.391981)
			(xy 37.815493 -251.433518) (xy 37.772625 -251.469193) (xy 37.725019 -251.498247) (xy 37.67369 -251.520059)
			(xy 37.619733 -251.534165) (xy 37.564296 -251.540265) (xy 37.508562 -251.538228) (xy 37.453719 -251.528098)
			(xy 37.400935 -251.510091) (xy 37.351335 -251.48459) (xy 37.305977 -251.452139) (xy 37.265828 -251.41343)
			(xy 37.231742 -251.369287) (xy 37.204446 -251.320652) (xy 37.184523 -251.268561) (xy 37.172397 -251.214124)
			(xy 37.168326 -251.158502) (xy 36.915852 -251.158502) (xy 36.915343 -251.186388) (xy 36.907223 -251.241564)
			(xy 36.891155 -251.294971) (xy 36.867483 -251.345468) (xy 36.83671 -251.391981) (xy 36.799493 -251.433518)
			(xy 36.756625 -251.469193) (xy 36.709019 -251.498247) (xy 36.65769 -251.520059) (xy 36.603733 -251.534165)
			(xy 36.548296 -251.540265) (xy 36.492562 -251.538228) (xy 36.437719 -251.528098) (xy 36.384935 -251.510091)
			(xy 36.335335 -251.48459) (xy 36.289977 -251.452139) (xy 36.249828 -251.41343) (xy 36.215742 -251.369287)
			(xy 36.188446 -251.320652) (xy 36.168523 -251.268561) (xy 36.156397 -251.214124) (xy 36.152326 -251.158502)
			(xy 35.899852 -251.158502) (xy 35.899343 -251.186388) (xy 35.891223 -251.241564) (xy 35.875155 -251.294971)
			(xy 35.851483 -251.345468) (xy 35.82071 -251.391981) (xy 35.783493 -251.433518) (xy 35.740625 -251.469193)
			(xy 35.693019 -251.498247) (xy 35.64169 -251.520059) (xy 35.587733 -251.534165) (xy 35.532296 -251.540265)
			(xy 35.476562 -251.538228) (xy 35.421719 -251.528098) (xy 35.368935 -251.510091) (xy 35.319335 -251.48459)
			(xy 35.273977 -251.452139) (xy 35.233828 -251.41343) (xy 35.199742 -251.369287) (xy 35.172446 -251.320652)
			(xy 35.152523 -251.268561) (xy 35.140397 -251.214124) (xy 35.136326 -251.158502) (xy 34.883852 -251.158502)
			(xy 34.883343 -251.186388) (xy 34.875223 -251.241564) (xy 34.859155 -251.294971) (xy 34.835483 -251.345468)
			(xy 34.80471 -251.391981) (xy 34.767493 -251.433518) (xy 34.724625 -251.469193) (xy 34.677019 -251.498247)
			(xy 34.62569 -251.520059) (xy 34.571733 -251.534165) (xy 34.516296 -251.540265) (xy 34.460562 -251.538228)
			(xy 34.405719 -251.528098) (xy 34.352935 -251.510091) (xy 34.303335 -251.48459) (xy 34.257977 -251.452139)
			(xy 34.217828 -251.41343) (xy 34.183742 -251.369287) (xy 34.156446 -251.320652) (xy 34.136523 -251.268561)
			(xy 34.124397 -251.214124) (xy 34.120326 -251.158502) (xy 33.867852 -251.158502) (xy 33.867343 -251.186388)
			(xy 33.859223 -251.241564) (xy 33.843155 -251.294971) (xy 33.819483 -251.345468) (xy 33.78871 -251.391981)
			(xy 33.751493 -251.433518) (xy 33.708625 -251.469193) (xy 33.661019 -251.498247) (xy 33.60969 -251.520059)
			(xy 33.555733 -251.534165) (xy 33.500296 -251.540265) (xy 33.444562 -251.538228) (xy 33.389719 -251.528098)
			(xy 33.336935 -251.510091) (xy 33.287335 -251.48459) (xy 33.241977 -251.452139) (xy 33.201828 -251.41343)
			(xy 33.167742 -251.369287) (xy 33.140446 -251.320652) (xy 33.120523 -251.268561) (xy 33.108397 -251.214124)
			(xy 33.104326 -251.158502) (xy 32.851852 -251.158502) (xy 32.851343 -251.186388) (xy 32.843223 -251.241564)
			(xy 32.827155 -251.294971) (xy 32.803483 -251.345468) (xy 32.77271 -251.391981) (xy 32.735493 -251.433518)
			(xy 32.692625 -251.469193) (xy 32.645019 -251.498247) (xy 32.59369 -251.520059) (xy 32.539733 -251.534165)
			(xy 32.484296 -251.540265) (xy 32.428562 -251.538228) (xy 32.373719 -251.528098) (xy 32.320935 -251.510091)
			(xy 32.271335 -251.48459) (xy 32.225977 -251.452139) (xy 32.185828 -251.41343) (xy 32.151742 -251.369287)
			(xy 32.124446 -251.320652) (xy 32.104523 -251.268561) (xy 32.092397 -251.214124) (xy 32.088326 -251.158502)
			(xy 31.835852 -251.158502) (xy 31.835343 -251.186388) (xy 31.827223 -251.241564) (xy 31.811155 -251.294971)
			(xy 31.787483 -251.345468) (xy 31.75671 -251.391981) (xy 31.719493 -251.433518) (xy 31.676625 -251.469193)
			(xy 31.629019 -251.498247) (xy 31.57769 -251.520059) (xy 31.523733 -251.534165) (xy 31.468296 -251.540265)
			(xy 31.412562 -251.538228) (xy 31.357719 -251.528098) (xy 31.304935 -251.510091) (xy 31.255335 -251.48459)
			(xy 31.209977 -251.452139) (xy 31.169828 -251.41343) (xy 31.135742 -251.369287) (xy 31.108446 -251.320652)
			(xy 31.088523 -251.268561) (xy 31.076397 -251.214124) (xy 31.072326 -251.158502) (xy 30.819852 -251.158502)
			(xy 30.819343 -251.186388) (xy 30.811223 -251.241564) (xy 30.795155 -251.294971) (xy 30.771483 -251.345468)
			(xy 30.74071 -251.391981) (xy 30.703493 -251.433518) (xy 30.660625 -251.469193) (xy 30.613019 -251.498247)
			(xy 30.56169 -251.520059) (xy 30.507733 -251.534165) (xy 30.452296 -251.540265) (xy 30.396562 -251.538228)
			(xy 30.341719 -251.528098) (xy 30.288935 -251.510091) (xy 30.239335 -251.48459) (xy 30.193977 -251.452139)
			(xy 30.153828 -251.41343) (xy 30.119742 -251.369287) (xy 30.092446 -251.320652) (xy 30.072523 -251.268561)
			(xy 30.060397 -251.214124) (xy 30.056326 -251.158502) (xy 29.80332 -251.158502) (xy 29.80332 -251.185749)
			(xy 29.795565 -251.239693) (xy 29.780212 -251.291984) (xy 29.757574 -251.341558) (xy 29.728112 -251.387406)
			(xy 29.692426 -251.428595) (xy 29.651241 -251.464286) (xy 29.605396 -251.493753) (xy 29.555825 -251.516397)
			(xy 29.503536 -251.531756) (xy 29.449593 -251.539517) (xy 29.422344 -251.54001) (xy 29.395184 -251.539554)
			(xy 29.341408 -251.53189) (xy 29.289264 -251.516668) (xy 29.239811 -251.494196) (xy 29.194049 -251.464931)
			(xy 29.17317 -251.447554) (xy 29.16174 -251.437648) (xy 29.13253 -251.43333) (xy 29.034994 -251.478288)
			(xy 29.026374 -251.482689) (xy 29.013007 -251.496664) (xy 29.005764 -251.514595) (xy 29.005276 -251.524262)
			(xy 29.005276 -253.45644) (xy 39.200326 -253.45644) (xy 39.204397 -253.400818) (xy 39.216523 -253.346381)
			(xy 39.236446 -253.29429) (xy 39.263742 -253.245655) (xy 39.297828 -253.201512) (xy 39.337977 -253.162803)
			(xy 39.383335 -253.130352) (xy 39.432935 -253.104851) (xy 39.485719 -253.086844) (xy 39.540562 -253.076714)
			(xy 39.596296 -253.074677) (xy 39.651733 -253.080777) (xy 39.70569 -253.094883) (xy 39.757019 -253.116695)
			(xy 39.804625 -253.145749) (xy 39.847493 -253.181424) (xy 39.88471 -253.222961) (xy 39.915483 -253.269474)
			(xy 39.939155 -253.319971) (xy 39.955223 -253.373378) (xy 39.963343 -253.428554) (xy 39.963852 -253.45644)
			(xy 39.963343 -253.484326) (xy 39.955223 -253.539502) (xy 39.939155 -253.592909) (xy 39.915483 -253.643406)
			(xy 39.88471 -253.689919) (xy 39.847493 -253.731456) (xy 39.804625 -253.767131) (xy 39.757019 -253.796185)
			(xy 39.70569 -253.817997) (xy 39.651733 -253.832103) (xy 39.596296 -253.838203) (xy 39.540562 -253.836166)
			(xy 39.485719 -253.826036) (xy 39.432935 -253.808029) (xy 39.383335 -253.782528) (xy 39.337977 -253.750077)
			(xy 39.297828 -253.711368) (xy 39.263742 -253.667225) (xy 39.236446 -253.61859) (xy 39.216523 -253.566499)
			(xy 39.204397 -253.512062) (xy 39.200326 -253.45644) (xy 29.005276 -253.45644) (xy 29.005276 -254.861314)
			(xy 29.00485 -254.871383) (xy 28.997129 -254.889981) (xy 28.99029 -254.897382) (xy 27.8638 -256.023872)
			(xy 27.856965 -256.031274) (xy 27.849256 -256.049873) (xy 27.848814 -256.05994) (xy 27.848814 -256.975864)
			(xy 27.849249 -256.985929) (xy 27.856981 -257.004515) (xy 27.8638 -257.011932) (xy 28.087574 -257.235706)
			(xy 28.094977 -257.24254) (xy 28.113575 -257.250247) (xy 28.123642 -257.250692)
		)
		(stroke
			(width 0)
			(type solid)
		)
		(fill yes)
		(layer "In7.Cu")
		(net "GND")
	)
	(gr_poly
		(pts
			(xy 358.217724 -291.6682) (xy 358.227751 -291.667749) (xy 358.246307 -291.660157) (xy 358.253792 -291.653468)
			(xy 358.269794 -291.637466) (xy 358.276636 -291.630066) (xy 358.284359 -291.611468) (xy 358.28478 -291.601398)
			(xy 358.28478 -287.379664) (xy 358.284081 -287.367506) (xy 358.272937 -287.345892) (xy 358.263444 -287.338262)
			(xy 358.185974 -287.28289) (xy 358.161844 -287.279334) (xy 358.15016 -287.283398) (xy 358.124953 -287.29166)
			(xy 358.073193 -287.303275) (xy 358.020473 -287.309164) (xy 357.99395 -287.30956) (xy 357.962344 -287.309047)
			(xy 357.899672 -287.300805) (xy 357.838612 -287.284455) (xy 357.780207 -287.260278) (xy 357.725457 -287.228686)
			(xy 357.675297 -287.190219) (xy 357.630585 -287.145537) (xy 357.592087 -287.095401) (xy 357.560459 -287.040671)
			(xy 357.536244 -286.982282) (xy 357.519856 -286.921232) (xy 357.511573 -286.858565) (xy 357.511096 -286.82696)
			(xy 357.511096 -285.580074) (xy 357.510668 -285.570006) (xy 357.502946 -285.551409) (xy 357.49611 -285.544006)
			(xy 357.135176 -285.183326) (xy 357.11324 -285.160631) (xy 357.07484 -285.110538) (xy 357.043294 -285.055868)
			(xy 357.019139 -284.997554) (xy 357.002788 -284.936591) (xy 356.994518 -284.874017) (xy 356.993952 -284.842458)
			(xy 356.993952 -283.268674) (xy 356.993523 -283.258607) (xy 356.985796 -283.240014) (xy 356.978966 -283.232606)
			(xy 356.452678 -282.706318) (xy 356.445279 -282.699473) (xy 356.426681 -282.691744) (xy 356.41661 -282.691332)
			(xy 354.640134 -282.691332) (xy 354.629113 -282.691866) (xy 354.609091 -282.701081) (xy 354.601526 -282.709112)
			(xy 354.551234 -282.767532) (xy 354.544497 -282.776263) (xy 354.538459 -282.797451) (xy 354.53955 -282.808426)
			(xy 354.541673 -282.822874) (xy 354.543965 -282.85199) (xy 354.544122 -282.866592) (xy 354.543637 -282.893844)
			(xy 354.535881 -282.947793) (xy 354.520527 -283.00009) (xy 354.497886 -283.049669) (xy 354.468421 -283.095521)
			(xy 354.432729 -283.136714) (xy 354.391539 -283.172407) (xy 354.345688 -283.201876) (xy 354.29611 -283.224519)
			(xy 354.243815 -283.239877) (xy 354.189866 -283.247635) (xy 354.162614 -283.2481) (xy 354.135246 -283.247622)
			(xy 354.081074 -283.239787) (xy 354.028577 -283.224291) (xy 353.978834 -283.201451) (xy 353.932866 -283.171736)
			(xy 353.911916 -283.15412) (xy 353.911662 -283.15412) (xy 353.911662 -283.153866) (xy 353.904572 -283.148289)
			(xy 353.887655 -283.142064) (xy 353.878642 -283.141674) (xy 353.811586 -283.141674) (xy 353.80257 -283.142036)
			(xy 353.785655 -283.148284) (xy 353.778566 -283.153866) (xy 353.778312 -283.15412) (xy 353.75738 -283.171762)
			(xy 353.711414 -283.201488) (xy 353.661667 -283.224331) (xy 353.609164 -283.239822) (xy 353.554985 -283.247642)
			(xy 353.527614 -283.2481) (xy 353.500361 -283.247638) (xy 353.446409 -283.239882) (xy 353.39411 -283.224527)
			(xy 353.344528 -283.201886) (xy 353.298674 -283.172418) (xy 353.25748 -283.136724) (xy 353.221786 -283.095531)
			(xy 353.192317 -283.049677) (xy 353.169675 -283.000096) (xy 353.154319 -282.947797) (xy 353.146563 -282.893845)
			(xy 353.146106 -282.866592) (xy 353.146592 -282.839353) (xy 353.154343 -282.785429) (xy 353.169686 -282.733157)
			(xy 353.192309 -282.683598) (xy 353.221752 -282.637762) (xy 353.257417 -282.596581) (xy 353.298576 -282.560892)
			(xy 353.344394 -282.531421) (xy 353.393939 -282.508767) (xy 353.446202 -282.493392) (xy 353.500121 -282.485609)
			(xy 353.52736 -282.485084) (xy 353.527868 -282.485084) (xy 353.549458 -282.485846) (xy 353.549966 -282.485846)
			(xy 353.565714 -282.486862) (xy 353.592638 -282.470606) (xy 353.638104 -282.36926) (xy 353.641876 -282.359717)
			(xy 353.642272 -282.339219) (xy 353.634597 -282.320209) (xy 353.62769 -282.312618) (xy 352.758248 -281.443176)
			(xy 352.751391 -281.436911) (xy 352.734443 -281.429347) (xy 352.715913 -281.428323) (xy 352.70694 -281.43073)
			(xy 352.621088 -281.457654) (xy 352.612332 -281.460835) (xy 352.59775 -281.472402) (xy 352.58829 -281.488431)
			(xy 352.58629 -281.497532) (xy 352.581385 -281.52285) (xy 352.565661 -281.571965) (xy 352.543477 -281.618521)
			(xy 352.515234 -281.66167) (xy 352.49866 -281.681428) (xy 352.49231 -281.688794) (xy 352.48596 -281.706574)
			(xy 352.489262 -281.795728) (xy 352.497136 -281.813508) (xy 352.503994 -281.820112) (xy 352.525104 -281.84176)
			(xy 352.560896 -281.890488) (xy 352.588558 -281.944251) (xy 352.607396 -282.001703) (xy 352.61694 -282.061407)
			(xy 352.617532 -282.091638) (xy 352.617045 -282.119278) (xy 352.60907 -282.173979) (xy 352.593278 -282.226954)
			(xy 352.570001 -282.277094) (xy 352.539726 -282.323346) (xy 352.521774 -282.344368) (xy 352.513392 -282.353766)
			(xy 352.50755 -282.37815) (xy 352.53168 -282.47213) (xy 352.53535 -282.484096) (xy 352.55213 -282.502626)
			(xy 352.563684 -282.507436) (xy 352.591092 -282.517774) (xy 352.64261 -282.54565) (xy 352.689257 -282.581079)
			(xy 352.729936 -282.623227) (xy 352.763688 -282.671101) (xy 352.789719 -282.723576) (xy 352.807416 -282.779415)
			(xy 352.816363 -282.837304) (xy 352.816922 -282.866592) (xy 352.816321 -282.896428) (xy 352.807004 -282.955371)
			(xy 352.79838 -282.98394) (xy 352.795078 -282.994354) (xy 352.797364 -283.015944) (xy 352.847656 -283.100526)
			(xy 352.864928 -283.112972) (xy 352.87585 -283.115004) (xy 352.901649 -283.12041) (xy 352.951554 -283.137382)
			(xy 352.998648 -283.161062) (xy 353.042033 -283.190999) (xy 353.080885 -283.226624) (xy 353.114462 -283.267257)
			(xy 353.142127 -283.312126) (xy 353.163351 -283.360376) (xy 353.177732 -283.411089) (xy 353.184994 -283.463298)
			(xy 353.185476 -283.489654) (xy 353.18491 -283.519779) (xy 353.175444 -283.579282) (xy 353.15674 -283.636555)
			(xy 353.129263 -283.690175) (xy 353.093697 -283.738808) (xy 353.0727 -283.760418) (xy 353.065857 -283.767818)
			(xy 353.058129 -283.786416) (xy 353.057714 -283.796486) (xy 353.057714 -283.868622) (xy 353.058142 -283.87869)
			(xy 353.065863 -283.897287) (xy 353.0727 -283.90469) (xy 353.093675 -283.926317) (xy 353.129224 -283.974953)
			(xy 353.15669 -284.028571) (xy 353.175392 -284.085838) (xy 353.184864 -284.145332) (xy 353.185476 -284.175454)
			(xy 353.18499 -284.202705) (xy 353.177234 -284.256653) (xy 353.161879 -284.308948) (xy 353.139237 -284.358525)
			(xy 353.109771 -284.404375) (xy 353.07408 -284.445566) (xy 353.032889 -284.481257) (xy 352.987039 -284.510723)
			(xy 352.937462 -284.533365) (xy 352.885167 -284.54872) (xy 352.831219 -284.556476) (xy 352.776717 -284.556476)
			(xy 352.722769 -284.54872) (xy 352.670474 -284.533365) (xy 352.620897 -284.510723) (xy 352.575047 -284.481257)
			(xy 352.533856 -284.445566) (xy 352.498165 -284.404375) (xy 352.468699 -284.358525) (xy 352.446057 -284.308948)
			(xy 352.430702 -284.256653) (xy 352.422946 -284.202705) (xy 352.42246 -284.175454) (xy 352.423025 -284.145329)
			(xy 352.432491 -284.085827) (xy 352.451196 -284.028553) (xy 352.478674 -283.974934) (xy 352.514242 -283.926302)
			(xy 352.535236 -283.90469) (xy 352.542088 -283.897294) (xy 352.549828 -283.878695) (xy 352.550222 -283.868622)
			(xy 352.550222 -283.796486) (xy 352.549797 -283.786416) (xy 352.542081 -283.767814) (xy 352.535236 -283.760418)
			(xy 352.51426 -283.738792) (xy 352.478706 -283.690157) (xy 352.451236 -283.636539) (xy 352.432531 -283.579272)
			(xy 352.423057 -283.519776) (xy 352.42246 -283.489654) (xy 352.423057 -283.459817) (xy 352.432368 -283.400873)
			(xy 352.441002 -283.372306) (xy 352.444304 -283.361892) (xy 352.442018 -283.340302) (xy 352.391726 -283.25572)
			(xy 352.374454 -283.243274) (xy 352.363532 -283.241242) (xy 352.335683 -283.235367) (xy 352.282001 -283.216464)
			(xy 352.231726 -283.18979) (xy 352.185974 -283.15594) (xy 352.145762 -283.115664) (xy 352.111985 -283.069858)
			(xy 352.085392 -283.01954) (xy 352.066574 -282.965828) (xy 352.060764 -282.937966) (xy 352.058224 -282.92552)
			(xy 352.042984 -282.906216) (xy 351.941892 -282.862528) (xy 351.917254 -282.864306) (xy 351.906586 -282.871164)
			(xy 351.883593 -282.885156) (xy 351.834514 -282.907251) (xy 351.78282 -282.922243) (xy 351.729535 -282.929837)
			(xy 351.702624 -282.930346) (xy 351.684606 -282.93011) (xy 351.648733 -282.926671) (xy 351.630996 -282.923488)
			(xy 351.621344 -282.92171) (xy 351.602294 -282.925266) (xy 351.527364 -282.973272) (xy 351.515934 -282.98902)
			(xy 351.513648 -282.998418) (xy 351.506264 -283.025467) (xy 351.484649 -283.077203) (xy 351.455693 -283.125217)
			(xy 351.420019 -283.168473) (xy 351.378396 -283.206041) (xy 351.331721 -283.237109) (xy 351.281001 -283.261009)
			(xy 351.227328 -283.277226) (xy 351.171859 -283.28541) (xy 351.143824 -283.285946) (xy 351.116571 -283.285462)
			(xy 351.062618 -283.277708) (xy 351.010318 -283.262356) (xy 350.960736 -283.239716) (xy 350.91488 -283.210251)
			(xy 350.873683 -283.17456) (xy 350.837986 -283.13337) (xy 350.808513 -283.087519) (xy 350.785866 -283.03794)
			(xy 350.770505 -282.985642) (xy 350.762743 -282.931691) (xy 350.762316 -282.904438) (xy 350.7628 -282.876863)
			(xy 350.770738 -282.822288) (xy 350.786454 -282.769425) (xy 350.80962 -282.719377) (xy 350.839753 -282.673187)
			(xy 350.876225 -282.631819) (xy 350.896936 -282.613608) (xy 350.905024 -282.606066) (xy 350.914356 -282.586044)
			(xy 350.91497 -282.575) (xy 350.91497 -282.497276) (xy 350.91436 -282.486237) (xy 350.905003 -282.46623)
			(xy 350.896936 -282.458668) (xy 350.875462 -282.439757) (xy 350.837866 -282.396623) (xy 350.807121 -282.348366)
			(xy 350.783913 -282.296065) (xy 350.76876 -282.240889) (xy 350.764856 -282.212542) (xy 350.763332 -282.198064)
			(xy 350.745044 -282.175204) (xy 350.644714 -282.140406) (xy 350.635585 -282.137689) (xy 350.616569 -282.138488)
			(xy 350.599144 -282.146147) (xy 350.592136 -282.152598) (xy 349.769938 -282.97505) (xy 349.761696 -282.983155)
			(xy 349.744543 -282.998655) (xy 349.735648 -283.006038) (xy 349.731428 -283.009667) (xy 349.724503 -283.018375)
			(xy 349.721932 -283.02331) (xy 349.707708 -283.052774) (xy 349.708123 -283.062798) (xy 349.715789 -283.081323)
			(xy 349.729962 -283.095501) (xy 349.748484 -283.103173) (xy 349.758508 -283.103574) (xy 349.776034 -283.099256)
			(xy 349.786448 -283.095446) (xy 349.812843 -283.082996) (xy 349.868497 -283.065438) (xy 349.926179 -283.056582)
			(xy 349.955358 -283.056076) (xy 349.955612 -283.056076) (xy 349.982863 -283.056563) (xy 350.03681 -283.06432)
			(xy 350.089105 -283.079676) (xy 350.138681 -283.102318) (xy 350.184531 -283.131784) (xy 350.225722 -283.167476)
			(xy 350.261413 -283.208665) (xy 350.29088 -283.254515) (xy 350.313522 -283.304092) (xy 350.328879 -283.356386)
			(xy 350.336637 -283.410333) (xy 350.33712 -283.437584) (xy 350.336643 -283.464952) (xy 350.328809 -283.519125)
			(xy 350.313313 -283.571622) (xy 350.290474 -283.621366) (xy 350.260761 -283.667335) (xy 350.24314 -283.688282)
			(xy 350.24314 -283.688536) (xy 350.242886 -283.688536) (xy 350.237308 -283.695625) (xy 350.231079 -283.712542)
			(xy 350.230694 -283.721556) (xy 350.230694 -283.788612) (xy 350.231055 -283.797628) (xy 350.237305 -283.814542)
			(xy 350.242886 -283.821632) (xy 350.24314 -283.821886) (xy 350.260785 -283.842816) (xy 350.290518 -283.888781)
			(xy 350.313366 -283.938527) (xy 350.328861 -283.991031) (xy 350.336683 -284.045213) (xy 350.33712 -284.072584)
			(xy 350.336634 -284.099835) (xy 350.328878 -284.153783) (xy 350.313523 -284.206078) (xy 350.290881 -284.255655)
			(xy 350.261415 -284.301505) (xy 350.225724 -284.342696) (xy 350.184533 -284.378387) (xy 350.138683 -284.407853)
			(xy 350.089106 -284.430495) (xy 350.036811 -284.44585) (xy 349.982863 -284.453606) (xy 349.928361 -284.453606)
			(xy 349.874413 -284.44585) (xy 349.822118 -284.430495) (xy 349.772541 -284.407853) (xy 349.726691 -284.378387)
			(xy 349.6855 -284.342696) (xy 349.649809 -284.301505) (xy 349.620343 -284.255655) (xy 349.597701 -284.206078)
			(xy 349.582346 -284.153783) (xy 349.57459 -284.099835) (xy 349.574104 -284.072584) (xy 349.574577 -284.045214)
			(xy 349.582403 -283.991037) (xy 349.597892 -283.938535) (xy 349.620726 -283.888786) (xy 349.650436 -283.84281)
			(xy 349.668084 -283.821886) (xy 349.668084 -283.821632) (xy 349.668338 -283.821632) (xy 349.673925 -283.814545)
			(xy 349.680172 -283.797629) (xy 349.68053 -283.788612) (xy 349.68053 -283.721556) (xy 349.680164 -283.712542)
			(xy 349.673908 -283.695634) (xy 349.668338 -283.688536) (xy 349.668084 -283.688282) (xy 349.654622 -283.672026)
			(xy 349.650304 -283.666692) (xy 349.632853 -283.642444) (xy 349.604912 -283.589643) (xy 349.585537 -283.533134)
			(xy 349.575204 -283.474296) (xy 349.574104 -283.444442) (xy 349.574104 -283.437584) (xy 349.574755 -283.406253)
			(xy 349.585037 -283.344439) (xy 349.605286 -283.285137) (xy 349.61957 -283.257244) (xy 349.61957 -283.25699)
			(xy 349.623675 -283.248455) (xy 349.625906 -283.229661) (xy 349.621186 -283.211332) (xy 349.616014 -283.203396)
			(xy 349.55353 -283.11729) (xy 349.52686 -283.106622) (xy 349.512382 -283.109162) (xy 349.491536 -283.112618)
			(xy 349.449438 -283.116306) (xy 349.428308 -283.116528) (xy 348.616778 -283.116528) (xy 348.585146 -283.11601)
			(xy 348.522424 -283.107753) (xy 348.461316 -283.091383) (xy 348.402865 -283.067181) (xy 348.348072 -283.035559)
			(xy 348.297873 -282.997059) (xy 348.275148 -282.97505) (xy 348.012258 -282.711906) (xy 348.004857 -282.705065)
			(xy 347.986259 -282.697345) (xy 347.97619 -282.69692) (xy 346.41282 -282.69692) (xy 346.381262 -282.69637)
			(xy 346.318693 -282.688079) (xy 346.257735 -282.671714) (xy 346.199427 -282.647553) (xy 346.144759 -282.616008)
			(xy 346.094663 -282.577615) (xy 346.071952 -282.555696) (xy 344.62466 -281.10815) (xy 344.617262 -281.101305)
			(xy 344.598663 -281.093577) (xy 344.588592 -281.093164) (xy 344.133424 -281.093164) (xy 344.124572 -281.093549)
			(xy 344.10792 -281.099567) (xy 344.094288 -281.110866) (xy 344.089482 -281.11831) (xy 344.045286 -281.194002)
			(xy 344.041146 -281.20182) (xy 344.037929 -281.219201) (xy 344.040807 -281.236642) (xy 344.044778 -281.244548)
			(xy 344.056371 -281.266013) (xy 344.074615 -281.311258) (xy 344.086949 -281.358459) (xy 344.09317 -281.406845)
			(xy 344.093546 -281.431238) (xy 344.093078 -281.458536) (xy 344.085292 -281.512575) (xy 344.069885 -281.564954)
			(xy 344.047172 -281.614602) (xy 344.017616 -281.660506) (xy 344.000074 -281.681428) (xy 343.993724 -281.688794)
			(xy 343.987374 -281.706574) (xy 343.990676 -281.795728) (xy 343.99855 -281.813508) (xy 344.005408 -281.820112)
			(xy 344.026517 -281.84176) (xy 344.062308 -281.890489) (xy 344.089969 -281.944252) (xy 344.108806 -282.001704)
			(xy 344.118349 -282.061407) (xy 344.118946 -282.091638) (xy 344.118459 -282.119278) (xy 344.110484 -282.173979)
			(xy 344.094693 -282.226955) (xy 344.071416 -282.277095) (xy 344.041142 -282.323348) (xy 344.023188 -282.344368)
			(xy 344.014806 -282.353766) (xy 344.008964 -282.37815) (xy 344.033094 -282.47213) (xy 344.036764 -282.484095)
			(xy 344.053547 -282.502621) (xy 344.065098 -282.507436) (xy 344.092505 -282.517775) (xy 344.144022 -282.545652)
			(xy 344.190667 -282.581081) (xy 344.231344 -282.623229) (xy 344.265095 -282.671104) (xy 344.291125 -282.723578)
			(xy 344.308821 -282.779416) (xy 344.317768 -282.837304) (xy 344.318336 -282.866592) (xy 344.317787 -282.893855)
			(xy 344.647947 -282.893855) (xy 344.647947 -282.839345) (xy 344.655705 -282.785391) (xy 344.671063 -282.73309)
			(xy 344.693708 -282.683507) (xy 344.723179 -282.637651) (xy 344.758877 -282.596457) (xy 344.800074 -282.560763)
			(xy 344.845931 -282.531295) (xy 344.895516 -282.508653) (xy 344.947818 -282.493299) (xy 345.001773 -282.485545)
			(xy 345.029028 -282.485084) (xy 345.0564 -282.485513) (xy 345.110581 -282.493337) (xy 345.163086 -282.508833)
			(xy 345.212832 -282.531684) (xy 345.258796 -282.561418) (xy 345.279726 -282.579064) (xy 345.27998 -282.579318)
			(xy 345.287067 -282.584904) (xy 345.303983 -282.591151) (xy 345.313 -282.59151) (xy 345.380056 -282.59151)
			(xy 345.389071 -282.59113) (xy 345.405988 -282.584898) (xy 345.413076 -282.579318) (xy 345.413076 -282.579064)
			(xy 345.41333 -282.579064) (xy 345.434273 -282.561439) (xy 345.480243 -282.531726) (xy 345.529988 -282.508888)
			(xy 345.582486 -282.493394) (xy 345.63666 -282.485561) (xy 345.664028 -282.485084) (xy 345.691277 -282.485588)
			(xy 345.745221 -282.493347) (xy 345.797511 -282.508704) (xy 345.847084 -282.531347) (xy 345.89293 -282.560813)
			(xy 345.934116 -282.596504) (xy 345.969804 -282.637693) (xy 345.999267 -282.683541) (xy 346.021905 -282.733115)
			(xy 346.037259 -282.785406) (xy 346.045014 -282.839351) (xy 346.045014 -282.893849) (xy 346.037259 -282.947794)
			(xy 346.021905 -283.000085) (xy 345.999267 -283.049659) (xy 345.969804 -283.095507) (xy 345.934116 -283.136696)
			(xy 345.89293 -283.172387) (xy 345.847084 -283.201853) (xy 345.797511 -283.224496) (xy 345.745221 -283.239853)
			(xy 345.691277 -283.247612) (xy 345.664028 -283.2481) (xy 345.636658 -283.247618) (xy 345.58248 -283.239804)
			(xy 345.529977 -283.224318) (xy 345.48023 -283.20148) (xy 345.434262 -283.171759) (xy 345.41333 -283.15412)
			(xy 345.413076 -283.153866) (xy 345.406003 -283.148259) (xy 345.389076 -283.142026) (xy 345.380056 -283.141674)
			(xy 345.313 -283.141674) (xy 345.303984 -283.142037) (xy 345.287067 -283.148281) (xy 345.27998 -283.153866)
			(xy 345.27998 -283.15412) (xy 345.279726 -283.15412) (xy 345.258798 -283.171763) (xy 345.212823 -283.201474)
			(xy 345.163075 -283.224309) (xy 345.110574 -283.239799) (xy 345.056397 -283.247626) (xy 345.029028 -283.2481)
			(xy 345.001773 -283.247655) (xy 344.947818 -283.239901) (xy 344.895516 -283.224547) (xy 344.845931 -283.201905)
			(xy 344.800074 -283.172437) (xy 344.758877 -283.136743) (xy 344.723179 -283.095549) (xy 344.693708 -283.049693)
			(xy 344.671063 -283.00011) (xy 344.655705 -282.947809) (xy 344.647947 -282.893855) (xy 344.317787 -282.893855)
			(xy 344.317735 -282.896428) (xy 344.308418 -282.955371) (xy 344.299794 -282.98394) (xy 344.296492 -282.994354)
			(xy 344.298778 -283.015944) (xy 344.34907 -283.100526) (xy 344.366342 -283.112972) (xy 344.377264 -283.115004)
			(xy 344.403067 -283.120406) (xy 344.452982 -283.137369) (xy 344.500085 -283.161044) (xy 344.54348 -283.190978)
			(xy 344.582341 -283.226601) (xy 344.615927 -283.267236) (xy 344.643599 -283.312108) (xy 344.664829 -283.360362)
			(xy 344.679213 -283.41108) (xy 344.686478 -283.463295) (xy 344.68689 -283.489654) (xy 344.686324 -283.519779)
			(xy 344.676858 -283.579282) (xy 344.658155 -283.636556) (xy 344.630678 -283.690177) (xy 344.595113 -283.738811)
			(xy 344.574114 -283.760418) (xy 344.567269 -283.767817) (xy 344.559539 -283.786415) (xy 344.559128 -283.796486)
			(xy 344.559128 -283.868622) (xy 344.559556 -283.87869) (xy 344.567279 -283.897286) (xy 344.574114 -283.90469)
			(xy 344.595092 -283.926315) (xy 344.630649 -283.974949) (xy 344.658122 -284.028566) (xy 344.676828 -284.085835)
			(xy 344.686302 -284.145331) (xy 344.68689 -284.175454) (xy 344.686404 -284.202705) (xy 344.678648 -284.256653)
			(xy 344.663293 -284.308948) (xy 344.640651 -284.358525) (xy 344.611185 -284.404375) (xy 344.575494 -284.445566)
			(xy 344.534303 -284.481257) (xy 344.488453 -284.510723) (xy 344.438876 -284.533365) (xy 344.386581 -284.54872)
			(xy 344.332633 -284.556476) (xy 344.278131 -284.556476) (xy 344.224183 -284.54872) (xy 344.171888 -284.533365)
			(xy 344.122311 -284.510723) (xy 344.076461 -284.481257) (xy 344.03527 -284.445566) (xy 343.999579 -284.404375)
			(xy 343.970113 -284.358525) (xy 343.947471 -284.308948) (xy 343.932116 -284.256653) (xy 343.92436 -284.202705)
			(xy 343.923874 -284.175454) (xy 343.924439 -284.145329) (xy 343.933905 -284.085827) (xy 343.95261 -284.028554)
			(xy 343.980089 -283.974935) (xy 344.015658 -283.926304) (xy 344.03665 -283.90469) (xy 344.0435 -283.897293)
			(xy 344.051239 -283.878695) (xy 344.051636 -283.868622) (xy 344.051636 -283.796486) (xy 344.051209 -283.786418)
			(xy 344.043484 -283.767824) (xy 344.03665 -283.760418) (xy 344.015673 -283.738793) (xy 343.980118 -283.690158)
			(xy 343.952647 -283.63654) (xy 343.933942 -283.579272) (xy 343.924467 -283.519777) (xy 343.923874 -283.489654)
			(xy 343.924471 -283.459817) (xy 343.933782 -283.400873) (xy 343.942416 -283.372306) (xy 343.945718 -283.361892)
			(xy 343.943432 -283.340302) (xy 343.89314 -283.25572) (xy 343.875868 -283.243274) (xy 343.864946 -283.241242)
			(xy 343.837097 -283.235368) (xy 343.783413 -283.216466) (xy 343.733136 -283.189794) (xy 343.687382 -283.155944)
			(xy 343.647169 -283.115668) (xy 343.61339 -283.069862) (xy 343.586796 -283.019543) (xy 343.567977 -282.96583)
			(xy 343.562178 -282.937966) (xy 343.559638 -282.92552) (xy 343.544398 -282.906216) (xy 343.443306 -282.862528)
			(xy 343.418668 -282.864306) (xy 343.408 -282.871164) (xy 343.385007 -282.885157) (xy 343.335928 -282.907253)
			(xy 343.284235 -282.922248) (xy 343.23095 -282.929844) (xy 343.204038 -282.930346) (xy 343.18602 -282.93011)
			(xy 343.150146 -282.926673) (xy 343.13241 -282.923488) (xy 343.122758 -282.92171) (xy 343.103708 -282.925266)
			(xy 343.028778 -282.973272) (xy 343.017348 -282.98902) (xy 343.015062 -282.998418) (xy 343.007678 -283.025468)
			(xy 342.986064 -283.077204) (xy 342.957108 -283.125219) (xy 342.921434 -283.168477) (xy 342.879811 -283.206046)
			(xy 342.833137 -283.237116) (xy 342.782416 -283.261018) (xy 342.728743 -283.277237) (xy 342.673273 -283.285422)
			(xy 342.645238 -283.285946) (xy 342.617984 -283.285463) (xy 342.56403 -283.277711) (xy 342.511729 -283.262359)
			(xy 342.462144 -283.239721) (xy 342.416286 -283.210256) (xy 342.375088 -283.174565) (xy 342.339389 -283.133375)
			(xy 342.309915 -283.087523) (xy 342.287267 -283.037943) (xy 342.271905 -282.985644) (xy 342.264143 -282.931692)
			(xy 342.26373 -282.904438) (xy 342.264214 -282.876862) (xy 342.272151 -282.822285) (xy 342.287864 -282.76942)
			(xy 342.311026 -282.719369) (xy 342.341155 -282.673174) (xy 342.377622 -282.6318) (xy 342.39835 -282.613608)
			(xy 342.406436 -282.606065) (xy 342.415765 -282.586043) (xy 342.416384 -282.575) (xy 342.416384 -282.497276)
			(xy 342.415775 -282.486236) (xy 342.406419 -282.466228) (xy 342.39835 -282.458668) (xy 342.386967 -282.448808)
			(xy 342.365604 -282.427576) (xy 342.355678 -282.41625) (xy 342.348407 -282.408573) (xy 342.329382 -282.399401)
			(xy 342.318848 -282.39847) (xy 342.244426 -282.395422) (xy 342.233898 -282.395564) (xy 342.214339 -282.403293)
			(xy 342.20658 -282.410408) (xy 341.73414 -282.882848) (xy 341.7275 -282.890215) (xy 341.719901 -282.908514)
			(xy 341.719752 -282.928327) (xy 341.722964 -282.937712) (xy 341.757762 -283.024072) (xy 341.76187 -283.033112)
			(xy 341.77566 -283.047372) (xy 341.793832 -283.055326) (xy 341.803736 -283.056076) (xy 341.830435 -283.057122)
			(xy 341.883164 -283.065762) (xy 341.93417 -283.081676) (xy 341.982457 -283.104552) (xy 342.027078 -283.133944)
			(xy 342.06716 -283.169276) (xy 342.101919 -283.209857) (xy 342.130674 -283.254891) (xy 342.152863 -283.303497)
			(xy 342.16805 -283.354725) (xy 342.17594 -283.407571) (xy 342.176608 -283.434282) (xy 342.176608 -283.437838)
			(xy 342.176048 -283.467868) (xy 342.16663 -283.527185) (xy 342.148018 -283.584288) (xy 342.120672 -283.637762)
			(xy 342.103456 -283.662374) (xy 342.100916 -283.66593) (xy 342.097386 -283.672221) (xy 342.093655 -283.686148)
			(xy 342.09355 -283.693362) (xy 342.09736 -283.74594) (xy 342.109044 -283.757624) (xy 342.109552 -283.758132)
			(xy 342.551512 -284.200092) (xy 342.571784 -284.22101) (xy 342.607277 -284.267199) (xy 342.63644 -284.317623)
			(xy 342.658776 -284.371422) (xy 342.673903 -284.427674) (xy 342.681562 -284.485419) (xy 342.682068 -284.514544)
			(xy 342.682068 -285.608522) (xy 342.683592 -285.614618) (xy 342.689999 -285.642693) (xy 342.696873 -285.69987)
			(xy 342.697308 -285.728664) (xy 342.697308 -286.596328) (xy 342.696878 -286.625122) (xy 342.690004 -286.6823)
			(xy 342.683592 -286.710374) (xy 342.682068 -286.71647) (xy 342.682068 -291.524436) (xy 342.68537 -291.53231)
			(xy 342.806782 -291.653722) (xy 342.81228 -291.658713) (xy 342.825444 -291.665565) (xy 342.83269 -291.667184)
			(xy 342.842342 -291.6682)
		)
		(stroke
			(width 0)
			(type solid)
		)
		(fill yes)
		(layer "In7.Cu")
		(net "GND")
	)
	(gr_poly
		(pts
			(xy 231.303068 -321.442842) (xy 231.313057 -321.442309) (xy 231.331492 -321.434597) (xy 231.338882 -321.427856)
			(xy 232.28808 -320.478658) (xy 232.294886 -320.471312) (xy 232.302607 -320.452849) (xy 232.303066 -320.442844)
			(xy 232.303066 -310.621172) (xy 232.302616 -310.609749) (xy 232.292842 -310.589109) (xy 232.28427 -310.581548)
			(xy 232.213912 -310.524652) (xy 232.19156 -310.519318) (xy 232.180384 -310.521604) (xy 232.160805 -310.525509)
			(xy 232.121099 -310.529709) (xy 232.101136 -310.529986) (xy 232.073883 -310.529525) (xy 232.019931 -310.521773)
			(xy 231.967632 -310.506421) (xy 231.91805 -310.483782) (xy 231.872195 -310.454316) (xy 231.831001 -310.418625)
			(xy 231.795305 -310.377433) (xy 231.765836 -310.331581) (xy 231.743192 -310.282002) (xy 231.727835 -310.229704)
			(xy 231.720077 -310.175753) (xy 231.720077 -310.121247) (xy 231.727835 -310.067296) (xy 231.743192 -310.014998)
			(xy 231.765836 -309.965419) (xy 231.795305 -309.919567) (xy 231.831001 -309.878375) (xy 231.872195 -309.842684)
			(xy 231.91805 -309.813218) (xy 231.967632 -309.790579) (xy 232.019931 -309.775227) (xy 232.073883 -309.767475)
			(xy 232.101136 -309.76697) (xy 232.1211 -309.767235) (xy 232.160806 -309.771436) (xy 232.180384 -309.775352)
			(xy 232.19156 -309.777638) (xy 232.213912 -309.772304) (xy 232.28427 -309.715408) (xy 232.292712 -309.707742)
			(xy 232.302482 -309.687171) (xy 232.303066 -309.675784) (xy 232.303066 -308.977284) (xy 232.278682 -308.948836)
			(xy 232.259886 -308.946042) (xy 232.233183 -308.941483) (xy 232.181331 -308.925811) (xy 232.132216 -308.902962)
			(xy 232.086827 -308.873396) (xy 232.046076 -308.837706) (xy 232.010784 -308.796612) (xy 231.981658 -308.750939)
			(xy 231.959286 -308.701605) (xy 231.944117 -308.649603) (xy 231.936456 -308.595978) (xy 231.936457 -308.541808)
			(xy 231.94412 -308.488183) (xy 231.959291 -308.436182) (xy 231.981665 -308.386849) (xy 232.010792 -308.341176)
			(xy 232.046087 -308.300083) (xy 232.086838 -308.264396) (xy 232.132229 -308.234831) (xy 232.181344 -308.211984)
			(xy 232.233198 -308.196313) (xy 232.259886 -308.191662) (xy 232.278682 -308.188868) (xy 232.303066 -308.16042)
			(xy 232.303066 -307.892704) (xy 232.278682 -307.864256) (xy 232.259886 -307.861462) (xy 232.233182 -307.856903)
			(xy 232.181326 -307.841231) (xy 232.132209 -307.818381) (xy 232.086817 -307.788813) (xy 232.046064 -307.753122)
			(xy 232.010769 -307.712026) (xy 231.981642 -307.666351) (xy 231.959269 -307.617014) (xy 231.944098 -307.56501)
			(xy 231.936437 -307.511382) (xy 231.936437 -307.45721) (xy 231.9441 -307.403582) (xy 231.959272 -307.351578)
			(xy 231.981646 -307.302242) (xy 232.010775 -307.256567) (xy 232.04607 -307.215472) (xy 232.086824 -307.179782)
			(xy 232.132216 -307.150215) (xy 232.181334 -307.127366) (xy 232.23319 -307.111695) (xy 232.259886 -307.107082)
			(xy 232.278682 -307.104288) (xy 232.303066 -307.07584) (xy 232.303066 -304.958496) (xy 232.302641 -304.948427)
			(xy 232.294922 -304.929827) (xy 232.28808 -304.922428) (xy 231.883458 -304.517806) (xy 231.876057 -304.510965)
			(xy 231.857459 -304.503245) (xy 231.84739 -304.50282) (xy 218.601798 -304.50282) (xy 218.591728 -304.503244)
			(xy 218.573126 -304.510961) (xy 218.56573 -304.517806) (xy 218.240102 -304.843434) (xy 218.233261 -304.850834)
			(xy 218.225538 -304.869432) (xy 218.225116 -304.879502) (xy 218.225116 -306.744116) (xy 221.949516 -306.744116)
			(xy 221.953587 -306.688494) (xy 221.965713 -306.634057) (xy 221.985636 -306.581966) (xy 222.012932 -306.533331)
			(xy 222.047018 -306.489188) (xy 222.087167 -306.450479) (xy 222.132525 -306.418028) (xy 222.182125 -306.392527)
			(xy 222.234909 -306.37452) (xy 222.289752 -306.36439) (xy 222.345486 -306.362353) (xy 222.400923 -306.368453)
			(xy 222.45488 -306.382559) (xy 222.506209 -306.404371) (xy 222.553815 -306.433425) (xy 222.596683 -306.4691)
			(xy 222.6339 -306.510637) (xy 222.664673 -306.55715) (xy 222.688345 -306.607647) (xy 222.704413 -306.661054)
			(xy 222.712533 -306.71623) (xy 222.713042 -306.744116) (xy 222.712533 -306.772002) (xy 222.71032 -306.787042)
			(xy 229.223568 -306.787042) (xy 229.227639 -306.73142) (xy 229.239765 -306.676983) (xy 229.259688 -306.624892)
			(xy 229.286984 -306.576257) (xy 229.32107 -306.532114) (xy 229.361219 -306.493405) (xy 229.406577 -306.460954)
			(xy 229.456177 -306.435453) (xy 229.508961 -306.417446) (xy 229.563804 -306.407316) (xy 229.619538 -306.405279)
			(xy 229.674975 -306.411379) (xy 229.728932 -306.425485) (xy 229.780261 -306.447297) (xy 229.827867 -306.476351)
			(xy 229.870735 -306.512026) (xy 229.907952 -306.553563) (xy 229.938725 -306.600076) (xy 229.962397 -306.650573)
			(xy 229.978465 -306.70398) (xy 229.986585 -306.759156) (xy 229.987094 -306.787042) (xy 229.986585 -306.814928)
			(xy 229.978465 -306.870104) (xy 229.962397 -306.923511) (xy 229.938725 -306.974008) (xy 229.907952 -307.020521)
			(xy 229.870735 -307.062058) (xy 229.827867 -307.097733) (xy 229.780261 -307.126787) (xy 229.728932 -307.148599)
			(xy 229.674975 -307.162705) (xy 229.619538 -307.168805) (xy 229.563804 -307.166768) (xy 229.508961 -307.156638)
			(xy 229.456177 -307.138631) (xy 229.406577 -307.11313) (xy 229.361219 -307.080679) (xy 229.32107 -307.04197)
			(xy 229.286984 -306.997827) (xy 229.259688 -306.949192) (xy 229.239765 -306.897101) (xy 229.227639 -306.842664)
			(xy 229.223568 -306.787042) (xy 222.71032 -306.787042) (xy 222.704413 -306.827178) (xy 222.688345 -306.880585)
			(xy 222.664673 -306.931082) (xy 222.6339 -306.977595) (xy 222.596683 -307.019132) (xy 222.553815 -307.054807)
			(xy 222.506209 -307.083861) (xy 222.45488 -307.105673) (xy 222.400923 -307.119779) (xy 222.345486 -307.125879)
			(xy 222.289752 -307.123842) (xy 222.234909 -307.113712) (xy 222.182125 -307.095705) (xy 222.132525 -307.070204)
			(xy 222.087167 -307.037753) (xy 222.047018 -306.999044) (xy 222.012932 -306.954901) (xy 221.985636 -306.906266)
			(xy 221.965713 -306.854175) (xy 221.953587 -306.799738) (xy 221.949516 -306.744116) (xy 218.225116 -306.744116)
			(xy 218.225116 -307.446426) (xy 226.875084 -307.446426) (xy 226.879155 -307.390804) (xy 226.891281 -307.336367)
			(xy 226.911204 -307.284276) (xy 226.9385 -307.235641) (xy 226.972586 -307.191498) (xy 227.012735 -307.152789)
			(xy 227.058093 -307.120338) (xy 227.107693 -307.094837) (xy 227.160477 -307.07683) (xy 227.21532 -307.0667)
			(xy 227.271054 -307.064663) (xy 227.326491 -307.070763) (xy 227.380448 -307.084869) (xy 227.431777 -307.106681)
			(xy 227.479383 -307.135735) (xy 227.522251 -307.17141) (xy 227.559468 -307.212947) (xy 227.590241 -307.25946)
			(xy 227.613913 -307.309957) (xy 227.629981 -307.363364) (xy 227.638101 -307.41854) (xy 227.63861 -307.446426)
			(xy 227.638101 -307.474312) (xy 227.629981 -307.529488) (xy 227.613913 -307.582895) (xy 227.590241 -307.633392)
			(xy 227.559468 -307.679905) (xy 227.522251 -307.721442) (xy 227.479383 -307.757117) (xy 227.431777 -307.786171)
			(xy 227.380448 -307.807983) (xy 227.326491 -307.822089) (xy 227.271054 -307.828189) (xy 227.21532 -307.826152)
			(xy 227.160477 -307.816022) (xy 227.107693 -307.798015) (xy 227.058093 -307.772514) (xy 227.012735 -307.740063)
			(xy 226.972586 -307.701354) (xy 226.9385 -307.657211) (xy 226.911204 -307.608576) (xy 226.891281 -307.556485)
			(xy 226.879155 -307.502048) (xy 226.875084 -307.446426) (xy 218.225116 -307.446426) (xy 218.225116 -307.988462)
			(xy 218.225387 -307.996019) (xy 218.229762 -308.010488) (xy 218.233752 -308.01691) (xy 218.249754 -308.040278)
			(xy 218.26093 -308.049422) (xy 218.268042 -308.05247) (xy 218.344927 -308.084434) (xy 218.495791 -308.154939)
			(xy 218.642998 -308.232791) (xy 218.786191 -308.317801) (xy 218.913647 -308.402228) (xy 227.932994 -308.402228)
			(xy 227.937065 -308.346606) (xy 227.949191 -308.292169) (xy 227.969114 -308.240078) (xy 227.99641 -308.191443)
			(xy 228.030496 -308.1473) (xy 228.070645 -308.108591) (xy 228.116003 -308.07614) (xy 228.165603 -308.050639)
			(xy 228.218387 -308.032632) (xy 228.27323 -308.022502) (xy 228.328964 -308.020465) (xy 228.384401 -308.026565)
			(xy 228.438358 -308.040671) (xy 228.489687 -308.062483) (xy 228.537293 -308.091537) (xy 228.580161 -308.127212)
			(xy 228.617378 -308.168749) (xy 228.648151 -308.215262) (xy 228.671823 -308.265759) (xy 228.687891 -308.319166)
			(xy 228.696011 -308.374342) (xy 228.69652 -308.402228) (xy 228.696011 -308.430114) (xy 228.687891 -308.48529)
			(xy 228.671823 -308.538697) (xy 228.648151 -308.589194) (xy 228.617378 -308.635707) (xy 228.580161 -308.677244)
			(xy 228.537293 -308.712919) (xy 228.489687 -308.741973) (xy 228.438358 -308.763785) (xy 228.384401 -308.777891)
			(xy 228.328964 -308.783991) (xy 228.27323 -308.781954) (xy 228.218387 -308.771824) (xy 228.165603 -308.753817)
			(xy 228.116003 -308.728316) (xy 228.070645 -308.695865) (xy 228.030496 -308.657156) (xy 227.99641 -308.613013)
			(xy 227.969114 -308.564378) (xy 227.949191 -308.512287) (xy 227.937065 -308.45785) (xy 227.932994 -308.402228)
			(xy 218.913647 -308.402228) (xy 218.925022 -308.409763) (xy 219.059153 -308.508454) (xy 219.188259 -308.613632)
			(xy 219.312026 -308.725044) (xy 219.430154 -308.842419) (xy 219.542355 -308.965471) (xy 219.585858 -309.018178)
			(xy 229.941118 -309.018178) (xy 229.945189 -308.962556) (xy 229.957315 -308.908119) (xy 229.977238 -308.856028)
			(xy 230.004534 -308.807393) (xy 230.03862 -308.76325) (xy 230.078769 -308.724541) (xy 230.124127 -308.69209)
			(xy 230.173727 -308.666589) (xy 230.226511 -308.648582) (xy 230.281354 -308.638452) (xy 230.337088 -308.636415)
			(xy 230.392525 -308.642515) (xy 230.446482 -308.656621) (xy 230.497811 -308.678433) (xy 230.545417 -308.707487)
			(xy 230.588285 -308.743162) (xy 230.625502 -308.784699) (xy 230.656275 -308.831212) (xy 230.679947 -308.881709)
			(xy 230.696015 -308.935116) (xy 230.704135 -308.990292) (xy 230.704644 -309.018178) (xy 230.704135 -309.046064)
			(xy 230.696015 -309.10124) (xy 230.679947 -309.154647) (xy 230.656275 -309.205144) (xy 230.625502 -309.251657)
			(xy 230.588285 -309.293194) (xy 230.545417 -309.328869) (xy 230.497811 -309.357923) (xy 230.446482 -309.379735)
			(xy 230.392525 -309.393841) (xy 230.337088 -309.399941) (xy 230.281354 -309.397904) (xy 230.226511 -309.387774)
			(xy 230.173727 -309.369767) (xy 230.124127 -309.344266) (xy 230.078769 -309.311815) (xy 230.03862 -309.273106)
			(xy 230.004534 -309.228963) (xy 229.977238 -309.180328) (xy 229.957315 -309.128237) (xy 229.945189 -309.0738)
			(xy 229.941118 -309.018178) (xy 219.585858 -309.018178) (xy 219.648358 -309.093901) (xy 219.747904 -309.227399)
			(xy 219.840752 -309.365638) (xy 219.926676 -309.508284) (xy 220.005468 -309.654991) (xy 220.076937 -309.805401)
			(xy 220.119812 -309.908448) (xy 226.32111 -309.908448) (xy 226.325181 -309.852826) (xy 226.337307 -309.798389)
			(xy 226.35723 -309.746298) (xy 226.384526 -309.697663) (xy 226.418612 -309.65352) (xy 226.458761 -309.614811)
			(xy 226.504119 -309.58236) (xy 226.553719 -309.556859) (xy 226.606503 -309.538852) (xy 226.661346 -309.528722)
			(xy 226.71708 -309.526685) (xy 226.772517 -309.532785) (xy 226.826474 -309.546891) (xy 226.877803 -309.568703)
			(xy 226.925409 -309.597757) (xy 226.968277 -309.633432) (xy 227.005494 -309.674969) (xy 227.036267 -309.721482)
			(xy 227.047351 -309.745126) (xy 228.036626 -309.745126) (xy 228.040697 -309.689504) (xy 228.052823 -309.635067)
			(xy 228.072746 -309.582976) (xy 228.100042 -309.534341) (xy 228.134128 -309.490198) (xy 228.174277 -309.451489)
			(xy 228.219635 -309.419038) (xy 228.269235 -309.393537) (xy 228.322019 -309.37553) (xy 228.376862 -309.3654)
			(xy 228.432596 -309.363363) (xy 228.488033 -309.369463) (xy 228.54199 -309.383569) (xy 228.593319 -309.405381)
			(xy 228.640925 -309.434435) (xy 228.683793 -309.47011) (xy 228.72101 -309.511647) (xy 228.751783 -309.55816)
			(xy 228.775455 -309.608657) (xy 228.791523 -309.662064) (xy 228.799643 -309.71724) (xy 228.800152 -309.745126)
			(xy 228.799643 -309.773012) (xy 228.791523 -309.828188) (xy 228.775455 -309.881595) (xy 228.751783 -309.932092)
			(xy 228.72101 -309.978605) (xy 228.683793 -310.020142) (xy 228.640925 -310.055817) (xy 228.593319 -310.084871)
			(xy 228.54199 -310.106683) (xy 228.488033 -310.120789) (xy 228.432596 -310.126889) (xy 228.376862 -310.124852)
			(xy 228.322019 -310.114722) (xy 228.269235 -310.096715) (xy 228.219635 -310.071214) (xy 228.174277 -310.038763)
			(xy 228.134128 -310.000054) (xy 228.100042 -309.955911) (xy 228.072746 -309.907276) (xy 228.052823 -309.855185)
			(xy 228.040697 -309.800748) (xy 228.036626 -309.745126) (xy 227.047351 -309.745126) (xy 227.059939 -309.771979)
			(xy 227.076007 -309.825386) (xy 227.084127 -309.880562) (xy 227.084636 -309.908448) (xy 227.084127 -309.936334)
			(xy 227.076007 -309.99151) (xy 227.059939 -310.044917) (xy 227.036267 -310.095414) (xy 227.005494 -310.141927)
			(xy 226.968277 -310.183464) (xy 226.925409 -310.219139) (xy 226.877803 -310.248193) (xy 226.826474 -310.270005)
			(xy 226.772517 -310.284111) (xy 226.71708 -310.290211) (xy 226.661346 -310.288174) (xy 226.606503 -310.278044)
			(xy 226.553719 -310.260037) (xy 226.504119 -310.234536) (xy 226.458761 -310.202085) (xy 226.418612 -310.163376)
			(xy 226.384526 -310.119233) (xy 226.35723 -310.070598) (xy 226.337307 -310.018507) (xy 226.325181 -309.96407)
			(xy 226.32111 -309.908448) (xy 220.119812 -309.908448) (xy 220.140908 -309.959149) (xy 220.197226 -310.115863)
			(xy 220.245755 -310.275161) (xy 220.286377 -310.436657) (xy 220.317192 -310.590946) (xy 230.918764 -310.590946)
			(xy 230.922835 -310.535324) (xy 230.934961 -310.480887) (xy 230.954884 -310.428796) (xy 230.98218 -310.380161)
			(xy 231.016266 -310.336018) (xy 231.056415 -310.297309) (xy 231.101773 -310.264858) (xy 231.151373 -310.239357)
			(xy 231.204157 -310.22135) (xy 231.259 -310.21122) (xy 231.314734 -310.209183) (xy 231.370171 -310.215283)
			(xy 231.424128 -310.229389) (xy 231.475457 -310.251201) (xy 231.523063 -310.280255) (xy 231.565931 -310.31593)
			(xy 231.603148 -310.357467) (xy 231.633921 -310.40398) (xy 231.657593 -310.454477) (xy 231.673661 -310.507884)
			(xy 231.681781 -310.56306) (xy 231.68229 -310.590946) (xy 231.681781 -310.618832) (xy 231.673661 -310.674008)
			(xy 231.657593 -310.727415) (xy 231.633921 -310.777912) (xy 231.603148 -310.824425) (xy 231.565931 -310.865962)
			(xy 231.523063 -310.901637) (xy 231.475457 -310.930691) (xy 231.424128 -310.952503) (xy 231.370171 -310.966609)
			(xy 231.314734 -310.972709) (xy 231.259 -310.970672) (xy 231.204157 -310.960542) (xy 231.151373 -310.942535)
			(xy 231.101773 -310.917034) (xy 231.056415 -310.884583) (xy 231.016266 -310.845874) (xy 230.98218 -310.801731)
			(xy 230.954884 -310.753096) (xy 230.934961 -310.701005) (xy 230.922835 -310.646568) (xy 230.918764 -310.590946)
			(xy 220.317192 -310.590946) (xy 220.318992 -310.599958) (xy 220.343523 -310.764667) (xy 220.359908 -310.930385)
			(xy 220.368109 -311.096709) (xy 220.368622 -311.179972) (xy 220.3684 -311.215786) (xy 227.498908 -311.215786)
			(xy 227.502979 -311.160164) (xy 227.515105 -311.105727) (xy 227.535028 -311.053636) (xy 227.562324 -311.005001)
			(xy 227.59641 -310.960858) (xy 227.636559 -310.922149) (xy 227.681917 -310.889698) (xy 227.731517 -310.864197)
			(xy 227.784301 -310.84619) (xy 227.839144 -310.83606) (xy 227.894878 -310.834023) (xy 227.950315 -310.840123)
			(xy 228.004272 -310.854229) (xy 228.055601 -310.876041) (xy 228.103207 -310.905095) (xy 228.146075 -310.94077)
			(xy 228.183292 -310.982307) (xy 228.214065 -311.02882) (xy 228.237737 -311.079317) (xy 228.253805 -311.132724)
			(xy 228.261925 -311.1879) (xy 228.262434 -311.215786) (xy 228.261925 -311.243672) (xy 228.253805 -311.298848)
			(xy 228.237737 -311.352255) (xy 228.214065 -311.402752) (xy 228.183292 -311.449265) (xy 228.146075 -311.490802)
			(xy 228.103207 -311.526477) (xy 228.055601 -311.555531) (xy 228.025463 -311.568338) (xy 229.820468 -311.568338)
			(xy 229.824539 -311.512716) (xy 229.836665 -311.458279) (xy 229.856588 -311.406188) (xy 229.883884 -311.357553)
			(xy 229.91797 -311.31341) (xy 229.958119 -311.274701) (xy 230.003477 -311.24225) (xy 230.053077 -311.216749)
			(xy 230.105861 -311.198742) (xy 230.160704 -311.188612) (xy 230.216438 -311.186575) (xy 230.271875 -311.192675)
			(xy 230.325832 -311.206781) (xy 230.377161 -311.228593) (xy 230.424767 -311.257647) (xy 230.467635 -311.293322)
			(xy 230.504852 -311.334859) (xy 230.535625 -311.381372) (xy 230.559297 -311.431869) (xy 230.575365 -311.485276)
			(xy 230.583485 -311.540452) (xy 230.583994 -311.568338) (xy 230.583485 -311.596224) (xy 230.575365 -311.6514)
			(xy 230.559297 -311.704807) (xy 230.535625 -311.755304) (xy 230.504852 -311.801817) (xy 230.467635 -311.843354)
			(xy 230.424767 -311.879029) (xy 230.377161 -311.908083) (xy 230.325832 -311.929895) (xy 230.271875 -311.944001)
			(xy 230.216438 -311.950101) (xy 230.160704 -311.948064) (xy 230.105861 -311.937934) (xy 230.053077 -311.919927)
			(xy 230.003477 -311.894426) (xy 229.958119 -311.861975) (xy 229.91797 -311.823266) (xy 229.883884 -311.779123)
			(xy 229.856588 -311.730488) (xy 229.836665 -311.678397) (xy 229.824539 -311.62396) (xy 229.820468 -311.568338)
			(xy 228.025463 -311.568338) (xy 228.004272 -311.577343) (xy 227.950315 -311.591449) (xy 227.894878 -311.597549)
			(xy 227.839144 -311.595512) (xy 227.784301 -311.585382) (xy 227.731517 -311.567375) (xy 227.681917 -311.541874)
			(xy 227.636559 -311.509423) (xy 227.59641 -311.470714) (xy 227.562324 -311.426571) (xy 227.535028 -311.377936)
			(xy 227.515105 -311.325845) (xy 227.502979 -311.271408) (xy 227.498908 -311.215786) (xy 220.3684 -311.215786)
			(xy 220.368105 -311.263498) (xy 220.359845 -311.430345) (xy 220.34335 -311.59658) (xy 220.31866 -311.761796)
			(xy 220.285835 -311.925591) (xy 220.244954 -312.087563) (xy 220.196119 -312.247317) (xy 220.139449 -312.404462)
			(xy 220.075081 -312.558614) (xy 220.003174 -312.709397) (xy 219.923903 -312.856442) (xy 219.837461 -312.99939)
			(xy 219.761591 -313.111896) (xy 230.52354 -313.111896) (xy 230.527611 -313.056274) (xy 230.539737 -313.001837)
			(xy 230.55966 -312.949746) (xy 230.586956 -312.901111) (xy 230.621042 -312.856968) (xy 230.661191 -312.818259)
			(xy 230.706549 -312.785808) (xy 230.756149 -312.760307) (xy 230.808933 -312.7423) (xy 230.863776 -312.73217)
			(xy 230.91951 -312.730133) (xy 230.974947 -312.736233) (xy 231.028904 -312.750339) (xy 231.080233 -312.772151)
			(xy 231.127839 -312.801205) (xy 231.170707 -312.83688) (xy 231.207924 -312.878417) (xy 231.238697 -312.92493)
			(xy 231.262369 -312.975427) (xy 231.278437 -313.028834) (xy 231.286557 -313.08401) (xy 231.287066 -313.111896)
			(xy 231.286557 -313.139782) (xy 231.278437 -313.194958) (xy 231.262369 -313.248365) (xy 231.238697 -313.298862)
			(xy 231.207924 -313.345375) (xy 231.170707 -313.386912) (xy 231.127839 -313.422587) (xy 231.080233 -313.451641)
			(xy 231.028904 -313.473453) (xy 230.974947 -313.487559) (xy 230.91951 -313.493659) (xy 230.863776 -313.491622)
			(xy 230.808933 -313.481492) (xy 230.756149 -313.463485) (xy 230.706549 -313.437984) (xy 230.661191 -313.405533)
			(xy 230.621042 -313.366824) (xy 230.586956 -313.322681) (xy 230.55966 -313.274046) (xy 230.539737 -313.221955)
			(xy 230.527611 -313.167518) (xy 230.52354 -313.111896) (xy 219.761591 -313.111896) (xy 219.744061 -313.137891)
			(xy 219.64393 -313.271607) (xy 219.537313 -313.40021) (xy 219.42447 -313.523388) (xy 219.305678 -313.640838)
			(xy 219.181226 -313.752274) (xy 219.05142 -313.857423) (xy 218.984322 -313.90717) (xy 218.917904 -313.955231)
			(xy 218.781107 -314.045621) (xy 218.64009 -314.129273) (xy 218.495183 -314.205991) (xy 218.346727 -314.275595)
			(xy 218.27109 -314.30722) (xy 218.263978 -314.310268) (xy 218.252548 -314.319412) (xy 218.233752 -314.347098)
			(xy 218.229728 -314.353506) (xy 218.225347 -314.367982) (xy 218.225116 -314.375546) (xy 218.225116 -320.816732)
			(xy 224.888044 -320.816732) (xy 224.888518 -320.789362) (xy 224.896332 -320.735183) (xy 224.911819 -320.682679)
			(xy 224.934659 -320.632932) (xy 224.964383 -320.586966) (xy 224.982024 -320.566034) (xy 224.98812 -320.558922)
			(xy 224.99447 -320.541904) (xy 224.99447 -320.45656) (xy 224.98812 -320.439542) (xy 224.982024 -320.43243)
			(xy 224.964389 -320.411494) (xy 224.934676 -320.365523) (xy 224.911839 -320.315776) (xy 224.896347 -320.263276)
			(xy 224.888518 -320.209101) (xy 224.888044 -320.181732) (xy 224.888608 -320.154484) (xy 224.896359 -320.100541)
			(xy 224.911707 -320.048251) (xy 224.934341 -319.998677) (xy 224.9638 -319.952829) (xy 224.999483 -319.91164)
			(xy 225.040665 -319.875948) (xy 225.086507 -319.84648) (xy 225.136076 -319.823835) (xy 225.188363 -319.808476)
			(xy 225.242304 -319.800714) (xy 225.269552 -319.800224) (xy 225.296921 -319.800712) (xy 225.3511 -319.808524)
			(xy 225.403603 -319.824007) (xy 225.45335 -319.846844) (xy 225.499318 -319.876565) (xy 225.52025 -319.894204)
			(xy 225.527362 -319.9003) (xy 225.54438 -319.90665) (xy 225.629724 -319.90665) (xy 225.646742 -319.9003)
			(xy 225.653854 -319.894204) (xy 225.674787 -319.876563) (xy 225.720755 -319.846839) (xy 225.770501 -319.823993)
			(xy 225.823003 -319.808497) (xy 225.877181 -319.800668) (xy 225.931923 -319.800668) (xy 225.986101 -319.808497)
			(xy 226.038603 -319.823993) (xy 226.088349 -319.846839) (xy 226.134317 -319.876563) (xy 226.15525 -319.894204)
			(xy 226.162362 -319.9003) (xy 226.17938 -319.90665) (xy 226.264724 -319.90665) (xy 226.281742 -319.9003)
			(xy 226.288854 -319.894204) (xy 226.309793 -319.876574) (xy 226.355764 -319.84686) (xy 226.40551 -319.824023)
			(xy 226.458009 -319.80853) (xy 226.512183 -319.800699) (xy 226.539552 -319.800224) (xy 226.566805 -319.8007)
			(xy 226.620757 -319.808451) (xy 226.673057 -319.823803) (xy 226.722639 -319.846442) (xy 226.768494 -319.875908)
			(xy 226.809688 -319.911601) (xy 226.845382 -319.952793) (xy 226.87485 -319.998647) (xy 226.897492 -320.048228)
			(xy 226.912845 -320.100527) (xy 226.920599 -320.154479) (xy 226.92106 -320.181732) (xy 226.920622 -320.209103)
			(xy 226.912799 -320.263284) (xy 226.897304 -320.315788) (xy 226.874456 -320.365534) (xy 226.844725 -320.4115)
			(xy 226.82708 -320.43243) (xy 226.820984 -320.439542) (xy 226.814634 -320.45656) (xy 226.814634 -320.541904)
			(xy 226.820984 -320.558922) (xy 226.82708 -320.566034) (xy 226.844699 -320.586983) (xy 226.874414 -320.632951)
			(xy 226.897254 -320.682694) (xy 226.91275 -320.735191) (xy 226.920583 -320.789364) (xy 226.92106 -320.816732)
			(xy 226.920675 -320.843988) (xy 226.912912 -320.897944) (xy 226.89755 -320.950246) (xy 226.8749 -320.99983)
			(xy 226.845424 -321.045685) (xy 226.809722 -321.086879) (xy 226.768521 -321.122572) (xy 226.72266 -321.152038)
			(xy 226.673071 -321.174678) (xy 226.620766 -321.190029) (xy 226.566808 -321.19778) (xy 226.539552 -321.19824)
			(xy 226.512182 -321.197758) (xy 226.458003 -321.189946) (xy 226.4055 -321.174462) (xy 226.355752 -321.151623)
			(xy 226.309786 -321.121901) (xy 226.288854 -321.10426) (xy 226.281742 -321.098164) (xy 226.264724 -321.091814)
			(xy 226.17938 -321.091814) (xy 226.162362 -321.098164) (xy 226.15525 -321.10426) (xy 226.134317 -321.121901)
			(xy 226.088349 -321.151625) (xy 226.038603 -321.174471) (xy 225.986101 -321.189967) (xy 225.931923 -321.197796)
			(xy 225.877181 -321.197796) (xy 225.823003 -321.189967) (xy 225.770501 -321.174471) (xy 225.720755 -321.151625)
			(xy 225.674787 -321.121901) (xy 225.653854 -321.10426) (xy 225.646742 -321.098164) (xy 225.629724 -321.091814)
			(xy 225.54438 -321.091814) (xy 225.527362 -321.098164) (xy 225.52025 -321.10426) (xy 225.499305 -321.121883)
			(xy 225.453336 -321.151599) (xy 225.403592 -321.174438) (xy 225.351094 -321.189933) (xy 225.29692 -321.197764)
			(xy 225.269552 -321.19824) (xy 225.242301 -321.197767) (xy 225.188355 -321.190005) (xy 225.136062 -321.174645)
			(xy 225.086486 -321.152001) (xy 225.040638 -321.122532) (xy 224.999449 -321.08684) (xy 224.963758 -321.04565)
			(xy 224.934292 -320.9998) (xy 224.911649 -320.950223) (xy 224.896292 -320.89793) (xy 224.888532 -320.843983)
			(xy 224.888044 -320.816732) (xy 218.225116 -320.816732) (xy 218.225116 -321.122548) (xy 218.225548 -321.132614)
			(xy 218.233277 -321.151204) (xy 218.240102 -321.158616) (xy 218.509342 -321.427856) (xy 218.516741 -321.4347)
			(xy 218.535339 -321.442427) (xy 218.54541 -321.442842)
		)
		(stroke
			(width 0)
			(type solid)
		)
		(fill yes)
		(layer "In7.Cu")
		(net "GND")
	)
	(gr_poly
		(pts
			(xy 419.493192 -252.853444) (xy 419.501653 -252.85305) (xy 419.517605 -252.847379) (xy 419.530837 -252.836819)
			(xy 419.53561 -252.829822) (xy 419.539166 -252.822964) (xy 419.574726 -252.742446) (xy 419.578282 -252.733083)
			(xy 419.578672 -252.71308) (xy 419.575488 -252.703584) (xy 419.56736 -252.683264) (xy 419.561518 -252.676406)
			(xy 419.543655 -252.655401) (xy 419.513534 -252.609215) (xy 419.490377 -252.559173) (xy 419.474667 -252.506319)
			(xy 419.46673 -252.451754) (xy 419.466268 -252.424184) (xy 419.466268 -252.415548) (xy 419.467393 -252.388306)
			(xy 419.476414 -252.334535) (xy 419.492994 -252.282594) (xy 419.516795 -252.233541) (xy 419.547334 -252.188374)
			(xy 419.583988 -252.148011) (xy 419.626012 -252.113274) (xy 419.672551 -252.08487) (xy 419.697408 -252.073664)
			(xy 419.709854 -252.06833) (xy 419.725602 -252.047502) (xy 419.74008 -251.94895) (xy 419.740991 -251.940319)
			(xy 419.737608 -251.923309) (xy 419.733476 -251.915676) (xy 419.728904 -251.908056) (xy 419.7223 -251.902468)
			(xy 419.701301 -251.884242) (xy 419.66429 -251.842748) (xy 419.633698 -251.796319) (xy 419.610173 -251.745939)
			(xy 419.594214 -251.692676) (xy 419.586159 -251.637661) (xy 419.585648 -251.60986) (xy 419.586134 -251.582609)
			(xy 419.59389 -251.528661) (xy 419.609245 -251.476366) (xy 419.631887 -251.426789) (xy 419.661353 -251.380939)
			(xy 419.697044 -251.339748) (xy 419.738235 -251.304057) (xy 419.784085 -251.274591) (xy 419.833662 -251.251949)
			(xy 419.885957 -251.236594) (xy 419.939905 -251.228838) (xy 419.994407 -251.228838) (xy 420.048355 -251.236594)
			(xy 420.10065 -251.251949) (xy 420.150227 -251.274591) (xy 420.196077 -251.304057) (xy 420.237268 -251.339748)
			(xy 420.272959 -251.380939) (xy 420.302425 -251.426789) (xy 420.325067 -251.476366) (xy 420.340422 -251.528661)
			(xy 420.348178 -251.582609) (xy 420.348664 -251.60986) (xy 420.348157 -251.637661) (xy 420.340075 -251.692674)
			(xy 420.324093 -251.74593) (xy 420.300549 -251.796302) (xy 420.26994 -251.842722) (xy 420.232917 -251.884206)
			(xy 420.190263 -251.919876) (xy 420.142883 -251.948975) (xy 420.117524 -251.96038) (xy 420.105078 -251.965714)
			(xy 420.08933 -251.986542) (xy 420.074852 -252.085094) (xy 420.073931 -252.093727) (xy 420.0773 -252.110746)
			(xy 420.081456 -252.118368) (xy 420.086028 -252.125988) (xy 420.092632 -252.131576) (xy 420.113095 -252.149323)
			(xy 420.149298 -252.189611) (xy 420.179446 -252.23461) (xy 420.202932 -252.283418) (xy 420.219287 -252.335055)
			(xy 420.228181 -252.388484) (xy 420.229284 -252.415548) (xy 420.229284 -252.424184) (xy 420.2288 -252.451753)
			(xy 420.220866 -252.506318) (xy 420.205162 -252.559172) (xy 420.182013 -252.609216) (xy 420.151903 -252.655407)
			(xy 420.134034 -252.676406) (xy 420.128192 -252.683264) (xy 420.120064 -252.703584) (xy 420.116796 -252.713065)
			(xy 420.117188 -252.733101) (xy 420.120826 -252.742446) (xy 420.156386 -252.822964) (xy 420.159942 -252.829822)
			(xy 420.164727 -252.836815) (xy 420.177946 -252.847402) (xy 420.193895 -252.853097) (xy 420.20236 -252.853444)
			(xy 443.76975 -252.853444) (xy 443.779047 -252.853033) (xy 443.796426 -252.846424) (xy 443.810334 -252.834083)
			(xy 443.814962 -252.826012) (xy 443.862968 -252.733048) (xy 443.860936 -252.704854) (xy 443.852808 -252.69317)
			(xy 443.836223 -252.668842) (xy 443.809943 -252.616156) (xy 443.792067 -252.560059) (xy 443.783018 -252.501882)
			(xy 443.78245 -252.472444) (xy 443.782936 -252.445193) (xy 443.790692 -252.391245) (xy 443.806047 -252.33895)
			(xy 443.828689 -252.289373) (xy 443.858155 -252.243523) (xy 443.893846 -252.202332) (xy 443.935037 -252.166641)
			(xy 443.980887 -252.137175) (xy 444.030464 -252.114533) (xy 444.082759 -252.099178) (xy 444.136707 -252.091422)
			(xy 444.191209 -252.091422) (xy 444.245157 -252.099178) (xy 444.297452 -252.114533) (xy 444.347029 -252.137175)
			(xy 444.392879 -252.166641) (xy 444.43407 -252.202332) (xy 444.469761 -252.243523) (xy 444.499227 -252.289373)
			(xy 444.521869 -252.33895) (xy 444.537224 -252.391245) (xy 444.54498 -252.445193) (xy 444.545466 -252.472444)
			(xy 444.544923 -252.501884) (xy 444.53588 -252.560066) (xy 444.517999 -252.616165) (xy 444.491707 -252.668849)
			(xy 444.475108 -252.69317) (xy 444.46698 -252.704854) (xy 444.464948 -252.733048) (xy 444.512954 -252.826012)
			(xy 444.51758 -252.834094) (xy 444.53146 -252.846485) (xy 444.548861 -252.85307) (xy 444.558166 -252.853444)
			(xy 444.843916 -252.853444) (xy 444.853925 -252.852954) (xy 444.872419 -252.845293) (xy 444.886577 -252.831142)
			(xy 444.894248 -252.812652) (xy 444.894716 -252.802644) (xy 444.894716 -252.185678) (xy 444.874904 -252.159008)
			(xy 444.858648 -252.154182) (xy 444.833006 -252.145783) (xy 444.784202 -252.122774) (xy 444.739124 -252.093122)
			(xy 444.69867 -252.057418) (xy 444.663646 -252.016373) (xy 444.634751 -251.970806) (xy 444.61256 -251.921624)
			(xy 444.597515 -251.869808) (xy 444.589915 -251.816389) (xy 444.589914 -251.762433) (xy 444.59751 -251.709014)
			(xy 444.612552 -251.657197) (xy 444.63474 -251.608014) (xy 444.663633 -251.562445) (xy 444.698654 -251.521398)
			(xy 444.739106 -251.485692) (xy 444.784182 -251.456037) (xy 444.832985 -251.433025) (xy 444.858648 -251.424694)
			(xy 444.874904 -251.419868) (xy 444.894716 -251.393198) (xy 444.894716 -250.518168) (xy 444.894173 -250.508183)
			(xy 444.886453 -250.489758) (xy 444.87973 -250.482354) (xy 443.867286 -249.46991) (xy 443.85994 -249.463101)
			(xy 443.841478 -249.455372) (xy 443.831472 -249.454924) (xy 439.86069 -249.454924) (xy 439.827816 -249.454495)
			(xy 439.762479 -249.447163) (xy 439.698375 -249.432557) (xy 439.63631 -249.410863) (xy 439.577066 -249.382353)
			(xy 439.521389 -249.347385) (xy 439.469979 -249.306401) (xy 439.446416 -249.283474) (xy 421.00754 -230.844598)
			(xy 420.984591 -230.821045) (xy 420.943564 -230.769647) (xy 420.908554 -230.713977) (xy 420.880001 -230.654735)
			(xy 420.858266 -230.592668) (xy 420.84362 -230.528555) (xy 420.83625 -230.463206) (xy 420.835836 -230.430324)
			(xy 420.835836 -197.292214) (xy 420.835347 -197.282253) (xy 420.827758 -197.26383) (xy 420.821104 -197.2564)
			(xy 420.474394 -196.90969) (xy 420.447247 -196.881622) (xy 420.399853 -196.819562) (xy 420.379906 -196.785992)
			(xy 420.373556 -196.783198) (xy 420.35857 -196.781674) (xy 420.302182 -196.793104) (xy 420.292243 -196.795554)
			(xy 420.275336 -196.807062) (xy 420.264263 -196.824257) (xy 420.26205 -196.834252) (xy 415.997245 -221.323662)
			(xy 417.33419 -221.323662) (xy 417.338261 -221.26804) (xy 417.350387 -221.213603) (xy 417.37031 -221.161512)
			(xy 417.397606 -221.112877) (xy 417.431692 -221.068734) (xy 417.471841 -221.030025) (xy 417.517199 -220.997574)
			(xy 417.566799 -220.972073) (xy 417.619583 -220.954066) (xy 417.674426 -220.943936) (xy 417.73016 -220.941899)
			(xy 417.785597 -220.947999) (xy 417.839554 -220.962105) (xy 417.890883 -220.983917) (xy 417.938489 -221.012971)
			(xy 417.981357 -221.048646) (xy 418.018574 -221.090183) (xy 418.049347 -221.136696) (xy 418.073019 -221.187193)
			(xy 418.089087 -221.2406) (xy 418.097207 -221.295776) (xy 418.097716 -221.323662) (xy 418.097207 -221.351548)
			(xy 418.089087 -221.406724) (xy 418.073019 -221.460131) (xy 418.049347 -221.510628) (xy 418.018574 -221.557141)
			(xy 417.981357 -221.598678) (xy 417.938489 -221.634353) (xy 417.890883 -221.663407) (xy 417.839554 -221.685219)
			(xy 417.785597 -221.699325) (xy 417.73016 -221.705425) (xy 417.674426 -221.703388) (xy 417.619583 -221.693258)
			(xy 417.566799 -221.675251) (xy 417.517199 -221.64975) (xy 417.471841 -221.617299) (xy 417.431692 -221.57859)
			(xy 417.397606 -221.534447) (xy 417.37031 -221.485812) (xy 417.350387 -221.433721) (xy 417.338261 -221.379284)
			(xy 417.33419 -221.323662) (xy 415.997245 -221.323662) (xy 415.550174 -223.89084) (xy 418.05809 -223.89084)
			(xy 418.062161 -223.835218) (xy 418.074287 -223.780781) (xy 418.09421 -223.72869) (xy 418.121506 -223.680055)
			(xy 418.155592 -223.635912) (xy 418.195741 -223.597203) (xy 418.241099 -223.564752) (xy 418.290699 -223.539251)
			(xy 418.343483 -223.521244) (xy 418.398326 -223.511114) (xy 418.45406 -223.509077) (xy 418.509497 -223.515177)
			(xy 418.563454 -223.529283) (xy 418.614783 -223.551095) (xy 418.662389 -223.580149) (xy 418.705257 -223.615824)
			(xy 418.742474 -223.657361) (xy 418.773247 -223.703874) (xy 418.796919 -223.754371) (xy 418.812987 -223.807778)
			(xy 418.821107 -223.862954) (xy 418.821616 -223.89084) (xy 418.821107 -223.918726) (xy 418.812987 -223.973902)
			(xy 418.796919 -224.027309) (xy 418.773247 -224.077806) (xy 418.742474 -224.124319) (xy 418.705257 -224.165856)
			(xy 418.662389 -224.201531) (xy 418.614783 -224.230585) (xy 418.563454 -224.252397) (xy 418.509497 -224.266503)
			(xy 418.45406 -224.272603) (xy 418.398326 -224.270566) (xy 418.343483 -224.260436) (xy 418.290699 -224.242429)
			(xy 418.241099 -224.216928) (xy 418.195741 -224.184477) (xy 418.155592 -224.145768) (xy 418.121506 -224.101625)
			(xy 418.09421 -224.05299) (xy 418.074287 -224.000899) (xy 418.062161 -223.946462) (xy 418.05809 -223.89084)
			(xy 415.550174 -223.89084) (xy 415.386774 -224.829116) (xy 415.408364 -224.86239) (xy 415.427922 -224.867216)
			(xy 415.455024 -224.874575) (xy 415.506868 -224.896158) (xy 415.554993 -224.925101) (xy 415.598358 -224.960781)
			(xy 415.63603 -225.002429) (xy 415.667194 -225.049145) (xy 415.69118 -225.099923) (xy 415.707469 -225.153666)
			(xy 415.71571 -225.209215) (xy 415.716212 -225.237294) (xy 415.71619 -225.238564) (xy 418.305232 -225.238564)
			(xy 418.309303 -225.182942) (xy 418.321429 -225.128505) (xy 418.341352 -225.076414) (xy 418.368648 -225.027779)
			(xy 418.402734 -224.983636) (xy 418.442883 -224.944927) (xy 418.488241 -224.912476) (xy 418.537841 -224.886975)
			(xy 418.590625 -224.868968) (xy 418.645468 -224.858838) (xy 418.701202 -224.856801) (xy 418.756639 -224.862901)
			(xy 418.810596 -224.877007) (xy 418.861925 -224.898819) (xy 418.909531 -224.927873) (xy 418.952399 -224.963548)
			(xy 418.989616 -225.005085) (xy 419.020389 -225.051598) (xy 419.044061 -225.102095) (xy 419.060129 -225.155502)
			(xy 419.068249 -225.210678) (xy 419.068758 -225.238564) (xy 419.068249 -225.26645) (xy 419.060129 -225.321626)
			(xy 419.044061 -225.375033) (xy 419.020389 -225.42553) (xy 418.989616 -225.472043) (xy 418.952399 -225.51358)
			(xy 418.909531 -225.549255) (xy 418.861925 -225.578309) (xy 418.810596 -225.600121) (xy 418.756639 -225.614227)
			(xy 418.701202 -225.620327) (xy 418.645468 -225.61829) (xy 418.590625 -225.60816) (xy 418.537841 -225.590153)
			(xy 418.488241 -225.564652) (xy 418.442883 -225.532201) (xy 418.402734 -225.493492) (xy 418.368648 -225.449349)
			(xy 418.341352 -225.400714) (xy 418.321429 -225.348623) (xy 418.309303 -225.294186) (xy 418.305232 -225.238564)
			(xy 415.71619 -225.238564) (xy 415.715749 -225.264547) (xy 415.707993 -225.318499) (xy 415.692637 -225.370798)
			(xy 415.669995 -225.420379) (xy 415.640527 -225.466233) (xy 415.604834 -225.507427) (xy 415.563641 -225.543121)
			(xy 415.517788 -225.57259) (xy 415.468207 -225.595234) (xy 415.415909 -225.610591) (xy 415.361957 -225.618348)
			(xy 415.334704 -225.618802) (xy 415.297366 -225.617024) (xy 415.2773 -225.614992) (xy 415.245804 -225.639122)
			(xy 414.320253 -230.952802) (xy 417.376354 -230.952802) (xy 417.380425 -230.89718) (xy 417.392551 -230.842743)
			(xy 417.412474 -230.790652) (xy 417.43977 -230.742017) (xy 417.473856 -230.697874) (xy 417.514005 -230.659165)
			(xy 417.559363 -230.626714) (xy 417.608963 -230.601213) (xy 417.661747 -230.583206) (xy 417.71659 -230.573076)
			(xy 417.772324 -230.571039) (xy 417.827761 -230.577139) (xy 417.881718 -230.591245) (xy 417.933047 -230.613057)
			(xy 417.980653 -230.642111) (xy 418.023521 -230.677786) (xy 418.060738 -230.719323) (xy 418.091511 -230.765836)
			(xy 418.115183 -230.816333) (xy 418.131251 -230.86974) (xy 418.139371 -230.924916) (xy 418.13988 -230.952802)
			(xy 418.139371 -230.980688) (xy 418.131251 -231.035864) (xy 418.115183 -231.089271) (xy 418.091511 -231.139768)
			(xy 418.060738 -231.186281) (xy 418.023521 -231.227818) (xy 417.980653 -231.263493) (xy 417.933047 -231.292547)
			(xy 417.881718 -231.314359) (xy 417.827761 -231.328465) (xy 417.772324 -231.334565) (xy 417.71659 -231.332528)
			(xy 417.661747 -231.322398) (xy 417.608963 -231.304391) (xy 417.559363 -231.27889) (xy 417.514005 -231.246439)
			(xy 417.473856 -231.20773) (xy 417.43977 -231.163587) (xy 417.412474 -231.114952) (xy 417.392551 -231.062861)
			(xy 417.380425 -231.008424) (xy 417.376354 -230.952802) (xy 414.320253 -230.952802) (xy 413.904684 -233.338624)
			(xy 413.878014 -233.492802) (xy 414.907982 -233.492802) (xy 414.912053 -233.43718) (xy 414.924179 -233.382743)
			(xy 414.944102 -233.330652) (xy 414.971398 -233.282017) (xy 415.005484 -233.237874) (xy 415.045633 -233.199165)
			(xy 415.090991 -233.166714) (xy 415.140591 -233.141213) (xy 415.193375 -233.123206) (xy 415.248218 -233.113076)
			(xy 415.303952 -233.111039) (xy 415.359389 -233.117139) (xy 415.413346 -233.131245) (xy 415.464675 -233.153057)
			(xy 415.512281 -233.182111) (xy 415.555149 -233.217786) (xy 415.592366 -233.259323) (xy 415.623139 -233.305836)
			(xy 415.646811 -233.356333) (xy 415.662879 -233.40974) (xy 415.670999 -233.464916) (xy 415.671508 -233.492802)
			(xy 415.671485 -233.494072) (xy 418.149784 -233.494072) (xy 418.153855 -233.43845) (xy 418.165981 -233.384013)
			(xy 418.185904 -233.331922) (xy 418.2132 -233.283287) (xy 418.247286 -233.239144) (xy 418.287435 -233.200435)
			(xy 418.332793 -233.167984) (xy 418.382393 -233.142483) (xy 418.435177 -233.124476) (xy 418.49002 -233.114346)
			(xy 418.545754 -233.112309) (xy 418.601191 -233.118409) (xy 418.655148 -233.132515) (xy 418.706477 -233.154327)
			(xy 418.754083 -233.183381) (xy 418.796951 -233.219056) (xy 418.834168 -233.260593) (xy 418.864941 -233.307106)
			(xy 418.888613 -233.357603) (xy 418.904681 -233.41101) (xy 418.912801 -233.466186) (xy 418.91331 -233.494072)
			(xy 418.912801 -233.521958) (xy 418.904681 -233.577134) (xy 418.888613 -233.630541) (xy 418.864941 -233.681038)
			(xy 418.834168 -233.727551) (xy 418.796951 -233.769088) (xy 418.754083 -233.804763) (xy 418.706477 -233.833817)
			(xy 418.655148 -233.855629) (xy 418.601191 -233.869735) (xy 418.545754 -233.875835) (xy 418.49002 -233.873798)
			(xy 418.435177 -233.863668) (xy 418.382393 -233.845661) (xy 418.332793 -233.82016) (xy 418.287435 -233.787709)
			(xy 418.247286 -233.749) (xy 418.2132 -233.704857) (xy 418.185904 -233.656222) (xy 418.165981 -233.604131)
			(xy 418.153855 -233.549694) (xy 418.149784 -233.494072) (xy 415.671485 -233.494072) (xy 415.670999 -233.520688)
			(xy 415.662879 -233.575864) (xy 415.646811 -233.629271) (xy 415.623139 -233.679768) (xy 415.592366 -233.726281)
			(xy 415.555149 -233.767818) (xy 415.512281 -233.803493) (xy 415.464675 -233.832547) (xy 415.413346 -233.854359)
			(xy 415.359389 -233.868465) (xy 415.303952 -233.874565) (xy 415.248218 -233.872528) (xy 415.193375 -233.862398)
			(xy 415.140591 -233.844391) (xy 415.090991 -233.81889) (xy 415.045633 -233.786439) (xy 415.005484 -233.74773)
			(xy 414.971398 -233.703587) (xy 414.944102 -233.654952) (xy 414.924179 -233.602861) (xy 414.912053 -233.548424)
			(xy 414.907982 -233.492802) (xy 413.878014 -233.492802) (xy 413.585915 -235.181394) (xy 418.770052 -235.181394)
			(xy 418.774123 -235.125772) (xy 418.786249 -235.071335) (xy 418.806172 -235.019244) (xy 418.833468 -234.970609)
			(xy 418.867554 -234.926466) (xy 418.907703 -234.887757) (xy 418.953061 -234.855306) (xy 419.002661 -234.829805)
			(xy 419.055445 -234.811798) (xy 419.110288 -234.801668) (xy 419.166022 -234.799631) (xy 419.221459 -234.805731)
			(xy 419.275416 -234.819837) (xy 419.326745 -234.841649) (xy 419.374351 -234.870703) (xy 419.417219 -234.906378)
			(xy 419.454436 -234.947915) (xy 419.485209 -234.994428) (xy 419.508881 -235.044925) (xy 419.524949 -235.098332)
			(xy 419.533069 -235.153508) (xy 419.533578 -235.181394) (xy 419.533069 -235.20928) (xy 419.524949 -235.264456)
			(xy 419.508881 -235.317863) (xy 419.485209 -235.36836) (xy 419.454436 -235.414873) (xy 419.417219 -235.45641)
			(xy 419.374351 -235.492085) (xy 419.326745 -235.521139) (xy 419.275416 -235.542951) (xy 419.221459 -235.557057)
			(xy 419.166022 -235.563157) (xy 419.110288 -235.56112) (xy 419.055445 -235.55099) (xy 419.002661 -235.532983)
			(xy 418.953061 -235.507482) (xy 418.907703 -235.475031) (xy 418.867554 -235.436322) (xy 418.833468 -235.392179)
			(xy 418.806172 -235.343544) (xy 418.786249 -235.291453) (xy 418.774123 -235.237016) (xy 418.770052 -235.181394)
			(xy 413.585915 -235.181394) (xy 412.873727 -239.29848) (xy 417.276532 -239.29848) (xy 417.280603 -239.242858)
			(xy 417.292729 -239.188421) (xy 417.312652 -239.13633) (xy 417.339948 -239.087695) (xy 417.374034 -239.043552)
			(xy 417.414183 -239.004843) (xy 417.459541 -238.972392) (xy 417.509141 -238.946891) (xy 417.561925 -238.928884)
			(xy 417.616768 -238.918754) (xy 417.672502 -238.916717) (xy 417.727939 -238.922817) (xy 417.781896 -238.936923)
			(xy 417.833225 -238.958735) (xy 417.880831 -238.987789) (xy 417.923699 -239.023464) (xy 417.960916 -239.065001)
			(xy 417.991689 -239.111514) (xy 418.015361 -239.162011) (xy 418.031429 -239.215418) (xy 418.039549 -239.270594)
			(xy 418.040058 -239.29848) (xy 418.039549 -239.326366) (xy 418.031429 -239.381542) (xy 418.015361 -239.434949)
			(xy 417.991689 -239.485446) (xy 417.960916 -239.531959) (xy 417.923699 -239.573496) (xy 417.880831 -239.609171)
			(xy 417.833225 -239.638225) (xy 417.781896 -239.660037) (xy 417.727939 -239.674143) (xy 417.672502 -239.680243)
			(xy 417.616768 -239.678206) (xy 417.561925 -239.668076) (xy 417.509141 -239.650069) (xy 417.459541 -239.624568)
			(xy 417.414183 -239.592117) (xy 417.374034 -239.553408) (xy 417.339948 -239.509265) (xy 417.312652 -239.46063)
			(xy 417.292729 -239.408539) (xy 417.280603 -239.354102) (xy 417.276532 -239.29848) (xy 412.873727 -239.29848)
			(xy 412.722845 -240.170716) (xy 418.30828 -240.170716) (xy 418.312351 -240.115094) (xy 418.324477 -240.060657)
			(xy 418.3444 -240.008566) (xy 418.371696 -239.959931) (xy 418.405782 -239.915788) (xy 418.445931 -239.877079)
			(xy 418.491289 -239.844628) (xy 418.540889 -239.819127) (xy 418.593673 -239.80112) (xy 418.648516 -239.79099)
			(xy 418.70425 -239.788953) (xy 418.759687 -239.795053) (xy 418.813644 -239.809159) (xy 418.864973 -239.830971)
			(xy 418.912579 -239.860025) (xy 418.955447 -239.8957) (xy 418.992664 -239.937237) (xy 419.023437 -239.98375)
			(xy 419.047109 -240.034247) (xy 419.063177 -240.087654) (xy 419.071297 -240.14283) (xy 419.071806 -240.170716)
			(xy 419.071297 -240.198602) (xy 419.063177 -240.253778) (xy 419.047109 -240.307185) (xy 419.023437 -240.357682)
			(xy 418.992664 -240.404195) (xy 418.955447 -240.445732) (xy 418.912579 -240.481407) (xy 418.864973 -240.510461)
			(xy 418.813644 -240.532273) (xy 418.759687 -240.546379) (xy 418.70425 -240.552479) (xy 418.648516 -240.550442)
			(xy 418.593673 -240.540312) (xy 418.540889 -240.522305) (xy 418.491289 -240.496804) (xy 418.445931 -240.464353)
			(xy 418.405782 -240.425644) (xy 418.371696 -240.381501) (xy 418.3444 -240.332866) (xy 418.324477 -240.280775)
			(xy 418.312351 -240.226338) (xy 418.30828 -240.170716) (xy 412.722845 -240.170716) (xy 412.434349 -241.83848)
			(xy 415.611816 -241.83848) (xy 415.615887 -241.782858) (xy 415.628013 -241.728421) (xy 415.647936 -241.67633)
			(xy 415.675232 -241.627695) (xy 415.709318 -241.583552) (xy 415.749467 -241.544843) (xy 415.794825 -241.512392)
			(xy 415.844425 -241.486891) (xy 415.897209 -241.468884) (xy 415.952052 -241.458754) (xy 416.007786 -241.456717)
			(xy 416.063223 -241.462817) (xy 416.11718 -241.476923) (xy 416.168509 -241.498735) (xy 416.216115 -241.527789)
			(xy 416.258983 -241.563464) (xy 416.2962 -241.605001) (xy 416.326973 -241.651514) (xy 416.350645 -241.702011)
			(xy 416.366713 -241.755418) (xy 416.374833 -241.810594) (xy 416.375342 -241.83848) (xy 416.375319 -241.83975)
			(xy 418.075362 -241.83975) (xy 418.079433 -241.784128) (xy 418.091559 -241.729691) (xy 418.111482 -241.6776)
			(xy 418.138778 -241.628965) (xy 418.172864 -241.584822) (xy 418.213013 -241.546113) (xy 418.258371 -241.513662)
			(xy 418.307971 -241.488161) (xy 418.360755 -241.470154) (xy 418.415598 -241.460024) (xy 418.471332 -241.457987)
			(xy 418.526769 -241.464087) (xy 418.580726 -241.478193) (xy 418.632055 -241.500005) (xy 418.679661 -241.529059)
			(xy 418.722529 -241.564734) (xy 418.759746 -241.606271) (xy 418.790519 -241.652784) (xy 418.814191 -241.703281)
			(xy 418.830259 -241.756688) (xy 418.838379 -241.811864) (xy 418.838888 -241.83975) (xy 418.838379 -241.867636)
			(xy 418.830259 -241.922812) (xy 418.814191 -241.976219) (xy 418.790519 -242.026716) (xy 418.759746 -242.073229)
			(xy 418.722529 -242.114766) (xy 418.679661 -242.150441) (xy 418.632055 -242.179495) (xy 418.580726 -242.201307)
			(xy 418.526769 -242.215413) (xy 418.471332 -242.221513) (xy 418.415598 -242.219476) (xy 418.360755 -242.209346)
			(xy 418.307971 -242.191339) (xy 418.258371 -242.165838) (xy 418.213013 -242.133387) (xy 418.172864 -242.094678)
			(xy 418.138778 -242.050535) (xy 418.111482 -242.0019) (xy 418.091559 -241.949809) (xy 418.079433 -241.895372)
			(xy 418.075362 -241.83975) (xy 416.375319 -241.83975) (xy 416.374833 -241.866366) (xy 416.366713 -241.921542)
			(xy 416.350645 -241.974949) (xy 416.326973 -242.025446) (xy 416.2962 -242.071959) (xy 416.258983 -242.113496)
			(xy 416.216115 -242.149171) (xy 416.168509 -242.178225) (xy 416.11718 -242.200037) (xy 416.063223 -242.214143)
			(xy 416.007786 -242.220243) (xy 415.952052 -242.218206) (xy 415.897209 -242.208076) (xy 415.844425 -242.190069)
			(xy 415.794825 -242.164568) (xy 415.749467 -242.132117) (xy 415.709318 -242.093408) (xy 415.675232 -242.049265)
			(xy 415.647936 -242.00063) (xy 415.628013 -241.948539) (xy 415.615887 -241.894102) (xy 415.611816 -241.83848)
			(xy 412.434349 -241.83848) (xy 411.146443 -249.283728) (xy 418.099492 -249.283728) (xy 418.103563 -249.228106)
			(xy 418.115689 -249.173669) (xy 418.135612 -249.121578) (xy 418.162908 -249.072943) (xy 418.196994 -249.0288)
			(xy 418.237143 -248.990091) (xy 418.282501 -248.95764) (xy 418.332101 -248.932139) (xy 418.384885 -248.914132)
			(xy 418.439728 -248.904002) (xy 418.495462 -248.901965) (xy 418.550899 -248.908065) (xy 418.604856 -248.922171)
			(xy 418.656185 -248.943983) (xy 418.703791 -248.973037) (xy 418.746659 -249.008712) (xy 418.783876 -249.050249)
			(xy 418.814649 -249.096762) (xy 418.838321 -249.147259) (xy 418.854389 -249.200666) (xy 418.862509 -249.255842)
			(xy 418.863018 -249.283728) (xy 418.862633 -249.30481) (xy 419.084504 -249.30481) (xy 419.088575 -249.249188)
			(xy 419.100701 -249.194751) (xy 419.120624 -249.14266) (xy 419.14792 -249.094025) (xy 419.182006 -249.049882)
			(xy 419.222155 -249.011173) (xy 419.267513 -248.978722) (xy 419.317113 -248.953221) (xy 419.369897 -248.935214)
			(xy 419.42474 -248.925084) (xy 419.480474 -248.923047) (xy 419.535911 -248.929147) (xy 419.589868 -248.943253)
			(xy 419.641197 -248.965065) (xy 419.688803 -248.994119) (xy 419.731671 -249.029794) (xy 419.768888 -249.071331)
			(xy 419.799661 -249.117844) (xy 419.823333 -249.168341) (xy 419.839401 -249.221748) (xy 419.847521 -249.276924)
			(xy 419.84803 -249.30481) (xy 419.847521 -249.332696) (xy 419.839401 -249.387872) (xy 419.823333 -249.441279)
			(xy 419.799661 -249.491776) (xy 419.768888 -249.538289) (xy 419.731671 -249.579826) (xy 419.688803 -249.615501)
			(xy 419.641197 -249.644555) (xy 419.589868 -249.666367) (xy 419.535911 -249.680473) (xy 419.480474 -249.686573)
			(xy 419.42474 -249.684536) (xy 419.369897 -249.674406) (xy 419.317113 -249.656399) (xy 419.267513 -249.630898)
			(xy 419.222155 -249.598447) (xy 419.182006 -249.559738) (xy 419.14792 -249.515595) (xy 419.120624 -249.46696)
			(xy 419.100701 -249.414869) (xy 419.088575 -249.360432) (xy 419.084504 -249.30481) (xy 418.862633 -249.30481)
			(xy 418.862509 -249.311614) (xy 418.854389 -249.36679) (xy 418.838321 -249.420197) (xy 418.814649 -249.470694)
			(xy 418.783876 -249.517207) (xy 418.746659 -249.558744) (xy 418.703791 -249.594419) (xy 418.656185 -249.623473)
			(xy 418.604856 -249.645285) (xy 418.550899 -249.659391) (xy 418.495462 -249.665491) (xy 418.439728 -249.663454)
			(xy 418.384885 -249.653324) (xy 418.332101 -249.635317) (xy 418.282501 -249.609816) (xy 418.237143 -249.577365)
			(xy 418.196994 -249.538656) (xy 418.162908 -249.494513) (xy 418.135612 -249.445878) (xy 418.115689 -249.393787)
			(xy 418.103563 -249.33935) (xy 418.099492 -249.283728) (xy 411.146443 -249.283728) (xy 410.899249 -250.712732)
			(xy 443.057278 -250.712732) (xy 443.061349 -250.65711) (xy 443.073475 -250.602673) (xy 443.093398 -250.550582)
			(xy 443.120694 -250.501947) (xy 443.15478 -250.457804) (xy 443.194929 -250.419095) (xy 443.240287 -250.386644)
			(xy 443.289887 -250.361143) (xy 443.342671 -250.343136) (xy 443.397514 -250.333006) (xy 443.453248 -250.330969)
			(xy 443.508685 -250.337069) (xy 443.562642 -250.351175) (xy 443.613971 -250.372987) (xy 443.661577 -250.402041)
			(xy 443.704445 -250.437716) (xy 443.741662 -250.479253) (xy 443.772435 -250.525766) (xy 443.796107 -250.576263)
			(xy 443.812175 -250.62967) (xy 443.820295 -250.684846) (xy 443.820804 -250.712732) (xy 443.820295 -250.740618)
			(xy 443.812175 -250.795794) (xy 443.796107 -250.849201) (xy 443.772435 -250.899698) (xy 443.753964 -250.927616)
			(xy 443.943738 -250.927616) (xy 443.947809 -250.871994) (xy 443.959935 -250.817557) (xy 443.979858 -250.765466)
			(xy 444.007154 -250.716831) (xy 444.04124 -250.672688) (xy 444.081389 -250.633979) (xy 444.126747 -250.601528)
			(xy 444.176347 -250.576027) (xy 444.229131 -250.55802) (xy 444.283974 -250.54789) (xy 444.339708 -250.545853)
			(xy 444.395145 -250.551953) (xy 444.449102 -250.566059) (xy 444.500431 -250.587871) (xy 444.548037 -250.616925)
			(xy 444.590905 -250.6526) (xy 444.628122 -250.694137) (xy 444.658895 -250.74065) (xy 444.682567 -250.791147)
			(xy 444.698635 -250.844554) (xy 444.706755 -250.89973) (xy 444.707264 -250.927616) (xy 444.706755 -250.955502)
			(xy 444.698635 -251.010678) (xy 444.682567 -251.064085) (xy 444.658895 -251.114582) (xy 444.628122 -251.161095)
			(xy 444.590905 -251.202632) (xy 444.548037 -251.238307) (xy 444.500431 -251.267361) (xy 444.449102 -251.289173)
			(xy 444.395145 -251.303279) (xy 444.339708 -251.309379) (xy 444.283974 -251.307342) (xy 444.229131 -251.297212)
			(xy 444.176347 -251.279205) (xy 444.126747 -251.253704) (xy 444.081389 -251.221253) (xy 444.04124 -251.182544)
			(xy 444.007154 -251.138401) (xy 443.979858 -251.089766) (xy 443.959935 -251.037675) (xy 443.947809 -250.983238)
			(xy 443.943738 -250.927616) (xy 443.753964 -250.927616) (xy 443.741662 -250.946211) (xy 443.704445 -250.987748)
			(xy 443.661577 -251.023423) (xy 443.613971 -251.052477) (xy 443.562642 -251.074289) (xy 443.508685 -251.088395)
			(xy 443.453248 -251.094495) (xy 443.397514 -251.092458) (xy 443.342671 -251.082328) (xy 443.289887 -251.064321)
			(xy 443.240287 -251.03882) (xy 443.194929 -251.006369) (xy 443.15478 -250.96766) (xy 443.120694 -250.923517)
			(xy 443.093398 -250.874882) (xy 443.073475 -250.822791) (xy 443.061349 -250.768354) (xy 443.057278 -250.712732)
			(xy 410.899249 -250.712732) (xy 410.737558 -251.647452) (xy 410.736796 -251.656088) (xy 410.736796 -252.000512)
			(xy 410.737221 -252.010581) (xy 410.744938 -252.029183) (xy 410.751782 -252.03658) (xy 411.55366 -252.838458)
			(xy 411.56106 -252.8453) (xy 411.579658 -252.853019) (xy 411.589728 -252.853444) (xy 419.492684 -252.853444)
		)
		(stroke
			(width 0)
			(type solid)
		)
		(fill yes)
		(layer "In7.Cu")
		(net "GND")
	)
	(gr_poly
		(pts
			(xy 27.147266 -300.497748) (xy 27.15733 -300.497311) (xy 27.175912 -300.489574) (xy 27.183334 -300.482762)
			(xy 27.972512 -299.693584) (xy 27.979365 -299.686189) (xy 27.987108 -299.66759) (xy 27.987498 -299.657516)
			(xy 27.987498 -299.56506) (xy 27.987162 -299.556421) (xy 27.981411 -299.540129) (xy 27.97055 -299.526692)
			(xy 27.963368 -299.52188) (xy 27.878278 -299.469556) (xy 27.852116 -299.468286) (xy 27.840178 -299.474382)
			(xy 27.813478 -299.487195) (xy 27.757098 -299.505313) (xy 27.698592 -299.514482) (xy 27.668982 -299.515022)
			(xy 27.641731 -299.514535) (xy 27.587783 -299.506776) (xy 27.535488 -299.491419) (xy 27.485912 -299.468776)
			(xy 27.440062 -299.439308) (xy 27.398872 -299.403615) (xy 27.363181 -299.362424) (xy 27.333716 -299.316573)
			(xy 27.311075 -299.266995) (xy 27.29572 -299.2147) (xy 27.287964 -299.160751) (xy 27.287964 -299.106249)
			(xy 27.29572 -299.0523) (xy 27.311075 -299.000005) (xy 27.333716 -298.950427) (xy 27.363181 -298.904576)
			(xy 27.398872 -298.863385) (xy 27.440062 -298.827692) (xy 27.485912 -298.798224) (xy 27.535488 -298.775581)
			(xy 27.587783 -298.760224) (xy 27.641731 -298.752465) (xy 27.668982 -298.752006) (xy 27.697258 -298.752517)
			(xy 27.753192 -298.760858) (xy 27.807282 -298.777362) (xy 27.858346 -298.801665) (xy 27.882088 -298.81703)
			(xy 27.889629 -298.821722) (xy 27.90685 -298.826024) (xy 27.924501 -298.824158) (xy 27.932634 -298.820586)
			(xy 27.958796 -298.807886) (xy 27.967204 -298.803391) (xy 27.980162 -298.789423) (xy 27.987133 -298.771692)
			(xy 27.987498 -298.762166) (xy 27.987498 -298.759626) (xy 28.00604 -298.727368) (xy 28.009185 -298.721491)
			(xy 28.012662 -298.708629) (xy 28.012898 -298.701968) (xy 28.012898 -296.350944) (xy 28.012563 -296.342053)
			(xy 28.006478 -296.325346) (xy 27.995029 -296.31174) (xy 27.987498 -296.307002) (xy 27.899106 -296.256202)
			(xy 27.872182 -296.256202) (xy 27.860244 -296.26306) (xy 27.838373 -296.275295) (xy 27.792108 -296.29456)
			(xy 27.743719 -296.307602) (xy 27.694039 -296.314199) (xy 27.668982 -296.314622) (xy 27.641731 -296.314135)
			(xy 27.587783 -296.306376) (xy 27.535488 -296.291019) (xy 27.485912 -296.268376) (xy 27.440062 -296.238908)
			(xy 27.398872 -296.203215) (xy 27.363181 -296.162024) (xy 27.333716 -296.116173) (xy 27.311075 -296.066595)
			(xy 27.29572 -296.0143) (xy 27.287964 -295.960351) (xy 27.287964 -295.905849) (xy 27.29572 -295.8519)
			(xy 27.311075 -295.799605) (xy 27.333716 -295.750027) (xy 27.363181 -295.704176) (xy 27.398872 -295.662985)
			(xy 27.440062 -295.627292) (xy 27.485912 -295.597824) (xy 27.535488 -295.575181) (xy 27.587783 -295.559824)
			(xy 27.641731 -295.552065) (xy 27.668982 -295.551606) (xy 27.694039 -295.552021) (xy 27.743718 -295.558621)
			(xy 27.792105 -295.571671) (xy 27.838365 -295.590946) (xy 27.860244 -295.603168) (xy 27.872182 -295.610026)
			(xy 27.899106 -295.610026) (xy 27.987498 -295.559226) (xy 27.994989 -295.554446) (xy 28.006397 -295.540841)
			(xy 28.01248 -295.524161) (xy 28.012898 -295.515284) (xy 28.012898 -293.150544) (xy 28.012563 -293.141653)
			(xy 28.006478 -293.124946) (xy 27.995029 -293.11134) (xy 27.987498 -293.106602) (xy 27.899106 -293.055802)
			(xy 27.872182 -293.055802) (xy 27.860244 -293.06266) (xy 27.838373 -293.074895) (xy 27.792108 -293.09416)
			(xy 27.743719 -293.107202) (xy 27.694039 -293.113799) (xy 27.668982 -293.114222) (xy 27.641731 -293.113735)
			(xy 27.587783 -293.105976) (xy 27.535488 -293.090619) (xy 27.485912 -293.067976) (xy 27.440062 -293.038508)
			(xy 27.398872 -293.002815) (xy 27.363181 -292.961624) (xy 27.333716 -292.915773) (xy 27.311075 -292.866195)
			(xy 27.29572 -292.8139) (xy 27.287964 -292.759951) (xy 27.287964 -292.705449) (xy 27.29572 -292.6515)
			(xy 27.311075 -292.599205) (xy 27.333716 -292.549627) (xy 27.363181 -292.503776) (xy 27.398872 -292.462585)
			(xy 27.440062 -292.426892) (xy 27.485912 -292.397424) (xy 27.535488 -292.374781) (xy 27.587783 -292.359424)
			(xy 27.641731 -292.351665) (xy 27.668982 -292.351206) (xy 27.694039 -292.351621) (xy 27.743718 -292.358221)
			(xy 27.792105 -292.371271) (xy 27.838365 -292.390546) (xy 27.860244 -292.402768) (xy 27.872182 -292.409626)
			(xy 27.899106 -292.409626) (xy 27.987498 -292.358826) (xy 27.994989 -292.354046) (xy 28.006397 -292.340441)
			(xy 28.01248 -292.323761) (xy 28.012898 -292.314884) (xy 28.012898 -286.749744) (xy 28.012563 -286.740853)
			(xy 28.006478 -286.724146) (xy 27.995029 -286.71054) (xy 27.987498 -286.705802) (xy 27.899106 -286.655002)
			(xy 27.872182 -286.655002) (xy 27.860244 -286.66186) (xy 27.838373 -286.674095) (xy 27.792108 -286.69336)
			(xy 27.743719 -286.706402) (xy 27.694039 -286.712999) (xy 27.668982 -286.713422) (xy 27.641731 -286.712935)
			(xy 27.587783 -286.705176) (xy 27.535488 -286.689819) (xy 27.485912 -286.667176) (xy 27.440062 -286.637708)
			(xy 27.398872 -286.602015) (xy 27.363181 -286.560824) (xy 27.333716 -286.514973) (xy 27.311075 -286.465395)
			(xy 27.29572 -286.4131) (xy 27.287964 -286.359151) (xy 27.287964 -286.304649) (xy 27.29572 -286.2507)
			(xy 27.311075 -286.198405) (xy 27.333716 -286.148827) (xy 27.363181 -286.102976) (xy 27.398872 -286.061785)
			(xy 27.440062 -286.026092) (xy 27.485912 -285.996624) (xy 27.535488 -285.973981) (xy 27.587783 -285.958624)
			(xy 27.641731 -285.950865) (xy 27.668982 -285.950406) (xy 27.694039 -285.950821) (xy 27.743718 -285.957421)
			(xy 27.792105 -285.970471) (xy 27.838365 -285.989746) (xy 27.860244 -286.001968) (xy 27.872182 -286.008826)
			(xy 27.899106 -286.008826) (xy 27.987498 -285.958026) (xy 27.994989 -285.953246) (xy 28.006397 -285.939641)
			(xy 28.01248 -285.922961) (xy 28.012898 -285.914084) (xy 28.012898 -283.549344) (xy 28.012563 -283.540453)
			(xy 28.006478 -283.523746) (xy 27.995029 -283.51014) (xy 27.987498 -283.505402) (xy 27.899106 -283.454602)
			(xy 27.872182 -283.454602) (xy 27.860244 -283.46146) (xy 27.838373 -283.473695) (xy 27.792108 -283.49296)
			(xy 27.743719 -283.506002) (xy 27.694039 -283.512599) (xy 27.668982 -283.513022) (xy 27.641731 -283.512535)
			(xy 27.587783 -283.504776) (xy 27.535488 -283.489419) (xy 27.485912 -283.466776) (xy 27.440062 -283.437308)
			(xy 27.398872 -283.401615) (xy 27.363181 -283.360424) (xy 27.333716 -283.314573) (xy 27.311075 -283.264995)
			(xy 27.29572 -283.2127) (xy 27.287964 -283.158751) (xy 27.287964 -283.104249) (xy 27.29572 -283.0503)
			(xy 27.311075 -282.998005) (xy 27.333716 -282.948427) (xy 27.363181 -282.902576) (xy 27.398872 -282.861385)
			(xy 27.440062 -282.825692) (xy 27.485912 -282.796224) (xy 27.535488 -282.773581) (xy 27.587783 -282.758224)
			(xy 27.641731 -282.750465) (xy 27.668982 -282.750006) (xy 27.694039 -282.750421) (xy 27.743718 -282.757021)
			(xy 27.792105 -282.770071) (xy 27.838365 -282.789346) (xy 27.860244 -282.801568) (xy 27.872182 -282.808426)
			(xy 27.899106 -282.808426) (xy 27.987498 -282.757626) (xy 27.994989 -282.752846) (xy 28.006397 -282.739241)
			(xy 28.01248 -282.722561) (xy 28.012898 -282.713684) (xy 28.012898 -280.348944) (xy 28.012563 -280.340053)
			(xy 28.006478 -280.323346) (xy 27.995029 -280.30974) (xy 27.987498 -280.305002) (xy 27.899106 -280.254202)
			(xy 27.872182 -280.254202) (xy 27.860244 -280.26106) (xy 27.838373 -280.273295) (xy 27.792108 -280.29256)
			(xy 27.743719 -280.305602) (xy 27.694039 -280.312199) (xy 27.668982 -280.312622) (xy 27.641731 -280.312135)
			(xy 27.587783 -280.304376) (xy 27.535488 -280.289019) (xy 27.485912 -280.266376) (xy 27.440062 -280.236908)
			(xy 27.398872 -280.201215) (xy 27.363181 -280.160024) (xy 27.333716 -280.114173) (xy 27.311075 -280.064595)
			(xy 27.29572 -280.0123) (xy 27.287964 -279.958351) (xy 27.287964 -279.903849) (xy 27.29572 -279.8499)
			(xy 27.311075 -279.797605) (xy 27.333716 -279.748027) (xy 27.363181 -279.702176) (xy 27.398872 -279.660985)
			(xy 27.440062 -279.625292) (xy 27.485912 -279.595824) (xy 27.535488 -279.573181) (xy 27.587783 -279.557824)
			(xy 27.641731 -279.550065) (xy 27.668982 -279.549606) (xy 27.694039 -279.550021) (xy 27.743718 -279.556621)
			(xy 27.792105 -279.569671) (xy 27.838365 -279.588946) (xy 27.860244 -279.601168) (xy 27.872182 -279.608026)
			(xy 27.899106 -279.608026) (xy 27.987498 -279.557226) (xy 27.994989 -279.552446) (xy 28.006397 -279.538841)
			(xy 28.01248 -279.522161) (xy 28.012898 -279.513284) (xy 28.012898 -278.885396) (xy 28.012474 -278.875326)
			(xy 28.004758 -278.856723) (xy 27.997912 -278.849328) (xy 24.495252 -275.346668) (xy 24.488405 -275.33927)
			(xy 24.480674 -275.320672) (xy 24.480266 -275.3106) (xy 24.480266 -268.781276) (xy 24.480695 -268.771209)
			(xy 24.488423 -268.752617) (xy 24.495252 -268.745208) (xy 31.128716 -262.111744) (xy 31.129224 -262.111236)
			(xy 31.135808 -262.103856) (xy 31.143258 -262.085556) (xy 31.143702 -262.075676) (xy 31.143702 -259.659628)
			(xy 31.142686 -259.654294) (xy 31.138909 -259.63502) (xy 31.134841 -259.595954) (xy 31.134558 -259.576316)
			(xy 31.134815 -259.556676) (xy 31.138891 -259.517609) (xy 31.142686 -259.498338) (xy 31.143702 -259.493004)
			(xy 31.143702 -258.122674) (xy 31.143274 -258.112606) (xy 31.135553 -258.094008) (xy 31.128716 -258.086606)
			(xy 30.678374 -257.636264) (xy 30.671262 -257.628898) (xy 30.652466 -257.621278) (xy 27.89936 -257.621278)
			(xy 27.889293 -257.620847) (xy 27.870702 -257.61312) (xy 27.863292 -257.606292) (xy 27.432254 -257.175254)
			(xy 27.425409 -257.167856) (xy 27.417683 -257.149257) (xy 27.417268 -257.139186) (xy 27.417268 -256.396744)
			(xy 27.416834 -256.386679) (xy 27.409102 -256.368092) (xy 27.402282 -256.360676) (xy 27.201876 -256.16027)
			(xy 27.19448 -256.15342) (xy 27.175881 -256.145683) (xy 27.165808 -256.145284) (xy 25.299924 -256.145284)
			(xy 25.28986 -256.14572) (xy 25.271274 -256.153452) (xy 25.263856 -256.16027) (xy 23.817834 -257.606292)
			(xy 23.810432 -257.613129) (xy 23.791834 -257.62084) (xy 23.781766 -257.621278) (xy 22.723602 -257.621278)
			(xy 22.699726 -257.63601) (xy 22.692868 -257.64871) (xy 22.679698 -257.67328) (xy 22.64727 -257.718624)
			(xy 22.608584 -257.758763) (xy 22.564465 -257.792839) (xy 22.515855 -257.820128) (xy 22.463788 -257.840046)
			(xy 22.409376 -257.852169) (xy 22.353778 -257.856239) (xy 22.29818 -257.852169) (xy 22.243768 -257.840046)
			(xy 22.191701 -257.820128) (xy 22.143091 -257.792839) (xy 22.098972 -257.758763) (xy 22.060286 -257.718624)
			(xy 22.027858 -257.67328) (xy 22.014688 -257.64871) (xy 22.00783 -257.63601) (xy 21.983954 -257.621278)
			(xy 21.631656 -257.621278) (xy 21.621589 -257.621708) (xy 21.602994 -257.629432) (xy 21.595588 -257.636264)
			(xy 20.962366 -258.269486) (xy 20.955 -258.276598) (xy 20.94738 -258.295394) (xy 20.94738 -258.665472)
			(xy 21.126448 -258.665472) (xy 21.130519 -258.60985) (xy 21.142645 -258.555413) (xy 21.162568 -258.503322)
			(xy 21.189864 -258.454687) (xy 21.22395 -258.410544) (xy 21.264099 -258.371835) (xy 21.309457 -258.339384)
			(xy 21.359057 -258.313883) (xy 21.411841 -258.295876) (xy 21.466684 -258.285746) (xy 21.522418 -258.283709)
			(xy 21.577855 -258.289809) (xy 21.631812 -258.303915) (xy 21.683141 -258.325727) (xy 21.730747 -258.354781)
			(xy 21.773615 -258.390456) (xy 21.810832 -258.431993) (xy 21.841605 -258.478506) (xy 21.865277 -258.529003)
			(xy 21.881345 -258.58241) (xy 21.889465 -258.637586) (xy 21.889691 -258.649978) (xy 22.926292 -258.649978)
			(xy 22.930363 -258.594356) (xy 22.942489 -258.539919) (xy 22.962412 -258.487828) (xy 22.989708 -258.439193)
			(xy 23.023794 -258.39505) (xy 23.063943 -258.356341) (xy 23.109301 -258.32389) (xy 23.158901 -258.298389)
			(xy 23.211685 -258.280382) (xy 23.266528 -258.270252) (xy 23.322262 -258.268215) (xy 23.377699 -258.274315)
			(xy 23.431656 -258.288421) (xy 23.482985 -258.310233) (xy 23.530591 -258.339287) (xy 23.573459 -258.374962)
			(xy 23.610676 -258.416499) (xy 23.641449 -258.463012) (xy 23.665121 -258.513509) (xy 23.681189 -258.566916)
			(xy 23.689309 -258.622092) (xy 23.689818 -258.649978) (xy 23.689309 -258.677864) (xy 23.687357 -258.691126)
			(xy 24.410668 -258.691126) (xy 24.414739 -258.635504) (xy 24.426865 -258.581067) (xy 24.446788 -258.528976)
			(xy 24.474084 -258.480341) (xy 24.50817 -258.436198) (xy 24.548319 -258.397489) (xy 24.593677 -258.365038)
			(xy 24.643277 -258.339537) (xy 24.696061 -258.32153) (xy 24.750904 -258.3114) (xy 24.806638 -258.309363)
			(xy 24.862075 -258.315463) (xy 24.916032 -258.329569) (xy 24.967361 -258.351381) (xy 25.014967 -258.380435)
			(xy 25.057835 -258.41611) (xy 25.095052 -258.457647) (xy 25.125825 -258.50416) (xy 25.149497 -258.554657)
			(xy 25.165565 -258.608064) (xy 25.173685 -258.66324) (xy 25.174194 -258.691126) (xy 25.173685 -258.719012)
			(xy 25.165565 -258.774188) (xy 25.149497 -258.827595) (xy 25.125825 -258.878092) (xy 25.095052 -258.924605)
			(xy 25.057835 -258.966142) (xy 25.014967 -259.001817) (xy 24.967361 -259.030871) (xy 24.916032 -259.052683)
			(xy 24.862075 -259.066789) (xy 24.806638 -259.072889) (xy 24.750904 -259.070852) (xy 24.696061 -259.060722)
			(xy 24.643277 -259.042715) (xy 24.593677 -259.017214) (xy 24.548319 -258.984763) (xy 24.50817 -258.946054)
			(xy 24.474084 -258.901911) (xy 24.446788 -258.853276) (xy 24.426865 -258.801185) (xy 24.414739 -258.746748)
			(xy 24.410668 -258.691126) (xy 23.687357 -258.691126) (xy 23.681189 -258.73304) (xy 23.665121 -258.786447)
			(xy 23.641449 -258.836944) (xy 23.610676 -258.883457) (xy 23.573459 -258.924994) (xy 23.530591 -258.960669)
			(xy 23.482985 -258.989723) (xy 23.431656 -259.011535) (xy 23.377699 -259.025641) (xy 23.322262 -259.031741)
			(xy 23.266528 -259.029704) (xy 23.211685 -259.019574) (xy 23.158901 -259.001567) (xy 23.109301 -258.976066)
			(xy 23.063943 -258.943615) (xy 23.023794 -258.904906) (xy 22.989708 -258.860763) (xy 22.962412 -258.812128)
			(xy 22.942489 -258.760037) (xy 22.930363 -258.7056) (xy 22.926292 -258.649978) (xy 21.889691 -258.649978)
			(xy 21.889974 -258.665472) (xy 21.889465 -258.693358) (xy 21.881345 -258.748534) (xy 21.865277 -258.801941)
			(xy 21.841605 -258.852438) (xy 21.810832 -258.898951) (xy 21.773615 -258.940488) (xy 21.730747 -258.976163)
			(xy 21.683141 -259.005217) (xy 21.631812 -259.027029) (xy 21.577855 -259.041135) (xy 21.522418 -259.047235)
			(xy 21.466684 -259.045198) (xy 21.411841 -259.035068) (xy 21.359057 -259.017061) (xy 21.309457 -258.99156)
			(xy 21.264099 -258.959109) (xy 21.22395 -258.9204) (xy 21.189864 -258.876257) (xy 21.162568 -258.827622)
			(xy 21.142645 -258.775531) (xy 21.130519 -258.721094) (xy 21.126448 -258.665472) (xy 20.94738 -258.665472)
			(xy 20.94738 -259.576316) (xy 30.245048 -259.576316) (xy 30.249119 -259.520694) (xy 30.261245 -259.466257)
			(xy 30.281168 -259.414166) (xy 30.308464 -259.365531) (xy 30.34255 -259.321388) (xy 30.382699 -259.282679)
			(xy 30.428057 -259.250228) (xy 30.477657 -259.224727) (xy 30.530441 -259.20672) (xy 30.585284 -259.19659)
			(xy 30.641018 -259.194553) (xy 30.696455 -259.200653) (xy 30.750412 -259.214759) (xy 30.801741 -259.236571)
			(xy 30.849347 -259.265625) (xy 30.892215 -259.3013) (xy 30.929432 -259.342837) (xy 30.960205 -259.38935)
			(xy 30.983877 -259.439847) (xy 30.999945 -259.493254) (xy 31.008065 -259.54843) (xy 31.008574 -259.576316)
			(xy 31.008065 -259.604202) (xy 30.999945 -259.659378) (xy 30.983877 -259.712785) (xy 30.960205 -259.763282)
			(xy 30.929432 -259.809795) (xy 30.892215 -259.851332) (xy 30.849347 -259.887007) (xy 30.801741 -259.916061)
			(xy 30.750412 -259.937873) (xy 30.696455 -259.951979) (xy 30.641018 -259.958079) (xy 30.585284 -259.956042)
			(xy 30.530441 -259.945912) (xy 30.477657 -259.927905) (xy 30.428057 -259.902404) (xy 30.382699 -259.869953)
			(xy 30.34255 -259.831244) (xy 30.308464 -259.787101) (xy 30.281168 -259.738466) (xy 30.261245 -259.686375)
			(xy 30.249119 -259.631938) (xy 30.245048 -259.576316) (xy 20.94738 -259.576316) (xy 20.94738 -260.740398)
			(xy 22.04339 -260.740398) (xy 22.043956 -260.711756) (xy 22.05252 -260.655116) (xy 22.069455 -260.600392)
			(xy 22.09438 -260.548815) (xy 22.126735 -260.501543) (xy 22.165793 -260.459639) (xy 22.187916 -260.44144)
			(xy 22.196298 -260.434836) (xy 22.206204 -260.415786) (xy 22.212808 -260.31952) (xy 22.205696 -260.299454)
			(xy 22.198076 -260.29158) (xy 22.178306 -260.270146) (xy 22.144874 -260.222374) (xy 22.119096 -260.170073)
			(xy 22.101571 -260.11446) (xy 22.092708 -260.056828) (xy 22.092158 -260.027674) (xy 22.092644 -260.000423)
			(xy 22.1004 -259.946475) (xy 22.115755 -259.89418) (xy 22.138397 -259.844603) (xy 22.167863 -259.798753)
			(xy 22.203554 -259.757562) (xy 22.244745 -259.721871) (xy 22.290595 -259.692405) (xy 22.340172 -259.669763)
			(xy 22.392467 -259.654408) (xy 22.446415 -259.646652) (xy 22.500917 -259.646652) (xy 22.554865 -259.654408)
			(xy 22.60716 -259.669763) (xy 22.656737 -259.692405) (xy 22.702587 -259.721871) (xy 22.743778 -259.757562)
			(xy 22.779469 -259.798753) (xy 22.808935 -259.844603) (xy 22.831577 -259.89418) (xy 22.846932 -259.946475)
			(xy 22.854688 -260.000423) (xy 22.855174 -260.027674) (xy 22.854672 -260.056319) (xy 22.85251 -260.0706)
			(xy 23.642826 -260.0706) (xy 23.646897 -260.014978) (xy 23.659023 -259.960541) (xy 23.678946 -259.90845)
			(xy 23.706242 -259.859815) (xy 23.740328 -259.815672) (xy 23.780477 -259.776963) (xy 23.825835 -259.744512)
			(xy 23.875435 -259.719011) (xy 23.928219 -259.701004) (xy 23.983062 -259.690874) (xy 24.038796 -259.688837)
			(xy 24.094233 -259.694937) (xy 24.14819 -259.709043) (xy 24.199519 -259.730855) (xy 24.247125 -259.759909)
			(xy 24.289993 -259.795584) (xy 24.32721 -259.837121) (xy 24.357983 -259.883634) (xy 24.381655 -259.934131)
			(xy 24.397723 -259.987538) (xy 24.405843 -260.042714) (xy 24.406352 -260.0706) (xy 24.405843 -260.098486)
			(xy 24.402695 -260.119876) (xy 27.661868 -260.119876) (xy 27.665939 -260.064254) (xy 27.678065 -260.009817)
			(xy 27.697988 -259.957726) (xy 27.725284 -259.909091) (xy 27.75937 -259.864948) (xy 27.799519 -259.826239)
			(xy 27.844877 -259.793788) (xy 27.894477 -259.768287) (xy 27.947261 -259.75028) (xy 28.002104 -259.74015)
			(xy 28.057838 -259.738113) (xy 28.113275 -259.744213) (xy 28.167232 -259.758319) (xy 28.218561 -259.780131)
			(xy 28.266167 -259.809185) (xy 28.309035 -259.84486) (xy 28.346252 -259.886397) (xy 28.377025 -259.93291)
			(xy 28.400697 -259.983407) (xy 28.416765 -260.036814) (xy 28.424885 -260.09199) (xy 28.425394 -260.119876)
			(xy 28.424885 -260.147762) (xy 28.416765 -260.202938) (xy 28.400697 -260.256345) (xy 28.377025 -260.306842)
			(xy 28.346252 -260.353355) (xy 28.309035 -260.394892) (xy 28.266167 -260.430567) (xy 28.218561 -260.459621)
			(xy 28.167232 -260.481433) (xy 28.113275 -260.495539) (xy 28.057838 -260.501639) (xy 28.002104 -260.499602)
			(xy 27.947261 -260.489472) (xy 27.894477 -260.471465) (xy 27.844877 -260.445964) (xy 27.799519 -260.413513)
			(xy 27.75937 -260.374804) (xy 27.725284 -260.330661) (xy 27.697988 -260.282026) (xy 27.678065 -260.229935)
			(xy 27.665939 -260.175498) (xy 27.661868 -260.119876) (xy 24.402695 -260.119876) (xy 24.397723 -260.153662)
			(xy 24.381655 -260.207069) (xy 24.357983 -260.257566) (xy 24.32721 -260.304079) (xy 24.289993 -260.345616)
			(xy 24.247125 -260.381291) (xy 24.199519 -260.410345) (xy 24.14819 -260.432157) (xy 24.094233 -260.446263)
			(xy 24.038796 -260.452363) (xy 23.983062 -260.450326) (xy 23.928219 -260.440196) (xy 23.875435 -260.422189)
			(xy 23.825835 -260.396688) (xy 23.780477 -260.364237) (xy 23.740328 -260.325528) (xy 23.706242 -260.281385)
			(xy 23.678946 -260.23275) (xy 23.659023 -260.180659) (xy 23.646897 -260.126222) (xy 23.642826 -260.0706)
			(xy 22.85251 -260.0706) (xy 22.846097 -260.112963) (xy 22.82915 -260.167688) (xy 22.804213 -260.219265)
			(xy 22.771846 -260.266535) (xy 22.732776 -260.308435) (xy 22.710648 -260.326632) (xy 22.702266 -260.333236)
			(xy 22.69236 -260.352286) (xy 22.685756 -260.448552) (xy 22.692868 -260.468618) (xy 22.700488 -260.476492)
			(xy 22.720239 -260.497943) (xy 22.749139 -260.53923) (xy 26.534616 -260.53923) (xy 26.538687 -260.483608)
			(xy 26.550813 -260.429171) (xy 26.570736 -260.37708) (xy 26.598032 -260.328445) (xy 26.632118 -260.284302)
			(xy 26.672267 -260.245593) (xy 26.717625 -260.213142) (xy 26.767225 -260.187641) (xy 26.820009 -260.169634)
			(xy 26.874852 -260.159504) (xy 26.930586 -260.157467) (xy 26.986023 -260.163567) (xy 27.03998 -260.177673)
			(xy 27.091309 -260.199485) (xy 27.138915 -260.228539) (xy 27.181783 -260.264214) (xy 27.219 -260.305751)
			(xy 27.249773 -260.352264) (xy 27.273445 -260.402761) (xy 27.289513 -260.456168) (xy 27.297633 -260.511344)
			(xy 27.298142 -260.53923) (xy 27.297633 -260.567116) (xy 27.289513 -260.622292) (xy 27.273445 -260.675699)
			(xy 27.249773 -260.726196) (xy 27.219 -260.772709) (xy 27.181783 -260.814246) (xy 27.138915 -260.849921)
			(xy 27.091309 -260.878975) (xy 27.03998 -260.900787) (xy 26.986023 -260.914893) (xy 26.930586 -260.920993)
			(xy 26.874852 -260.918956) (xy 26.820009 -260.908826) (xy 26.767225 -260.890819) (xy 26.717625 -260.865318)
			(xy 26.672267 -260.832867) (xy 26.632118 -260.794158) (xy 26.598032 -260.750015) (xy 26.570736 -260.70138)
			(xy 26.550813 -260.649289) (xy 26.538687 -260.594852) (xy 26.534616 -260.53923) (xy 22.749139 -260.53923)
			(xy 22.753675 -260.54571) (xy 22.779457 -260.598007) (xy 22.796986 -260.653616) (xy 22.805854 -260.711245)
			(xy 22.806406 -260.740398) (xy 22.80592 -260.767649) (xy 22.798164 -260.821597) (xy 22.782809 -260.873892)
			(xy 22.760167 -260.923469) (xy 22.730701 -260.969319) (xy 22.69501 -261.01051) (xy 22.653819 -261.046201)
			(xy 22.607969 -261.075667) (xy 22.558392 -261.098309) (xy 22.506097 -261.113664) (xy 22.452149 -261.12142)
			(xy 22.397647 -261.12142) (xy 22.343699 -261.113664) (xy 22.291404 -261.098309) (xy 22.241827 -261.075667)
			(xy 22.195977 -261.046201) (xy 22.154786 -261.01051) (xy 22.119095 -260.969319) (xy 22.089629 -260.923469)
			(xy 22.066987 -260.873892) (xy 22.051632 -260.821597) (xy 22.043876 -260.767649) (xy 22.04339 -260.740398)
			(xy 20.94738 -260.740398) (xy 20.94738 -261.764272) (xy 24.31872 -261.764272) (xy 24.322791 -261.70865)
			(xy 24.334917 -261.654213) (xy 24.35484 -261.602122) (xy 24.382136 -261.553487) (xy 24.416222 -261.509344)
			(xy 24.456371 -261.470635) (xy 24.501729 -261.438184) (xy 24.551329 -261.412683) (xy 24.604113 -261.394676)
			(xy 24.658956 -261.384546) (xy 24.71469 -261.382509) (xy 24.770127 -261.388609) (xy 24.824084 -261.402715)
			(xy 24.875413 -261.424527) (xy 24.923019 -261.453581) (xy 24.965887 -261.489256) (xy 25.003104 -261.530793)
			(xy 25.033877 -261.577306) (xy 25.057549 -261.627803) (xy 25.073617 -261.68121) (xy 25.081737 -261.736386)
			(xy 25.082246 -261.764272) (xy 25.081737 -261.792158) (xy 25.073617 -261.847334) (xy 25.057549 -261.900741)
			(xy 25.033877 -261.951238) (xy 25.003104 -261.997751) (xy 24.965887 -262.039288) (xy 24.923019 -262.074963)
			(xy 24.875413 -262.104017) (xy 24.824084 -262.125829) (xy 24.770127 -262.139935) (xy 24.71469 -262.146035)
			(xy 24.658956 -262.143998) (xy 24.604113 -262.133868) (xy 24.551329 -262.115861) (xy 24.501729 -262.09036)
			(xy 24.456371 -262.057909) (xy 24.416222 -262.0192) (xy 24.382136 -261.975057) (xy 24.35484 -261.926422)
			(xy 24.334917 -261.874331) (xy 24.322791 -261.819894) (xy 24.31872 -261.764272) (xy 20.94738 -261.764272)
			(xy 20.94738 -262.519668) (xy 22.592282 -262.519668) (xy 22.596353 -262.464046) (xy 22.608479 -262.409609)
			(xy 22.628402 -262.357518) (xy 22.655698 -262.308883) (xy 22.689784 -262.26474) (xy 22.729933 -262.226031)
			(xy 22.775291 -262.19358) (xy 22.824891 -262.168079) (xy 22.877675 -262.150072) (xy 22.932518 -262.139942)
			(xy 22.988252 -262.137905) (xy 23.043689 -262.144005) (xy 23.097646 -262.158111) (xy 23.148975 -262.179923)
			(xy 23.196581 -262.208977) (xy 23.239449 -262.244652) (xy 23.276666 -262.286189) (xy 23.307439 -262.332702)
			(xy 23.331111 -262.383199) (xy 23.347179 -262.436606) (xy 23.355299 -262.491782) (xy 23.355808 -262.519668)
			(xy 23.355299 -262.547554) (xy 23.347179 -262.60273) (xy 23.331111 -262.656137) (xy 23.307439 -262.706634)
			(xy 23.276666 -262.753147) (xy 23.239449 -262.794684) (xy 23.196581 -262.830359) (xy 23.148975 -262.859413)
			(xy 23.097646 -262.881225) (xy 23.043689 -262.895331) (xy 22.988252 -262.901431) (xy 22.932518 -262.899394)
			(xy 22.877675 -262.889264) (xy 22.824891 -262.871257) (xy 22.775291 -262.845756) (xy 22.729933 -262.813305)
			(xy 22.689784 -262.774596) (xy 22.655698 -262.730453) (xy 22.628402 -262.681818) (xy 22.608479 -262.629727)
			(xy 22.596353 -262.57529) (xy 22.592282 -262.519668) (xy 20.94738 -262.519668) (xy 20.94738 -262.912352)
			(xy 25.168858 -262.912352) (xy 25.172929 -262.85673) (xy 25.185055 -262.802293) (xy 25.204978 -262.750202)
			(xy 25.232274 -262.701567) (xy 25.26636 -262.657424) (xy 25.306509 -262.618715) (xy 25.351867 -262.586264)
			(xy 25.401467 -262.560763) (xy 25.454251 -262.542756) (xy 25.509094 -262.532626) (xy 25.564828 -262.530589)
			(xy 25.620265 -262.536689) (xy 25.674222 -262.550795) (xy 25.725551 -262.572607) (xy 25.773157 -262.601661)
			(xy 25.816025 -262.637336) (xy 25.853242 -262.678873) (xy 25.884015 -262.725386) (xy 25.907687 -262.775883)
			(xy 25.923755 -262.82929) (xy 25.931875 -262.884466) (xy 25.932384 -262.912352) (xy 25.931875 -262.940238)
			(xy 25.923755 -262.995414) (xy 25.907687 -263.048821) (xy 25.884015 -263.099318) (xy 25.853242 -263.145831)
			(xy 25.816025 -263.187368) (xy 25.773157 -263.223043) (xy 25.725551 -263.252097) (xy 25.674222 -263.273909)
			(xy 25.620265 -263.288015) (xy 25.564828 -263.294115) (xy 25.509094 -263.292078) (xy 25.454251 -263.281948)
			(xy 25.401467 -263.263941) (xy 25.351867 -263.23844) (xy 25.306509 -263.205989) (xy 25.26636 -263.16728)
			(xy 25.232274 -263.123137) (xy 25.204978 -263.074502) (xy 25.185055 -263.022411) (xy 25.172929 -262.967974)
			(xy 25.168858 -262.912352) (xy 20.94738 -262.912352) (xy 20.94738 -278.443182) (xy 25.719276 -278.443182)
			(xy 25.723347 -278.38756) (xy 25.735473 -278.333123) (xy 25.755396 -278.281032) (xy 25.782692 -278.232397)
			(xy 25.816778 -278.188254) (xy 25.856927 -278.149545) (xy 25.902285 -278.117094) (xy 25.951885 -278.091593)
			(xy 26.004669 -278.073586) (xy 26.059512 -278.063456) (xy 26.115246 -278.061419) (xy 26.170683 -278.067519)
			(xy 26.22464 -278.081625) (xy 26.275969 -278.103437) (xy 26.323575 -278.132491) (xy 26.366443 -278.168166)
			(xy 26.40366 -278.209703) (xy 26.434433 -278.256216) (xy 26.458105 -278.306713) (xy 26.474173 -278.36012)
			(xy 26.482293 -278.415296) (xy 26.482802 -278.443182) (xy 26.482293 -278.471068) (xy 26.474173 -278.526244)
			(xy 26.458105 -278.579651) (xy 26.434433 -278.630148) (xy 26.40366 -278.676661) (xy 26.366443 -278.718198)
			(xy 26.323575 -278.753873) (xy 26.275969 -278.782927) (xy 26.22464 -278.804739) (xy 26.170683 -278.818845)
			(xy 26.115246 -278.824945) (xy 26.059512 -278.822908) (xy 26.004669 -278.812778) (xy 25.951885 -278.794771)
			(xy 25.902285 -278.76927) (xy 25.856927 -278.736819) (xy 25.816778 -278.69811) (xy 25.782692 -278.653967)
			(xy 25.755396 -278.605332) (xy 25.735473 -278.553241) (xy 25.723347 -278.498804) (xy 25.719276 -278.443182)
			(xy 20.94738 -278.443182) (xy 20.94738 -279.931114) (xy 25.811478 -279.931114) (xy 25.815549 -279.875492)
			(xy 25.827675 -279.821055) (xy 25.847598 -279.768964) (xy 25.874894 -279.720329) (xy 25.90898 -279.676186)
			(xy 25.949129 -279.637477) (xy 25.994487 -279.605026) (xy 26.044087 -279.579525) (xy 26.096871 -279.561518)
			(xy 26.151714 -279.551388) (xy 26.207448 -279.549351) (xy 26.262885 -279.555451) (xy 26.316842 -279.569557)
			(xy 26.368171 -279.591369) (xy 26.415777 -279.620423) (xy 26.458645 -279.656098) (xy 26.495862 -279.697635)
			(xy 26.526635 -279.744148) (xy 26.550307 -279.794645) (xy 26.566375 -279.848052) (xy 26.574495 -279.903228)
			(xy 26.575004 -279.931114) (xy 26.574495 -279.959) (xy 26.566375 -280.014176) (xy 26.550307 -280.067583)
			(xy 26.526635 -280.11808) (xy 26.495862 -280.164593) (xy 26.458645 -280.20613) (xy 26.415777 -280.241805)
			(xy 26.368171 -280.270859) (xy 26.316842 -280.292671) (xy 26.262885 -280.306777) (xy 26.207448 -280.312877)
			(xy 26.151714 -280.31084) (xy 26.096871 -280.30071) (xy 26.044087 -280.282703) (xy 25.994487 -280.257202)
			(xy 25.949129 -280.224751) (xy 25.90898 -280.186042) (xy 25.874894 -280.141899) (xy 25.847598 -280.093264)
			(xy 25.827675 -280.041173) (xy 25.815549 -279.986736) (xy 25.811478 -279.931114) (xy 20.94738 -279.931114)
			(xy 20.94738 -283.131514) (xy 25.811478 -283.131514) (xy 25.815549 -283.075892) (xy 25.827675 -283.021455)
			(xy 25.847598 -282.969364) (xy 25.874894 -282.920729) (xy 25.90898 -282.876586) (xy 25.949129 -282.837877)
			(xy 25.994487 -282.805426) (xy 26.044087 -282.779925) (xy 26.096871 -282.761918) (xy 26.151714 -282.751788)
			(xy 26.207448 -282.749751) (xy 26.262885 -282.755851) (xy 26.316842 -282.769957) (xy 26.368171 -282.791769)
			(xy 26.415777 -282.820823) (xy 26.458645 -282.856498) (xy 26.495862 -282.898035) (xy 26.526635 -282.944548)
			(xy 26.550307 -282.995045) (xy 26.566375 -283.048452) (xy 26.574495 -283.103628) (xy 26.575004 -283.131514)
			(xy 26.574495 -283.1594) (xy 26.566375 -283.214576) (xy 26.550307 -283.267983) (xy 26.526635 -283.31848)
			(xy 26.495862 -283.364993) (xy 26.458645 -283.40653) (xy 26.415777 -283.442205) (xy 26.368171 -283.471259)
			(xy 26.316842 -283.493071) (xy 26.262885 -283.507177) (xy 26.207448 -283.513277) (xy 26.151714 -283.51124)
			(xy 26.096871 -283.50111) (xy 26.044087 -283.483103) (xy 25.994487 -283.457602) (xy 25.949129 -283.425151)
			(xy 25.90898 -283.386442) (xy 25.874894 -283.342299) (xy 25.847598 -283.293664) (xy 25.827675 -283.241573)
			(xy 25.815549 -283.187136) (xy 25.811478 -283.131514) (xy 20.94738 -283.131514) (xy 20.94738 -286.331914)
			(xy 25.811478 -286.331914) (xy 25.815549 -286.276292) (xy 25.827675 -286.221855) (xy 25.847598 -286.169764)
			(xy 25.874894 -286.121129) (xy 25.90898 -286.076986) (xy 25.949129 -286.038277) (xy 25.994487 -286.005826)
			(xy 26.044087 -285.980325) (xy 26.096871 -285.962318) (xy 26.151714 -285.952188) (xy 26.207448 -285.950151)
			(xy 26.262885 -285.956251) (xy 26.316842 -285.970357) (xy 26.368171 -285.992169) (xy 26.415777 -286.021223)
			(xy 26.458645 -286.056898) (xy 26.495862 -286.098435) (xy 26.526635 -286.144948) (xy 26.550307 -286.195445)
			(xy 26.566375 -286.248852) (xy 26.574495 -286.304028) (xy 26.575004 -286.331914) (xy 26.574495 -286.3598)
			(xy 26.566375 -286.414976) (xy 26.550307 -286.468383) (xy 26.526635 -286.51888) (xy 26.495862 -286.565393)
			(xy 26.458645 -286.60693) (xy 26.415777 -286.642605) (xy 26.368171 -286.671659) (xy 26.316842 -286.693471)
			(xy 26.262885 -286.707577) (xy 26.207448 -286.713677) (xy 26.151714 -286.71164) (xy 26.096871 -286.70151)
			(xy 26.044087 -286.683503) (xy 25.994487 -286.658002) (xy 25.949129 -286.625551) (xy 25.90898 -286.586842)
			(xy 25.874894 -286.542699) (xy 25.847598 -286.494064) (xy 25.827675 -286.441973) (xy 25.815549 -286.387536)
			(xy 25.811478 -286.331914) (xy 20.94738 -286.331914) (xy 20.94738 -292.732714) (xy 25.811478 -292.732714)
			(xy 25.815549 -292.677092) (xy 25.827675 -292.622655) (xy 25.847598 -292.570564) (xy 25.874894 -292.521929)
			(xy 25.90898 -292.477786) (xy 25.949129 -292.439077) (xy 25.994487 -292.406626) (xy 26.044087 -292.381125)
			(xy 26.096871 -292.363118) (xy 26.151714 -292.352988) (xy 26.207448 -292.350951) (xy 26.262885 -292.357051)
			(xy 26.316842 -292.371157) (xy 26.368171 -292.392969) (xy 26.415777 -292.422023) (xy 26.458645 -292.457698)
			(xy 26.495862 -292.499235) (xy 26.526635 -292.545748) (xy 26.550307 -292.596245) (xy 26.566375 -292.649652)
			(xy 26.574495 -292.704828) (xy 26.575004 -292.732714) (xy 26.574495 -292.7606) (xy 26.566375 -292.815776)
			(xy 26.550307 -292.869183) (xy 26.526635 -292.91968) (xy 26.495862 -292.966193) (xy 26.458645 -293.00773)
			(xy 26.415777 -293.043405) (xy 26.368171 -293.072459) (xy 26.316842 -293.094271) (xy 26.262885 -293.108377)
			(xy 26.207448 -293.114477) (xy 26.151714 -293.11244) (xy 26.096871 -293.10231) (xy 26.044087 -293.084303)
			(xy 25.994487 -293.058802) (xy 25.949129 -293.026351) (xy 25.90898 -292.987642) (xy 25.874894 -292.943499)
			(xy 25.847598 -292.894864) (xy 25.827675 -292.842773) (xy 25.815549 -292.788336) (xy 25.811478 -292.732714)
			(xy 20.94738 -292.732714) (xy 20.94738 -295.933114) (xy 25.811478 -295.933114) (xy 25.815549 -295.877492)
			(xy 25.827675 -295.823055) (xy 25.847598 -295.770964) (xy 25.874894 -295.722329) (xy 25.90898 -295.678186)
			(xy 25.949129 -295.639477) (xy 25.994487 -295.607026) (xy 26.044087 -295.581525) (xy 26.096871 -295.563518)
			(xy 26.151714 -295.553388) (xy 26.207448 -295.551351) (xy 26.262885 -295.557451) (xy 26.316842 -295.571557)
			(xy 26.368171 -295.593369) (xy 26.415777 -295.622423) (xy 26.458645 -295.658098) (xy 26.495862 -295.699635)
			(xy 26.526635 -295.746148) (xy 26.550307 -295.796645) (xy 26.566375 -295.850052) (xy 26.574495 -295.905228)
			(xy 26.575004 -295.933114) (xy 26.574495 -295.961) (xy 26.566375 -296.016176) (xy 26.550307 -296.069583)
			(xy 26.526635 -296.12008) (xy 26.495862 -296.166593) (xy 26.458645 -296.20813) (xy 26.415777 -296.243805)
			(xy 26.368171 -296.272859) (xy 26.316842 -296.294671) (xy 26.262885 -296.308777) (xy 26.207448 -296.314877)
			(xy 26.151714 -296.31284) (xy 26.096871 -296.30271) (xy 26.044087 -296.284703) (xy 25.994487 -296.259202)
			(xy 25.949129 -296.226751) (xy 25.90898 -296.188042) (xy 25.874894 -296.143899) (xy 25.847598 -296.095264)
			(xy 25.827675 -296.043173) (xy 25.815549 -295.988736) (xy 25.811478 -295.933114) (xy 20.94738 -295.933114)
			(xy 20.94738 -297.649138) (xy 20.947843 -297.659014) (xy 20.955289 -297.677309) (xy 20.961858 -297.684698)
			(xy 20.962112 -297.684952) (xy 21.669502 -298.392342) (xy 21.676614 -298.395898) (xy 21.747709 -298.432434)
			(xy 21.886744 -298.511336) (xy 22.021892 -298.596725) (xy 22.152851 -298.68841) (xy 22.279327 -298.786186)
			(xy 22.401037 -298.889834) (xy 22.51771 -298.999123) (xy 22.629083 -299.113806) (xy 22.646489 -299.133514)
			(xy 25.826718 -299.133514) (xy 25.830789 -299.077892) (xy 25.842915 -299.023455) (xy 25.862838 -298.971364)
			(xy 25.890134 -298.922729) (xy 25.92422 -298.878586) (xy 25.964369 -298.839877) (xy 26.009727 -298.807426)
			(xy 26.059327 -298.781925) (xy 26.112111 -298.763918) (xy 26.166954 -298.753788) (xy 26.222688 -298.751751)
			(xy 26.278125 -298.757851) (xy 26.332082 -298.771957) (xy 26.383411 -298.793769) (xy 26.431017 -298.822823)
			(xy 26.473885 -298.858498) (xy 26.511102 -298.900035) (xy 26.541875 -298.946548) (xy 26.565547 -298.997045)
			(xy 26.581615 -299.050452) (xy 26.589735 -299.105628) (xy 26.590244 -299.133514) (xy 26.589735 -299.1614)
			(xy 26.581615 -299.216576) (xy 26.565547 -299.269983) (xy 26.541875 -299.32048) (xy 26.511102 -299.366993)
			(xy 26.473885 -299.40853) (xy 26.431017 -299.444205) (xy 26.383411 -299.473259) (xy 26.332082 -299.495071)
			(xy 26.278125 -299.509177) (xy 26.222688 -299.515277) (xy 26.166954 -299.51324) (xy 26.112111 -299.50311)
			(xy 26.059327 -299.485103) (xy 26.009727 -299.459602) (xy 25.964369 -299.427151) (xy 25.92422 -299.388442)
			(xy 25.890134 -299.344299) (xy 25.862838 -299.295664) (xy 25.842915 -299.243573) (xy 25.830789 -299.189136)
			(xy 25.826718 -299.133514) (xy 22.646489 -299.133514) (xy 22.734908 -299.233629) (xy 22.834948 -299.358322)
			(xy 22.928978 -299.487607) (xy 22.973284 -299.554138) (xy 22.980801 -299.564325) (xy 23.00306 -299.576317)
			(xy 23.015702 -299.576998) (xy 23.617936 -299.576998) (xy 23.628003 -299.577428) (xy 23.646598 -299.585151)
			(xy 23.654004 -299.591984) (xy 24.544782 -300.482762) (xy 24.552183 -300.4896) (xy 24.570782 -300.49731)
			(xy 24.58085 -300.497748)
		)
		(stroke
			(width 0)
			(type solid)
		)
		(fill yes)
		(layer "In7.Cu")
		(net "P1V8_PLL0_PEX0")
	)
	(gr_poly
		(pts
			(xy 221.639384 -88.410796) (xy 221.649345 -88.410306) (xy 221.667764 -88.402714) (xy 221.675198 -88.396064)
			(xy 221.90202 -88.169242) (xy 221.905322 -88.132412) (xy 221.894654 -88.117172) (xy 221.880037 -88.09555)
			(xy 221.856174 -88.049134) (xy 221.838852 -87.999901) (xy 221.833186 -87.974424) (xy 221.830482 -87.963926)
			(xy 221.817716 -87.946429) (xy 221.808548 -87.940642) (xy 221.783845 -87.925969) (xy 221.73875 -87.890366)
			(xy 221.699502 -87.848406) (xy 221.666986 -87.801038) (xy 221.641936 -87.749331) (xy 221.62492 -87.694453)
			(xy 221.616321 -87.637646) (xy 221.615762 -87.608918) (xy 221.616247 -87.581665) (xy 221.624001 -87.527714)
			(xy 221.639354 -87.475415) (xy 221.661994 -87.425834) (xy 221.691459 -87.379979) (xy 221.72715 -87.338784)
			(xy 221.768341 -87.303088) (xy 221.814192 -87.273617) (xy 221.86377 -87.250971) (xy 221.916067 -87.235611)
			(xy 221.970017 -87.22785) (xy 221.99727 -87.22741) (xy 222.026317 -87.227959) (xy 222.083739 -87.236773)
			(xy 222.139162 -87.254187) (xy 222.191305 -87.279799) (xy 222.238966 -87.313016) (xy 222.281042 -87.353073)
			(xy 222.316562 -87.399043) (xy 222.344706 -87.449865) (xy 222.364823 -87.504365) (xy 222.371158 -87.532718)
			(xy 222.373834 -87.54328) (xy 222.386599 -87.560913) (xy 222.395796 -87.566754) (xy 222.426022 -87.585804)
			(xy 222.441262 -87.596472) (xy 222.478092 -87.59317) (xy 224.898204 -85.173058) (xy 224.906317 -85.163876)
			(xy 224.913602 -85.140524) (xy 224.912174 -85.128354) (xy 224.899982 -85.058758) (xy 224.898717 -85.052706)
			(xy 224.893719 -85.041401) (xy 224.890076 -85.036406) (xy 224.886012 -85.031326) (xy 224.876868 -85.02396)
			(xy 224.87128 -85.02142) (xy 224.846912 -85.009571) (xy 224.8015 -84.980013) (xy 224.760727 -84.944327)
			(xy 224.725412 -84.903233) (xy 224.696266 -84.857555) (xy 224.673874 -84.808214) (xy 224.658688 -84.756202)
			(xy 224.651013 -84.702564) (xy 224.650554 -84.675472) (xy 224.651042 -84.648221) (xy 224.658801 -84.594274)
			(xy 224.674158 -84.541981) (xy 224.696801 -84.492405) (xy 224.726267 -84.446555) (xy 224.761958 -84.405365)
			(xy 224.803147 -84.369673) (xy 224.848996 -84.340205) (xy 224.898571 -84.317562) (xy 224.950865 -84.302203)
			(xy 225.004811 -84.294442) (xy 225.032062 -84.293964) (xy 225.046032 -84.293964) (xy 225.064828 -84.286598)
			(xy 225.123248 -84.228432) (xy 225.130169 -84.221064) (xy 225.138045 -84.202462) (xy 225.138488 -84.192364)
			(xy 225.138488 -84.14258) (xy 225.137997 -84.132492) (xy 225.130132 -84.113904) (xy 225.123248 -84.106512)
			(xy 225.064828 -84.048346) (xy 225.046032 -84.04098) (xy 225.035872 -84.04098) (xy 225.032062 -84.04098)
			(xy 225.004815 -84.040491) (xy 224.950875 -84.032731) (xy 224.898589 -84.017374) (xy 224.84902 -83.994732)
			(xy 224.803178 -83.965267) (xy 224.761995 -83.929578) (xy 224.72631 -83.888392) (xy 224.69685 -83.842547)
			(xy 224.674213 -83.792976) (xy 224.658861 -83.740688) (xy 224.651106 -83.686747) (xy 224.651106 -83.632253)
			(xy 224.658861 -83.578312) (xy 224.674213 -83.526024) (xy 224.69685 -83.476453) (xy 224.72631 -83.430608)
			(xy 224.761995 -83.389422) (xy 224.803178 -83.353733) (xy 224.84902 -83.324268) (xy 224.898589 -83.301626)
			(xy 224.950875 -83.286269) (xy 225.004815 -83.278509) (xy 225.032062 -83.277964) (xy 225.046032 -83.277964)
			(xy 225.064828 -83.270598) (xy 225.123248 -83.212432) (xy 225.130169 -83.205064) (xy 225.138045 -83.186462)
			(xy 225.138488 -83.176364) (xy 225.138488 -83.12658) (xy 225.137997 -83.116492) (xy 225.130132 -83.097904)
			(xy 225.123248 -83.090512) (xy 225.064828 -83.032346) (xy 225.046032 -83.02498) (xy 225.035872 -83.02498)
			(xy 225.032062 -83.02498) (xy 225.004815 -83.024491) (xy 224.950875 -83.016731) (xy 224.898589 -83.001374)
			(xy 224.84902 -82.978732) (xy 224.803178 -82.949267) (xy 224.761995 -82.913578) (xy 224.72631 -82.872392)
			(xy 224.69685 -82.826547) (xy 224.674213 -82.776976) (xy 224.658861 -82.724688) (xy 224.651106 -82.670747)
			(xy 224.651106 -82.616253) (xy 224.658861 -82.562312) (xy 224.674213 -82.510024) (xy 224.69685 -82.460453)
			(xy 224.72631 -82.414608) (xy 224.761995 -82.373422) (xy 224.803178 -82.337733) (xy 224.84902 -82.308268)
			(xy 224.898589 -82.285626) (xy 224.950875 -82.270269) (xy 225.004815 -82.262509) (xy 225.032062 -82.261964)
			(xy 225.046032 -82.261964) (xy 225.064828 -82.254598) (xy 225.123248 -82.196432) (xy 225.130169 -82.189064)
			(xy 225.138045 -82.170462) (xy 225.138488 -82.160364) (xy 225.138488 -82.11058) (xy 225.137997 -82.100492)
			(xy 225.130132 -82.081904) (xy 225.123248 -82.074512) (xy 225.064828 -82.016346) (xy 225.046032 -82.00898)
			(xy 225.035872 -82.00898) (xy 225.032062 -82.00898) (xy 225.004815 -82.008491) (xy 224.950875 -82.000731)
			(xy 224.898589 -81.985374) (xy 224.84902 -81.962732) (xy 224.803178 -81.933267) (xy 224.761995 -81.897578)
			(xy 224.72631 -81.856392) (xy 224.69685 -81.810547) (xy 224.674213 -81.760976) (xy 224.658861 -81.708688)
			(xy 224.651106 -81.654747) (xy 224.651106 -81.600253) (xy 224.658861 -81.546312) (xy 224.674213 -81.494024)
			(xy 224.69685 -81.444453) (xy 224.72631 -81.398608) (xy 224.761995 -81.357422) (xy 224.803178 -81.321733)
			(xy 224.84902 -81.292268) (xy 224.898589 -81.269626) (xy 224.950875 -81.254269) (xy 225.004815 -81.246509)
			(xy 225.032062 -81.245964) (xy 225.046032 -81.245964) (xy 225.064828 -81.238598) (xy 225.123248 -81.180432)
			(xy 225.130169 -81.173064) (xy 225.138045 -81.154462) (xy 225.138488 -81.144364) (xy 225.138488 -81.09458)
			(xy 225.13801 -81.084614) (xy 225.130433 -81.066179) (xy 225.123756 -81.058766) (xy 225.066098 -81.000854)
			(xy 225.048064 -80.99298) (xy 225.03765 -80.99298) (xy 225.010566 -80.992253) (xy 224.957006 -80.984089)
			(xy 224.90514 -80.96843) (xy 224.856011 -80.945591) (xy 224.810608 -80.91603) (xy 224.769843 -80.880343)
			(xy 224.734537 -80.839248) (xy 224.7054 -80.793572) (xy 224.683019 -80.744232) (xy 224.667843 -80.692223)
			(xy 224.660178 -80.638589) (xy 224.660178 -80.58441) (xy 224.667843 -80.530777) (xy 224.683019 -80.478767)
			(xy 224.705401 -80.429428) (xy 224.734537 -80.383751) (xy 224.769843 -80.342656) (xy 224.810608 -80.30697)
			(xy 224.856012 -80.277409) (xy 224.905141 -80.25457) (xy 224.957007 -80.23891) (xy 225.010567 -80.230747)
			(xy 225.03765 -80.229964) (xy 225.048064 -80.229964) (xy 225.066098 -80.22209) (xy 225.123756 -80.164178)
			(xy 225.130431 -80.156765) (xy 225.137996 -80.138329) (xy 225.138488 -80.128364) (xy 225.138488 -80.07858)
			(xy 225.13801 -80.068614) (xy 225.130433 -80.050179) (xy 225.123756 -80.042766) (xy 225.066098 -79.984854)
			(xy 225.048064 -79.97698) (xy 225.03765 -79.97698) (xy 225.010566 -79.976253) (xy 224.957006 -79.968089)
			(xy 224.90514 -79.95243) (xy 224.856011 -79.929591) (xy 224.810608 -79.90003) (xy 224.769843 -79.864343)
			(xy 224.734537 -79.823248) (xy 224.7054 -79.777572) (xy 224.683019 -79.728232) (xy 224.667843 -79.676223)
			(xy 224.660178 -79.622589) (xy 224.660178 -79.56841) (xy 224.667843 -79.514777) (xy 224.683019 -79.462767)
			(xy 224.705401 -79.413428) (xy 224.734537 -79.367751) (xy 224.769843 -79.326656) (xy 224.810608 -79.29097)
			(xy 224.856012 -79.261409) (xy 224.905141 -79.23857) (xy 224.957007 -79.22291) (xy 225.010567 -79.214747)
			(xy 225.03765 -79.213964) (xy 225.048064 -79.213964) (xy 225.066098 -79.20609) (xy 225.123756 -79.148178)
			(xy 225.130431 -79.140765) (xy 225.137996 -79.122329) (xy 225.138488 -79.112364) (xy 225.138488 -79.06258)
			(xy 225.13801 -79.052614) (xy 225.130433 -79.034179) (xy 225.123756 -79.026766) (xy 225.066098 -78.968854)
			(xy 225.048064 -78.96098) (xy 225.03765 -78.96098) (xy 225.010566 -78.960253) (xy 224.957006 -78.952089)
			(xy 224.90514 -78.93643) (xy 224.856011 -78.913591) (xy 224.810608 -78.88403) (xy 224.769843 -78.848343)
			(xy 224.734537 -78.807248) (xy 224.7054 -78.761572) (xy 224.683019 -78.712232) (xy 224.667843 -78.660223)
			(xy 224.660178 -78.606589) (xy 224.660178 -78.55241) (xy 224.667843 -78.498777) (xy 224.683019 -78.446767)
			(xy 224.705401 -78.397428) (xy 224.734537 -78.351751) (xy 224.769843 -78.310656) (xy 224.810608 -78.27497)
			(xy 224.856012 -78.245409) (xy 224.905141 -78.22257) (xy 224.957007 -78.20691) (xy 225.010567 -78.198747)
			(xy 225.03765 -78.197964) (xy 225.048064 -78.197964) (xy 225.066098 -78.19009) (xy 225.123756 -78.132178)
			(xy 225.130431 -78.124765) (xy 225.137996 -78.106329) (xy 225.138488 -78.096364) (xy 225.138488 -78.04658)
			(xy 225.13801 -78.036614) (xy 225.130433 -78.018179) (xy 225.123756 -78.010766) (xy 225.066098 -77.952854)
			(xy 225.048064 -77.94498) (xy 225.03765 -77.94498) (xy 225.010566 -77.944253) (xy 224.957006 -77.936089)
			(xy 224.90514 -77.92043) (xy 224.856011 -77.897591) (xy 224.810608 -77.86803) (xy 224.769843 -77.832343)
			(xy 224.734537 -77.791248) (xy 224.7054 -77.745572) (xy 224.683019 -77.696232) (xy 224.667843 -77.644223)
			(xy 224.660178 -77.590589) (xy 224.660178 -77.53641) (xy 224.667843 -77.482777) (xy 224.683019 -77.430767)
			(xy 224.705401 -77.381428) (xy 224.734537 -77.335751) (xy 224.769843 -77.294656) (xy 224.810608 -77.25897)
			(xy 224.856012 -77.229409) (xy 224.905141 -77.20657) (xy 224.957007 -77.19091) (xy 225.010567 -77.182747)
			(xy 225.03765 -77.181964) (xy 225.048064 -77.181964) (xy 225.066098 -77.17409) (xy 225.123756 -77.116178)
			(xy 225.130431 -77.108765) (xy 225.137996 -77.090329) (xy 225.138488 -77.080364) (xy 225.138488 -74.015854)
			(xy 225.137974 -74.005679) (xy 225.129967 -73.986963) (xy 225.122994 -73.979532) (xy 225.063304 -73.921366)
			(xy 225.044508 -73.914) (xy 225.03384 -73.914254) (xy 225.023172 -73.914508) (xy 224.995922 -73.91402)
			(xy 224.941977 -73.906261) (xy 224.889686 -73.890903) (xy 224.840112 -73.86826) (xy 224.794265 -73.838793)
			(xy 224.753078 -73.803102) (xy 224.71739 -73.761912) (xy 224.687926 -73.716063) (xy 224.665287 -73.666488)
			(xy 224.649933 -73.614195) (xy 224.642178 -73.56025) (xy 224.642178 -73.50575) (xy 224.649933 -73.451805)
			(xy 224.665287 -73.399512) (xy 224.687926 -73.349937) (xy 224.71739 -73.304088) (xy 224.753078 -73.262898)
			(xy 224.794265 -73.227207) (xy 224.840112 -73.19774) (xy 224.889686 -73.175097) (xy 224.941977 -73.159739)
			(xy 224.995922 -73.15198) (xy 225.023172 -73.151492) (xy 225.03384 -73.151746) (xy 225.044508 -73.152)
			(xy 225.063304 -73.144634) (xy 225.122994 -73.086468) (xy 225.130017 -73.079072) (xy 225.138023 -73.060333)
			(xy 225.138488 -73.050146) (xy 225.138488 -72.782176) (xy 225.138002 -72.772455) (xy 225.130688 -72.754436)
			(xy 225.124264 -72.747124) (xy 225.068892 -72.689212) (xy 225.051366 -72.681084) (xy 225.04146 -72.680576)
			(xy 225.015108 -72.678909) (xy 224.963202 -72.669219) (xy 224.913128 -72.652464) (xy 224.865843 -72.628966)
			(xy 224.822249 -72.599173) (xy 224.783179 -72.563653) (xy 224.74938 -72.523086) (xy 224.721496 -72.478246)
			(xy 224.700062 -72.42999) (xy 224.685486 -72.37924) (xy 224.681288 -72.35317) (xy 224.679256 -72.338692)
			(xy 224.660968 -72.316848) (xy 224.560892 -72.28332) (xy 224.551818 -72.280707) (xy 224.532971 -72.281645)
			(xy 224.515741 -72.289339) (xy 224.508822 -72.295766) (xy 223.210374 -73.594214) (xy 223.186797 -73.617126)
			(xy 223.135384 -73.658103) (xy 223.079707 -73.693068) (xy 223.020466 -73.721579) (xy 222.958406 -73.74328)
			(xy 222.894306 -73.757896) (xy 222.828973 -73.765245) (xy 222.7961 -73.765664) (xy 222.373952 -73.765664)
			(xy 222.363959 -73.766191) (xy 222.34551 -73.773887) (xy 222.338138 -73.78065) (xy 221.513654 -74.605134)
			(xy 222.27997 -74.605134) (xy 222.284041 -74.549512) (xy 222.296167 -74.495075) (xy 222.31609 -74.442984)
			(xy 222.343386 -74.394349) (xy 222.377472 -74.350206) (xy 222.417621 -74.311497) (xy 222.462979 -74.279046)
			(xy 222.512579 -74.253545) (xy 222.565363 -74.235538) (xy 222.620206 -74.225408) (xy 222.67594 -74.223371)
			(xy 222.731377 -74.229471) (xy 222.785334 -74.243577) (xy 222.836663 -74.265389) (xy 222.884269 -74.294443)
			(xy 222.927137 -74.330118) (xy 222.964354 -74.371655) (xy 222.995127 -74.418168) (xy 223.018799 -74.468665)
			(xy 223.034867 -74.522072) (xy 223.042987 -74.577248) (xy 223.043496 -74.605134) (xy 223.042987 -74.63302)
			(xy 223.034867 -74.688196) (xy 223.018799 -74.741603) (xy 222.995127 -74.7921) (xy 222.964354 -74.838613)
			(xy 222.927137 -74.88015) (xy 222.884269 -74.915825) (xy 222.836663 -74.944879) (xy 222.785334 -74.966691)
			(xy 222.731377 -74.980797) (xy 222.67594 -74.986897) (xy 222.620206 -74.98486) (xy 222.565363 -74.97473)
			(xy 222.512579 -74.956723) (xy 222.462979 -74.931222) (xy 222.417621 -74.898771) (xy 222.377472 -74.860062)
			(xy 222.343386 -74.815919) (xy 222.31609 -74.767284) (xy 222.296167 -74.715193) (xy 222.284041 -74.660756)
			(xy 222.27997 -74.605134) (xy 221.513654 -74.605134) (xy 219.247212 -76.871576) (xy 221.119192 -76.871576)
			(xy 221.119673 -76.844139) (xy 221.127512 -76.789829) (xy 221.143054 -76.737203) (xy 221.165977 -76.687347)
			(xy 221.195808 -76.641291) (xy 221.231932 -76.599986) (xy 221.273602 -76.564284) (xy 221.319959 -76.534922)
			(xy 221.370046 -76.512507) (xy 221.396306 -76.504546) (xy 221.406974 -76.501498) (xy 221.423738 -76.487274)
			(xy 221.465394 -76.397358) (xy 221.465648 -76.375006) (xy 221.461076 -76.3651) (xy 221.450328 -76.340252)
			(xy 221.435172 -76.288281) (xy 221.427515 -76.234688) (xy 221.42704 -76.20762) (xy 221.427526 -76.180369)
			(xy 221.435282 -76.126421) (xy 221.450637 -76.074126) (xy 221.473279 -76.024549) (xy 221.502745 -75.978699)
			(xy 221.538436 -75.937508) (xy 221.579627 -75.901817) (xy 221.625477 -75.872351) (xy 221.675054 -75.849709)
			(xy 221.727349 -75.834354) (xy 221.781297 -75.826598) (xy 221.835799 -75.826598) (xy 221.889747 -75.834354)
			(xy 221.942042 -75.849709) (xy 221.991619 -75.872351) (xy 222.037469 -75.901817) (xy 222.07866 -75.937508)
			(xy 222.114351 -75.978699) (xy 222.143817 -76.024549) (xy 222.166459 -76.074126) (xy 222.181814 -76.126421)
			(xy 222.18957 -76.180369) (xy 222.190056 -76.20762) (xy 222.189609 -76.235058) (xy 222.181769 -76.289372)
			(xy 222.166226 -76.342001) (xy 222.1433 -76.391859) (xy 222.113464 -76.437916) (xy 222.077335 -76.479222)
			(xy 222.035659 -76.514922) (xy 221.989297 -76.544281) (xy 221.939205 -76.566691) (xy 221.912942 -76.57465)
			(xy 221.902274 -76.577698) (xy 221.88551 -76.591922) (xy 221.843854 -76.681838) (xy 221.8436 -76.70419)
			(xy 221.848172 -76.714096) (xy 221.858915 -76.738945) (xy 221.874075 -76.790916) (xy 221.881733 -76.844508)
			(xy 221.882208 -76.871576) (xy 221.881722 -76.898827) (xy 221.873966 -76.952775) (xy 221.858611 -77.00507)
			(xy 221.835969 -77.054647) (xy 221.806503 -77.100497) (xy 221.770812 -77.141688) (xy 221.729621 -77.177379)
			(xy 221.683771 -77.206845) (xy 221.634194 -77.229487) (xy 221.581899 -77.244842) (xy 221.527951 -77.252598)
			(xy 221.473449 -77.252598) (xy 221.419501 -77.244842) (xy 221.367206 -77.229487) (xy 221.317629 -77.206845)
			(xy 221.271779 -77.177379) (xy 221.230588 -77.141688) (xy 221.194897 -77.100497) (xy 221.165431 -77.054647)
			(xy 221.142789 -77.00507) (xy 221.127434 -76.952775) (xy 221.119678 -76.898827) (xy 221.119192 -76.871576)
			(xy 219.247212 -76.871576) (xy 218.555316 -77.563472) (xy 220.578678 -77.563472) (xy 220.582749 -77.50785)
			(xy 220.594875 -77.453413) (xy 220.614798 -77.401322) (xy 220.642094 -77.352687) (xy 220.67618 -77.308544)
			(xy 220.716329 -77.269835) (xy 220.761687 -77.237384) (xy 220.811287 -77.211883) (xy 220.864071 -77.193876)
			(xy 220.918914 -77.183746) (xy 220.974648 -77.181709) (xy 221.030085 -77.187809) (xy 221.084042 -77.201915)
			(xy 221.135371 -77.223727) (xy 221.182977 -77.252781) (xy 221.225845 -77.288456) (xy 221.263062 -77.329993)
			(xy 221.293835 -77.376506) (xy 221.317507 -77.427003) (xy 221.333575 -77.48041) (xy 221.341695 -77.535586)
			(xy 221.342204 -77.563472) (xy 222.62465 -77.563472) (xy 222.625214 -77.534544) (xy 222.633953 -77.477352)
			(xy 222.651228 -77.422136) (xy 222.676641 -77.37016) (xy 222.709611 -77.322618) (xy 222.749381 -77.280599)
			(xy 222.79504 -77.245066) (xy 222.84554 -77.216834) (xy 222.899723 -77.196551) (xy 222.927926 -77.190092)
			(xy 222.942126 -77.186685) (xy 222.967846 -77.172874) (xy 222.988617 -77.152358) (xy 223.002745 -77.126811)
			(xy 223.009079 -77.098312) (xy 223.007103 -77.069185) (xy 222.996978 -77.041803) (xy 222.988632 -77.029818)
			(xy 222.970842 -77.004942) (xy 222.942568 -76.950716) (xy 222.923305 -76.892674) (xy 222.913547 -76.832303)
			(xy 222.91294 -76.801726) (xy 222.913426 -76.774475) (xy 222.921182 -76.720527) (xy 222.936537 -76.668232)
			(xy 222.959179 -76.618655) (xy 222.988645 -76.572805) (xy 223.024336 -76.531614) (xy 223.065527 -76.495923)
			(xy 223.111377 -76.466457) (xy 223.160954 -76.443815) (xy 223.213249 -76.42846) (xy 223.267197 -76.420704)
			(xy 223.321699 -76.420704) (xy 223.375647 -76.42846) (xy 223.427942 -76.443815) (xy 223.477519 -76.466457)
			(xy 223.523369 -76.495923) (xy 223.56456 -76.531614) (xy 223.600251 -76.572805) (xy 223.629717 -76.618655)
			(xy 223.652359 -76.668232) (xy 223.667714 -76.720527) (xy 223.67547 -76.774475) (xy 223.675956 -76.801726)
			(xy 223.675386 -76.830654) (xy 223.666647 -76.887845) (xy 223.649373 -76.943061) (xy 223.62396 -76.995036)
			(xy 223.590991 -77.042578) (xy 223.551222 -77.084598) (xy 223.505564 -77.120131) (xy 223.455065 -77.148363)
			(xy 223.400882 -77.168647) (xy 223.37268 -77.175106) (xy 223.358481 -77.178519) (xy 223.332761 -77.192328)
			(xy 223.31199 -77.212843) (xy 223.297862 -77.238389) (xy 223.291528 -77.266887) (xy 223.293503 -77.296014)
			(xy 223.303628 -77.323395) (xy 223.311974 -77.33538) (xy 223.329764 -77.360257) (xy 223.358038 -77.414483)
			(xy 223.377301 -77.472524) (xy 223.387059 -77.532895) (xy 223.387666 -77.563472) (xy 223.38718 -77.590723)
			(xy 223.379424 -77.644671) (xy 223.364069 -77.696966) (xy 223.341427 -77.746543) (xy 223.311961 -77.792393)
			(xy 223.27627 -77.833584) (xy 223.235079 -77.869275) (xy 223.189229 -77.898741) (xy 223.139652 -77.921383)
			(xy 223.087357 -77.936738) (xy 223.033409 -77.944494) (xy 222.978907 -77.944494) (xy 222.924959 -77.936738)
			(xy 222.872664 -77.921383) (xy 222.823087 -77.898741) (xy 222.777237 -77.869275) (xy 222.736046 -77.833584)
			(xy 222.700355 -77.792393) (xy 222.670889 -77.746543) (xy 222.648247 -77.696966) (xy 222.632892 -77.644671)
			(xy 222.625136 -77.590723) (xy 222.62465 -77.563472) (xy 221.342204 -77.563472) (xy 221.341695 -77.591358)
			(xy 221.333575 -77.646534) (xy 221.317507 -77.699941) (xy 221.293835 -77.750438) (xy 221.263062 -77.796951)
			(xy 221.225845 -77.838488) (xy 221.182977 -77.874163) (xy 221.135371 -77.903217) (xy 221.084042 -77.925029)
			(xy 221.030085 -77.939135) (xy 220.974648 -77.945235) (xy 220.918914 -77.943198) (xy 220.864071 -77.933068)
			(xy 220.811287 -77.915061) (xy 220.761687 -77.88956) (xy 220.716329 -77.857109) (xy 220.67618 -77.8184)
			(xy 220.642094 -77.774257) (xy 220.614798 -77.725622) (xy 220.594875 -77.673531) (xy 220.582749 -77.619094)
			(xy 220.578678 -77.563472) (xy 218.555316 -77.563472) (xy 217.539316 -78.579472) (xy 218.929202 -78.579472)
			(xy 218.933273 -78.52385) (xy 218.945399 -78.469413) (xy 218.965322 -78.417322) (xy 218.992618 -78.368687)
			(xy 219.026704 -78.324544) (xy 219.066853 -78.285835) (xy 219.112211 -78.253384) (xy 219.161811 -78.227883)
			(xy 219.214595 -78.209876) (xy 219.269438 -78.199746) (xy 219.325172 -78.197709) (xy 219.380609 -78.203809)
			(xy 219.434566 -78.217915) (xy 219.485895 -78.239727) (xy 219.533501 -78.268781) (xy 219.576369 -78.304456)
			(xy 219.613586 -78.345993) (xy 219.644359 -78.392506) (xy 219.668031 -78.443003) (xy 219.684099 -78.49641)
			(xy 219.692219 -78.551586) (xy 219.692728 -78.579472) (xy 222.62414 -78.579472) (xy 222.628211 -78.52385)
			(xy 222.640337 -78.469413) (xy 222.66026 -78.417322) (xy 222.687556 -78.368687) (xy 222.721642 -78.324544)
			(xy 222.761791 -78.285835) (xy 222.807149 -78.253384) (xy 222.856749 -78.227883) (xy 222.909533 -78.209876)
			(xy 222.964376 -78.199746) (xy 223.02011 -78.197709) (xy 223.075547 -78.203809) (xy 223.129504 -78.217915)
			(xy 223.180833 -78.239727) (xy 223.228439 -78.268781) (xy 223.271307 -78.304456) (xy 223.308524 -78.345993)
			(xy 223.339297 -78.392506) (xy 223.362969 -78.443003) (xy 223.379037 -78.49641) (xy 223.387157 -78.551586)
			(xy 223.387666 -78.579472) (xy 223.387157 -78.607358) (xy 223.379037 -78.662534) (xy 223.362969 -78.715941)
			(xy 223.339297 -78.766438) (xy 223.308524 -78.812951) (xy 223.271307 -78.854488) (xy 223.228439 -78.890163)
			(xy 223.180833 -78.919217) (xy 223.129504 -78.941029) (xy 223.075547 -78.955135) (xy 223.02011 -78.961235)
			(xy 222.964376 -78.959198) (xy 222.909533 -78.949068) (xy 222.856749 -78.931061) (xy 222.807149 -78.90556)
			(xy 222.761791 -78.873109) (xy 222.721642 -78.8344) (xy 222.687556 -78.790257) (xy 222.66026 -78.741622)
			(xy 222.640337 -78.689531) (xy 222.628211 -78.635094) (xy 222.62414 -78.579472) (xy 219.692728 -78.579472)
			(xy 219.692219 -78.607358) (xy 219.684099 -78.662534) (xy 219.668031 -78.715941) (xy 219.644359 -78.766438)
			(xy 219.613586 -78.812951) (xy 219.576369 -78.854488) (xy 219.533501 -78.890163) (xy 219.485895 -78.919217)
			(xy 219.434566 -78.941029) (xy 219.380609 -78.955135) (xy 219.325172 -78.961235) (xy 219.269438 -78.959198)
			(xy 219.214595 -78.949068) (xy 219.161811 -78.931061) (xy 219.112211 -78.90556) (xy 219.066853 -78.873109)
			(xy 219.026704 -78.8344) (xy 218.992618 -78.790257) (xy 218.965322 -78.741622) (xy 218.945399 -78.689531)
			(xy 218.933273 -78.635094) (xy 218.929202 -78.579472) (xy 217.539316 -78.579472) (xy 216.523316 -79.595472)
			(xy 220.578678 -79.595472) (xy 220.582749 -79.53985) (xy 220.594875 -79.485413) (xy 220.614798 -79.433322)
			(xy 220.642094 -79.384687) (xy 220.67618 -79.340544) (xy 220.716329 -79.301835) (xy 220.761687 -79.269384)
			(xy 220.811287 -79.243883) (xy 220.864071 -79.225876) (xy 220.918914 -79.215746) (xy 220.974648 -79.213709)
			(xy 221.030085 -79.219809) (xy 221.084042 -79.233915) (xy 221.135371 -79.255727) (xy 221.182977 -79.284781)
			(xy 221.225845 -79.320456) (xy 221.263062 -79.361993) (xy 221.293835 -79.408506) (xy 221.317507 -79.459003)
			(xy 221.333575 -79.51241) (xy 221.341695 -79.567586) (xy 221.342204 -79.595472) (xy 222.62414 -79.595472)
			(xy 222.628211 -79.53985) (xy 222.640337 -79.485413) (xy 222.66026 -79.433322) (xy 222.687556 -79.384687)
			(xy 222.721642 -79.340544) (xy 222.761791 -79.301835) (xy 222.807149 -79.269384) (xy 222.856749 -79.243883)
			(xy 222.909533 -79.225876) (xy 222.964376 -79.215746) (xy 223.02011 -79.213709) (xy 223.075547 -79.219809)
			(xy 223.129504 -79.233915) (xy 223.180833 -79.255727) (xy 223.228439 -79.284781) (xy 223.271307 -79.320456)
			(xy 223.308524 -79.361993) (xy 223.339297 -79.408506) (xy 223.362969 -79.459003) (xy 223.379037 -79.51241)
			(xy 223.387157 -79.567586) (xy 223.387666 -79.595472) (xy 223.387157 -79.623358) (xy 223.379037 -79.678534)
			(xy 223.362969 -79.731941) (xy 223.339297 -79.782438) (xy 223.308524 -79.828951) (xy 223.271307 -79.870488)
			(xy 223.228439 -79.906163) (xy 223.180833 -79.935217) (xy 223.129504 -79.957029) (xy 223.075547 -79.971135)
			(xy 223.02011 -79.977235) (xy 222.964376 -79.975198) (xy 222.909533 -79.965068) (xy 222.856749 -79.947061)
			(xy 222.807149 -79.92156) (xy 222.761791 -79.889109) (xy 222.721642 -79.8504) (xy 222.687556 -79.806257)
			(xy 222.66026 -79.757622) (xy 222.640337 -79.705531) (xy 222.628211 -79.651094) (xy 222.62414 -79.595472)
			(xy 221.342204 -79.595472) (xy 221.341695 -79.623358) (xy 221.333575 -79.678534) (xy 221.317507 -79.731941)
			(xy 221.293835 -79.782438) (xy 221.263062 -79.828951) (xy 221.225845 -79.870488) (xy 221.182977 -79.906163)
			(xy 221.135371 -79.935217) (xy 221.084042 -79.957029) (xy 221.030085 -79.971135) (xy 220.974648 -79.977235)
			(xy 220.918914 -79.975198) (xy 220.864071 -79.965068) (xy 220.811287 -79.947061) (xy 220.761687 -79.92156)
			(xy 220.716329 -79.889109) (xy 220.67618 -79.8504) (xy 220.642094 -79.806257) (xy 220.614798 -79.757622)
			(xy 220.594875 -79.705531) (xy 220.582749 -79.651094) (xy 220.578678 -79.595472) (xy 216.523316 -79.595472)
			(xy 215.608408 -80.51038) (xy 218.929202 -80.51038) (xy 218.933273 -80.454758) (xy 218.945399 -80.400321)
			(xy 218.965322 -80.34823) (xy 218.992618 -80.299595) (xy 219.026704 -80.255452) (xy 219.066853 -80.216743)
			(xy 219.112211 -80.184292) (xy 219.161811 -80.158791) (xy 219.214595 -80.140784) (xy 219.269438 -80.130654)
			(xy 219.325172 -80.128617) (xy 219.380609 -80.134717) (xy 219.434566 -80.148823) (xy 219.485895 -80.170635)
			(xy 219.533501 -80.199689) (xy 219.576369 -80.235364) (xy 219.613586 -80.276901) (xy 219.644359 -80.323414)
			(xy 219.668031 -80.373911) (xy 219.684099 -80.427318) (xy 219.692219 -80.482494) (xy 219.692728 -80.51038)
			(xy 219.692219 -80.538266) (xy 219.684099 -80.593442) (xy 219.678675 -80.611472) (xy 222.62414 -80.611472)
			(xy 222.628211 -80.55585) (xy 222.640337 -80.501413) (xy 222.66026 -80.449322) (xy 222.687556 -80.400687)
			(xy 222.721642 -80.356544) (xy 222.761791 -80.317835) (xy 222.807149 -80.285384) (xy 222.856749 -80.259883)
			(xy 222.909533 -80.241876) (xy 222.964376 -80.231746) (xy 223.02011 -80.229709) (xy 223.075547 -80.235809)
			(xy 223.129504 -80.249915) (xy 223.180833 -80.271727) (xy 223.228439 -80.300781) (xy 223.271307 -80.336456)
			(xy 223.308524 -80.377993) (xy 223.339297 -80.424506) (xy 223.362969 -80.475003) (xy 223.379037 -80.52841)
			(xy 223.387157 -80.583586) (xy 223.387666 -80.611472) (xy 223.387157 -80.639358) (xy 223.379037 -80.694534)
			(xy 223.362969 -80.747941) (xy 223.339297 -80.798438) (xy 223.308524 -80.844951) (xy 223.271307 -80.886488)
			(xy 223.228439 -80.922163) (xy 223.180833 -80.951217) (xy 223.129504 -80.973029) (xy 223.075547 -80.987135)
			(xy 223.02011 -80.993235) (xy 222.964376 -80.991198) (xy 222.909533 -80.981068) (xy 222.856749 -80.963061)
			(xy 222.807149 -80.93756) (xy 222.761791 -80.905109) (xy 222.721642 -80.8664) (xy 222.687556 -80.822257)
			(xy 222.66026 -80.773622) (xy 222.640337 -80.721531) (xy 222.628211 -80.667094) (xy 222.62414 -80.611472)
			(xy 219.678675 -80.611472) (xy 219.668031 -80.646849) (xy 219.644359 -80.697346) (xy 219.613586 -80.743859)
			(xy 219.576369 -80.785396) (xy 219.533501 -80.821071) (xy 219.485895 -80.850125) (xy 219.434566 -80.871937)
			(xy 219.380609 -80.886043) (xy 219.325172 -80.892143) (xy 219.269438 -80.890106) (xy 219.214595 -80.879976)
			(xy 219.161811 -80.861969) (xy 219.112211 -80.836468) (xy 219.066853 -80.804017) (xy 219.026704 -80.765308)
			(xy 218.992618 -80.721165) (xy 218.965322 -80.67253) (xy 218.945399 -80.620439) (xy 218.933273 -80.566002)
			(xy 218.929202 -80.51038) (xy 215.608408 -80.51038) (xy 215.51265 -80.606138) (xy 215.50584 -80.613483)
			(xy 215.498114 -80.631946) (xy 215.497664 -80.641952) (xy 215.497664 -81.627472) (xy 220.578678 -81.627472)
			(xy 220.582749 -81.57185) (xy 220.594875 -81.517413) (xy 220.614798 -81.465322) (xy 220.642094 -81.416687)
			(xy 220.67618 -81.372544) (xy 220.716329 -81.333835) (xy 220.761687 -81.301384) (xy 220.811287 -81.275883)
			(xy 220.864071 -81.257876) (xy 220.918914 -81.247746) (xy 220.974648 -81.245709) (xy 221.030085 -81.251809)
			(xy 221.084042 -81.265915) (xy 221.135371 -81.287727) (xy 221.182977 -81.316781) (xy 221.225845 -81.352456)
			(xy 221.263062 -81.393993) (xy 221.293835 -81.440506) (xy 221.317507 -81.491003) (xy 221.333575 -81.54441)
			(xy 221.341695 -81.599586) (xy 221.342204 -81.627472) (xy 222.62414 -81.627472) (xy 222.628211 -81.57185)
			(xy 222.640337 -81.517413) (xy 222.66026 -81.465322) (xy 222.687556 -81.416687) (xy 222.721642 -81.372544)
			(xy 222.761791 -81.333835) (xy 222.807149 -81.301384) (xy 222.856749 -81.275883) (xy 222.909533 -81.257876)
			(xy 222.964376 -81.247746) (xy 223.02011 -81.245709) (xy 223.075547 -81.251809) (xy 223.129504 -81.265915)
			(xy 223.180833 -81.287727) (xy 223.228439 -81.316781) (xy 223.271307 -81.352456) (xy 223.308524 -81.393993)
			(xy 223.339297 -81.440506) (xy 223.362969 -81.491003) (xy 223.379037 -81.54441) (xy 223.387157 -81.599586)
			(xy 223.387666 -81.627472) (xy 223.387157 -81.655358) (xy 223.379037 -81.710534) (xy 223.362969 -81.763941)
			(xy 223.339297 -81.814438) (xy 223.308524 -81.860951) (xy 223.271307 -81.902488) (xy 223.228439 -81.938163)
			(xy 223.180833 -81.967217) (xy 223.129504 -81.989029) (xy 223.075547 -82.003135) (xy 223.02011 -82.009235)
			(xy 222.964376 -82.007198) (xy 222.909533 -81.997068) (xy 222.856749 -81.979061) (xy 222.807149 -81.95356)
			(xy 222.761791 -81.921109) (xy 222.721642 -81.8824) (xy 222.687556 -81.838257) (xy 222.66026 -81.789622)
			(xy 222.640337 -81.737531) (xy 222.628211 -81.683094) (xy 222.62414 -81.627472) (xy 221.342204 -81.627472)
			(xy 221.341695 -81.655358) (xy 221.333575 -81.710534) (xy 221.317507 -81.763941) (xy 221.293835 -81.814438)
			(xy 221.263062 -81.860951) (xy 221.225845 -81.902488) (xy 221.182977 -81.938163) (xy 221.135371 -81.967217)
			(xy 221.084042 -81.989029) (xy 221.030085 -82.003135) (xy 220.974648 -82.009235) (xy 220.918914 -82.007198)
			(xy 220.864071 -81.997068) (xy 220.811287 -81.979061) (xy 220.761687 -81.95356) (xy 220.716329 -81.921109)
			(xy 220.67618 -81.8824) (xy 220.642094 -81.838257) (xy 220.614798 -81.789622) (xy 220.594875 -81.737531)
			(xy 220.582749 -81.683094) (xy 220.578678 -81.627472) (xy 215.497664 -81.627472) (xy 215.497664 -82.42427)
			(xy 218.848938 -82.42427) (xy 218.853009 -82.368648) (xy 218.865135 -82.314211) (xy 218.885058 -82.26212)
			(xy 218.912354 -82.213485) (xy 218.94644 -82.169342) (xy 218.986589 -82.130633) (xy 219.031947 -82.098182)
			(xy 219.081547 -82.072681) (xy 219.134331 -82.054674) (xy 219.189174 -82.044544) (xy 219.244908 -82.042507)
			(xy 219.300345 -82.048607) (xy 219.354302 -82.062713) (xy 219.405631 -82.084525) (xy 219.453237 -82.113579)
			(xy 219.496105 -82.149254) (xy 219.533322 -82.190791) (xy 219.564095 -82.237304) (xy 219.587767 -82.287801)
			(xy 219.603835 -82.341208) (xy 219.611955 -82.396384) (xy 219.612464 -82.42427) (xy 219.611955 -82.452156)
			(xy 219.603835 -82.507332) (xy 219.587767 -82.560739) (xy 219.564095 -82.611236) (xy 219.542768 -82.643472)
			(xy 222.62414 -82.643472) (xy 222.628211 -82.58785) (xy 222.640337 -82.533413) (xy 222.66026 -82.481322)
			(xy 222.687556 -82.432687) (xy 222.721642 -82.388544) (xy 222.761791 -82.349835) (xy 222.807149 -82.317384)
			(xy 222.856749 -82.291883) (xy 222.909533 -82.273876) (xy 222.964376 -82.263746) (xy 223.02011 -82.261709)
			(xy 223.075547 -82.267809) (xy 223.129504 -82.281915) (xy 223.180833 -82.303727) (xy 223.228439 -82.332781)
			(xy 223.271307 -82.368456) (xy 223.308524 -82.409993) (xy 223.339297 -82.456506) (xy 223.362969 -82.507003)
			(xy 223.379037 -82.56041) (xy 223.387157 -82.615586) (xy 223.387666 -82.643472) (xy 223.387157 -82.671358)
			(xy 223.379037 -82.726534) (xy 223.362969 -82.779941) (xy 223.339297 -82.830438) (xy 223.308524 -82.876951)
			(xy 223.271307 -82.918488) (xy 223.228439 -82.954163) (xy 223.180833 -82.983217) (xy 223.129504 -83.005029)
			(xy 223.075547 -83.019135) (xy 223.02011 -83.025235) (xy 222.964376 -83.023198) (xy 222.909533 -83.013068)
			(xy 222.856749 -82.995061) (xy 222.807149 -82.96956) (xy 222.761791 -82.937109) (xy 222.721642 -82.8984)
			(xy 222.687556 -82.854257) (xy 222.66026 -82.805622) (xy 222.640337 -82.753531) (xy 222.628211 -82.699094)
			(xy 222.62414 -82.643472) (xy 219.542768 -82.643472) (xy 219.533322 -82.657749) (xy 219.496105 -82.699286)
			(xy 219.453237 -82.734961) (xy 219.405631 -82.764015) (xy 219.354302 -82.785827) (xy 219.300345 -82.799933)
			(xy 219.244908 -82.806033) (xy 219.189174 -82.803996) (xy 219.134331 -82.793866) (xy 219.081547 -82.775859)
			(xy 219.031947 -82.750358) (xy 218.986589 -82.717907) (xy 218.94644 -82.679198) (xy 218.912354 -82.635055)
			(xy 218.885058 -82.58642) (xy 218.865135 -82.534329) (xy 218.853009 -82.479892) (xy 218.848938 -82.42427)
			(xy 215.497664 -82.42427) (xy 215.497664 -83.85556) (xy 218.830142 -83.85556) (xy 218.834213 -83.799938)
			(xy 218.846339 -83.745501) (xy 218.866262 -83.69341) (xy 218.893558 -83.644775) (xy 218.927644 -83.600632)
			(xy 218.967793 -83.561923) (xy 219.013151 -83.529472) (xy 219.062751 -83.503971) (xy 219.115535 -83.485964)
			(xy 219.170378 -83.475834) (xy 219.226112 -83.473797) (xy 219.281549 -83.479897) (xy 219.335506 -83.494003)
			(xy 219.338765 -83.495388) (xy 220.578678 -83.495388) (xy 220.582749 -83.439766) (xy 220.594875 -83.385329)
			(xy 220.614798 -83.333238) (xy 220.642094 -83.284603) (xy 220.67618 -83.24046) (xy 220.716329 -83.201751)
			(xy 220.761687 -83.1693) (xy 220.811287 -83.143799) (xy 220.864071 -83.125792) (xy 220.918914 -83.115662)
			(xy 220.974648 -83.113625) (xy 221.030085 -83.119725) (xy 221.084042 -83.133831) (xy 221.135371 -83.155643)
			(xy 221.182977 -83.184697) (xy 221.225845 -83.220372) (xy 221.263062 -83.261909) (xy 221.293835 -83.308422)
			(xy 221.317507 -83.358919) (xy 221.333575 -83.412326) (xy 221.341695 -83.467502) (xy 221.342204 -83.495388)
			(xy 221.341695 -83.523274) (xy 221.333575 -83.57845) (xy 221.317507 -83.631857) (xy 221.304562 -83.659472)
			(xy 222.62414 -83.659472) (xy 222.628211 -83.60385) (xy 222.640337 -83.549413) (xy 222.66026 -83.497322)
			(xy 222.687556 -83.448687) (xy 222.721642 -83.404544) (xy 222.761791 -83.365835) (xy 222.807149 -83.333384)
			(xy 222.856749 -83.307883) (xy 222.909533 -83.289876) (xy 222.964376 -83.279746) (xy 223.02011 -83.277709)
			(xy 223.075547 -83.283809) (xy 223.129504 -83.297915) (xy 223.180833 -83.319727) (xy 223.228439 -83.348781)
			(xy 223.271307 -83.384456) (xy 223.308524 -83.425993) (xy 223.339297 -83.472506) (xy 223.362969 -83.523003)
			(xy 223.379037 -83.57641) (xy 223.387157 -83.631586) (xy 223.387666 -83.659472) (xy 223.387157 -83.687358)
			(xy 223.379037 -83.742534) (xy 223.362969 -83.795941) (xy 223.339297 -83.846438) (xy 223.308524 -83.892951)
			(xy 223.271307 -83.934488) (xy 223.228439 -83.970163) (xy 223.180833 -83.999217) (xy 223.129504 -84.021029)
			(xy 223.075547 -84.035135) (xy 223.02011 -84.041235) (xy 222.964376 -84.039198) (xy 222.909533 -84.029068)
			(xy 222.856749 -84.011061) (xy 222.807149 -83.98556) (xy 222.761791 -83.953109) (xy 222.721642 -83.9144)
			(xy 222.687556 -83.870257) (xy 222.66026 -83.821622) (xy 222.640337 -83.769531) (xy 222.628211 -83.715094)
			(xy 222.62414 -83.659472) (xy 221.304562 -83.659472) (xy 221.293835 -83.682354) (xy 221.263062 -83.728867)
			(xy 221.225845 -83.770404) (xy 221.182977 -83.806079) (xy 221.135371 -83.835133) (xy 221.084042 -83.856945)
			(xy 221.030085 -83.871051) (xy 220.974648 -83.877151) (xy 220.918914 -83.875114) (xy 220.864071 -83.864984)
			(xy 220.811287 -83.846977) (xy 220.761687 -83.821476) (xy 220.716329 -83.789025) (xy 220.67618 -83.750316)
			(xy 220.642094 -83.706173) (xy 220.614798 -83.657538) (xy 220.594875 -83.605447) (xy 220.582749 -83.55101)
			(xy 220.578678 -83.495388) (xy 219.338765 -83.495388) (xy 219.386835 -83.515815) (xy 219.434441 -83.544869)
			(xy 219.477309 -83.580544) (xy 219.514526 -83.622081) (xy 219.545299 -83.668594) (xy 219.568971 -83.719091)
			(xy 219.585039 -83.772498) (xy 219.593159 -83.827674) (xy 219.593668 -83.85556) (xy 219.593159 -83.883446)
			(xy 219.585039 -83.938622) (xy 219.568971 -83.992029) (xy 219.545299 -84.042526) (xy 219.514526 -84.089039)
			(xy 219.477309 -84.130576) (xy 219.434441 -84.166251) (xy 219.386835 -84.195305) (xy 219.335506 -84.217117)
			(xy 219.281549 -84.231223) (xy 219.226112 -84.237323) (xy 219.170378 -84.235286) (xy 219.115535 -84.225156)
			(xy 219.062751 -84.207149) (xy 219.013151 -84.181648) (xy 218.967793 -84.149197) (xy 218.927644 -84.110488)
			(xy 218.893558 -84.066345) (xy 218.866262 -84.01771) (xy 218.846339 -83.965619) (xy 218.834213 -83.911182)
			(xy 218.830142 -83.85556) (xy 215.497664 -83.85556) (xy 215.497664 -84.765388) (xy 220.578678 -84.765388)
			(xy 220.582749 -84.709766) (xy 220.594875 -84.655329) (xy 220.614798 -84.603238) (xy 220.642094 -84.554603)
			(xy 220.67618 -84.51046) (xy 220.716329 -84.471751) (xy 220.761687 -84.4393) (xy 220.811287 -84.413799)
			(xy 220.864071 -84.395792) (xy 220.918914 -84.385662) (xy 220.974648 -84.383625) (xy 221.030085 -84.389725)
			(xy 221.084042 -84.403831) (xy 221.135371 -84.425643) (xy 221.182977 -84.454697) (xy 221.225845 -84.490372)
			(xy 221.263062 -84.531909) (xy 221.293835 -84.578422) (xy 221.317507 -84.628919) (xy 221.331513 -84.675472)
			(xy 222.62414 -84.675472) (xy 222.628211 -84.61985) (xy 222.640337 -84.565413) (xy 222.66026 -84.513322)
			(xy 222.687556 -84.464687) (xy 222.721642 -84.420544) (xy 222.761791 -84.381835) (xy 222.807149 -84.349384)
			(xy 222.856749 -84.323883) (xy 222.909533 -84.305876) (xy 222.964376 -84.295746) (xy 223.02011 -84.293709)
			(xy 223.075547 -84.299809) (xy 223.129504 -84.313915) (xy 223.180833 -84.335727) (xy 223.228439 -84.364781)
			(xy 223.271307 -84.400456) (xy 223.308524 -84.441993) (xy 223.339297 -84.488506) (xy 223.362969 -84.539003)
			(xy 223.379037 -84.59241) (xy 223.387157 -84.647586) (xy 223.387666 -84.675472) (xy 223.387157 -84.703358)
			(xy 223.379037 -84.758534) (xy 223.362969 -84.811941) (xy 223.339297 -84.862438) (xy 223.308524 -84.908951)
			(xy 223.271307 -84.950488) (xy 223.228439 -84.986163) (xy 223.180833 -85.015217) (xy 223.129504 -85.037029)
			(xy 223.075547 -85.051135) (xy 223.02011 -85.057235) (xy 222.964376 -85.055198) (xy 222.909533 -85.045068)
			(xy 222.856749 -85.027061) (xy 222.807149 -85.00156) (xy 222.761791 -84.969109) (xy 222.721642 -84.9304)
			(xy 222.687556 -84.886257) (xy 222.66026 -84.837622) (xy 222.640337 -84.785531) (xy 222.628211 -84.731094)
			(xy 222.62414 -84.675472) (xy 221.331513 -84.675472) (xy 221.333575 -84.682326) (xy 221.341695 -84.737502)
			(xy 221.342204 -84.765388) (xy 221.341695 -84.793274) (xy 221.333575 -84.84845) (xy 221.317507 -84.901857)
			(xy 221.293835 -84.952354) (xy 221.263062 -84.998867) (xy 221.225845 -85.040404) (xy 221.182977 -85.076079)
			(xy 221.135371 -85.105133) (xy 221.084042 -85.126945) (xy 221.030085 -85.141051) (xy 220.974648 -85.147151)
			(xy 220.918914 -85.145114) (xy 220.864071 -85.134984) (xy 220.811287 -85.116977) (xy 220.761687 -85.091476)
			(xy 220.716329 -85.059025) (xy 220.67618 -85.020316) (xy 220.642094 -84.976173) (xy 220.614798 -84.927538)
			(xy 220.594875 -84.875447) (xy 220.582749 -84.82101) (xy 220.578678 -84.765388) (xy 215.497664 -84.765388)
			(xy 215.497664 -87.123524) (xy 218.507562 -87.123524) (xy 218.511633 -87.067902) (xy 218.523759 -87.013465)
			(xy 218.543682 -86.961374) (xy 218.570978 -86.912739) (xy 218.605064 -86.868596) (xy 218.645213 -86.829887)
			(xy 218.690571 -86.797436) (xy 218.740171 -86.771935) (xy 218.792955 -86.753928) (xy 218.847798 -86.743798)
			(xy 218.903532 -86.741761) (xy 218.958969 -86.747861) (xy 219.012926 -86.761967) (xy 219.064255 -86.783779)
			(xy 219.111861 -86.812833) (xy 219.154729 -86.848508) (xy 219.191946 -86.890045) (xy 219.222719 -86.936558)
			(xy 219.246391 -86.987055) (xy 219.262459 -87.040462) (xy 219.266646 -87.068914) (xy 220.702884 -87.068914)
			(xy 220.706955 -87.013292) (xy 220.719081 -86.958855) (xy 220.739004 -86.906764) (xy 220.7663 -86.858129)
			(xy 220.800386 -86.813986) (xy 220.840535 -86.775277) (xy 220.885893 -86.742826) (xy 220.935493 -86.717325)
			(xy 220.988277 -86.699318) (xy 221.04312 -86.689188) (xy 221.098854 -86.687151) (xy 221.154291 -86.693251)
			(xy 221.208248 -86.707357) (xy 221.259577 -86.729169) (xy 221.307183 -86.758223) (xy 221.350051 -86.793898)
			(xy 221.387268 -86.835435) (xy 221.418041 -86.881948) (xy 221.441713 -86.932445) (xy 221.457781 -86.985852)
			(xy 221.465901 -87.041028) (xy 221.46641 -87.068914) (xy 221.465901 -87.0968) (xy 221.457781 -87.151976)
			(xy 221.441713 -87.205383) (xy 221.418041 -87.25588) (xy 221.387268 -87.302393) (xy 221.350051 -87.34393)
			(xy 221.307183 -87.379605) (xy 221.259577 -87.408659) (xy 221.208248 -87.430471) (xy 221.154291 -87.444577)
			(xy 221.098854 -87.450677) (xy 221.04312 -87.44864) (xy 220.988277 -87.43851) (xy 220.935493 -87.420503)
			(xy 220.885893 -87.395002) (xy 220.840535 -87.362551) (xy 220.800386 -87.323842) (xy 220.7663 -87.279699)
			(xy 220.739004 -87.231064) (xy 220.719081 -87.178973) (xy 220.706955 -87.124536) (xy 220.702884 -87.068914)
			(xy 219.266646 -87.068914) (xy 219.270579 -87.095638) (xy 219.271088 -87.123524) (xy 219.270579 -87.15141)
			(xy 219.262459 -87.206586) (xy 219.246391 -87.259993) (xy 219.222719 -87.31049) (xy 219.191946 -87.357003)
			(xy 219.154729 -87.39854) (xy 219.111861 -87.434215) (xy 219.064255 -87.463269) (xy 219.012926 -87.485081)
			(xy 218.958969 -87.499187) (xy 218.903532 -87.505287) (xy 218.847798 -87.50325) (xy 218.792955 -87.49312)
			(xy 218.740171 -87.475113) (xy 218.690571 -87.449612) (xy 218.645213 -87.417161) (xy 218.605064 -87.378452)
			(xy 218.570978 -87.334309) (xy 218.543682 -87.285674) (xy 218.523759 -87.233583) (xy 218.511633 -87.179146)
			(xy 218.507562 -87.123524) (xy 215.497664 -87.123524) (xy 215.497664 -87.1347) (xy 215.497237 -87.167574)
			(xy 215.489905 -87.232912) (xy 215.475302 -87.297018) (xy 215.453609 -87.359084) (xy 215.425101 -87.41833)
			(xy 215.390136 -87.47401) (xy 215.349154 -87.525423) (xy 215.326214 -87.548974) (xy 215.150446 -87.724742)
			(xy 215.143601 -87.732141) (xy 215.135875 -87.750739) (xy 215.13546 -87.76081) (xy 215.13546 -88.37168)
			(xy 215.14308 -88.390222) (xy 215.148922 -88.396064) (xy 215.156293 -88.402807) (xy 215.174754 -88.410397)
			(xy 215.184736 -88.410796)
		)
		(stroke
			(width 0)
			(type solid)
		)
		(fill yes)
		(layer "In7.Cu")
		(net "GND")
	)
	(gr_poly
		(pts
			(xy 191.77762 -197.8533) (xy 191.787497 -197.85284) (xy 191.805795 -197.845396) (xy 191.81318 -197.838822)
			(xy 191.813434 -197.838568) (xy 191.839596 -197.812406) (xy 191.846994 -197.805558) (xy 191.865592 -197.797821)
			(xy 191.875664 -197.79742) (xy 198.080884 -197.79742) (xy 198.090756 -197.796949) (xy 198.10904 -197.789491)
			(xy 198.116444 -197.782942) (xy 198.116698 -197.782688) (xy 198.69658 -197.202552) (xy 198.703421 -197.195152)
			(xy 198.711141 -197.176554) (xy 198.711566 -197.166484) (xy 198.711566 -191.588644) (xy 198.712001 -191.57858)
			(xy 198.719737 -191.559996) (xy 198.726552 -191.552576) (xy 202.782678 -187.49645) (xy 202.783186 -187.495942)
			(xy 202.789764 -187.488559) (xy 202.797207 -187.47026) (xy 202.797664 -187.460382) (xy 202.797664 -168.215818)
			(xy 202.798104 -168.205756) (xy 202.805846 -168.187179) (xy 202.81265 -168.17975) (xy 207.415638 -163.576762)
			(xy 207.416146 -163.576254) (xy 207.42273 -163.568874) (xy 207.430184 -163.550574) (xy 207.430624 -163.540694)
			(xy 207.430624 -131.558538) (xy 207.423004 -131.539742) (xy 207.415638 -131.53263) (xy 202.172062 -126.289308)
			(xy 202.149568 -126.266167) (xy 202.109336 -126.215702) (xy 202.075006 -126.161051) (xy 202.047011 -126.102899)
			(xy 202.025702 -126.04198) (xy 202.011347 -125.979057) (xy 202.004127 -125.914924) (xy 202.00366 -125.882654)
			(xy 202.00366 -119.310404) (xy 202.003236 -119.300334) (xy 201.995519 -119.281733) (xy 201.988674 -119.274336)
			(xy 200.221342 -117.507258) (xy 200.198846 -117.484117) (xy 200.158611 -117.433653) (xy 200.124278 -117.379002)
			(xy 200.096279 -117.320851) (xy 200.074966 -117.259932) (xy 200.060606 -117.197009) (xy 200.053381 -117.132874)
			(xy 200.05294 -117.100604) (xy 200.05294 -113.923826) (xy 200.053411 -113.891559) (xy 200.060665 -113.827435)
			(xy 200.07504 -113.764522) (xy 200.096357 -113.703611) (xy 200.124347 -113.645463) (xy 200.158661 -113.590808)
			(xy 200.198869 -113.540331) (xy 200.221342 -113.517172) (xy 201.239374 -112.499394) (xy 201.243209 -112.495364)
			(xy 201.24923 -112.486011) (xy 201.251312 -112.480852) (xy 201.25436 -112.47247) (xy 201.25436 -105.74274)
			(xy 201.253925 -105.732676) (xy 201.24619 -105.714091) (xy 201.239374 -105.706672) (xy 199.679052 -104.14635)
			(xy 199.669146 -104.137714) (xy 199.668892 -104.13746) (xy 199.661842 -104.132533) (xy 199.645483 -104.127252)
			(xy 199.628297 -104.127662) (xy 199.620124 -104.130348) (xy 199.607932 -104.13492) (xy 199.591168 -104.154986)
			(xy 199.486012 -104.683814) (xy 199.496934 -104.7115) (xy 199.509126 -104.720136) (xy 199.529661 -104.735603)
			(xy 199.566792 -104.771159) (xy 199.598821 -104.811372) (xy 199.62517 -104.855516) (xy 199.645363 -104.902794)
			(xy 199.659035 -104.952352) (xy 199.665941 -105.003295) (xy 199.666352 -105.029) (xy 199.66588 -105.05637)
			(xy 199.658055 -105.110547) (xy 199.642567 -105.16305) (xy 199.619732 -105.212799) (xy 199.590021 -105.258774)
			(xy 199.572372 -105.279698) (xy 199.566276 -105.28681) (xy 199.559926 -105.303828) (xy 199.559926 -105.389172)
			(xy 199.566276 -105.40619) (xy 199.572372 -105.413302) (xy 199.590015 -105.434233) (xy 199.619743 -105.480199)
			(xy 199.642588 -105.529945) (xy 199.658079 -105.582449) (xy 199.665898 -105.636629) (xy 199.666352 -105.664)
			(xy 199.665866 -105.691252) (xy 199.65811 -105.745202) (xy 199.642755 -105.7975) (xy 199.620115 -105.84708)
			(xy 199.590649 -105.892933) (xy 199.554958 -105.934127) (xy 199.513769 -105.969823) (xy 199.467918 -105.999294)
			(xy 199.418341 -106.02194) (xy 199.366046 -106.037301) (xy 199.312096 -106.045063) (xy 199.284844 -106.045508)
			(xy 199.260968 -106.044746) (xy 199.241664 -106.043476) (xy 199.211692 -106.06659) (xy 198.819382 -108.044234)
			(xy 198.958708 -108.044234) (xy 198.959194 -108.016983) (xy 198.96695 -107.963035) (xy 198.982305 -107.91074)
			(xy 199.004947 -107.861163) (xy 199.034413 -107.815313) (xy 199.070104 -107.774122) (xy 199.111295 -107.738431)
			(xy 199.157145 -107.708965) (xy 199.206722 -107.686323) (xy 199.259017 -107.670968) (xy 199.312965 -107.663212)
			(xy 199.367467 -107.663212) (xy 199.421415 -107.670968) (xy 199.47371 -107.686323) (xy 199.523287 -107.708965)
			(xy 199.569137 -107.738431) (xy 199.610328 -107.774122) (xy 199.646019 -107.815313) (xy 199.675485 -107.861163)
			(xy 199.698127 -107.91074) (xy 199.713482 -107.963035) (xy 199.721238 -108.016983) (xy 199.721724 -108.044234)
			(xy 199.721188 -108.071805) (xy 199.713246 -108.126373) (xy 199.697531 -108.17923) (xy 199.674372 -108.229273)
			(xy 199.644251 -108.275463) (xy 199.607794 -108.316835) (xy 199.565762 -108.352529) (xy 199.542654 -108.367576)
			(xy 199.530079 -108.376034) (xy 199.510215 -108.398904) (xy 199.497933 -108.426595) (xy 199.494314 -108.45667)
			(xy 199.499675 -108.486484) (xy 199.513547 -108.513414) (xy 199.534707 -108.53509) (xy 199.547734 -108.542836)
			(xy 199.573125 -108.557309) (xy 199.619559 -108.592795) (xy 199.660042 -108.634944) (xy 199.693626 -108.682772)
			(xy 199.719528 -108.73516) (xy 199.737142 -108.790884) (xy 199.746056 -108.848641) (xy 199.746616 -108.877862)
			(xy 199.74613 -108.905113) (xy 199.738374 -108.959061) (xy 199.723019 -109.011356) (xy 199.700377 -109.060933)
			(xy 199.670911 -109.106783) (xy 199.63522 -109.147974) (xy 199.594029 -109.183665) (xy 199.548179 -109.213131)
			(xy 199.498602 -109.235773) (xy 199.446307 -109.251128) (xy 199.392359 -109.258884) (xy 199.337857 -109.258884)
			(xy 199.283909 -109.251128) (xy 199.231614 -109.235773) (xy 199.182037 -109.213131) (xy 199.136187 -109.183665)
			(xy 199.094996 -109.147974) (xy 199.059305 -109.106783) (xy 199.029839 -109.060933) (xy 199.007197 -109.011356)
			(xy 198.991842 -108.959061) (xy 198.984086 -108.905113) (xy 198.9836 -108.877862) (xy 198.984122 -108.85029)
			(xy 198.992065 -108.795721) (xy 199.007781 -108.742864) (xy 199.030943 -108.692819) (xy 199.061066 -108.64663)
			(xy 199.097525 -108.605259) (xy 199.13956 -108.569566) (xy 199.16267 -108.55452) (xy 199.175246 -108.546064)
			(xy 199.195105 -108.523192) (xy 199.207383 -108.495502) (xy 199.211001 -108.465428) (xy 199.20564 -108.435615)
			(xy 199.191772 -108.408686) (xy 199.170615 -108.387008) (xy 199.15759 -108.37926) (xy 199.132203 -108.36478)
			(xy 199.085768 -108.329297) (xy 199.045284 -108.287149) (xy 199.011698 -108.239323) (xy 198.985795 -108.186935)
			(xy 198.968181 -108.131212) (xy 198.959268 -108.073455) (xy 198.958708 -108.044234) (xy 198.819382 -108.044234)
			(xy 198.029068 -112.028224) (xy 198.042276 -112.057688) (xy 198.056246 -112.065816) (xy 198.080339 -112.080653)
			(xy 198.124264 -112.116319) (xy 198.162439 -112.158081) (xy 198.194029 -112.205023) (xy 198.218341 -112.256114)
			(xy 198.234842 -112.310236) (xy 198.243169 -112.366201) (xy 198.243698 -112.394492) (xy 198.243234 -112.421768)
			(xy 198.235465 -112.475763) (xy 198.220084 -112.528101) (xy 198.197405 -112.577714) (xy 198.167891 -112.623592)
			(xy 198.132143 -112.664797) (xy 198.090891 -112.700491) (xy 198.044975 -112.729945) (xy 197.995332 -112.752559)
			(xy 197.942974 -112.767871) (xy 197.916038 -112.77219) (xy 197.900036 -112.774476) (xy 197.876414 -112.796574)
			(xy 197.064376 -116.890292) (xy 197.06336 -116.89969) (xy 197.04939 -118.095268) (xy 197.071234 -118.123208)
			(xy 197.088506 -118.127526) (xy 197.114809 -118.134402) (xy 197.165287 -118.154585) (xy 197.212392 -118.181726)
			(xy 197.255169 -118.215276) (xy 197.292755 -118.254554) (xy 197.308978 -118.27637) (xy 197.314707 -118.283715)
			(xy 197.33021 -118.294013) (xy 197.339204 -118.296436) (xy 197.36943 -118.303294) (xy 197.378708 -118.304934)
			(xy 197.397332 -118.30219) (xy 197.405752 -118.29796) (xy 197.431734 -118.283693) (xy 197.486595 -118.261247)
			(xy 197.543899 -118.246084) (xy 197.602682 -118.238459) (xy 197.63232 -118.238016) (xy 197.662288 -118.238486)
			(xy 197.72171 -118.246312) (xy 197.779602 -118.261827) (xy 197.834974 -118.284766) (xy 197.886878 -118.314736)
			(xy 197.934426 -118.351224) (xy 197.976805 -118.393607) (xy 198.013289 -118.441159) (xy 198.043254 -118.493066)
			(xy 198.066187 -118.54844) (xy 198.081696 -118.606333) (xy 198.089517 -118.665756) (xy 198.090028 -118.695724)
			(xy 198.090028 -119.559324) (xy 198.089536 -119.589291) (xy 198.081711 -119.648712) (xy 198.066197 -119.706604)
			(xy 198.043259 -119.761975) (xy 198.013291 -119.813879) (xy 197.976805 -119.861428) (xy 197.934425 -119.903807)
			(xy 197.886876 -119.940293) (xy 197.834972 -119.970261) (xy 197.7796 -119.993198) (xy 197.721708 -120.008712)
			(xy 197.662287 -120.016537) (xy 197.63232 -120.017032) (xy 197.602653 -120.016572) (xy 197.543814 -120.008934)
			(xy 197.486452 -119.993771) (xy 197.431524 -119.971334) (xy 197.405498 -119.957088) (xy 197.397135 -119.952695)
			(xy 197.378475 -119.94983) (xy 197.369176 -119.9515) (xy 197.33895 -119.958358) (xy 197.329962 -119.960801)
			(xy 197.314448 -119.971079) (xy 197.308724 -119.978424) (xy 197.291227 -120.002044) (xy 197.25017 -120.044109)
			(xy 197.203139 -120.079367) (xy 197.151249 -120.106982) (xy 197.095733 -120.126297) (xy 197.066916 -120.132094)
			(xy 197.048882 -120.135396) (xy 197.025514 -120.163082) (xy 197.011697 -121.365772) (xy 199.81672 -121.365772)
			(xy 199.81672 -120.502172) (xy 199.81721 -120.472204) (xy 199.825033 -120.412782) (xy 199.840546 -120.354889)
			(xy 199.863482 -120.299516) (xy 199.893449 -120.24761) (xy 199.929936 -120.20006) (xy 199.972316 -120.15768)
			(xy 200.019866 -120.121193) (xy 200.071772 -120.091226) (xy 200.127145 -120.06829) (xy 200.185038 -120.052777)
			(xy 200.24446 -120.044954) (xy 200.304396 -120.044954) (xy 200.363818 -120.052777) (xy 200.421711 -120.06829)
			(xy 200.477084 -120.091226) (xy 200.52899 -120.121193) (xy 200.57654 -120.15768) (xy 200.61892 -120.20006)
			(xy 200.655407 -120.24761) (xy 200.685374 -120.299516) (xy 200.70831 -120.354889) (xy 200.723823 -120.412782)
			(xy 200.731646 -120.472204) (xy 200.732136 -120.502172) (xy 200.732136 -121.365772) (xy 200.731646 -121.39574)
			(xy 200.723823 -121.455162) (xy 200.70831 -121.513055) (xy 200.685374 -121.568428) (xy 200.655407 -121.620334)
			(xy 200.61892 -121.667884) (xy 200.57654 -121.710264) (xy 200.52899 -121.746751) (xy 200.477084 -121.776718)
			(xy 200.421711 -121.799654) (xy 200.363818 -121.815167) (xy 200.304396 -121.82299) (xy 200.24446 -121.82299)
			(xy 200.185038 -121.815167) (xy 200.127145 -121.799654) (xy 200.071772 -121.776718) (xy 200.019866 -121.746751)
			(xy 199.972316 -121.710264) (xy 199.929936 -121.667884) (xy 199.893449 -121.620334) (xy 199.863482 -121.568428)
			(xy 199.840546 -121.513055) (xy 199.825033 -121.455162) (xy 199.81721 -121.39574) (xy 199.81672 -121.365772)
			(xy 197.011697 -121.365772) (xy 197.007988 -121.688606) (xy 197.03288 -121.717562) (xy 197.05193 -121.720356)
			(xy 197.07737 -121.724409) (xy 197.126927 -121.738472) (xy 197.174142 -121.759075) (xy 197.218155 -121.785843)
			(xy 197.258166 -121.818289) (xy 197.293449 -121.855824) (xy 197.308724 -121.876566) (xy 197.314455 -121.883907)
			(xy 197.329962 -121.894192) (xy 197.33895 -121.896632) (xy 197.369176 -121.90349) (xy 197.378475 -121.90509)
			(xy 197.397108 -121.902221) (xy 197.405498 -121.897902) (xy 197.431502 -121.883591) (xy 197.486417 -121.861064)
			(xy 197.543785 -121.845834) (xy 197.602642 -121.838155) (xy 197.63232 -121.837704) (xy 197.662298 -121.838175)
			(xy 197.721742 -121.846006) (xy 197.779654 -121.861532) (xy 197.835043 -121.884486) (xy 197.88696 -121.914476)
			(xy 197.934517 -121.950989) (xy 197.9769 -121.993398) (xy 198.013383 -122.040978) (xy 198.04334 -122.092914)
			(xy 198.06626 -122.148317) (xy 198.08175 -122.206239) (xy 198.089544 -122.265687) (xy 198.090028 -122.295666)
			(xy 198.090028 -123.159266) (xy 198.089538 -123.189234) (xy 198.081715 -123.248656) (xy 198.066202 -123.306549)
			(xy 198.043266 -123.361922) (xy 198.013299 -123.413828) (xy 197.976812 -123.461378) (xy 197.934432 -123.503758)
			(xy 197.886882 -123.540245) (xy 197.834976 -123.570212) (xy 197.779603 -123.593148) (xy 197.72171 -123.608661)
			(xy 197.662288 -123.616484) (xy 197.602352 -123.616484) (xy 197.54293 -123.608661) (xy 197.485037 -123.593148)
			(xy 197.429664 -123.570212) (xy 197.377758 -123.540245) (xy 197.330208 -123.503758) (xy 197.287828 -123.461378)
			(xy 197.251341 -123.413828) (xy 197.221374 -123.361922) (xy 197.198438 -123.306549) (xy 197.182925 -123.248656)
			(xy 197.175102 -123.189234) (xy 197.174612 -123.159266) (xy 197.174612 -122.57532) (xy 197.174076 -122.564299)
			(xy 197.164864 -122.544276) (xy 197.156832 -122.536712) (xy 197.089522 -122.479308) (xy 197.068186 -122.473212)
			(xy 197.057264 -122.47499) (xy 197.04304 -122.476768) (xy 197.02399 -122.479054) (xy 196.99859 -122.507502)
			(xy 196.9702 -124.965714) (xy 199.81672 -124.965714) (xy 199.81672 -124.102114) (xy 199.81721 -124.072146)
			(xy 199.825033 -124.012724) (xy 199.840546 -123.954831) (xy 199.863482 -123.899458) (xy 199.893449 -123.847552)
			(xy 199.929936 -123.800002) (xy 199.972316 -123.757622) (xy 200.019866 -123.721135) (xy 200.071772 -123.691168)
			(xy 200.127145 -123.668232) (xy 200.185038 -123.652719) (xy 200.24446 -123.644896) (xy 200.304396 -123.644896)
			(xy 200.363818 -123.652719) (xy 200.421711 -123.668232) (xy 200.477084 -123.691168) (xy 200.52899 -123.721135)
			(xy 200.57654 -123.757622) (xy 200.61892 -123.800002) (xy 200.655407 -123.847552) (xy 200.685374 -123.899458)
			(xy 200.70831 -123.954831) (xy 200.723823 -124.012724) (xy 200.731646 -124.072146) (xy 200.732136 -124.102114)
			(xy 200.732136 -124.965714) (xy 200.731646 -124.995682) (xy 200.723823 -125.055104) (xy 200.70831 -125.112997)
			(xy 200.685374 -125.16837) (xy 200.655407 -125.220276) (xy 200.61892 -125.267826) (xy 200.57654 -125.310206)
			(xy 200.52899 -125.346693) (xy 200.477084 -125.37666) (xy 200.421711 -125.399596) (xy 200.363818 -125.415109)
			(xy 200.304396 -125.422932) (xy 200.24446 -125.422932) (xy 200.185038 -125.415109) (xy 200.127145 -125.399596)
			(xy 200.071772 -125.37666) (xy 200.019866 -125.346693) (xy 199.972316 -125.310206) (xy 199.929936 -125.267826)
			(xy 199.893449 -125.220276) (xy 199.863482 -125.16837) (xy 199.840546 -125.112997) (xy 199.825033 -125.055104)
			(xy 199.81721 -124.995682) (xy 199.81672 -124.965714) (xy 196.9702 -124.965714) (xy 196.903176 -130.769106)
			(xy 197.174612 -130.769106) (xy 197.174612 -129.905506) (xy 197.175102 -129.875538) (xy 197.182925 -129.816116)
			(xy 197.198438 -129.758223) (xy 197.221374 -129.70285) (xy 197.251341 -129.650944) (xy 197.287828 -129.603394)
			(xy 197.330208 -129.561014) (xy 197.377758 -129.524527) (xy 197.429664 -129.49456) (xy 197.485037 -129.471624)
			(xy 197.54293 -129.456111) (xy 197.602352 -129.448288) (xy 197.662288 -129.448288) (xy 197.72171 -129.456111)
			(xy 197.779603 -129.471624) (xy 197.834976 -129.49456) (xy 197.886882 -129.524527) (xy 197.934432 -129.561014)
			(xy 197.976812 -129.603394) (xy 198.013299 -129.650944) (xy 198.043266 -129.70285) (xy 198.066202 -129.758223)
			(xy 198.081715 -129.816116) (xy 198.089538 -129.875538) (xy 198.090028 -129.905506) (xy 198.090028 -130.769106)
			(xy 198.089538 -130.799074) (xy 198.081715 -130.858496) (xy 198.066202 -130.916389) (xy 198.043266 -130.971762)
			(xy 198.013299 -131.023668) (xy 197.976812 -131.071218) (xy 197.934432 -131.113598) (xy 197.886882 -131.150085)
			(xy 197.834976 -131.180052) (xy 197.779603 -131.202988) (xy 197.72171 -131.218501) (xy 197.662288 -131.226324)
			(xy 197.602352 -131.226324) (xy 197.54293 -131.218501) (xy 197.485037 -131.202988) (xy 197.429664 -131.180052)
			(xy 197.377758 -131.150085) (xy 197.330208 -131.113598) (xy 197.287828 -131.071218) (xy 197.251341 -131.023668)
			(xy 197.221374 -130.971762) (xy 197.198438 -130.916389) (xy 197.182925 -130.858496) (xy 197.175102 -130.799074)
			(xy 197.174612 -130.769106) (xy 196.903176 -130.769106) (xy 196.88231 -132.575808) (xy 199.81672 -132.575808)
			(xy 199.81672 -131.712208) (xy 199.81721 -131.68224) (xy 199.825033 -131.622818) (xy 199.840546 -131.564925)
			(xy 199.863482 -131.509552) (xy 199.893449 -131.457646) (xy 199.929936 -131.410096) (xy 199.972316 -131.367716)
			(xy 200.019866 -131.331229) (xy 200.071772 -131.301262) (xy 200.127145 -131.278326) (xy 200.185038 -131.262813)
			(xy 200.24446 -131.25499) (xy 200.304396 -131.25499) (xy 200.363818 -131.262813) (xy 200.421711 -131.278326)
			(xy 200.477084 -131.301262) (xy 200.52899 -131.331229) (xy 200.57654 -131.367716) (xy 200.61892 -131.410096)
			(xy 200.655407 -131.457646) (xy 200.685374 -131.509552) (xy 200.70831 -131.564925) (xy 200.723823 -131.622818)
			(xy 200.731646 -131.68224) (xy 200.732136 -131.712208) (xy 200.732136 -132.575808) (xy 200.731646 -132.605776)
			(xy 200.723823 -132.665198) (xy 200.70831 -132.723091) (xy 200.685374 -132.778464) (xy 200.655407 -132.83037)
			(xy 200.61892 -132.87792) (xy 200.57654 -132.9203) (xy 200.52899 -132.956787) (xy 200.477084 -132.986754)
			(xy 200.421711 -133.00969) (xy 200.363818 -133.025203) (xy 200.304396 -133.033026) (xy 200.24446 -133.033026)
			(xy 200.185038 -133.025203) (xy 200.127145 -133.00969) (xy 200.071772 -132.986754) (xy 200.019866 -132.956787)
			(xy 199.972316 -132.9203) (xy 199.929936 -132.87792) (xy 199.893449 -132.83037) (xy 199.863482 -132.778464)
			(xy 199.840546 -132.723091) (xy 199.825033 -132.665198) (xy 199.81721 -132.605776) (xy 199.81672 -132.575808)
			(xy 196.88231 -132.575808) (xy 196.861597 -134.369302) (xy 197.174612 -134.369302) (xy 197.174612 -133.505702)
			(xy 197.175102 -133.475734) (xy 197.182925 -133.416312) (xy 197.198438 -133.358419) (xy 197.221374 -133.303046)
			(xy 197.251341 -133.25114) (xy 197.287828 -133.20359) (xy 197.330208 -133.16121) (xy 197.377758 -133.124723)
			(xy 197.429664 -133.094756) (xy 197.485037 -133.07182) (xy 197.54293 -133.056307) (xy 197.602352 -133.048484)
			(xy 197.662288 -133.048484) (xy 197.72171 -133.056307) (xy 197.779603 -133.07182) (xy 197.834976 -133.094756)
			(xy 197.886882 -133.124723) (xy 197.934432 -133.16121) (xy 197.976812 -133.20359) (xy 198.013299 -133.25114)
			(xy 198.043266 -133.303046) (xy 198.066202 -133.358419) (xy 198.081715 -133.416312) (xy 198.089538 -133.475734)
			(xy 198.090028 -133.505702) (xy 198.090028 -134.369302) (xy 198.089538 -134.39927) (xy 198.081715 -134.458692)
			(xy 198.066202 -134.516585) (xy 198.043266 -134.571958) (xy 198.013299 -134.623864) (xy 197.976812 -134.671414)
			(xy 197.934432 -134.713794) (xy 197.886882 -134.750281) (xy 197.834976 -134.780248) (xy 197.779603 -134.803184)
			(xy 197.72171 -134.818697) (xy 197.662288 -134.82652) (xy 197.602352 -134.82652) (xy 197.54293 -134.818697)
			(xy 197.485037 -134.803184) (xy 197.429664 -134.780248) (xy 197.377758 -134.750281) (xy 197.330208 -134.713794)
			(xy 197.287828 -134.671414) (xy 197.251341 -134.623864) (xy 197.221374 -134.571958) (xy 197.198438 -134.516585)
			(xy 197.182925 -134.458692) (xy 197.175102 -134.39927) (xy 197.174612 -134.369302) (xy 196.861597 -134.369302)
			(xy 196.840735 -136.17575) (xy 199.81672 -136.17575) (xy 199.81672 -135.31215) (xy 199.81721 -135.282182)
			(xy 199.825033 -135.22276) (xy 199.840546 -135.164867) (xy 199.863482 -135.109494) (xy 199.893449 -135.057588)
			(xy 199.929936 -135.010038) (xy 199.972316 -134.967658) (xy 200.019866 -134.931171) (xy 200.071772 -134.901204)
			(xy 200.127145 -134.878268) (xy 200.185038 -134.862755) (xy 200.24446 -134.854932) (xy 200.304396 -134.854932)
			(xy 200.363818 -134.862755) (xy 200.421711 -134.878268) (xy 200.477084 -134.901204) (xy 200.52899 -134.931171)
			(xy 200.57654 -134.967658) (xy 200.61892 -135.010038) (xy 200.655407 -135.057588) (xy 200.685374 -135.109494)
			(xy 200.70831 -135.164867) (xy 200.723823 -135.22276) (xy 200.731646 -135.282182) (xy 200.732136 -135.31215)
			(xy 200.732136 -136.17575) (xy 200.731646 -136.205718) (xy 200.723823 -136.26514) (xy 200.70831 -136.323033)
			(xy 200.685374 -136.378406) (xy 200.655407 -136.430312) (xy 200.61892 -136.477862) (xy 200.57654 -136.520242)
			(xy 200.52899 -136.556729) (xy 200.477084 -136.586696) (xy 200.421711 -136.609632) (xy 200.363818 -136.625145)
			(xy 200.304396 -136.632968) (xy 200.24446 -136.632968) (xy 200.185038 -136.625145) (xy 200.127145 -136.609632)
			(xy 200.071772 -136.586696) (xy 200.019866 -136.556729) (xy 199.972316 -136.520242) (xy 199.929936 -136.477862)
			(xy 199.893449 -136.430312) (xy 199.863482 -136.378406) (xy 199.840546 -136.323033) (xy 199.825033 -136.26514)
			(xy 199.81721 -136.205718) (xy 199.81672 -136.17575) (xy 196.840735 -136.17575) (xy 196.836792 -136.517126)
			(xy 196.836792 -136.521952) (xy 196.838467 -136.536297) (xy 196.848774 -136.563261) (xy 196.866219 -136.58626)
			(xy 196.889406 -136.603455) (xy 196.916479 -136.613471) (xy 196.945274 -136.615506) (xy 196.959474 -136.612884)
			(xy 196.979241 -136.608941) (xy 197.019329 -136.604736) (xy 197.039484 -136.604502) (xy 197.066737 -136.604964)
			(xy 197.120689 -136.612719) (xy 197.172989 -136.628074) (xy 197.22257 -136.650716) (xy 197.268425 -136.680184)
			(xy 197.309618 -136.715877) (xy 197.345313 -136.757071) (xy 197.374781 -136.802925) (xy 197.397424 -136.852506)
			(xy 197.412779 -136.904805) (xy 197.420535 -136.958757) (xy 197.420992 -136.98601) (xy 197.420913 -136.998748)
			(xy 197.419259 -137.024169) (xy 197.41769 -137.03681) (xy 197.413479 -137.064449) (xy 197.398024 -137.118178)
			(xy 197.374898 -137.169078) (xy 197.344596 -137.216061) (xy 197.307767 -137.258123) (xy 197.265197 -137.294365)
			(xy 197.217797 -137.324011) (xy 197.166581 -137.346427) (xy 197.112643 -137.361134) (xy 197.08495 -137.364978)
			(xy 197.06971 -137.366502) (xy 197.039484 -137.367772) (xy 197.03923 -137.367772) (xy 197.016922 -137.367438)
			(xy 196.972613 -137.362214) (xy 196.950838 -137.357358) (xy 196.936103 -137.354431) (xy 196.906138 -137.356326)
			(xy 196.878014 -137.366844) (xy 196.85416 -137.385079) (xy 196.836632 -137.409457) (xy 196.826943 -137.437877)
			(xy 196.82587 -137.452862) (xy 196.82587 -137.453878) (xy 196.814539 -138.434318) (xy 198.100948 -138.434318)
			(xy 198.105019 -138.378696) (xy 198.117145 -138.324259) (xy 198.137068 -138.272168) (xy 198.164364 -138.223533)
			(xy 198.19845 -138.17939) (xy 198.238599 -138.140681) (xy 198.283957 -138.10823) (xy 198.333557 -138.082729)
			(xy 198.386341 -138.064722) (xy 198.441184 -138.054592) (xy 198.496918 -138.052555) (xy 198.552355 -138.058655)
			(xy 198.606312 -138.072761) (xy 198.657641 -138.094573) (xy 198.705247 -138.123627) (xy 198.748115 -138.159302)
			(xy 198.785332 -138.200839) (xy 198.816105 -138.247352) (xy 198.839777 -138.297849) (xy 198.855845 -138.351256)
			(xy 198.863965 -138.406432) (xy 198.864474 -138.434318) (xy 198.863965 -138.462204) (xy 198.855845 -138.51738)
			(xy 198.839777 -138.570787) (xy 198.816105 -138.621284) (xy 198.785332 -138.667797) (xy 198.748115 -138.709334)
			(xy 198.705247 -138.745009) (xy 198.657641 -138.774063) (xy 198.606312 -138.795875) (xy 198.552355 -138.809981)
			(xy 198.496918 -138.816081) (xy 198.441184 -138.814044) (xy 198.386341 -138.803914) (xy 198.333557 -138.785907)
			(xy 198.283957 -138.760406) (xy 198.238599 -138.727955) (xy 198.19845 -138.689246) (xy 198.164364 -138.645103)
			(xy 198.137068 -138.596468) (xy 198.117145 -138.544377) (xy 198.105019 -138.48994) (xy 198.100948 -138.434318)
			(xy 196.814539 -138.434318) (xy 196.790263 -140.534898) (xy 197.155814 -140.534898) (xy 197.159885 -140.479276)
			(xy 197.172011 -140.424839) (xy 197.191934 -140.372748) (xy 197.21923 -140.324113) (xy 197.253316 -140.27997)
			(xy 197.293465 -140.241261) (xy 197.338823 -140.20881) (xy 197.388423 -140.183309) (xy 197.441207 -140.165302)
			(xy 197.49605 -140.155172) (xy 197.551784 -140.153135) (xy 197.607221 -140.159235) (xy 197.661178 -140.173341)
			(xy 197.712507 -140.195153) (xy 197.760113 -140.224207) (xy 197.802981 -140.259882) (xy 197.840198 -140.301419)
			(xy 197.870971 -140.347932) (xy 197.894643 -140.398429) (xy 197.910711 -140.451836) (xy 197.918831 -140.507012)
			(xy 197.91934 -140.534898) (xy 197.918831 -140.562784) (xy 197.910711 -140.61796) (xy 197.894643 -140.671367)
			(xy 197.870971 -140.721864) (xy 197.840198 -140.768377) (xy 197.802981 -140.809914) (xy 197.760113 -140.845589)
			(xy 197.712507 -140.874643) (xy 197.661178 -140.896455) (xy 197.607221 -140.910561) (xy 197.551784 -140.916661)
			(xy 197.49605 -140.914624) (xy 197.441207 -140.904494) (xy 197.388423 -140.886487) (xy 197.338823 -140.860986)
			(xy 197.293465 -140.828535) (xy 197.253316 -140.789826) (xy 197.21923 -140.745683) (xy 197.191934 -140.697048)
			(xy 197.172011 -140.644957) (xy 197.159885 -140.59052) (xy 197.155814 -140.534898) (xy 196.790263 -140.534898)
			(xy 196.756235 -143.479266) (xy 197.174612 -143.479266) (xy 197.174612 -142.615666) (xy 197.175102 -142.585698)
			(xy 197.182925 -142.526276) (xy 197.198438 -142.468383) (xy 197.221374 -142.41301) (xy 197.251341 -142.361104)
			(xy 197.287828 -142.313554) (xy 197.330208 -142.271174) (xy 197.377758 -142.234687) (xy 197.429664 -142.20472)
			(xy 197.485037 -142.181784) (xy 197.54293 -142.166271) (xy 197.602352 -142.158448) (xy 197.662288 -142.158448)
			(xy 197.72171 -142.166271) (xy 197.779603 -142.181784) (xy 197.834976 -142.20472) (xy 197.886882 -142.234687)
			(xy 197.934432 -142.271174) (xy 197.976812 -142.313554) (xy 198.013299 -142.361104) (xy 198.043266 -142.41301)
			(xy 198.066202 -142.468383) (xy 198.081715 -142.526276) (xy 198.089538 -142.585698) (xy 198.090028 -142.615666)
			(xy 198.090028 -143.479266) (xy 198.089538 -143.509234) (xy 198.081715 -143.568656) (xy 198.066202 -143.626549)
			(xy 198.043266 -143.681922) (xy 198.013299 -143.733828) (xy 197.976812 -143.781378) (xy 197.934432 -143.823758)
			(xy 197.886882 -143.860245) (xy 197.834976 -143.890212) (xy 197.779603 -143.913148) (xy 197.72171 -143.928661)
			(xy 197.662288 -143.936484) (xy 197.602352 -143.936484) (xy 197.54293 -143.928661) (xy 197.485037 -143.913148)
			(xy 197.429664 -143.890212) (xy 197.377758 -143.860245) (xy 197.330208 -143.823758) (xy 197.287828 -143.781378)
			(xy 197.251341 -143.733828) (xy 197.221374 -143.681922) (xy 197.198438 -143.626549) (xy 197.182925 -143.568656)
			(xy 197.175102 -143.509234) (xy 197.174612 -143.479266) (xy 196.756235 -143.479266) (xy 196.749416 -144.069308)
			(xy 196.749162 -144.088104) (xy 196.749162 -144.088612) (xy 196.748654 -144.12468) (xy 196.748654 -144.125188)
			(xy 196.7484 -144.130522) (xy 196.742304 -144.17802) (xy 196.742304 -144.178274) (xy 196.741288 -144.185386)
			(xy 196.599545 -145.285714) (xy 199.81672 -145.285714) (xy 199.81672 -144.422114) (xy 199.81721 -144.392146)
			(xy 199.825033 -144.332724) (xy 199.840546 -144.274831) (xy 199.863482 -144.219458) (xy 199.893449 -144.167552)
			(xy 199.929936 -144.120002) (xy 199.972316 -144.077622) (xy 200.019866 -144.041135) (xy 200.071772 -144.011168)
			(xy 200.127145 -143.988232) (xy 200.185038 -143.972719) (xy 200.24446 -143.964896) (xy 200.304396 -143.964896)
			(xy 200.363818 -143.972719) (xy 200.421711 -143.988232) (xy 200.477084 -144.011168) (xy 200.52899 -144.041135)
			(xy 200.57654 -144.077622) (xy 200.61892 -144.120002) (xy 200.655407 -144.167552) (xy 200.685374 -144.219458)
			(xy 200.70831 -144.274831) (xy 200.723823 -144.332724) (xy 200.731646 -144.392146) (xy 200.732136 -144.422114)
			(xy 200.732136 -145.285714) (xy 200.731646 -145.315682) (xy 200.723823 -145.375104) (xy 200.70831 -145.432997)
			(xy 200.685374 -145.48837) (xy 200.655407 -145.540276) (xy 200.61892 -145.587826) (xy 200.57654 -145.630206)
			(xy 200.52899 -145.666693) (xy 200.477084 -145.69666) (xy 200.421711 -145.719596) (xy 200.363818 -145.735109)
			(xy 200.304396 -145.742932) (xy 200.24446 -145.742932) (xy 200.185038 -145.735109) (xy 200.127145 -145.719596)
			(xy 200.071772 -145.69666) (xy 200.019866 -145.666693) (xy 199.972316 -145.630206) (xy 199.929936 -145.587826)
			(xy 199.893449 -145.540276) (xy 199.863482 -145.48837) (xy 199.840546 -145.432997) (xy 199.825033 -145.375104)
			(xy 199.81721 -145.315682) (xy 199.81672 -145.285714) (xy 196.599545 -145.285714) (xy 196.36851 -147.079208)
			(xy 197.174612 -147.079208) (xy 197.174612 -146.215608) (xy 197.175102 -146.18564) (xy 197.182925 -146.126218)
			(xy 197.198438 -146.068325) (xy 197.221374 -146.012952) (xy 197.251341 -145.961046) (xy 197.287828 -145.913496)
			(xy 197.330208 -145.871116) (xy 197.377758 -145.834629) (xy 197.429664 -145.804662) (xy 197.485037 -145.781726)
			(xy 197.54293 -145.766213) (xy 197.602352 -145.75839) (xy 197.662288 -145.75839) (xy 197.72171 -145.766213)
			(xy 197.779603 -145.781726) (xy 197.834976 -145.804662) (xy 197.886882 -145.834629) (xy 197.934432 -145.871116)
			(xy 197.976812 -145.913496) (xy 198.013299 -145.961046) (xy 198.043266 -146.012952) (xy 198.066202 -146.068325)
			(xy 198.081715 -146.126218) (xy 198.089538 -146.18564) (xy 198.090028 -146.215608) (xy 198.090028 -147.079208)
			(xy 198.089538 -147.109176) (xy 198.081715 -147.168598) (xy 198.066202 -147.226491) (xy 198.043266 -147.281864)
			(xy 198.013299 -147.33377) (xy 197.976812 -147.38132) (xy 197.934432 -147.4237) (xy 197.886882 -147.460187)
			(xy 197.834976 -147.490154) (xy 197.779603 -147.51309) (xy 197.72171 -147.528603) (xy 197.662288 -147.536426)
			(xy 197.602352 -147.536426) (xy 197.54293 -147.528603) (xy 197.485037 -147.51309) (xy 197.429664 -147.490154)
			(xy 197.377758 -147.460187) (xy 197.330208 -147.4237) (xy 197.287828 -147.38132) (xy 197.251341 -147.33377)
			(xy 197.221374 -147.281864) (xy 197.198438 -147.226491) (xy 197.182925 -147.168598) (xy 197.175102 -147.109176)
			(xy 197.174612 -147.079208) (xy 196.36851 -147.079208) (xy 196.135773 -148.88591) (xy 199.81672 -148.88591)
			(xy 199.81672 -148.02231) (xy 199.81721 -147.992342) (xy 199.825033 -147.93292) (xy 199.840546 -147.875027)
			(xy 199.863482 -147.819654) (xy 199.893449 -147.767748) (xy 199.929936 -147.720198) (xy 199.972316 -147.677818)
			(xy 200.019866 -147.641331) (xy 200.071772 -147.611364) (xy 200.127145 -147.588428) (xy 200.185038 -147.572915)
			(xy 200.24446 -147.565092) (xy 200.304396 -147.565092) (xy 200.363818 -147.572915) (xy 200.421711 -147.588428)
			(xy 200.477084 -147.611364) (xy 200.52899 -147.641331) (xy 200.57654 -147.677818) (xy 200.61892 -147.720198)
			(xy 200.655407 -147.767748) (xy 200.685374 -147.819654) (xy 200.70831 -147.875027) (xy 200.723823 -147.93292)
			(xy 200.731646 -147.992342) (xy 200.732136 -148.02231) (xy 200.732136 -148.88591) (xy 200.731646 -148.915878)
			(xy 200.723823 -148.9753) (xy 200.70831 -149.033193) (xy 200.685374 -149.088566) (xy 200.655407 -149.140472)
			(xy 200.61892 -149.188022) (xy 200.57654 -149.230402) (xy 200.52899 -149.266889) (xy 200.477084 -149.296856)
			(xy 200.421711 -149.319792) (xy 200.363818 -149.335305) (xy 200.304396 -149.343128) (xy 200.24446 -149.343128)
			(xy 200.185038 -149.335305) (xy 200.127145 -149.319792) (xy 200.071772 -149.296856) (xy 200.019866 -149.266889)
			(xy 199.972316 -149.230402) (xy 199.929936 -149.188022) (xy 199.893449 -149.140472) (xy 199.863482 -149.088566)
			(xy 199.840546 -149.033193) (xy 199.825033 -148.9753) (xy 199.81721 -148.915878) (xy 199.81672 -148.88591)
			(xy 196.135773 -148.88591) (xy 195.90477 -150.67915) (xy 197.174612 -150.67915) (xy 197.174612 -149.81555)
			(xy 197.175102 -149.785582) (xy 197.182925 -149.72616) (xy 197.198438 -149.668267) (xy 197.221374 -149.612894)
			(xy 197.251341 -149.560988) (xy 197.287828 -149.513438) (xy 197.330208 -149.471058) (xy 197.377758 -149.434571)
			(xy 197.429664 -149.404604) (xy 197.485037 -149.381668) (xy 197.54293 -149.366155) (xy 197.602352 -149.358332)
			(xy 197.662288 -149.358332) (xy 197.72171 -149.366155) (xy 197.779603 -149.381668) (xy 197.834976 -149.404604)
			(xy 197.886882 -149.434571) (xy 197.934432 -149.471058) (xy 197.976812 -149.513438) (xy 198.013299 -149.560988)
			(xy 198.043266 -149.612894) (xy 198.066202 -149.668267) (xy 198.081715 -149.72616) (xy 198.089538 -149.785582)
			(xy 198.090028 -149.81555) (xy 198.090028 -150.67915) (xy 198.089538 -150.709118) (xy 198.081715 -150.76854)
			(xy 198.066202 -150.826433) (xy 198.043266 -150.881806) (xy 198.013299 -150.933712) (xy 197.976812 -150.981262)
			(xy 197.934432 -151.023642) (xy 197.886882 -151.060129) (xy 197.834976 -151.090096) (xy 197.779603 -151.113032)
			(xy 197.72171 -151.128545) (xy 197.662288 -151.136368) (xy 197.602352 -151.136368) (xy 197.54293 -151.128545)
			(xy 197.485037 -151.113032) (xy 197.429664 -151.090096) (xy 197.377758 -151.060129) (xy 197.330208 -151.023642)
			(xy 197.287828 -150.981262) (xy 197.251341 -150.933712) (xy 197.221374 -150.881806) (xy 197.198438 -150.826433)
			(xy 197.182925 -150.76854) (xy 197.175102 -150.709118) (xy 197.174612 -150.67915) (xy 195.90477 -150.67915)
			(xy 195.672033 -152.485852) (xy 199.81672 -152.485852) (xy 199.81672 -151.622252) (xy 199.81721 -151.592284)
			(xy 199.825033 -151.532862) (xy 199.840546 -151.474969) (xy 199.863482 -151.419596) (xy 199.893449 -151.36769)
			(xy 199.929936 -151.32014) (xy 199.972316 -151.27776) (xy 200.019866 -151.241273) (xy 200.071772 -151.211306)
			(xy 200.127145 -151.18837) (xy 200.185038 -151.172857) (xy 200.24446 -151.165034) (xy 200.304396 -151.165034)
			(xy 200.363818 -151.172857) (xy 200.421711 -151.18837) (xy 200.477084 -151.211306) (xy 200.52899 -151.241273)
			(xy 200.57654 -151.27776) (xy 200.61892 -151.32014) (xy 200.655407 -151.36769) (xy 200.685374 -151.419596)
			(xy 200.70831 -151.474969) (xy 200.723823 -151.532862) (xy 200.731646 -151.592284) (xy 200.732136 -151.622252)
			(xy 200.732136 -152.485852) (xy 200.731646 -152.51582) (xy 200.723823 -152.575242) (xy 200.70831 -152.633135)
			(xy 200.685374 -152.688508) (xy 200.655407 -152.740414) (xy 200.61892 -152.787964) (xy 200.57654 -152.830344)
			(xy 200.52899 -152.866831) (xy 200.477084 -152.896798) (xy 200.421711 -152.919734) (xy 200.363818 -152.935247)
			(xy 200.304396 -152.94307) (xy 200.24446 -152.94307) (xy 200.185038 -152.935247) (xy 200.127145 -152.919734)
			(xy 200.071772 -152.896798) (xy 200.019866 -152.866831) (xy 199.972316 -152.830344) (xy 199.929936 -152.787964)
			(xy 199.893449 -152.740414) (xy 199.863482 -152.688508) (xy 199.840546 -152.633135) (xy 199.825033 -152.575242)
			(xy 199.81721 -152.51582) (xy 199.81672 -152.485852) (xy 195.672033 -152.485852) (xy 195.440997 -154.279346)
			(xy 197.174612 -154.279346) (xy 197.174612 -153.415746) (xy 197.175102 -153.385778) (xy 197.182925 -153.326356)
			(xy 197.198438 -153.268463) (xy 197.221374 -153.21309) (xy 197.251341 -153.161184) (xy 197.287828 -153.113634)
			(xy 197.330208 -153.071254) (xy 197.377758 -153.034767) (xy 197.429664 -153.0048) (xy 197.485037 -152.981864)
			(xy 197.54293 -152.966351) (xy 197.602352 -152.958528) (xy 197.662288 -152.958528) (xy 197.72171 -152.966351)
			(xy 197.779603 -152.981864) (xy 197.834976 -153.0048) (xy 197.886882 -153.034767) (xy 197.934432 -153.071254)
			(xy 197.976812 -153.113634) (xy 198.013299 -153.161184) (xy 198.043266 -153.21309) (xy 198.066202 -153.268463)
			(xy 198.081715 -153.326356) (xy 198.089538 -153.385778) (xy 198.090028 -153.415746) (xy 198.090028 -154.279346)
			(xy 198.089538 -154.309314) (xy 198.081715 -154.368736) (xy 198.066202 -154.426629) (xy 198.043266 -154.482002)
			(xy 198.013299 -154.533908) (xy 197.976812 -154.581458) (xy 197.934432 -154.623838) (xy 197.886882 -154.660325)
			(xy 197.834976 -154.690292) (xy 197.779603 -154.713228) (xy 197.72171 -154.728741) (xy 197.662288 -154.736564)
			(xy 197.602352 -154.736564) (xy 197.54293 -154.728741) (xy 197.485037 -154.713228) (xy 197.429664 -154.690292)
			(xy 197.377758 -154.660325) (xy 197.330208 -154.623838) (xy 197.287828 -154.581458) (xy 197.251341 -154.533908)
			(xy 197.221374 -154.482002) (xy 197.198438 -154.426629) (xy 197.182925 -154.368736) (xy 197.175102 -154.309314)
			(xy 197.174612 -154.279346) (xy 195.440997 -154.279346) (xy 195.352162 -154.968956) (xy 195.349368 -154.989276)
			(xy 195.349368 -154.98953) (xy 195.349114 -154.991816) (xy 195.348098 -154.996896) (xy 195.348098 -154.997404)
			(xy 195.345558 -155.012644) (xy 195.158663 -156.085794) (xy 199.81672 -156.085794) (xy 199.81672 -155.222194)
			(xy 199.81721 -155.192226) (xy 199.825033 -155.132804) (xy 199.840546 -155.074911) (xy 199.863482 -155.019538)
			(xy 199.893449 -154.967632) (xy 199.929936 -154.920082) (xy 199.972316 -154.877702) (xy 200.019866 -154.841215)
			(xy 200.071772 -154.811248) (xy 200.127145 -154.788312) (xy 200.185038 -154.772799) (xy 200.24446 -154.764976)
			(xy 200.304396 -154.764976) (xy 200.363818 -154.772799) (xy 200.421711 -154.788312) (xy 200.477084 -154.811248)
			(xy 200.52899 -154.841215) (xy 200.57654 -154.877702) (xy 200.61892 -154.920082) (xy 200.655407 -154.967632)
			(xy 200.685374 -155.019538) (xy 200.70831 -155.074911) (xy 200.723823 -155.132804) (xy 200.731646 -155.192226)
			(xy 200.732136 -155.222194) (xy 200.732136 -156.085794) (xy 200.731646 -156.115762) (xy 200.723823 -156.175184)
			(xy 200.70831 -156.233077) (xy 200.685374 -156.28845) (xy 200.655407 -156.340356) (xy 200.61892 -156.387906)
			(xy 200.57654 -156.430286) (xy 200.52899 -156.466773) (xy 200.477084 -156.49674) (xy 200.421711 -156.519676)
			(xy 200.363818 -156.535189) (xy 200.304396 -156.543012) (xy 200.24446 -156.543012) (xy 200.185038 -156.535189)
			(xy 200.127145 -156.519676) (xy 200.071772 -156.49674) (xy 200.019866 -156.466773) (xy 199.972316 -156.430286)
			(xy 199.929936 -156.387906) (xy 199.893449 -156.340356) (xy 199.863482 -156.28845) (xy 199.840546 -156.233077)
			(xy 199.825033 -156.175184) (xy 199.81721 -156.115762) (xy 199.81672 -156.085794) (xy 195.158663 -156.085794)
			(xy 194.78704 -158.219648) (xy 197.282052 -158.219648) (xy 197.286123 -158.164026) (xy 197.298249 -158.109589)
			(xy 197.318172 -158.057498) (xy 197.345468 -158.008863) (xy 197.379554 -157.96472) (xy 197.419703 -157.926011)
			(xy 197.465061 -157.89356) (xy 197.514661 -157.868059) (xy 197.567445 -157.850052) (xy 197.622288 -157.839922)
			(xy 197.678022 -157.837885) (xy 197.733459 -157.843985) (xy 197.787416 -157.858091) (xy 197.838745 -157.879903)
			(xy 197.886351 -157.908957) (xy 197.929219 -157.944632) (xy 197.966436 -157.986169) (xy 197.997209 -158.032682)
			(xy 198.020881 -158.083179) (xy 198.036949 -158.136586) (xy 198.045069 -158.191762) (xy 198.045578 -158.219648)
			(xy 198.045069 -158.247534) (xy 198.036949 -158.30271) (xy 198.020881 -158.356117) (xy 197.997209 -158.406614)
			(xy 197.966436 -158.453127) (xy 197.929219 -158.494664) (xy 197.886351 -158.530339) (xy 197.838745 -158.559393)
			(xy 197.787416 -158.581205) (xy 197.733459 -158.595311) (xy 197.678022 -158.601411) (xy 197.622288 -158.599374)
			(xy 197.567445 -158.589244) (xy 197.514661 -158.571237) (xy 197.465061 -158.545736) (xy 197.419703 -158.513285)
			(xy 197.379554 -158.474576) (xy 197.345468 -158.430433) (xy 197.318172 -158.381798) (xy 197.298249 -158.329707)
			(xy 197.286123 -158.27527) (xy 197.282052 -158.219648) (xy 194.78704 -158.219648) (xy 194.60536 -159.262851)
			(xy 197.449403 -159.262851) (xy 197.449403 -159.208349) (xy 197.45716 -159.154401) (xy 197.472516 -159.102107)
			(xy 197.495159 -159.05253) (xy 197.524627 -159.006681) (xy 197.560321 -158.965492) (xy 197.601513 -158.929803)
			(xy 197.647365 -158.90034) (xy 197.696944 -158.877702) (xy 197.74924 -158.862352) (xy 197.803189 -158.8546)
			(xy 197.83044 -158.85414) (xy 197.861243 -158.854736) (xy 197.922045 -158.864666) (xy 197.980458 -158.884246)
			(xy 198.007986 -158.898082) (xy 198.013574 -158.900876) (xy 198.025512 -158.903924) (xy 199.184006 -158.903924)
			(xy 199.19401 -158.903456) (xy 199.212473 -158.895743) (xy 199.21982 -158.888938) (xy 201.87158 -156.237178)
			(xy 201.878241 -156.229753) (xy 201.885826 -156.211327) (xy 201.886312 -156.201364) (xy 201.886312 -140.743686)
			(xy 201.886082 -140.735597) (xy 201.881157 -140.720188) (xy 201.87666 -140.71346) (xy 201.859202 -140.688775)
			(xy 201.831521 -140.635024) (xy 201.812659 -140.577581) (xy 201.803088 -140.517884) (xy 201.802492 -140.487654)
			(xy 201.802978 -140.460403) (xy 201.810734 -140.406455) (xy 201.826089 -140.35416) (xy 201.848731 -140.304583)
			(xy 201.878197 -140.258733) (xy 201.913888 -140.217542) (xy 201.955079 -140.181851) (xy 202.000929 -140.152385)
			(xy 202.050506 -140.129743) (xy 202.102801 -140.114388) (xy 202.156749 -140.106632) (xy 202.211251 -140.106632)
			(xy 202.265199 -140.114388) (xy 202.317494 -140.129743) (xy 202.367071 -140.152385) (xy 202.412921 -140.181851)
			(xy 202.454112 -140.217542) (xy 202.489803 -140.258733) (xy 202.519269 -140.304583) (xy 202.541911 -140.35416)
			(xy 202.557266 -140.406455) (xy 202.565022 -140.460403) (xy 202.565508 -140.487654) (xy 202.565139 -140.513175)
			(xy 202.558384 -140.563767) (xy 202.552046 -140.588492) (xy 202.550268 -140.595096) (xy 202.550268 -156.35986)
			(xy 202.54978 -156.385947) (xy 202.541617 -156.43748) (xy 202.525486 -156.487098) (xy 202.501785 -156.533579)
			(xy 202.471099 -156.575776) (xy 202.452986 -156.594556) (xy 199.577198 -159.470344) (xy 199.558385 -159.488406)
			(xy 199.516178 -159.519037) (xy 199.469698 -159.542687) (xy 199.420091 -159.558774) (xy 199.368578 -159.566902)
			(xy 199.342502 -159.567372) (xy 198.025512 -159.567372) (xy 198.013574 -159.57042) (xy 198.007986 -159.573214)
			(xy 197.980447 -159.587024) (xy 197.922036 -159.606598) (xy 197.861241 -159.616541) (xy 197.83044 -159.617156)
			(xy 197.803189 -159.6166) (xy 197.74924 -159.608848) (xy 197.696944 -159.593498) (xy 197.647365 -159.57086)
			(xy 197.601513 -159.541397) (xy 197.560321 -159.505708) (xy 197.524627 -159.464519) (xy 197.495159 -159.41867)
			(xy 197.472516 -159.369093) (xy 197.45716 -159.316799) (xy 197.449403 -159.262851) (xy 194.60536 -159.262851)
			(xy 189.343284 -189.47765) (xy 189.344808 -189.491874) (xy 189.347602 -189.498478) (xy 189.356633 -189.52206)
			(xy 189.369117 -189.570989) (xy 189.372494 -189.596014) (xy 189.374272 -189.610746) (xy 189.375288 -189.640718)
			(xy 189.374785 -189.668521) (xy 189.366713 -189.723537) (xy 189.350745 -189.776801) (xy 189.327216 -189.827183)
			(xy 189.296626 -189.873618) (xy 189.278514 -189.894718) (xy 189.273688 -189.900052) (xy 189.267592 -189.912752)
			(xy 188.629544 -193.576194) (xy 188.631322 -193.580004) (xy 188.655252 -193.592034) (xy 188.699782 -193.621794)
			(xy 188.739716 -193.657486) (xy 188.774271 -193.698408) (xy 188.802768 -193.743757) (xy 188.824647 -193.792644)
			(xy 188.839481 -193.844108) (xy 188.846977 -193.89714) (xy 188.847476 -193.92392) (xy 188.846962 -193.952551)
			(xy 188.8384 -194.00917) (xy 188.821472 -194.063874) (xy 188.796557 -194.115432) (xy 188.764217 -194.162688)
			(xy 188.725176 -194.204579) (xy 188.680313 -194.240164) (xy 188.630635 -194.268644) (xy 188.604144 -194.27952)
			(xy 188.601858 -194.280536) (xy 188.585462 -194.287623) (xy 188.551625 -194.299075) (xy 188.534294 -194.303396)
			(xy 188.519308 -194.306952) (xy 188.49848 -194.328796) (xy 188.44895 -194.613022) (xy 188.447673 -194.623015)
			(xy 188.452144 -194.642642) (xy 188.457586 -194.651122) (xy 188.505084 -194.718178) (xy 188.522102 -194.7291)
			(xy 188.532008 -194.730624) (xy 188.558321 -194.735554) (xy 188.609326 -194.751813) (xy 188.657557 -194.775044)
			(xy 188.702065 -194.804791) (xy 188.741978 -194.840467) (xy 188.776511 -194.881374) (xy 188.804985 -194.926707)
			(xy 188.826842 -194.975576) (xy 188.841651 -195.027021) (xy 188.849122 -195.080031) (xy 188.849508 -195.106798)
			(xy 188.849036 -195.134167) (xy 188.841212 -195.188342) (xy 188.825723 -195.240843) (xy 188.802887 -195.29059)
			(xy 188.773175 -195.336562) (xy 188.737196 -195.377814) (xy 188.69569 -195.413499) (xy 188.649508 -195.442884)
			(xy 188.599601 -195.465365) (xy 188.57341 -195.47332) (xy 188.561472 -195.476876) (xy 188.543438 -195.493894)
			(xy 188.50864 -195.597018) (xy 188.51245 -195.621656) (xy 188.52007 -195.631816) (xy 188.534143 -195.651364)
			(xy 188.557789 -195.693328) (xy 188.575975 -195.737931) (xy 188.582554 -195.761102) (xy 188.585348 -195.771516)
			(xy 188.598048 -195.787518) (xy 188.681614 -195.832984) (xy 188.702188 -195.834762) (xy 188.712348 -195.83146)
			(xy 188.741143 -195.822662) (xy 188.800608 -195.813227) (xy 188.830712 -195.812664) (xy 188.857965 -195.813151)
			(xy 188.911915 -195.820909) (xy 188.964212 -195.836266) (xy 189.013792 -195.85891) (xy 189.059644 -195.888379)
			(xy 189.100836 -195.924073) (xy 189.136529 -195.965266) (xy 189.165996 -196.011119) (xy 189.188638 -196.060699)
			(xy 189.203993 -196.112997) (xy 189.21175 -196.166947) (xy 189.21175 -196.221453) (xy 189.203993 -196.275403)
			(xy 189.188638 -196.327701) (xy 189.165996 -196.377281) (xy 189.136529 -196.423134) (xy 189.100836 -196.464327)
			(xy 189.059644 -196.500021) (xy 189.013792 -196.52949) (xy 188.964212 -196.552134) (xy 188.911915 -196.567491)
			(xy 188.857965 -196.575249) (xy 188.830712 -196.57568) (xy 188.804332 -196.575228) (xy 188.752078 -196.567945)
			(xy 188.701326 -196.553532) (xy 188.653044 -196.532262) (xy 188.608154 -196.504541) (xy 188.567512 -196.470899)
			(xy 188.531894 -196.431978) (xy 188.50198 -196.388519) (xy 188.478339 -196.341353) (xy 188.461423 -196.291379)
			(xy 188.456062 -196.265546) (xy 188.453318 -196.254545) (xy 188.439874 -196.236327) (xy 188.430154 -196.230494)
			(xy 188.401706 -196.215) (xy 188.391513 -196.210098) (xy 188.368964 -196.208775) (xy 188.358272 -196.21246)
			(xy 188.333634 -196.221604) (xy 188.33854 -196.243693) (xy 188.343762 -196.288641) (xy 188.344048 -196.311266)
			(xy 188.343563 -196.339095) (xy 188.335573 -196.394176) (xy 188.319754 -196.447538) (xy 188.296434 -196.498074)
			(xy 188.266096 -196.544737) (xy 188.22937 -196.586558) (xy 188.187018 -196.622669) (xy 188.139918 -196.652323)
			(xy 188.114686 -196.664072) (xy 188.10349 -196.669725) (xy 188.088034 -196.689441) (xy 188.085222 -196.701664)
			(xy 188.080904 -196.72681) (xy 188.079638 -196.737244) (xy 188.084653 -196.757634) (xy 188.097389 -196.774327)
			(xy 188.106304 -196.779896) (xy 188.147198 -196.802756) (xy 188.157171 -196.807647) (xy 188.179301 -196.809223)
			(xy 188.18987 -196.805804) (xy 188.190378 -196.80555) (xy 188.21019 -196.79793) (xy 188.216794 -196.792088)
			(xy 188.237694 -196.774683) (xy 188.283493 -196.745352) (xy 188.332993 -196.722821) (xy 188.385191 -196.707548)
			(xy 188.439029 -196.699842) (xy 188.466222 -196.699378) (xy 188.493473 -196.699865) (xy 188.547421 -196.707625)
			(xy 188.599715 -196.722982) (xy 188.649291 -196.745625) (xy 188.69514 -196.775093) (xy 188.736329 -196.810786)
			(xy 188.77202 -196.851977) (xy 188.801485 -196.897828) (xy 188.824125 -196.947406) (xy 188.83948 -196.999701)
			(xy 188.847236 -197.053649) (xy 188.847236 -197.108151) (xy 188.83948 -197.162099) (xy 188.824125 -197.214394)
			(xy 188.801485 -197.263972) (xy 188.77202 -197.309823) (xy 188.736329 -197.351014) (xy 188.69514 -197.386707)
			(xy 188.649291 -197.416175) (xy 188.599715 -197.438818) (xy 188.547421 -197.454175) (xy 188.493473 -197.461935)
			(xy 188.466222 -197.462394) (xy 188.436825 -197.461852) (xy 188.378727 -197.45283) (xy 188.322702 -197.434997)
			(xy 188.270079 -197.408776) (xy 188.222104 -197.374788) (xy 188.179916 -197.333838) (xy 188.144513 -197.286897)
			(xy 188.13018 -197.261226) (xy 188.122306 -197.247002) (xy 188.09335 -197.232524) (xy 188.025786 -197.243446)
			(xy 188.015445 -197.245599) (xy 187.997679 -197.256979) (xy 187.986006 -197.274554) (xy 187.983622 -197.284848)
			(xy 187.895738 -197.790308) (xy 187.894245 -197.801963) (xy 187.900802 -197.824498) (xy 187.91672 -197.841743)
			(xy 187.927488 -197.846442) (xy 187.936239 -197.849591) (xy 187.954513 -197.853036) (xy 187.96381 -197.8533)
		)
		(stroke
			(width 0)
			(type solid)
		)
		(fill yes)
		(layer "In7.Cu")
		(net "GND")
	)
	(gr_poly
		(pts
			(xy 276.916642 -227.491036) (xy 276.927159 -227.490521) (xy 276.946454 -227.482142) (xy 276.95398 -227.47478)
			(xy 276.954234 -227.474526) (xy 276.960935 -227.466461) (xy 276.96775 -227.446654) (xy 276.967442 -227.436172)
			(xy 276.820376 -225.617786) (xy 276.17801 -217.66403) (xy 274.95881 -202.56881) (xy 274.441666 -196.167502)
			(xy 274.2692 -194.031616) (xy 274.086066 -191.765428) (xy 272.697194 -174.570136) (xy 272.697194 -174.569628)
			(xy 272.695416 -174.55007) (xy 272.461736 -171.656502) (xy 271.819878 -163.70554) (xy 271.818608 -163.686744)
			(xy 271.228566 -154.084528) (xy 271.228566 -154.083512) (xy 270.430752 -143.940784) (xy 270.430752 -143.93926)
			(xy 270.14043 -141.181328) (xy 270.137961 -141.156127) (xy 270.135293 -141.105556) (xy 270.135096 -141.080236)
			(xy 270.129254 -138.52398) (xy 270.129 -138.521694) (xy 270.129298 -138.488186) (xy 270.133875 -138.421326)
			(xy 270.138144 -138.38809) (xy 270.296132 -137.228834) (xy 270.296991 -137.219909) (xy 270.293133 -137.202411)
			(xy 270.283474 -137.187318) (xy 270.276574 -137.18159) (xy 270.27632 -137.181336) (xy 270.233394 -137.149078)
			(xy 270.203676 -137.12698) (xy 270.195548 -137.122408) (xy 270.154654 -137.122408) (xy 270.145256 -137.126472)
			(xy 270.11703 -137.137746) (xy 270.058354 -137.1536) (xy 269.9981 -137.161578) (xy 269.96771 -137.162032)
			(xy 269.957042 -137.162286) (xy 269.927522 -137.161144) (xy 269.869128 -137.152198) (xy 269.812369 -137.135816)
			(xy 269.758188 -137.11227) (xy 269.707485 -137.081952) (xy 269.661102 -137.045365) (xy 269.61981 -137.003116)
			(xy 269.584294 -136.955908) (xy 269.555144 -136.904525) (xy 269.532845 -136.849819) (xy 269.517766 -136.7927)
			(xy 269.510158 -136.734116) (xy 269.509748 -136.704578) (xy 269.509748 -135.840724) (xy 269.510236 -135.810765)
			(xy 269.518051 -135.751358) (xy 269.53355 -135.693479) (xy 269.556468 -135.638118) (xy 269.586414 -135.586219)
			(xy 269.622876 -135.538672) (xy 269.66523 -135.496289) (xy 269.712751 -135.459794) (xy 269.764628 -135.429811)
			(xy 269.819974 -135.406853) (xy 269.877842 -135.391314) (xy 269.937243 -135.383457) (xy 269.967202 -135.383016)
			(xy 269.96771 -135.383016) (xy 269.997345 -135.383489) (xy 270.05612 -135.391139) (xy 270.113419 -135.406298)
			(xy 270.168288 -135.428713) (xy 270.194278 -135.44296) (xy 270.202661 -135.447295) (xy 270.221321 -135.45002)
			(xy 270.2306 -135.448294) (xy 270.26108 -135.441436) (xy 270.270064 -135.438988) (xy 270.28557 -135.428705)
			(xy 270.291306 -135.42137) (xy 270.308249 -135.398503) (xy 270.347802 -135.357586) (xy 270.393003 -135.323009)
			(xy 270.442846 -135.295542) (xy 270.49622 -135.275797) (xy 270.52397 -135.269478) (xy 270.52905 -135.268208)
			(xy 270.55826 -135.237474) (xy 270.563565 -135.231523) (xy 270.570442 -135.217148) (xy 270.571722 -135.20928)
			(xy 270.89862 -132.811774) (xy 270.89862 -132.81025) (xy 270.995648 -131.91236) (xy 270.995902 -131.90728)
			(xy 271.12849 -119.60606) (xy 271.12849 -119.604028) (xy 270.740632 -106.795062) (xy 270.69161 -105.30078)
			(xy 270.685514 -105.120186) (xy 270.685514 -105.117646) (xy 270.6243 -104.356154) (xy 270.601694 -104.356916)
			(xy 270.57442 -104.356457) (xy 270.520427 -104.348698) (xy 270.46809 -104.333324) (xy 270.418479 -104.310649)
			(xy 270.372604 -104.281136) (xy 270.331404 -104.245387) (xy 270.295717 -104.204132) (xy 270.280638 -104.181402)
			(xy 270.27498 -104.173423) (xy 270.259029 -104.162134) (xy 270.240015 -104.157626) (xy 270.220693 -104.160553)
			(xy 270.212058 -104.165146) (xy 270.184505 -104.181879) (xy 270.125699 -104.208288) (xy 270.063769 -104.226184)
			(xy 269.999942 -104.235216) (xy 269.96771 -104.235758) (xy 269.937724 -104.235289) (xy 269.878265 -104.227463)
			(xy 269.820336 -104.211942) (xy 269.764929 -104.188992) (xy 269.712991 -104.159007) (xy 269.665412 -104.122499)
			(xy 269.623005 -104.080092) (xy 269.586496 -104.032514) (xy 269.55651 -103.980576) (xy 269.53356 -103.925169)
			(xy 269.518038 -103.867241) (xy 269.510211 -103.807782) (xy 269.509748 -103.777796) (xy 269.509748 -102.914196)
			(xy 269.510217 -102.884211) (xy 269.518046 -102.824753) (xy 269.533568 -102.766826) (xy 269.556518 -102.711421)
			(xy 269.586504 -102.659486) (xy 269.623013 -102.611908) (xy 269.665419 -102.569503) (xy 269.712997 -102.532996)
			(xy 269.764934 -102.503012) (xy 269.82034 -102.480063) (xy 269.878267 -102.464543) (xy 269.937725 -102.456716)
			(xy 269.96771 -102.456234) (xy 269.968218 -102.456234) (xy 269.999406 -102.456758) (xy 270.061203 -102.465226)
			(xy 270.121276 -102.482015) (xy 270.178509 -102.506815) (xy 270.205454 -102.522528) (xy 270.211296 -102.526084)
			(xy 270.218154 -102.528116) (xy 270.227775 -102.530337) (xy 270.247378 -102.528122) (xy 270.256254 -102.523798)
			(xy 270.274796 -102.513638) (xy 270.283432 -102.505764) (xy 270.286988 -102.500684) (xy 270.30664 -102.473359)
			(xy 270.353914 -102.425459) (xy 270.380968 -102.405434) (xy 270.395118 -102.395631) (xy 270.424884 -102.378336)
			(xy 270.440404 -102.37089) (xy 270.441166 -102.370382) (xy 270.447262 -102.367588) (xy 270.462502 -102.34041)
			(xy 270.32712 -100.65639) (xy 270.326152 -100.648291) (xy 270.319793 -100.633279) (xy 270.314674 -100.626926)
			(xy 270.291306 -100.597208) (xy 270.285582 -100.589856) (xy 270.270081 -100.579546) (xy 270.26108 -100.577142)
			(xy 270.230854 -100.570284) (xy 270.221576 -100.568647) (xy 270.202955 -100.571395) (xy 270.194532 -100.575618)
			(xy 270.168522 -100.589914) (xy 270.113603 -100.612418) (xy 270.056237 -100.627643) (xy 269.997386 -100.635333)
			(xy 269.96771 -100.635816) (xy 269.967202 -100.635816) (xy 269.954603 -100.635722) (xy 269.929442 -100.634324)
			(xy 269.91691 -100.633022) (xy 269.886755 -100.629157) (xy 269.827758 -100.614479) (xy 269.771222 -100.592124)
			(xy 269.718141 -100.562485) (xy 269.669448 -100.526083) (xy 269.626 -100.483558) (xy 269.588561 -100.435658)
			(xy 269.557789 -100.383225) (xy 269.534225 -100.327182) (xy 269.518284 -100.268514) (xy 269.510246 -100.208252)
			(xy 269.509748 -100.177854) (xy 269.509748 -99.314254) (xy 269.510241 -99.284272) (xy 269.518073 -99.224821)
			(xy 269.533598 -99.166902) (xy 269.55655 -99.111504) (xy 269.586536 -99.059575) (xy 269.623043 -99.012005)
			(xy 269.665447 -98.969606) (xy 269.713022 -98.933105) (xy 269.764954 -98.903125) (xy 269.820355 -98.88018)
			(xy 269.878276 -98.864663) (xy 269.937728 -98.856837) (xy 269.96771 -98.856292) (xy 269.981333 -98.856408)
			(xy 270.008529 -98.858064) (xy 270.022066 -98.859594) (xy 270.040994 -98.862098) (xy 270.078381 -98.869852)
			(xy 270.096742 -98.875088) (xy 270.096996 -98.875088) (xy 270.103854 -98.87712) (xy 270.108934 -98.878644)
			(xy 270.133318 -98.873564) (xy 270.134588 -98.872548) (xy 270.160242 -98.851466) (xy 270.16954 -98.843227)
			(xy 270.179385 -98.820451) (xy 270.179038 -98.808032) (xy 270.07947 -97.569528) (xy 270.07778 -97.557001)
			(xy 270.064041 -97.535822) (xy 270.053308 -97.529142) (xy 270.034004 -97.51822) (xy 270.026638 -97.514918)
			(xy 270.016365 -97.511707) (xy 269.994917 -97.513267) (xy 269.985236 -97.517966) (xy 269.984982 -97.517966)
			(xy 269.957454 -97.5318) (xy 269.89904 -97.551377) (xy 269.838239 -97.561305) (xy 269.807436 -97.561908)
			(xy 269.780181 -97.561447) (xy 269.726227 -97.553694) (xy 269.673924 -97.538341) (xy 269.62434 -97.515701)
			(xy 269.578482 -97.486234) (xy 269.537285 -97.45054) (xy 269.501588 -97.409347) (xy 269.472116 -97.363492)
			(xy 269.449471 -97.313909) (xy 269.434113 -97.261609) (xy 269.426355 -97.207654) (xy 269.426355 -97.153146)
			(xy 269.434113 -97.099191) (xy 269.449471 -97.046891) (xy 269.472116 -96.997308) (xy 269.501588 -96.951453)
			(xy 269.537285 -96.91026) (xy 269.578482 -96.874566) (xy 269.62434 -96.845099) (xy 269.673924 -96.822459)
			(xy 269.726227 -96.807106) (xy 269.780181 -96.799353) (xy 269.807436 -96.798892) (xy 269.808198 -96.798892)
			(xy 269.839179 -96.79954) (xy 269.900315 -96.809626) (xy 269.929864 -96.818958) (xy 269.934944 -96.820736)
			(xy 269.946097 -96.82258) (xy 269.968115 -96.817583) (xy 269.977362 -96.811084) (xy 269.99438 -96.797876)
			(xy 270.003918 -96.789534) (xy 270.014052 -96.766345) (xy 270.013684 -96.75368) (xy 269.999968 -96.578674)
			(xy 269.998468 -96.567172) (xy 269.986694 -96.547212) (xy 269.977362 -96.54032) (xy 269.967456 -96.533716)
			(xy 269.964408 -96.531684) (xy 269.955629 -96.52728) (xy 269.936165 -96.524798) (xy 269.926562 -96.526858)
			(xy 269.924022 -96.52762) (xy 269.895631 -96.536141) (xy 269.837073 -96.545327) (xy 269.807436 -96.545908)
			(xy 269.780181 -96.545447) (xy 269.726227 -96.537694) (xy 269.673924 -96.522341) (xy 269.62434 -96.499701)
			(xy 269.578482 -96.470234) (xy 269.537285 -96.43454) (xy 269.501588 -96.393347) (xy 269.472116 -96.347492)
			(xy 269.449471 -96.297909) (xy 269.434113 -96.245609) (xy 269.426355 -96.191654) (xy 269.426355 -96.137146)
			(xy 269.434113 -96.083191) (xy 269.449471 -96.030891) (xy 269.472116 -95.981308) (xy 269.501588 -95.935453)
			(xy 269.537285 -95.89426) (xy 269.578482 -95.858566) (xy 269.62434 -95.829099) (xy 269.673924 -95.806459)
			(xy 269.726227 -95.791106) (xy 269.780181 -95.783353) (xy 269.807436 -95.782892) (xy 269.808198 -95.782892)
			(xy 269.823118 -95.783016) (xy 269.852871 -95.785303) (xy 269.867634 -95.787464) (xy 269.878504 -95.788088)
			(xy 269.899149 -95.781232) (xy 269.907512 -95.774256) (xy 269.908528 -95.77324) (xy 269.915386 -95.76689)
			(xy 269.923449 -95.758602) (xy 269.93176 -95.737047) (xy 269.931388 -95.725488) (xy 269.898622 -95.318326)
			(xy 269.897577 -95.309887) (xy 269.890665 -95.29436) (xy 269.879059 -95.281944) (xy 269.871698 -95.277686)
			(xy 269.85341 -95.26778) (xy 269.847704 -95.265009) (xy 269.835369 -95.262063) (xy 269.829026 -95.261938)
			(xy 269.816326 -95.261938) (xy 269.804896 -95.268288) (xy 269.781984 -95.280572) (xy 269.73301 -95.298002)
			(xy 269.681789 -95.306871) (xy 269.655798 -95.307404) (xy 265.146028 -95.307404) (xy 265.135964 -95.307841)
			(xy 265.117379 -95.315574) (xy 265.10996 -95.32239) (xy 264.211562 -96.220788) (xy 264.204707 -96.228183)
			(xy 264.196958 -96.246781) (xy 264.196576 -96.256856) (xy 264.196576 -96.783144) (xy 264.200132 -96.792034)
			(xy 264.235108 -96.883119) (xy 264.299106 -97.067462) (xy 264.356218 -97.254053) (xy 264.406366 -97.442636)
			(xy 264.449481 -97.632949) (xy 264.485504 -97.824732) (xy 264.514385 -98.017719) (xy 264.536084 -98.211645)
			(xy 264.550572 -98.406243) (xy 264.557828 -98.601244) (xy 264.558272 -98.698812) (xy 264.558272 -98.700082)
			(xy 264.557778 -98.802057) (xy 264.549869 -99.005854) (xy 264.534065 -99.209191) (xy 264.510388 -99.411763)
			(xy 264.478873 -99.613263) (xy 264.43957 -99.813391) (xy 264.392536 -100.011844) (xy 264.337842 -100.208324)
			(xy 264.27557 -100.402535) (xy 264.205815 -100.594186) (xy 264.128681 -100.782987) (xy 264.044284 -100.968656)
			(xy 263.952752 -101.150913) (xy 263.854221 -101.329483) (xy 263.74884 -101.504099) (xy 263.636767 -101.674497)
			(xy 263.518171 -101.840421) (xy 263.406655 -101.984302) (xy 267.47724 -101.984302) (xy 267.47724 -101.120702)
			(xy 267.47773 -101.090718) (xy 267.485558 -101.031262) (xy 267.501079 -100.973337) (xy 267.524028 -100.917933)
			(xy 267.554012 -100.865999) (xy 267.590518 -100.818423) (xy 267.632923 -100.776018) (xy 267.680499 -100.739512)
			(xy 267.732433 -100.709528) (xy 267.787837 -100.686579) (xy 267.845762 -100.671058) (xy 267.905218 -100.66323)
			(xy 267.965186 -100.66323) (xy 268.024642 -100.671058) (xy 268.082567 -100.686579) (xy 268.137971 -100.709528)
			(xy 268.189905 -100.739512) (xy 268.237481 -100.776018) (xy 268.279886 -100.818423) (xy 268.316392 -100.865999)
			(xy 268.346376 -100.917933) (xy 268.369325 -100.973337) (xy 268.384846 -101.031262) (xy 268.392674 -101.090718)
			(xy 268.393164 -101.120702) (xy 268.393164 -101.984302) (xy 268.392674 -102.014286) (xy 268.384846 -102.073742)
			(xy 268.369325 -102.131667) (xy 268.346376 -102.187071) (xy 268.316392 -102.239005) (xy 268.279886 -102.286581)
			(xy 268.237481 -102.328986) (xy 268.189905 -102.365492) (xy 268.137971 -102.395476) (xy 268.082567 -102.418425)
			(xy 268.024642 -102.433946) (xy 267.965186 -102.441774) (xy 267.905218 -102.441774) (xy 267.845762 -102.433946)
			(xy 267.787837 -102.418425) (xy 267.732433 -102.395476) (xy 267.680499 -102.365492) (xy 267.632923 -102.328986)
			(xy 267.590518 -102.286581) (xy 267.554012 -102.239005) (xy 267.524028 -102.187071) (xy 267.501079 -102.131667)
			(xy 267.485558 -102.073742) (xy 267.47773 -102.014286) (xy 267.47724 -101.984302) (xy 263.406655 -101.984302)
			(xy 263.393231 -102.001622) (xy 263.262135 -102.157857) (xy 263.125078 -102.308891) (xy 262.982269 -102.454497)
			(xy 262.833921 -102.594457) (xy 262.680257 -102.728558) (xy 262.521509 -102.856601) (xy 262.357916 -102.978392)
			(xy 262.189723 -103.093747) (xy 262.017184 -103.202495) (xy 261.840558 -103.30447) (xy 261.66011 -103.39952)
			(xy 261.476113 -103.487501) (xy 261.288842 -103.568282) (xy 261.09858 -103.64174) (xy 260.905613 -103.707766)
			(xy 260.710231 -103.766259) (xy 260.512727 -103.817133) (xy 260.3134 -103.86031) (xy 260.112548 -103.895725)
			(xy 259.910474 -103.923326) (xy 259.707481 -103.943071) (xy 259.503876 -103.95493) (xy 259.299964 -103.958885)
			(xy 259.096052 -103.95493) (xy 258.892447 -103.943071) (xy 258.689454 -103.923326) (xy 258.48738 -103.895725)
			(xy 258.286528 -103.86031) (xy 258.087201 -103.817133) (xy 257.889697 -103.766259) (xy 257.694315 -103.707766)
			(xy 257.501348 -103.64174) (xy 257.311086 -103.568282) (xy 257.123815 -103.487501) (xy 256.939818 -103.39952)
			(xy 256.75937 -103.30447) (xy 256.582744 -103.202495) (xy 256.410205 -103.093747) (xy 256.242012 -102.978392)
			(xy 256.078419 -102.856601) (xy 255.919671 -102.728558) (xy 255.766007 -102.594457) (xy 255.617659 -102.454497)
			(xy 255.47485 -102.308891) (xy 255.337793 -102.157857) (xy 255.206697 -102.001622) (xy 255.081757 -101.840421)
			(xy 254.963161 -101.674497) (xy 254.851088 -101.504099) (xy 254.745707 -101.329483) (xy 254.647176 -101.150913)
			(xy 254.555644 -100.968656) (xy 254.471247 -100.782987) (xy 254.394113 -100.594186) (xy 254.324358 -100.402535)
			(xy 254.262086 -100.208324) (xy 254.207392 -100.011844) (xy 254.160358 -99.813391) (xy 254.121055 -99.613263)
			(xy 254.08954 -99.411763) (xy 254.065863 -99.209191) (xy 254.050059 -99.005854) (xy 254.04215 -98.802057)
			(xy 254.041656 -98.700082) (xy 254.041656 -98.69932) (xy 254.042167 -98.596418) (xy 254.050241 -98.390772)
			(xy 254.066355 -98.185599) (xy 254.090482 -97.981214) (xy 254.122588 -97.777929) (xy 254.162621 -97.576056)
			(xy 254.210522 -97.375904) (xy 254.266216 -97.177779) (xy 254.329619 -96.981984) (xy 254.400634 -96.78882)
			(xy 254.479151 -96.598582) (xy 254.56505 -96.411561) (xy 254.6582 -96.228044) (xy 254.758459 -96.048312)
			(xy 254.865672 -95.87264) (xy 254.922274 -95.786702) (xy 254.932434 -95.771462) (xy 254.928878 -95.735648)
			(xy 254.51562 -95.32239) (xy 254.508222 -95.315546) (xy 254.489622 -95.307827) (xy 254.479552 -95.307404)
			(xy 250.265946 -95.307404) (xy 250.25588 -95.307837) (xy 250.23729 -95.315566) (xy 250.229878 -95.32239)
			(xy 249.642376 -95.909892) (xy 249.636118 -95.916651) (xy 249.628504 -95.933407) (xy 249.627359 -95.951775)
			(xy 249.629676 -95.960692) (xy 251.936504 -103.572056) (xy 251.951236 -103.588566) (xy 251.95911 -103.591868)
			(xy 251.984929 -103.603051) (xy 252.033235 -103.631899) (xy 252.076775 -103.667536) (xy 252.114604 -103.709185)
			(xy 252.1459 -103.755943) (xy 252.169981 -103.806794) (xy 252.186327 -103.860632) (xy 252.19458 -103.916288)
			(xy 252.195076 -103.94442) (xy 252.195076 -103.947976) (xy 252.194568 -103.961692) (xy 252.194568 -103.9622)
			(xy 252.192888 -103.988886) (xy 252.182996 -104.041434) (xy 252.165871 -104.092087) (xy 252.141847 -104.139857)
			(xy 252.127004 -104.162098) (xy 252.126496 -104.163114) (xy 252.119384 -104.173782) (xy 252.119384 -104.174798)
			(xy 252.54667 -105.584498) (xy 266.86764 -105.584498) (xy 266.86764 -104.720898) (xy 266.86813 -104.690914)
			(xy 266.875958 -104.631458) (xy 266.891479 -104.573533) (xy 266.914428 -104.518129) (xy 266.944412 -104.466195)
			(xy 266.980918 -104.418619) (xy 267.023323 -104.376214) (xy 267.070899 -104.339708) (xy 267.122833 -104.309724)
			(xy 267.178237 -104.286775) (xy 267.236162 -104.271254) (xy 267.295618 -104.263426) (xy 267.355586 -104.263426)
			(xy 267.415042 -104.271254) (xy 267.472967 -104.286775) (xy 267.528371 -104.309724) (xy 267.580305 -104.339708)
			(xy 267.627881 -104.376214) (xy 267.670286 -104.418619) (xy 267.706792 -104.466195) (xy 267.736776 -104.518129)
			(xy 267.759725 -104.573533) (xy 267.775246 -104.631458) (xy 267.783074 -104.690914) (xy 267.783564 -104.720898)
			(xy 267.783564 -105.584498) (xy 267.783074 -105.614482) (xy 267.775246 -105.673938) (xy 267.759725 -105.731863)
			(xy 267.736776 -105.787267) (xy 267.706792 -105.839201) (xy 267.670286 -105.886777) (xy 267.627881 -105.929182)
			(xy 267.580305 -105.965688) (xy 267.528371 -105.995672) (xy 267.472967 -106.018621) (xy 267.415042 -106.034142)
			(xy 267.355586 -106.04197) (xy 267.295618 -106.04197) (xy 267.236162 -106.034142) (xy 267.178237 -106.018621)
			(xy 267.122833 -105.995672) (xy 267.070899 -105.965688) (xy 267.023323 -105.929182) (xy 266.980918 -105.886777)
			(xy 266.944412 -105.839201) (xy 266.914428 -105.787267) (xy 266.891479 -105.731863) (xy 266.875958 -105.673938)
			(xy 266.86813 -105.614482) (xy 266.86764 -105.584498) (xy 252.54667 -105.584498) (xy 253.090209 -107.377738)
			(xy 269.509748 -107.377738) (xy 269.509748 -106.514138) (xy 269.510238 -106.484154) (xy 269.518066 -106.424698)
			(xy 269.533587 -106.366773) (xy 269.556536 -106.311369) (xy 269.58652 -106.259435) (xy 269.623026 -106.211859)
			(xy 269.665431 -106.169454) (xy 269.713007 -106.132948) (xy 269.764941 -106.102964) (xy 269.820345 -106.080015)
			(xy 269.87827 -106.064494) (xy 269.937726 -106.056666) (xy 269.997694 -106.056666) (xy 270.05715 -106.064494)
			(xy 270.115075 -106.080015) (xy 270.170479 -106.102964) (xy 270.222413 -106.132948) (xy 270.269989 -106.169454)
			(xy 270.312394 -106.211859) (xy 270.3489 -106.259435) (xy 270.378884 -106.311369) (xy 270.401833 -106.366773)
			(xy 270.417354 -106.424698) (xy 270.425182 -106.484154) (xy 270.425672 -106.514138) (xy 270.425672 -107.377738)
			(xy 270.425182 -107.407722) (xy 270.417354 -107.467178) (xy 270.401833 -107.525103) (xy 270.378884 -107.580507)
			(xy 270.3489 -107.632441) (xy 270.312394 -107.680017) (xy 270.269989 -107.722422) (xy 270.222413 -107.758928)
			(xy 270.170479 -107.788912) (xy 270.115075 -107.811861) (xy 270.05715 -107.827382) (xy 269.997694 -107.83521)
			(xy 269.937726 -107.83521) (xy 269.87827 -107.827382) (xy 269.820345 -107.811861) (xy 269.764941 -107.788912)
			(xy 269.713007 -107.758928) (xy 269.665431 -107.722422) (xy 269.623026 -107.680017) (xy 269.58652 -107.632441)
			(xy 269.556536 -107.580507) (xy 269.533587 -107.525103) (xy 269.518066 -107.467178) (xy 269.510238 -107.407722)
			(xy 269.509748 -107.377738) (xy 253.090209 -107.377738) (xy 253.414022 -108.446062) (xy 253.639456 -109.18444)
			(xy 266.86764 -109.18444) (xy 266.86764 -108.32084) (xy 266.86813 -108.290856) (xy 266.875958 -108.2314)
			(xy 266.891479 -108.173475) (xy 266.914428 -108.118071) (xy 266.944412 -108.066137) (xy 266.980918 -108.018561)
			(xy 267.023323 -107.976156) (xy 267.070899 -107.93965) (xy 267.122833 -107.909666) (xy 267.178237 -107.886717)
			(xy 267.236162 -107.871196) (xy 267.295618 -107.863368) (xy 267.355586 -107.863368) (xy 267.415042 -107.871196)
			(xy 267.472967 -107.886717) (xy 267.528371 -107.909666) (xy 267.580305 -107.93965) (xy 267.627881 -107.976156)
			(xy 267.670286 -108.018561) (xy 267.706792 -108.066137) (xy 267.736776 -108.118071) (xy 267.759725 -108.173475)
			(xy 267.775246 -108.2314) (xy 267.783074 -108.290856) (xy 267.783564 -108.32084) (xy 267.783564 -109.18444)
			(xy 267.783074 -109.214424) (xy 267.775246 -109.27388) (xy 267.759725 -109.331805) (xy 267.736776 -109.387209)
			(xy 267.706792 -109.439143) (xy 267.670286 -109.486719) (xy 267.627881 -109.529124) (xy 267.580305 -109.56563)
			(xy 267.528371 -109.595614) (xy 267.472967 -109.618563) (xy 267.415042 -109.634084) (xy 267.355586 -109.641912)
			(xy 267.295618 -109.641912) (xy 267.236162 -109.634084) (xy 267.178237 -109.618563) (xy 267.122833 -109.595614)
			(xy 267.070899 -109.56563) (xy 267.023323 -109.529124) (xy 266.980918 -109.486719) (xy 266.944412 -109.439143)
			(xy 266.914428 -109.387209) (xy 266.891479 -109.331805) (xy 266.875958 -109.27388) (xy 266.86813 -109.214424)
			(xy 266.86764 -109.18444) (xy 253.639456 -109.18444) (xy 254.187026 -110.977934) (xy 269.509748 -110.977934)
			(xy 269.509748 -110.114334) (xy 269.510238 -110.08435) (xy 269.518066 -110.024894) (xy 269.533587 -109.966969)
			(xy 269.556536 -109.911565) (xy 269.58652 -109.859631) (xy 269.623026 -109.812055) (xy 269.665431 -109.76965)
			(xy 269.713007 -109.733144) (xy 269.764941 -109.70316) (xy 269.820345 -109.680211) (xy 269.87827 -109.66469)
			(xy 269.937726 -109.656862) (xy 269.997694 -109.656862) (xy 270.05715 -109.66469) (xy 270.115075 -109.680211)
			(xy 270.170479 -109.70316) (xy 270.222413 -109.733144) (xy 270.269989 -109.76965) (xy 270.312394 -109.812055)
			(xy 270.3489 -109.859631) (xy 270.378884 -109.911565) (xy 270.401833 -109.966969) (xy 270.417354 -110.024894)
			(xy 270.425182 -110.08435) (xy 270.425672 -110.114334) (xy 270.425672 -110.977934) (xy 270.425182 -111.007918)
			(xy 270.417354 -111.067374) (xy 270.401833 -111.125299) (xy 270.378884 -111.180703) (xy 270.3489 -111.232637)
			(xy 270.312394 -111.280213) (xy 270.269989 -111.322618) (xy 270.222413 -111.359124) (xy 270.170479 -111.389108)
			(xy 270.115075 -111.412057) (xy 270.05715 -111.427578) (xy 269.997694 -111.435406) (xy 269.937726 -111.435406)
			(xy 269.87827 -111.427578) (xy 269.820345 -111.412057) (xy 269.764941 -111.389108) (xy 269.713007 -111.359124)
			(xy 269.665431 -111.322618) (xy 269.623026 -111.280213) (xy 269.58652 -111.232637) (xy 269.556536 -111.180703)
			(xy 269.533587 -111.125299) (xy 269.518066 -111.067374) (xy 269.510238 -111.007918) (xy 269.509748 -110.977934)
			(xy 254.187026 -110.977934) (xy 254.691092 -112.628934) (xy 256.713734 -112.628934) (xy 256.717805 -112.573312)
			(xy 256.729931 -112.518875) (xy 256.749854 -112.466784) (xy 256.77715 -112.418149) (xy 256.811236 -112.374006)
			(xy 256.851385 -112.335297) (xy 256.896743 -112.302846) (xy 256.946343 -112.277345) (xy 256.999127 -112.259338)
			(xy 257.05397 -112.249208) (xy 257.109704 -112.247171) (xy 257.165141 -112.253271) (xy 257.219098 -112.267377)
			(xy 257.270427 -112.289189) (xy 257.318033 -112.318243) (xy 257.360901 -112.353918) (xy 257.398118 -112.395455)
			(xy 257.428891 -112.441968) (xy 257.452563 -112.492465) (xy 257.468631 -112.545872) (xy 257.476751 -112.601048)
			(xy 257.47726 -112.628934) (xy 257.476751 -112.65682) (xy 257.468631 -112.711996) (xy 257.452563 -112.765403)
			(xy 257.443666 -112.784382) (xy 266.86764 -112.784382) (xy 266.86764 -111.920782) (xy 266.86813 -111.890798)
			(xy 266.875958 -111.831342) (xy 266.891479 -111.773417) (xy 266.914428 -111.718013) (xy 266.944412 -111.666079)
			(xy 266.980918 -111.618503) (xy 267.023323 -111.576098) (xy 267.070899 -111.539592) (xy 267.122833 -111.509608)
			(xy 267.178237 -111.486659) (xy 267.236162 -111.471138) (xy 267.295618 -111.46331) (xy 267.355586 -111.46331)
			(xy 267.415042 -111.471138) (xy 267.472967 -111.486659) (xy 267.528371 -111.509608) (xy 267.580305 -111.539592)
			(xy 267.627881 -111.576098) (xy 267.670286 -111.618503) (xy 267.706792 -111.666079) (xy 267.736776 -111.718013)
			(xy 267.759725 -111.773417) (xy 267.775246 -111.831342) (xy 267.783074 -111.890798) (xy 267.783564 -111.920782)
			(xy 267.783564 -112.784382) (xy 267.783074 -112.814366) (xy 267.775246 -112.873822) (xy 267.759725 -112.931747)
			(xy 267.736776 -112.987151) (xy 267.706792 -113.039085) (xy 267.670286 -113.086661) (xy 267.627881 -113.129066)
			(xy 267.580305 -113.165572) (xy 267.528371 -113.195556) (xy 267.472967 -113.218505) (xy 267.415042 -113.234026)
			(xy 267.355586 -113.241854) (xy 267.295618 -113.241854) (xy 267.236162 -113.234026) (xy 267.178237 -113.218505)
			(xy 267.122833 -113.195556) (xy 267.070899 -113.165572) (xy 267.023323 -113.129066) (xy 266.980918 -113.086661)
			(xy 266.944412 -113.039085) (xy 266.914428 -112.987151) (xy 266.891479 -112.931747) (xy 266.875958 -112.873822)
			(xy 266.86813 -112.814366) (xy 266.86764 -112.784382) (xy 257.443666 -112.784382) (xy 257.428891 -112.8159)
			(xy 257.398118 -112.862413) (xy 257.360901 -112.90395) (xy 257.318033 -112.939625) (xy 257.270427 -112.968679)
			(xy 257.219098 -112.990491) (xy 257.165141 -113.004597) (xy 257.109704 -113.010697) (xy 257.05397 -113.00866)
			(xy 256.999127 -112.99853) (xy 256.946343 -112.980523) (xy 256.896743 -112.955022) (xy 256.851385 -112.922571)
			(xy 256.811236 -112.883862) (xy 256.77715 -112.839719) (xy 256.749854 -112.791084) (xy 256.729931 -112.738993)
			(xy 256.717805 -112.684556) (xy 256.713734 -112.628934) (xy 254.691092 -112.628934) (xy 255.86849 -116.485345)
			(xy 268.744349 -116.485345) (xy 268.752108 -116.431389) (xy 268.767466 -116.379086) (xy 268.790113 -116.329503)
			(xy 268.819585 -116.283646) (xy 268.855285 -116.242452) (xy 268.896483 -116.206758) (xy 268.942343 -116.177291)
			(xy 268.99193 -116.15465) (xy 269.044234 -116.139298) (xy 269.098191 -116.131546) (xy 269.125446 -116.131086)
			(xy 269.151761 -116.131527) (xy 269.20389 -116.138768) (xy 269.254533 -116.153093) (xy 269.302732 -116.17423)
			(xy 269.347575 -116.20178) (xy 269.388214 -116.235223) (xy 269.40637 -116.254276) (xy 269.413904 -116.261663)
			(xy 269.433174 -116.270197) (xy 269.443708 -116.270786) (xy 269.518384 -116.270786) (xy 269.528935 -116.270266)
			(xy 269.54823 -116.261725) (xy 269.555722 -116.254276) (xy 269.572729 -116.236404) (xy 269.610562 -116.204739)
			(xy 269.652166 -116.178223) (xy 269.67434 -116.167408) (xy 269.6845 -116.162582) (xy 269.698724 -116.145818)
			(xy 269.72514 -116.049044) (xy 269.721584 -116.027708) (xy 269.715234 -116.018564) (xy 269.715234 -116.01831)
			(xy 269.699661 -115.994468) (xy 269.675007 -115.943136) (xy 269.658245 -115.888714) (xy 269.649744 -115.832406)
			(xy 269.649194 -115.803934) (xy 269.649729 -115.775041) (xy 269.658412 -115.717911) (xy 269.675614 -115.662745)
			(xy 269.700941 -115.610805) (xy 269.733813 -115.563281) (xy 269.773479 -115.521259) (xy 269.819031 -115.485703)
			(xy 269.869425 -115.457425) (xy 269.923508 -115.437073) (xy 269.980043 -115.425114) (xy 270.008858 -115.422934)
			(xy 270.01978 -115.422426) (xy 270.039084 -115.412266) (xy 270.09979 -115.335304) (xy 270.105124 -115.314222)
			(xy 270.103092 -115.303554) (xy 270.100249 -115.286807) (xy 270.097194 -115.252975) (xy 270.096996 -115.23599)
			(xy 270.096996 -115.235228) (xy 270.097482 -115.207977) (xy 270.105238 -115.154029) (xy 270.120593 -115.101734)
			(xy 270.143235 -115.052157) (xy 270.172701 -115.006307) (xy 270.208392 -114.965116) (xy 270.249583 -114.929425)
			(xy 270.295433 -114.899959) (xy 270.34501 -114.877317) (xy 270.397305 -114.861962) (xy 270.451253 -114.854206)
			(xy 270.505755 -114.854206) (xy 270.559703 -114.861962) (xy 270.611998 -114.877317) (xy 270.661575 -114.899959)
			(xy 270.707425 -114.929425) (xy 270.748616 -114.965116) (xy 270.784307 -115.006307) (xy 270.813773 -115.052157)
			(xy 270.836415 -115.101734) (xy 270.85177 -115.154029) (xy 270.859526 -115.207977) (xy 270.860012 -115.235228)
			(xy 270.859529 -115.264123) (xy 270.850837 -115.321254) (xy 270.833628 -115.376421) (xy 270.808294 -115.42836)
			(xy 270.775415 -115.475884) (xy 270.735743 -115.517905) (xy 270.690187 -115.55346) (xy 270.639789 -115.581737)
			(xy 270.585703 -115.602089) (xy 270.529165 -115.614049) (xy 270.500348 -115.616228) (xy 270.489426 -115.616736)
			(xy 270.470122 -115.626896) (xy 270.409416 -115.703858) (xy 270.404082 -115.72494) (xy 270.406114 -115.735608)
			(xy 270.408965 -115.752353) (xy 270.412015 -115.786187) (xy 270.41221 -115.803172) (xy 270.41221 -115.803934)
			(xy 270.411729 -115.830916) (xy 270.404107 -115.884341) (xy 270.389035 -115.936158) (xy 270.366813 -115.985336)
			(xy 270.337884 -116.030892) (xy 270.302826 -116.071918) (xy 270.262338 -116.107596) (xy 270.217226 -116.137214)
			(xy 270.193008 -116.14912) (xy 270.182848 -116.153946) (xy 270.168624 -116.17071) (xy 270.142208 -116.267484)
			(xy 270.145764 -116.28882) (xy 270.152114 -116.297964) (xy 270.152114 -116.298218) (xy 270.167693 -116.322057)
			(xy 270.192347 -116.373389) (xy 270.209108 -116.427813) (xy 270.217606 -116.484121) (xy 270.218154 -116.512594)
			(xy 270.217617 -116.539843) (xy 270.209862 -116.593787) (xy 270.19451 -116.646077) (xy 270.171873 -116.695652)
			(xy 270.142412 -116.7415) (xy 270.106726 -116.782689) (xy 270.065542 -116.818381) (xy 270.019697 -116.847848)
			(xy 269.970126 -116.870492) (xy 269.917837 -116.885851) (xy 269.863895 -116.893613) (xy 269.836646 -116.894102)
			(xy 269.810331 -116.89367) (xy 269.758201 -116.886428) (xy 269.707557 -116.872102) (xy 269.659359 -116.850963)
			(xy 269.614516 -116.82341) (xy 269.573878 -116.789966) (xy 269.555722 -116.770912) (xy 269.548193 -116.76352)
			(xy 269.528919 -116.75499) (xy 269.518384 -116.754402) (xy 269.443708 -116.754402) (xy 269.433157 -116.754922)
			(xy 269.413862 -116.763464) (xy 269.40637 -116.770912) (xy 269.388224 -116.789977) (xy 269.347592 -116.823433)
			(xy 269.30275 -116.850991) (xy 269.254547 -116.872127) (xy 269.203898 -116.886442) (xy 269.151763 -116.893665)
			(xy 269.125446 -116.894102) (xy 269.098191 -116.893654) (xy 269.044234 -116.885902) (xy 268.99193 -116.87055)
			(xy 268.942343 -116.847909) (xy 268.896483 -116.818442) (xy 268.855285 -116.782748) (xy 268.819585 -116.741554)
			(xy 268.790113 -116.695697) (xy 268.767466 -116.646114) (xy 268.752108 -116.593811) (xy 268.74435 -116.539855)
			(xy 268.744349 -116.485345) (xy 255.86849 -116.485345) (xy 256.255944 -117.7544) (xy 269.288004 -117.7544)
			(xy 269.292075 -117.698778) (xy 269.304201 -117.644341) (xy 269.324124 -117.59225) (xy 269.35142 -117.543615)
			(xy 269.385506 -117.499472) (xy 269.425655 -117.460763) (xy 269.471013 -117.428312) (xy 269.520613 -117.402811)
			(xy 269.573397 -117.384804) (xy 269.62824 -117.374674) (xy 269.683974 -117.372637) (xy 269.739411 -117.378737)
			(xy 269.793368 -117.392843) (xy 269.844697 -117.414655) (xy 269.892303 -117.443709) (xy 269.935171 -117.479384)
			(xy 269.972388 -117.520921) (xy 270.003161 -117.567434) (xy 270.026833 -117.617931) (xy 270.042901 -117.671338)
			(xy 270.051021 -117.726514) (xy 270.05153 -117.7544) (xy 270.051021 -117.782286) (xy 270.042901 -117.837462)
			(xy 270.026833 -117.890869) (xy 270.003161 -117.941366) (xy 269.972388 -117.987879) (xy 269.935171 -118.029416)
			(xy 269.892303 -118.065091) (xy 269.844697 -118.094145) (xy 269.793368 -118.115957) (xy 269.739411 -118.130063)
			(xy 269.683974 -118.136163) (xy 269.62824 -118.134126) (xy 269.573397 -118.123996) (xy 269.520613 -118.105989)
			(xy 269.471013 -118.080488) (xy 269.425655 -118.048037) (xy 269.385506 -118.009328) (xy 269.35142 -117.965185)
			(xy 269.324124 -117.91655) (xy 269.304201 -117.864459) (xy 269.292075 -117.810022) (xy 269.288004 -117.7544)
			(xy 256.255944 -117.7544) (xy 256.510536 -118.588282) (xy 256.522208 -118.6281) (xy 256.539628 -118.709234)
			(xy 256.545334 -118.750334) (xy 256.550922 -118.79326) (xy 256.5527 -118.801388) (xy 256.631186 -119.060214)
			(xy 256.642606 -119.099363) (xy 256.659776 -119.179092) (xy 256.665476 -119.219472) (xy 256.77971 -120.087898)
			(xy 266.86764 -120.087898) (xy 266.86764 -119.224298) (xy 266.86813 -119.194314) (xy 266.875958 -119.134858)
			(xy 266.891479 -119.076933) (xy 266.914428 -119.021529) (xy 266.944412 -118.969595) (xy 266.980918 -118.922019)
			(xy 267.023323 -118.879614) (xy 267.070899 -118.843108) (xy 267.122833 -118.813124) (xy 267.178237 -118.790175)
			(xy 267.236162 -118.774654) (xy 267.295618 -118.766826) (xy 267.355586 -118.766826) (xy 267.415042 -118.774654)
			(xy 267.472967 -118.790175) (xy 267.528371 -118.813124) (xy 267.580305 -118.843108) (xy 267.627881 -118.879614)
			(xy 267.670286 -118.922019) (xy 267.706792 -118.969595) (xy 267.736776 -119.021529) (xy 267.759725 -119.076933)
			(xy 267.775246 -119.134858) (xy 267.783074 -119.194314) (xy 267.783564 -119.224298) (xy 267.783564 -120.087898)
			(xy 267.783074 -120.117882) (xy 267.775246 -120.177338) (xy 267.759725 -120.235263) (xy 267.736776 -120.290667)
			(xy 267.706792 -120.342601) (xy 267.670286 -120.390177) (xy 267.627881 -120.432582) (xy 267.580305 -120.469088)
			(xy 267.528371 -120.499072) (xy 267.472967 -120.522021) (xy 267.415042 -120.537542) (xy 267.355586 -120.54537)
			(xy 267.295618 -120.54537) (xy 267.236162 -120.537542) (xy 267.178237 -120.522021) (xy 267.122833 -120.499072)
			(xy 267.070899 -120.469088) (xy 267.023323 -120.432582) (xy 266.980918 -120.390177) (xy 266.944412 -120.342601)
			(xy 266.914428 -120.290667) (xy 266.891479 -120.235263) (xy 266.875958 -120.177338) (xy 266.86813 -120.117882)
			(xy 266.86764 -120.087898) (xy 256.77971 -120.087898) (xy 257.017334 -121.894346) (xy 269.509748 -121.894346)
			(xy 269.509748 -121.030746) (xy 269.510238 -121.000762) (xy 269.518066 -120.941306) (xy 269.533587 -120.883381)
			(xy 269.556536 -120.827977) (xy 269.58652 -120.776043) (xy 269.623026 -120.728467) (xy 269.665431 -120.686062)
			(xy 269.713007 -120.649556) (xy 269.764941 -120.619572) (xy 269.820345 -120.596623) (xy 269.87827 -120.581102)
			(xy 269.937726 -120.573274) (xy 269.997694 -120.573274) (xy 270.05715 -120.581102) (xy 270.115075 -120.596623)
			(xy 270.170479 -120.619572) (xy 270.222413 -120.649556) (xy 270.269989 -120.686062) (xy 270.312394 -120.728467)
			(xy 270.3489 -120.776043) (xy 270.378884 -120.827977) (xy 270.401833 -120.883381) (xy 270.417354 -120.941306)
			(xy 270.425182 -121.000762) (xy 270.425672 -121.030746) (xy 270.425672 -121.894346) (xy 270.425182 -121.92433)
			(xy 270.417354 -121.983786) (xy 270.401833 -122.041711) (xy 270.378884 -122.097115) (xy 270.3489 -122.149049)
			(xy 270.312394 -122.196625) (xy 270.269989 -122.23903) (xy 270.222413 -122.275536) (xy 270.170479 -122.30552)
			(xy 270.115075 -122.328469) (xy 270.05715 -122.34399) (xy 269.997694 -122.351818) (xy 269.937726 -122.351818)
			(xy 269.87827 -122.34399) (xy 269.820345 -122.328469) (xy 269.764941 -122.30552) (xy 269.713007 -122.275536)
			(xy 269.665431 -122.23903) (xy 269.623026 -122.196625) (xy 269.58652 -122.149049) (xy 269.556536 -122.097115)
			(xy 269.533587 -122.041711) (xy 269.518066 -121.983786) (xy 269.510238 -121.92433) (xy 269.509748 -121.894346)
			(xy 257.017334 -121.894346) (xy 257.253254 -123.68784) (xy 266.86764 -123.68784) (xy 266.86764 -122.82424)
			(xy 266.86813 -122.794256) (xy 266.875958 -122.7348) (xy 266.891479 -122.676875) (xy 266.914428 -122.621471)
			(xy 266.944412 -122.569537) (xy 266.980918 -122.521961) (xy 267.023323 -122.479556) (xy 267.070899 -122.44305)
			(xy 267.122833 -122.413066) (xy 267.178237 -122.390117) (xy 267.236162 -122.374596) (xy 267.295618 -122.366768)
			(xy 267.355586 -122.366768) (xy 267.415042 -122.374596) (xy 267.472967 -122.390117) (xy 267.528371 -122.413066)
			(xy 267.580305 -122.44305) (xy 267.627881 -122.479556) (xy 267.670286 -122.521961) (xy 267.706792 -122.569537)
			(xy 267.736776 -122.621471) (xy 267.759725 -122.676875) (xy 267.775246 -122.7348) (xy 267.783074 -122.794256)
			(xy 267.783564 -122.82424) (xy 267.783564 -123.68784) (xy 267.783074 -123.717824) (xy 267.775246 -123.77728)
			(xy 267.759725 -123.835205) (xy 267.736776 -123.890609) (xy 267.706792 -123.942543) (xy 267.670286 -123.990119)
			(xy 267.627881 -124.032524) (xy 267.580305 -124.06903) (xy 267.528371 -124.099014) (xy 267.472967 -124.121963)
			(xy 267.415042 -124.137484) (xy 267.355586 -124.145312) (xy 267.295618 -124.145312) (xy 267.236162 -124.137484)
			(xy 267.178237 -124.121963) (xy 267.122833 -124.099014) (xy 267.070899 -124.06903) (xy 267.023323 -124.032524)
			(xy 266.980918 -123.990119) (xy 266.944412 -123.942543) (xy 266.914428 -123.890609) (xy 266.891479 -123.835205)
			(xy 266.875958 -123.77728) (xy 266.86813 -123.717824) (xy 266.86764 -123.68784) (xy 257.253254 -123.68784)
			(xy 257.490911 -125.494542) (xy 269.509748 -125.494542) (xy 269.509748 -124.630942) (xy 269.510238 -124.600958)
			(xy 269.518066 -124.541502) (xy 269.533587 -124.483577) (xy 269.556536 -124.428173) (xy 269.58652 -124.376239)
			(xy 269.623026 -124.328663) (xy 269.665431 -124.286258) (xy 269.713007 -124.249752) (xy 269.764941 -124.219768)
			(xy 269.820345 -124.196819) (xy 269.87827 -124.181298) (xy 269.937726 -124.17347) (xy 269.997694 -124.17347)
			(xy 270.05715 -124.181298) (xy 270.115075 -124.196819) (xy 270.170479 -124.219768) (xy 270.222413 -124.249752)
			(xy 270.269989 -124.286258) (xy 270.312394 -124.328663) (xy 270.3489 -124.376239) (xy 270.378884 -124.428173)
			(xy 270.401833 -124.483577) (xy 270.417354 -124.541502) (xy 270.425182 -124.600958) (xy 270.425672 -124.630942)
			(xy 270.425672 -125.494542) (xy 270.425182 -125.524526) (xy 270.417354 -125.583982) (xy 270.401833 -125.641907)
			(xy 270.378884 -125.697311) (xy 270.3489 -125.749245) (xy 270.312394 -125.796821) (xy 270.269989 -125.839226)
			(xy 270.222413 -125.875732) (xy 270.170479 -125.905716) (xy 270.115075 -125.928665) (xy 270.05715 -125.944186)
			(xy 269.997694 -125.952014) (xy 269.937726 -125.952014) (xy 269.87827 -125.944186) (xy 269.820345 -125.928665)
			(xy 269.764941 -125.905716) (xy 269.713007 -125.875732) (xy 269.665431 -125.839226) (xy 269.623026 -125.796821)
			(xy 269.58652 -125.749245) (xy 269.556536 -125.697311) (xy 269.533587 -125.641907) (xy 269.518066 -125.583982)
			(xy 269.510238 -125.524526) (xy 269.509748 -125.494542) (xy 257.490911 -125.494542) (xy 258.254301 -131.297934)
			(xy 266.86764 -131.297934) (xy 266.86764 -130.434334) (xy 266.86813 -130.40435) (xy 266.875958 -130.344894)
			(xy 266.891479 -130.286969) (xy 266.914428 -130.231565) (xy 266.944412 -130.179631) (xy 266.980918 -130.132055)
			(xy 267.023323 -130.08965) (xy 267.070899 -130.053144) (xy 267.122833 -130.02316) (xy 267.178237 -130.000211)
			(xy 267.236162 -129.98469) (xy 267.295618 -129.976862) (xy 267.355586 -129.976862) (xy 267.415042 -129.98469)
			(xy 267.472967 -130.000211) (xy 267.528371 -130.02316) (xy 267.580305 -130.053144) (xy 267.627881 -130.08965)
			(xy 267.670286 -130.132055) (xy 267.706792 -130.179631) (xy 267.736776 -130.231565) (xy 267.759725 -130.286969)
			(xy 267.775246 -130.344894) (xy 267.783074 -130.40435) (xy 267.783564 -130.434334) (xy 267.783564 -131.297934)
			(xy 267.783074 -131.327918) (xy 267.775246 -131.387374) (xy 267.759725 -131.445299) (xy 267.736776 -131.500703)
			(xy 267.706792 -131.552637) (xy 267.670286 -131.600213) (xy 267.627881 -131.642618) (xy 267.580305 -131.679124)
			(xy 267.528371 -131.709108) (xy 267.472967 -131.732057) (xy 267.415042 -131.747578) (xy 267.355586 -131.755406)
			(xy 267.295618 -131.755406) (xy 267.236162 -131.747578) (xy 267.178237 -131.732057) (xy 267.122833 -131.709108)
			(xy 267.070899 -131.679124) (xy 267.023323 -131.642618) (xy 266.980918 -131.600213) (xy 266.944412 -131.552637)
			(xy 266.914428 -131.500703) (xy 266.891479 -131.445299) (xy 266.875958 -131.387374) (xy 266.86813 -131.327918)
			(xy 266.86764 -131.297934) (xy 258.254301 -131.297934) (xy 258.491925 -133.104382) (xy 269.509748 -133.104382)
			(xy 269.509748 -132.240782) (xy 269.510238 -132.210798) (xy 269.518066 -132.151342) (xy 269.533587 -132.093417)
			(xy 269.556536 -132.038013) (xy 269.58652 -131.986079) (xy 269.623026 -131.938503) (xy 269.665431 -131.896098)
			(xy 269.713007 -131.859592) (xy 269.764941 -131.829608) (xy 269.820345 -131.806659) (xy 269.87827 -131.791138)
			(xy 269.937726 -131.78331) (xy 269.997694 -131.78331) (xy 270.05715 -131.791138) (xy 270.115075 -131.806659)
			(xy 270.170479 -131.829608) (xy 270.222413 -131.859592) (xy 270.269989 -131.896098) (xy 270.312394 -131.938503)
			(xy 270.3489 -131.986079) (xy 270.378884 -132.038013) (xy 270.401833 -132.093417) (xy 270.417354 -132.151342)
			(xy 270.425182 -132.210798) (xy 270.425672 -132.240782) (xy 270.425672 -133.104382) (xy 270.425182 -133.134366)
			(xy 270.417354 -133.193822) (xy 270.401833 -133.251747) (xy 270.378884 -133.307151) (xy 270.3489 -133.359085)
			(xy 270.312394 -133.406661) (xy 270.269989 -133.449066) (xy 270.222413 -133.485572) (xy 270.170479 -133.515556)
			(xy 270.115075 -133.538505) (xy 270.05715 -133.554026) (xy 269.997694 -133.561854) (xy 269.937726 -133.561854)
			(xy 269.87827 -133.554026) (xy 269.820345 -133.538505) (xy 269.764941 -133.515556) (xy 269.713007 -133.485572)
			(xy 269.665431 -133.449066) (xy 269.623026 -133.406661) (xy 269.58652 -133.359085) (xy 269.556536 -133.307151)
			(xy 269.533587 -133.251747) (xy 269.518066 -133.193822) (xy 269.510238 -133.134366) (xy 269.509748 -133.104382)
			(xy 258.491925 -133.104382) (xy 258.727845 -134.897876) (xy 266.86764 -134.897876) (xy 266.86764 -134.034276)
			(xy 266.86813 -134.004292) (xy 266.875958 -133.944836) (xy 266.891479 -133.886911) (xy 266.914428 -133.831507)
			(xy 266.944412 -133.779573) (xy 266.980918 -133.731997) (xy 267.023323 -133.689592) (xy 267.070899 -133.653086)
			(xy 267.122833 -133.623102) (xy 267.178237 -133.600153) (xy 267.236162 -133.584632) (xy 267.295618 -133.576804)
			(xy 267.355586 -133.576804) (xy 267.415042 -133.584632) (xy 267.472967 -133.600153) (xy 267.528371 -133.623102)
			(xy 267.580305 -133.653086) (xy 267.627881 -133.689592) (xy 267.670286 -133.731997) (xy 267.706792 -133.779573)
			(xy 267.736776 -133.831507) (xy 267.759725 -133.886911) (xy 267.775246 -133.944836) (xy 267.783074 -134.004292)
			(xy 267.783564 -134.034276) (xy 267.783564 -134.897876) (xy 267.783074 -134.92786) (xy 267.775246 -134.987316)
			(xy 267.759725 -135.045241) (xy 267.736776 -135.100645) (xy 267.706792 -135.152579) (xy 267.670286 -135.200155)
			(xy 267.627881 -135.24256) (xy 267.580305 -135.279066) (xy 267.528371 -135.30905) (xy 267.472967 -135.331999)
			(xy 267.415042 -135.34752) (xy 267.355586 -135.355348) (xy 267.295618 -135.355348) (xy 267.236162 -135.34752)
			(xy 267.178237 -135.331999) (xy 267.122833 -135.30905) (xy 267.070899 -135.279066) (xy 267.023323 -135.24256)
			(xy 266.980918 -135.200155) (xy 266.944412 -135.152579) (xy 266.914428 -135.100645) (xy 266.891479 -135.045241)
			(xy 266.875958 -134.987316) (xy 266.86813 -134.92786) (xy 266.86764 -134.897876) (xy 258.727845 -134.897876)
			(xy 259.511716 -140.85697) (xy 267.812772 -140.85697) (xy 267.816843 -140.801348) (xy 267.828969 -140.746911)
			(xy 267.848892 -140.69482) (xy 267.876188 -140.646185) (xy 267.910274 -140.602042) (xy 267.950423 -140.563333)
			(xy 267.995781 -140.530882) (xy 268.045381 -140.505381) (xy 268.098165 -140.487374) (xy 268.153008 -140.477244)
			(xy 268.208742 -140.475207) (xy 268.264179 -140.481307) (xy 268.318136 -140.495413) (xy 268.369465 -140.517225)
			(xy 268.417071 -140.546279) (xy 268.459939 -140.581954) (xy 268.497156 -140.623491) (xy 268.527929 -140.670004)
			(xy 268.551601 -140.720501) (xy 268.567669 -140.773908) (xy 268.575789 -140.829084) (xy 268.576298 -140.85697)
			(xy 268.575789 -140.884856) (xy 268.567669 -140.940032) (xy 268.551601 -140.993439) (xy 268.527929 -141.043936)
			(xy 268.497156 -141.090449) (xy 268.459939 -141.131986) (xy 268.417071 -141.167661) (xy 268.369465 -141.196715)
			(xy 268.318136 -141.218527) (xy 268.264179 -141.232633) (xy 268.208742 -141.238733) (xy 268.153008 -141.236696)
			(xy 268.098165 -141.226566) (xy 268.045381 -141.208559) (xy 267.995781 -141.183058) (xy 267.950423 -141.150607)
			(xy 267.910274 -141.111898) (xy 267.876188 -141.067755) (xy 267.848892 -141.01912) (xy 267.828969 -140.967029)
			(xy 267.816843 -140.912592) (xy 267.812772 -140.85697) (xy 259.511716 -140.85697) (xy 259.950712 -144.194276)
			(xy 259.95122 -144.197324) (xy 261.675232 -153.3144) (xy 269.390874 -153.3144) (xy 269.394945 -153.258778)
			(xy 269.407071 -153.204341) (xy 269.426994 -153.15225) (xy 269.45429 -153.103615) (xy 269.488376 -153.059472)
			(xy 269.528525 -153.020763) (xy 269.573883 -152.988312) (xy 269.623483 -152.962811) (xy 269.676267 -152.944804)
			(xy 269.73111 -152.934674) (xy 269.786844 -152.932637) (xy 269.842281 -152.938737) (xy 269.896238 -152.952843)
			(xy 269.947567 -152.974655) (xy 269.995173 -153.003709) (xy 270.038041 -153.039384) (xy 270.075258 -153.080921)
			(xy 270.106031 -153.127434) (xy 270.129703 -153.177931) (xy 270.145771 -153.231338) (xy 270.153891 -153.286514)
			(xy 270.1544 -153.3144) (xy 270.153891 -153.342286) (xy 270.145771 -153.397462) (xy 270.129703 -153.450869)
			(xy 270.106031 -153.501366) (xy 270.075258 -153.547879) (xy 270.038041 -153.589416) (xy 269.995173 -153.625091)
			(xy 269.947567 -153.654145) (xy 269.896238 -153.675957) (xy 269.842281 -153.690063) (xy 269.786844 -153.696163)
			(xy 269.73111 -153.694126) (xy 269.676267 -153.683996) (xy 269.623483 -153.665989) (xy 269.573883 -153.640488)
			(xy 269.528525 -153.608037) (xy 269.488376 -153.569328) (xy 269.45429 -153.525185) (xy 269.426994 -153.47655)
			(xy 269.407071 -153.424459) (xy 269.394945 -153.370022) (xy 269.390874 -153.3144) (xy 261.675232 -153.3144)
			(xy 261.995596 -155.00858) (xy 269.19936 -155.00858) (xy 269.19936 -155.008326) (xy 269.199846 -154.981075)
			(xy 269.207602 -154.927127) (xy 269.222957 -154.874832) (xy 269.245599 -154.825255) (xy 269.275065 -154.779405)
			(xy 269.310756 -154.738214) (xy 269.351947 -154.702523) (xy 269.397797 -154.673057) (xy 269.447374 -154.650415)
			(xy 269.499669 -154.63506) (xy 269.553617 -154.627304) (xy 269.608119 -154.627304) (xy 269.662067 -154.63506)
			(xy 269.714362 -154.650415) (xy 269.763939 -154.673057) (xy 269.809789 -154.702523) (xy 269.85098 -154.738214)
			(xy 269.886671 -154.779405) (xy 269.916137 -154.825255) (xy 269.938779 -154.874832) (xy 269.954134 -154.927127)
			(xy 269.96189 -154.981075) (xy 269.962376 -155.008326) (xy 269.961963 -155.033651) (xy 269.955244 -155.083853)
			(xy 269.941941 -155.132724) (xy 269.922288 -155.179406) (xy 269.89663 -155.223076) (xy 269.88135 -155.243276)
			(xy 269.881096 -155.24353) (xy 269.875866 -155.250933) (xy 269.870543 -155.268248) (xy 269.870682 -155.277312)
			(xy 269.875508 -155.354274) (xy 269.883128 -155.371038) (xy 269.889732 -155.377642) (xy 269.910514 -155.399258)
			(xy 269.945773 -155.447753) (xy 269.973008 -155.50117) (xy 269.991547 -155.558191) (xy 270.000933 -155.617411)
			(xy 270.001492 -155.64739) (xy 270.001492 -155.647644) (xy 270.001006 -155.674895) (xy 269.99325 -155.728843)
			(xy 269.977895 -155.781138) (xy 269.955253 -155.830715) (xy 269.925787 -155.876565) (xy 269.890096 -155.917756)
			(xy 269.848905 -155.953447) (xy 269.803055 -155.982913) (xy 269.753478 -156.005555) (xy 269.701183 -156.02091)
			(xy 269.647235 -156.028666) (xy 269.592733 -156.028666) (xy 269.538785 -156.02091) (xy 269.48649 -156.005555)
			(xy 269.436913 -155.982913) (xy 269.391063 -155.953447) (xy 269.349872 -155.917756) (xy 269.314181 -155.876565)
			(xy 269.284715 -155.830715) (xy 269.262073 -155.781138) (xy 269.246718 -155.728843) (xy 269.238962 -155.674895)
			(xy 269.238476 -155.647644) (xy 269.238916 -155.62232) (xy 269.245627 -155.572119) (xy 269.258923 -155.523247)
			(xy 269.278571 -155.476565) (xy 269.304224 -155.432895) (xy 269.319502 -155.412694) (xy 269.319756 -155.41244)
			(xy 269.32496 -155.405022) (xy 269.330298 -155.387718) (xy 269.33017 -155.378658) (xy 269.325344 -155.301696)
			(xy 269.317724 -155.284932) (xy 269.31112 -155.278328) (xy 269.290315 -155.256734) (xy 269.25506 -155.208231)
			(xy 269.227831 -155.154809) (xy 269.209297 -155.097784) (xy 269.199916 -155.038561) (xy 269.19936 -155.00858)
			(xy 261.995596 -155.00858) (xy 262.443722 -157.3784) (xy 269.390874 -157.3784) (xy 269.394945 -157.322778)
			(xy 269.407071 -157.268341) (xy 269.426994 -157.21625) (xy 269.45429 -157.167615) (xy 269.488376 -157.123472)
			(xy 269.528525 -157.084763) (xy 269.573883 -157.052312) (xy 269.623483 -157.026811) (xy 269.676267 -157.008804)
			(xy 269.73111 -156.998674) (xy 269.786844 -156.996637) (xy 269.842281 -157.002737) (xy 269.896238 -157.016843)
			(xy 269.947567 -157.038655) (xy 269.995173 -157.067709) (xy 270.038041 -157.103384) (xy 270.075258 -157.144921)
			(xy 270.106031 -157.191434) (xy 270.129703 -157.241931) (xy 270.145771 -157.295338) (xy 270.153891 -157.350514)
			(xy 270.1544 -157.3784) (xy 270.153891 -157.406286) (xy 270.145771 -157.461462) (xy 270.129703 -157.514869)
			(xy 270.106031 -157.565366) (xy 270.075258 -157.611879) (xy 270.038041 -157.653416) (xy 269.995173 -157.689091)
			(xy 269.947567 -157.718145) (xy 269.896238 -157.739957) (xy 269.842281 -157.754063) (xy 269.786844 -157.760163)
			(xy 269.73111 -157.758126) (xy 269.676267 -157.747996) (xy 269.623483 -157.729989) (xy 269.573883 -157.704488)
			(xy 269.528525 -157.672037) (xy 269.488376 -157.633328) (xy 269.45429 -157.589185) (xy 269.426994 -157.54055)
			(xy 269.407071 -157.488459) (xy 269.394945 -157.434022) (xy 269.390874 -157.3784) (xy 262.443722 -157.3784)
			(xy 262.635844 -158.3944) (xy 269.390874 -158.3944) (xy 269.394945 -158.338778) (xy 269.407071 -158.284341)
			(xy 269.426994 -158.23225) (xy 269.45429 -158.183615) (xy 269.488376 -158.139472) (xy 269.528525 -158.100763)
			(xy 269.573883 -158.068312) (xy 269.623483 -158.042811) (xy 269.676267 -158.024804) (xy 269.73111 -158.014674)
			(xy 269.786844 -158.012637) (xy 269.842281 -158.018737) (xy 269.896238 -158.032843) (xy 269.947567 -158.054655)
			(xy 269.995173 -158.083709) (xy 270.038041 -158.119384) (xy 270.075258 -158.160921) (xy 270.106031 -158.207434)
			(xy 270.129703 -158.257931) (xy 270.145771 -158.311338) (xy 270.153891 -158.366514) (xy 270.1544 -158.3944)
			(xy 270.153891 -158.422286) (xy 270.145771 -158.477462) (xy 270.129703 -158.530869) (xy 270.106031 -158.581366)
			(xy 270.075258 -158.627879) (xy 270.038041 -158.669416) (xy 269.995173 -158.705091) (xy 269.947567 -158.734145)
			(xy 269.896238 -158.755957) (xy 269.842281 -158.770063) (xy 269.786844 -158.776163) (xy 269.73111 -158.774126)
			(xy 269.676267 -158.763996) (xy 269.623483 -158.745989) (xy 269.573883 -158.720488) (xy 269.528525 -158.688037)
			(xy 269.488376 -158.649328) (xy 269.45429 -158.605185) (xy 269.426994 -158.55655) (xy 269.407071 -158.504459)
			(xy 269.394945 -158.450022) (xy 269.390874 -158.3944) (xy 262.635844 -158.3944) (xy 263.144488 -161.08426)
			(xy 269.78305 -161.08426) (xy 269.787121 -161.028638) (xy 269.799247 -160.974201) (xy 269.81917 -160.92211)
			(xy 269.846466 -160.873475) (xy 269.880552 -160.829332) (xy 269.920701 -160.790623) (xy 269.966059 -160.758172)
			(xy 270.015659 -160.732671) (xy 270.068443 -160.714664) (xy 270.123286 -160.704534) (xy 270.17902 -160.702497)
			(xy 270.234457 -160.708597) (xy 270.288414 -160.722703) (xy 270.339743 -160.744515) (xy 270.387349 -160.773569)
			(xy 270.430217 -160.809244) (xy 270.467434 -160.850781) (xy 270.498207 -160.897294) (xy 270.521879 -160.947791)
			(xy 270.537947 -161.001198) (xy 270.546067 -161.056374) (xy 270.546576 -161.08426) (xy 270.546067 -161.112146)
			(xy 270.537947 -161.167322) (xy 270.521879 -161.220729) (xy 270.498207 -161.271226) (xy 270.467434 -161.317739)
			(xy 270.430217 -161.359276) (xy 270.387349 -161.394951) (xy 270.339743 -161.424005) (xy 270.288414 -161.445817)
			(xy 270.234457 -161.459923) (xy 270.17902 -161.466023) (xy 270.123286 -161.463986) (xy 270.068443 -161.453856)
			(xy 270.015659 -161.435849) (xy 269.966059 -161.410348) (xy 269.920701 -161.377897) (xy 269.880552 -161.339188)
			(xy 269.846466 -161.295045) (xy 269.81917 -161.24641) (xy 269.799247 -161.194319) (xy 269.787121 -161.139882)
			(xy 269.78305 -161.08426) (xy 263.144488 -161.08426) (xy 263.682383 -163.928806) (xy 270.618456 -163.928806)
			(xy 270.622527 -163.873184) (xy 270.634653 -163.818747) (xy 270.654576 -163.766656) (xy 270.681872 -163.718021)
			(xy 270.715958 -163.673878) (xy 270.756107 -163.635169) (xy 270.801465 -163.602718) (xy 270.851065 -163.577217)
			(xy 270.903849 -163.55921) (xy 270.958692 -163.54908) (xy 271.014426 -163.547043) (xy 271.069863 -163.553143)
			(xy 271.12382 -163.567249) (xy 271.175149 -163.589061) (xy 271.222755 -163.618115) (xy 271.265623 -163.65379)
			(xy 271.30284 -163.695327) (xy 271.333613 -163.74184) (xy 271.357285 -163.792337) (xy 271.373353 -163.845744)
			(xy 271.381473 -163.90092) (xy 271.381982 -163.928806) (xy 271.381473 -163.956692) (xy 271.373353 -164.011868)
			(xy 271.357285 -164.065275) (xy 271.333613 -164.115772) (xy 271.30284 -164.162285) (xy 271.265623 -164.203822)
			(xy 271.222755 -164.239497) (xy 271.175149 -164.268551) (xy 271.12382 -164.290363) (xy 271.069863 -164.304469)
			(xy 271.014426 -164.310569) (xy 270.958692 -164.308532) (xy 270.903849 -164.298402) (xy 270.851065 -164.280395)
			(xy 270.801465 -164.254894) (xy 270.756107 -164.222443) (xy 270.715958 -164.183734) (xy 270.681872 -164.139591)
			(xy 270.654576 -164.090956) (xy 270.634653 -164.038865) (xy 270.622527 -163.984428) (xy 270.618456 -163.928806)
			(xy 263.682383 -163.928806) (xy 270.564356 -200.322688) (xy 272.006314 -207.935576) (xy 273.75739 -217.17889)
			(xy 273.760159 -217.188282) (xy 273.771654 -217.204108) (xy 273.779742 -217.209624) (xy 273.85391 -217.249248)
			(xy 273.859222 -217.251775) (xy 273.870638 -217.2546) (xy 273.876516 -217.254836) (xy 273.896074 -217.250772)
			(xy 273.899376 -217.249502) (xy 273.922645 -217.240253) (xy 273.971 -217.227244) (xy 274.020643 -217.220682)
			(xy 274.04568 -217.220292) (xy 274.072934 -217.220754) (xy 274.126887 -217.228509) (xy 274.179187 -217.243863)
			(xy 274.22877 -217.266504) (xy 274.274625 -217.295972) (xy 274.31582 -217.331665) (xy 274.351516 -217.372859)
			(xy 274.380986 -217.418713) (xy 274.40363 -217.468294) (xy 274.418987 -217.520594) (xy 274.426745 -217.574546)
			(xy 274.427188 -217.6018) (xy 274.426703 -217.629039) (xy 274.418952 -217.682963) (xy 274.40361 -217.735237)
			(xy 274.380987 -217.784796) (xy 274.351544 -217.830632) (xy 274.31588 -217.871814) (xy 274.27472 -217.907504)
			(xy 274.228901 -217.936975) (xy 274.179356 -217.959628) (xy 274.127092 -217.975003) (xy 274.073173 -217.982786)
			(xy 274.045934 -217.983308) (xy 274.045426 -217.983308) (xy 274.035012 -217.983054) (xy 274.034758 -217.983054)
			(xy 274.024254 -217.983368) (xy 274.00485 -217.991378) (xy 273.997166 -217.998548) (xy 273.942048 -218.063064)
			(xy 273.935825 -218.071932) (xy 273.930811 -218.092988) (xy 273.932396 -218.103704) (xy 275.702776 -227.449634)
			(xy 275.705539 -227.461147) (xy 275.719797 -227.480012) (xy 275.740988 -227.490503) (xy 275.752814 -227.491036)
		)
		(stroke
			(width 0)
			(type solid)
		)
		(fill yes)
		(layer "In7.Cu")
		(net "GND")
	)
	(gr_poly
		(pts
			(xy 154.607768 -287.17367) (xy 154.626564 -287.169606) (xy 154.640163 -287.167312) (xy 154.667637 -287.164898)
			(xy 154.681428 -287.16478) (xy 156.923232 -287.16478) (xy 156.940231 -287.165283) (xy 156.973965 -287.169617)
			(xy 156.990542 -287.173416) (xy 156.991558 -287.17367) (xy 156.997654 -287.175194) (xy 160.352232 -287.175194)
			(xy 160.361884 -287.174178) (xy 160.369126 -287.172547) (xy 160.38229 -287.1657) (xy 160.387792 -287.160716)
			(xy 160.473136 -287.075372) (xy 160.478121 -287.069872) (xy 160.484959 -287.056704) (xy 160.486598 -287.049464)
			(xy 160.487614 -287.039812) (xy 160.487614 -286.38119) (xy 160.486852 -286.3723) (xy 159.352234 -285.237682)
			(xy 159.343344 -285.23692) (xy 159.314388 -285.246064) (xy 159.311594 -285.247842) (xy 159.290861 -285.261469)
			(xy 159.246174 -285.283023) (xy 159.19877 -285.297661) (xy 159.149711 -285.305056) (xy 159.124904 -285.3055)
			(xy 159.098915 -285.305017) (xy 159.047576 -285.296886) (xy 158.998142 -285.280824) (xy 158.951828 -285.257227)
			(xy 158.909777 -285.226674) (xy 158.873023 -285.18992) (xy 158.842471 -285.147868) (xy 158.818874 -285.101555)
			(xy 158.802813 -285.05212) (xy 158.794683 -285.000781) (xy 158.794196 -284.974792) (xy 158.794287 -284.962042)
			(xy 158.796193 -284.936613) (xy 158.798006 -284.923992) (xy 158.797752 -284.923992) (xy 158.80187 -284.900283)
			(xy 158.816072 -284.854306) (xy 158.836797 -284.810877) (xy 158.849822 -284.790642) (xy 158.853886 -284.7848)
			(xy 158.862776 -284.756352) (xy 158.862014 -284.747462) (xy 158.383478 -284.26918) (xy 158.37378 -284.268005)
			(xy 158.354713 -284.272185) (xy 158.346394 -284.277308) (xy 158.327328 -284.289769) (xy 158.28628 -284.309506)
			(xy 158.242754 -284.32292) (xy 158.197717 -284.329713) (xy 158.174944 -284.33014) (xy 158.150948 -284.329697)
			(xy 158.103545 -284.322196) (xy 158.057899 -284.307372) (xy 158.015135 -284.285589) (xy 157.976304 -284.257385)
			(xy 157.942364 -284.223453) (xy 157.91415 -284.18463) (xy 157.892357 -284.141871) (xy 157.877522 -284.096229)
			(xy 157.870009 -284.048828) (xy 157.869636 -284.024832) (xy 157.870076 -284.00206) (xy 157.876876 -283.957026)
			(xy 157.890285 -283.9135) (xy 157.910005 -283.872446) (xy 157.922468 -283.853382) (xy 157.92763 -283.845077)
			(xy 157.931826 -283.825997) (xy 157.930596 -283.816298) (xy 157.452314 -283.337762) (xy 157.443424 -283.337)
			(xy 157.414468 -283.346144) (xy 157.411674 -283.347922) (xy 157.39094 -283.361548) (xy 157.346254 -283.383101)
			(xy 157.298849 -283.397737) (xy 157.24979 -283.40513) (xy 157.224984 -283.40558) (xy 157.198996 -283.405096)
			(xy 157.147661 -283.396962) (xy 157.098231 -283.380898) (xy 157.051922 -283.357299) (xy 157.009875 -283.326746)
			(xy 156.973125 -283.289992) (xy 156.942578 -283.247941) (xy 156.918985 -283.201629) (xy 156.902927 -283.152196)
			(xy 156.894801 -283.10086) (xy 156.894276 -283.074872) (xy 156.894368 -283.062122) (xy 156.896275 -283.036693)
			(xy 156.898086 -283.024072) (xy 156.897832 -283.024072) (xy 156.901945 -283.000361) (xy 156.916136 -282.954377)
			(xy 156.936852 -282.910942) (xy 156.949902 -282.890722) (xy 156.953966 -282.88488) (xy 156.962856 -282.856432)
			(xy 156.962094 -282.847542) (xy 156.502354 -282.387802) (xy 156.493464 -282.38704) (xy 156.464508 -282.396184)
			(xy 156.461714 -282.397962) (xy 156.440981 -282.41159) (xy 156.396294 -282.433145) (xy 156.34889 -282.447786)
			(xy 156.299831 -282.455183) (xy 156.275024 -282.45562) (xy 156.249033 -282.455139) (xy 156.197691 -282.447011)
			(xy 156.148252 -282.430951) (xy 156.101935 -282.407354) (xy 156.059879 -282.376803) (xy 156.023121 -282.340048)
			(xy 155.992565 -282.297996) (xy 155.968963 -282.251681) (xy 155.952898 -282.202244) (xy 155.944764 -282.150903)
			(xy 155.944316 -282.124912) (xy 155.944406 -282.112162) (xy 155.946311 -282.086733) (xy 155.948126 -282.074112)
			(xy 155.947872 -282.074112) (xy 155.951988 -282.050402) (xy 155.966184 -282.004421) (xy 155.986903 -281.960988)
			(xy 155.999942 -281.940762) (xy 156.004006 -281.93492) (xy 156.012896 -281.906472) (xy 156.012134 -281.897582)
			(xy 155.552394 -281.437842) (xy 155.543504 -281.43708) (xy 155.514548 -281.446224) (xy 155.511754 -281.448002)
			(xy 155.49102 -281.461628) (xy 155.446334 -281.483179) (xy 155.398929 -281.497814) (xy 155.34987 -281.505204)
			(xy 155.325064 -281.50566) (xy 155.299078 -281.505174) (xy 155.247747 -281.497038) (xy 155.19832 -281.480972)
			(xy 155.152015 -281.457372) (xy 155.109973 -281.426818) (xy 155.073227 -281.390063) (xy 155.042684 -281.348013)
			(xy 155.019096 -281.301702) (xy 155.003042 -281.252272) (xy 154.994919 -281.200938) (xy 154.994356 -281.174952)
			(xy 154.994449 -281.162202) (xy 154.996357 -281.136774) (xy 154.998166 -281.124152) (xy 154.997912 -281.124152)
			(xy 155.002026 -281.100441) (xy 155.016218 -281.054459) (xy 155.036936 -281.011024) (xy 155.049982 -280.990802)
			(xy 155.054046 -280.98496) (xy 155.062936 -280.956512) (xy 155.062174 -280.947622) (xy 154.60218 -280.487628)
			(xy 154.592275 -280.48642) (xy 154.572814 -280.490748) (xy 154.564334 -280.49601) (xy 154.543757 -280.50983)
			(xy 154.499331 -280.531809) (xy 154.45212 -280.546906) (xy 154.403184 -280.554783) (xy 154.378406 -280.555446)
			(xy 154.372564 -280.555446) (xy 154.346833 -280.554759) (xy 154.296046 -280.546396) (xy 154.247167 -280.530267)
			(xy 154.201377 -280.506761) (xy 154.159781 -280.476445) (xy 154.123383 -280.440052) (xy 154.093062 -280.398459)
			(xy 154.06955 -280.352672) (xy 154.053414 -280.303796) (xy 154.045045 -280.253009) (xy 154.044396 -280.227278)
			(xy 154.044396 -280.22423) (xy 154.044905 -280.199102) (xy 154.052584 -280.149433) (xy 154.067679 -280.101495)
			(xy 154.089843 -280.056388) (xy 154.103832 -280.035508) (xy 154.109233 -280.02709) (xy 154.113544 -280.007576)
			(xy 154.112214 -279.997662) (xy 153.68016 -279.565608) (xy 153.68016 -279.555194) (xy 153.634948 -279.532334)
			(xy 153.624788 -279.528778) (xy 153.614965 -279.526631) (xy 153.595065 -279.5294) (xy 153.58618 -279.534112)
			(xy 153.561815 -279.548515) (xy 153.509063 -279.569013) (xy 153.453441 -279.579464) (xy 153.425144 -279.580086)
			(xy 153.42489 -279.580086) (xy 153.400898 -279.579639) (xy 153.353505 -279.572131) (xy 153.30787 -279.557301)
			(xy 153.265117 -279.535515) (xy 153.226298 -279.507309) (xy 153.19237 -279.473377) (xy 153.164168 -279.434556)
			(xy 153.142387 -279.3918) (xy 153.127562 -279.346164) (xy 153.120058 -279.29877) (xy 153.119582 -279.274778)
			(xy 153.120039 -279.250563) (xy 153.127669 -279.202738) (xy 153.142752 -279.156717) (xy 153.164908 -279.113653)
			(xy 153.193583 -279.074625) (xy 153.228058 -279.040611) (xy 153.267468 -279.012464) (xy 153.310827 -278.990889)
			(xy 153.357047 -278.976428) (xy 153.380948 -278.972518) (xy 153.389076 -278.971248) (xy 153.411682 -278.960072)
			(xy 153.415709 -278.958006) (xy 153.422995 -278.952639) (xy 153.42616 -278.949404) (xy 153.440384 -278.934164)
			(xy 153.446727 -278.926895) (xy 153.4539 -278.909003) (xy 153.454354 -278.899366) (xy 153.454354 -276.80031)
			(xy 153.453893 -276.790674) (xy 153.446725 -276.772781) (xy 153.440384 -276.765512) (xy 153.42616 -276.750272)
			(xy 153.422965 -276.747071) (xy 153.415685 -276.741707) (xy 153.411682 -276.739604) (xy 153.389076 -276.728428)
			(xy 153.380948 -276.727158) (xy 153.357049 -276.723215) (xy 153.310817 -276.708767) (xy 153.267445 -276.687204)
			(xy 153.22802 -276.659066) (xy 153.19353 -276.625059) (xy 153.16484 -276.586034) (xy 153.142668 -276.54297)
			(xy 153.127571 -276.496947) (xy 153.119926 -276.449118) (xy 153.119926 -276.400682) (xy 153.127571 -276.352852)
			(xy 153.142668 -276.306829) (xy 153.16484 -276.263765) (xy 153.193531 -276.224741) (xy 153.228021 -276.190733)
			(xy 153.267446 -276.162595) (xy 153.310818 -276.141033) (xy 153.357049 -276.126585) (xy 153.380948 -276.122638)
			(xy 153.389076 -276.121368) (xy 153.411682 -276.110192) (xy 153.415709 -276.108126) (xy 153.422998 -276.102762)
			(xy 153.42616 -276.099524) (xy 153.440384 -276.084284) (xy 153.44673 -276.077016) (xy 153.45391 -276.059124)
			(xy 153.454354 -276.049486) (xy 153.454354 -268.060932) (xy 153.454354 -268.05763) (xy 153.453448 -268.048786)
			(xy 153.446291 -268.032524) (xy 153.440384 -268.02588) (xy 153.386028 -267.973556) (xy 153.382271 -267.970116)
			(xy 153.373703 -267.964612) (xy 153.36901 -267.962634) (xy 153.359358 -267.959078) (xy 153.349198 -267.959332)
			(xy 153.335228 -267.959586) (xy 153.334974 -267.959586) (xy 153.307734 -267.959084) (xy 153.253812 -267.951302)
			(xy 153.201546 -267.935927) (xy 153.151998 -267.913272) (xy 153.106178 -267.8838) (xy 153.065016 -267.848108)
			(xy 153.029352 -267.806923) (xy 152.999909 -267.761084) (xy 152.977287 -267.711522) (xy 152.961946 -267.659245)
			(xy 152.954198 -267.605318) (xy 152.95372 -267.578078) (xy 152.954185 -267.550827) (xy 152.961945 -267.49688)
			(xy 152.977303 -267.444586) (xy 152.999947 -267.395011) (xy 153.029416 -267.349162) (xy 153.06511 -267.307975)
			(xy 153.106302 -267.272286) (xy 153.152155 -267.242823) (xy 153.201733 -267.220185) (xy 153.254029 -267.204834)
			(xy 153.307977 -267.197081) (xy 153.335228 -267.19657) (xy 153.349198 -267.196824) (xy 153.359358 -267.197078)
			(xy 153.36901 -267.193522) (xy 153.373728 -267.191589) (xy 153.382311 -267.186089) (xy 153.386028 -267.1826)
			(xy 153.440384 -267.130276) (xy 153.446222 -267.123587) (xy 153.453374 -267.10735) (xy 153.454354 -267.098526)
			(xy 153.454354 -266.945872) (xy 153.45419 -266.939861) (xy 153.451374 -266.928175) (xy 153.448766 -266.922758)
			(xy 153.446924 -266.919286) (xy 153.442326 -266.912911) (xy 153.439622 -266.910058) (xy 149.6695 -263.139936)
			(xy 149.662247 -263.133365) (xy 149.644217 -263.125801) (xy 149.634448 -263.125204) (xy 149.604222 -263.124696)
			(xy 149.594921 -263.12496) (xy 149.577456 -263.131335) (xy 149.570186 -263.137142) (xy 149.549326 -263.154446)
			(xy 149.503641 -263.183604) (xy 149.454291 -263.206006) (xy 149.402268 -263.221202) (xy 149.348618 -263.228886)
			(xy 149.32152 -263.229344) (xy 149.294267 -263.22886) (xy 149.240315 -263.221106) (xy 149.188016 -263.205753)
			(xy 149.138434 -263.183113) (xy 149.092578 -263.153648) (xy 149.051383 -263.117957) (xy 149.015686 -263.076767)
			(xy 148.986214 -263.030915) (xy 148.963567 -262.981337) (xy 148.948206 -262.92904) (xy 148.940444 -262.875089)
			(xy 148.940012 -262.847836) (xy 148.940012 -262.847074) (xy 148.940369 -262.824831) (xy 148.94559 -262.78065)
			(xy 148.950426 -262.758936) (xy 148.950426 -262.758682) (xy 148.951739 -262.75279) (xy 148.951871 -262.740723)
			(xy 148.95068 -262.734806) (xy 148.948394 -262.725154) (xy 148.890228 -262.650986) (xy 148.882672 -262.643081)
			(xy 148.862797 -262.634007) (xy 148.851874 -262.63346) (xy 138.837924 -262.63346) (xy 138.831915 -262.63363)
			(xy 138.820235 -262.636457) (xy 138.81481 -262.639048) (xy 138.811336 -262.640887) (xy 138.804957 -262.645482)
			(xy 138.80211 -262.648192) (xy 136.008872 -265.44143) (xy 136.006166 -265.444281) (xy 136.001573 -265.450659)
			(xy 135.999728 -265.45413) (xy 135.997142 -265.459556) (xy 135.994314 -265.471236) (xy 135.99414 -265.477244)
			(xy 135.99414 -270.89989) (xy 142.982451 -270.89989) (xy 142.98644 -270.75135) (xy 142.998397 -270.603237)
			(xy 143.018287 -270.45598) (xy 143.046052 -270.310004) (xy 143.081613 -270.165727) (xy 143.124867 -270.023568)
			(xy 143.175689 -269.883935) (xy 143.233933 -269.747232) (xy 143.299431 -269.613852) (xy 143.371994 -269.48418)
			(xy 143.451412 -269.35859) (xy 143.537457 -269.237443) (xy 143.629881 -269.12109) (xy 143.728417 -269.009866)
			(xy 143.832781 -268.904091) (xy 143.942673 -268.804071) (xy 144.057774 -268.710093) (xy 144.177754 -268.622429)
			(xy 144.302267 -268.541332) (xy 144.430953 -268.467035) (xy 144.563442 -268.399753) (xy 144.699351 -268.339679)
			(xy 144.838289 -268.286987) (xy 144.979855 -268.241828) (xy 145.123641 -268.204333) (xy 145.269232 -268.174611)
			(xy 145.416208 -268.152746) (xy 145.564147 -268.138802) (xy 145.71262 -268.132818) (xy 145.861201 -268.134813)
			(xy 146.00946 -268.144781) (xy 146.156971 -268.162692) (xy 146.303307 -268.188495) (xy 146.448048 -268.222115)
			(xy 146.590775 -268.263457) (xy 146.731078 -268.3124) (xy 146.868551 -268.368803) (xy 147.002798 -268.432504)
			(xy 147.133433 -268.50332) (xy 147.260078 -268.581045) (xy 147.382368 -268.665456) (xy 147.499951 -268.756309)
			(xy 147.612488 -268.853343) (xy 147.719655 -268.956278) (xy 147.821142 -269.064817) (xy 147.916656 -269.178646)
			(xy 148.005923 -269.297439) (xy 148.088684 -269.420851) (xy 148.164702 -269.548529) (xy 148.233757 -269.680102)
			(xy 148.29565 -269.815193) (xy 148.350203 -269.95341) (xy 148.397258 -270.094357) (xy 148.43668 -270.237627)
			(xy 148.468354 -270.382806) (xy 148.49219 -270.529475) (xy 148.508119 -270.677213) (xy 148.516095 -270.825593)
			(xy 148.516594 -270.89989) (xy 148.516095 -270.974187) (xy 148.508119 -271.122567) (xy 148.49219 -271.270305)
			(xy 148.468354 -271.416974) (xy 148.43668 -271.562153) (xy 148.397258 -271.705423) (xy 148.350203 -271.84637)
			(xy 148.29565 -271.984587) (xy 148.233757 -272.119678) (xy 148.164702 -272.251251) (xy 148.088684 -272.378929)
			(xy 148.005923 -272.502341) (xy 147.916656 -272.621134) (xy 147.821142 -272.734963) (xy 147.719655 -272.843502)
			(xy 147.612488 -272.946437) (xy 147.499951 -273.043471) (xy 147.382368 -273.134324) (xy 147.260078 -273.218735)
			(xy 147.133433 -273.29646) (xy 147.002798 -273.367276) (xy 146.868551 -273.430977) (xy 146.731078 -273.48738)
			(xy 146.590775 -273.536323) (xy 146.448048 -273.577665) (xy 146.303307 -273.611285) (xy 146.156971 -273.637088)
			(xy 146.00946 -273.654999) (xy 145.861201 -273.664967) (xy 145.71262 -273.666962) (xy 145.564147 -273.660978)
			(xy 145.416208 -273.647034) (xy 145.269232 -273.625169) (xy 145.123641 -273.595447) (xy 144.979855 -273.557952)
			(xy 144.838289 -273.512793) (xy 144.699351 -273.460101) (xy 144.563442 -273.400027) (xy 144.430953 -273.332745)
			(xy 144.302267 -273.258448) (xy 144.177754 -273.177351) (xy 144.057774 -273.089687) (xy 143.942673 -272.995709)
			(xy 143.832781 -272.895689) (xy 143.728417 -272.789914) (xy 143.629881 -272.67869) (xy 143.537457 -272.562337)
			(xy 143.451412 -272.44119) (xy 143.371994 -272.3156) (xy 143.299431 -272.185928) (xy 143.233933 -272.052548)
			(xy 143.175689 -271.915845) (xy 143.124867 -271.776212) (xy 143.081613 -271.634053) (xy 143.046052 -271.489776)
			(xy 143.018287 -271.3438) (xy 142.998397 -271.196543) (xy 142.98644 -271.04843) (xy 142.982451 -270.89989)
			(xy 135.99414 -270.89989) (xy 135.99414 -272.500852) (xy 135.994672 -272.511117) (xy 136.002808 -272.529974)
			(xy 136.009888 -272.537428) (xy 136.078468 -272.603214) (xy 136.08939 -272.602706) (xy 136.094724 -272.602452)
			(xy 136.100312 -272.602198) (xy 136.137758 -272.60065) (xy 136.212694 -272.599) (xy 136.250172 -272.598896)
			(xy 136.332612 -272.599386) (xy 136.4973 -272.60735) (xy 136.661411 -272.623262) (xy 136.824561 -272.647084)
			(xy 136.98637 -272.678761) (xy 137.146459 -272.718218) (xy 137.304455 -272.765364) (xy 137.459989 -272.820088)
			(xy 137.612697 -272.882263) (xy 137.762223 -272.951742) (xy 137.908218 -273.028365) (xy 138.05034 -273.111952)
			(xy 138.188258 -273.202308) (xy 138.321649 -273.299221) (xy 138.450203 -273.402466) (xy 138.573618 -273.511802)
			(xy 138.691607 -273.626972) (xy 138.803893 -273.747708) (xy 138.910215 -273.873728) (xy 139.010325 -274.004738)
			(xy 139.103988 -274.140432) (xy 139.190986 -274.280492) (xy 139.271115 -274.424592) (xy 139.344189 -274.572395)
			(xy 139.410037 -274.723555) (xy 139.468504 -274.877721) (xy 139.519455 -275.034531) (xy 139.562771 -275.19362)
			(xy 139.59835 -275.354616) (xy 139.626109 -275.517143) (xy 139.645983 -275.680821) (xy 139.657926 -275.845268)
			(xy 139.66191 -276.0101) (xy 139.657926 -276.174932) (xy 139.645983 -276.339379) (xy 139.635599 -276.424898)
			(xy 152.169126 -276.424898) (xy 152.173086 -276.375844) (xy 152.184863 -276.32806) (xy 152.204154 -276.282784)
			(xy 152.230457 -276.241188) (xy 152.263092 -276.204351) (xy 152.301213 -276.173226) (xy 152.343834 -276.148619)
			(xy 152.38985 -276.131167) (xy 152.438069 -276.121323) (xy 152.487244 -276.119342) (xy 152.536099 -276.125274)
			(xy 152.58337 -276.138966) (xy 152.627832 -276.160064) (xy 152.668335 -276.18802) (xy 152.703828 -276.222112)
			(xy 152.733393 -276.261456) (xy 152.756264 -276.305033) (xy 152.771848 -276.351714) (xy 152.779743 -276.400291)
			(xy 152.780238 -276.424898) (xy 152.779743 -276.449505) (xy 152.771848 -276.498082) (xy 152.756264 -276.544763)
			(xy 152.733393 -276.58834) (xy 152.703828 -276.627684) (xy 152.668335 -276.661776) (xy 152.627832 -276.689732)
			(xy 152.58337 -276.71083) (xy 152.536099 -276.724522) (xy 152.487244 -276.730454) (xy 152.438069 -276.728473)
			(xy 152.38985 -276.718629) (xy 152.343834 -276.701177) (xy 152.301213 -276.67657) (xy 152.263092 -276.645445)
			(xy 152.230457 -276.608608) (xy 152.204154 -276.567012) (xy 152.184863 -276.521736) (xy 152.173086 -276.473952)
			(xy 152.169126 -276.424898) (xy 139.635599 -276.424898) (xy 139.626109 -276.503057) (xy 139.59835 -276.665584)
			(xy 139.562771 -276.82658) (xy 139.519455 -276.985669) (xy 139.468504 -277.142479) (xy 139.410037 -277.296645)
			(xy 139.344189 -277.447805) (xy 139.271115 -277.595608) (xy 139.190986 -277.739708) (xy 139.103988 -277.879768)
			(xy 139.010325 -278.015462) (xy 138.910215 -278.146472) (xy 138.803893 -278.272492) (xy 138.691607 -278.393228)
			(xy 138.573618 -278.508398) (xy 138.450203 -278.617734) (xy 138.321649 -278.720979) (xy 138.188258 -278.817892)
			(xy 138.05034 -278.908248) (xy 137.908218 -278.991835) (xy 137.762223 -279.068458) (xy 137.612697 -279.137937)
			(xy 137.459989 -279.200112) (xy 137.304455 -279.254836) (xy 137.237625 -279.274778) (xy 152.169126 -279.274778)
			(xy 152.173086 -279.225724) (xy 152.184863 -279.17794) (xy 152.204154 -279.132664) (xy 152.230457 -279.091068)
			(xy 152.263092 -279.054231) (xy 152.301213 -279.023106) (xy 152.343834 -278.998499) (xy 152.38985 -278.981047)
			(xy 152.438069 -278.971203) (xy 152.487244 -278.969222) (xy 152.536099 -278.975154) (xy 152.58337 -278.988846)
			(xy 152.627832 -279.009944) (xy 152.668335 -279.0379) (xy 152.703828 -279.071992) (xy 152.733393 -279.111336)
			(xy 152.756264 -279.154913) (xy 152.771848 -279.201594) (xy 152.779743 -279.250171) (xy 152.780238 -279.274778)
			(xy 152.779743 -279.299385) (xy 152.771848 -279.347962) (xy 152.756264 -279.394643) (xy 152.733393 -279.43822)
			(xy 152.703828 -279.477564) (xy 152.668335 -279.511656) (xy 152.627832 -279.539612) (xy 152.58337 -279.56071)
			(xy 152.536099 -279.574402) (xy 152.487244 -279.580334) (xy 152.438069 -279.578353) (xy 152.38985 -279.568509)
			(xy 152.343834 -279.551057) (xy 152.301213 -279.52645) (xy 152.263092 -279.495325) (xy 152.230457 -279.458488)
			(xy 152.204154 -279.416892) (xy 152.184863 -279.371616) (xy 152.173086 -279.323832) (xy 152.169126 -279.274778)
			(xy 137.237625 -279.274778) (xy 137.146459 -279.301982) (xy 136.98637 -279.341439) (xy 136.824561 -279.373116)
			(xy 136.661411 -279.396938) (xy 136.4973 -279.41285) (xy 136.332612 -279.420814) (xy 136.250172 -279.421336)
			(xy 136.212695 -279.42123) (xy 136.137758 -279.419578) (xy 136.100312 -279.418034) (xy 136.094724 -279.41778)
			(xy 136.08939 -279.417526) (xy 136.078468 -279.417018) (xy 136.009888 -279.482804) (xy 136.00276 -279.490225)
			(xy 135.994622 -279.509103) (xy 135.99414 -279.51938) (xy 135.99414 -280.693114) (xy 147.43811 -280.693114)
			(xy 147.438654 -280.663732) (xy 147.447683 -280.605665) (xy 147.465514 -280.549671) (xy 147.491725 -280.497075)
			(xy 147.525695 -280.449124) (xy 147.56662 -280.406952) (xy 147.589748 -280.388822) (xy 147.598672 -280.381342)
			(xy 147.609132 -280.360568) (xy 147.609814 -280.348944) (xy 147.611084 -280.256996) (xy 147.601178 -280.235914)
			(xy 147.592034 -280.228548) (xy 147.570186 -280.210342) (xy 147.531644 -280.168524) (xy 147.499736 -280.121449)
			(xy 147.475169 -280.070159) (xy 147.458486 -280.015791) (xy 147.450058 -279.959549) (xy 147.44954 -279.931114)
			(xy 147.450026 -279.903863) (xy 147.457782 -279.849915) (xy 147.473137 -279.79762) (xy 147.495779 -279.748043)
			(xy 147.525245 -279.702193) (xy 147.560936 -279.661002) (xy 147.602127 -279.625311) (xy 147.647977 -279.595845)
			(xy 147.697554 -279.573203) (xy 147.749849 -279.557848) (xy 147.803797 -279.550092) (xy 147.858299 -279.550092)
			(xy 147.912247 -279.557848) (xy 147.964542 -279.573203) (xy 148.014119 -279.595845) (xy 148.059969 -279.625311)
			(xy 148.10116 -279.661002) (xy 148.136851 -279.702193) (xy 148.166317 -279.748043) (xy 148.188959 -279.79762)
			(xy 148.204314 -279.849915) (xy 148.21207 -279.903863) (xy 148.212556 -279.931114) (xy 148.212006 -279.960496)
			(xy 148.202975 -280.018561) (xy 148.185143 -280.074554) (xy 148.158933 -280.127149) (xy 148.124966 -280.175101)
			(xy 148.084044 -280.217274) (xy 148.060918 -280.235406) (xy 148.051975 -280.242867) (xy 148.041527 -280.263656)
			(xy 148.040852 -280.275284) (xy 148.039582 -280.367232) (xy 148.049488 -280.388314) (xy 148.058632 -280.39568)
			(xy 148.080459 -280.413909) (xy 148.118999 -280.455724) (xy 148.150908 -280.502795) (xy 148.175478 -280.55408)
			(xy 148.192166 -280.608443) (xy 148.200603 -280.664681) (xy 148.201126 -280.693114) (xy 148.8346 -280.693114)
			(xy 148.838671 -280.637492) (xy 148.850797 -280.583055) (xy 148.87072 -280.530964) (xy 148.898016 -280.482329)
			(xy 148.932102 -280.438186) (xy 148.972251 -280.399477) (xy 149.017609 -280.367026) (xy 149.067209 -280.341525)
			(xy 149.119993 -280.323518) (xy 149.174836 -280.313388) (xy 149.23057 -280.311351) (xy 149.286007 -280.317451)
			(xy 149.339964 -280.331557) (xy 149.391293 -280.353369) (xy 149.438899 -280.382423) (xy 149.481767 -280.418098)
			(xy 149.518984 -280.459635) (xy 149.549757 -280.506148) (xy 149.573429 -280.556645) (xy 149.589497 -280.610052)
			(xy 149.597617 -280.665228) (xy 149.598126 -280.693114) (xy 149.597617 -280.721) (xy 149.589497 -280.776176)
			(xy 149.573429 -280.829583) (xy 149.549757 -280.88008) (xy 149.518984 -280.926593) (xy 149.481767 -280.96813)
			(xy 149.438899 -281.003805) (xy 149.391293 -281.032859) (xy 149.339964 -281.054671) (xy 149.286007 -281.068777)
			(xy 149.23057 -281.074877) (xy 149.174836 -281.07284) (xy 149.119993 -281.06271) (xy 149.067209 -281.044703)
			(xy 149.017609 -281.019202) (xy 148.972251 -280.986751) (xy 148.932102 -280.948042) (xy 148.898016 -280.903899)
			(xy 148.87072 -280.855264) (xy 148.850797 -280.803173) (xy 148.838671 -280.748736) (xy 148.8346 -280.693114)
			(xy 148.201126 -280.693114) (xy 148.20064 -280.720365) (xy 148.192884 -280.774313) (xy 148.177529 -280.826608)
			(xy 148.154887 -280.876185) (xy 148.125421 -280.922035) (xy 148.08973 -280.963226) (xy 148.048539 -280.998917)
			(xy 148.002689 -281.028383) (xy 147.953112 -281.051025) (xy 147.900817 -281.06638) (xy 147.846869 -281.074136)
			(xy 147.792367 -281.074136) (xy 147.738419 -281.06638) (xy 147.686124 -281.051025) (xy 147.636547 -281.028383)
			(xy 147.590697 -280.998917) (xy 147.549506 -280.963226) (xy 147.513815 -280.922035) (xy 147.484349 -280.876185)
			(xy 147.461707 -280.826608) (xy 147.446352 -280.774313) (xy 147.438596 -280.720365) (xy 147.43811 -280.693114)
			(xy 135.99414 -280.693114) (xy 135.99414 -281.174952) (xy 152.169126 -281.174952) (xy 152.173086 -281.125898)
			(xy 152.184863 -281.078114) (xy 152.204154 -281.032838) (xy 152.230457 -280.991242) (xy 152.263092 -280.954405)
			(xy 152.301213 -280.92328) (xy 152.343834 -280.898673) (xy 152.38985 -280.881221) (xy 152.438069 -280.871377)
			(xy 152.487244 -280.869396) (xy 152.536099 -280.875328) (xy 152.58337 -280.88902) (xy 152.627832 -280.910118)
			(xy 152.668335 -280.938074) (xy 152.703828 -280.972166) (xy 152.733393 -281.01151) (xy 152.756264 -281.055087)
			(xy 152.771848 -281.101768) (xy 152.779743 -281.150345) (xy 152.780238 -281.174952) (xy 153.119086 -281.174952)
			(xy 153.123046 -281.125898) (xy 153.134823 -281.078114) (xy 153.154114 -281.032838) (xy 153.180417 -280.991242)
			(xy 153.213052 -280.954405) (xy 153.251173 -280.92328) (xy 153.293794 -280.898673) (xy 153.33981 -280.881221)
			(xy 153.388029 -280.871377) (xy 153.437204 -280.869396) (xy 153.486059 -280.875328) (xy 153.53333 -280.88902)
			(xy 153.577792 -280.910118) (xy 153.618295 -280.938074) (xy 153.653788 -280.972166) (xy 153.683353 -281.01151)
			(xy 153.706224 -281.055087) (xy 153.721808 -281.101768) (xy 153.729703 -281.150345) (xy 153.730198 -281.174952)
			(xy 153.729703 -281.199559) (xy 153.721808 -281.248136) (xy 153.706224 -281.294817) (xy 153.683353 -281.338394)
			(xy 153.653788 -281.377738) (xy 153.618295 -281.41183) (xy 153.577792 -281.439786) (xy 153.53333 -281.460884)
			(xy 153.486059 -281.474576) (xy 153.437204 -281.480508) (xy 153.388029 -281.478527) (xy 153.33981 -281.468683)
			(xy 153.293794 -281.451231) (xy 153.251173 -281.426624) (xy 153.213052 -281.395499) (xy 153.180417 -281.358662)
			(xy 153.154114 -281.317066) (xy 153.134823 -281.27179) (xy 153.123046 -281.224006) (xy 153.119086 -281.174952)
			(xy 152.780238 -281.174952) (xy 152.779743 -281.199559) (xy 152.771848 -281.248136) (xy 152.756264 -281.294817)
			(xy 152.733393 -281.338394) (xy 152.703828 -281.377738) (xy 152.668335 -281.41183) (xy 152.627832 -281.439786)
			(xy 152.58337 -281.460884) (xy 152.536099 -281.474576) (xy 152.487244 -281.480508) (xy 152.438069 -281.478527)
			(xy 152.38985 -281.468683) (xy 152.343834 -281.451231) (xy 152.301213 -281.426624) (xy 152.263092 -281.395499)
			(xy 152.230457 -281.358662) (xy 152.204154 -281.317066) (xy 152.184863 -281.27179) (xy 152.173086 -281.224006)
			(xy 152.169126 -281.174952) (xy 135.99414 -281.174952) (xy 135.99414 -281.829256) (xy 141.911576 -281.829256)
			(xy 141.915647 -281.773634) (xy 141.927773 -281.719197) (xy 141.947696 -281.667106) (xy 141.974992 -281.618471)
			(xy 142.009078 -281.574328) (xy 142.049227 -281.535619) (xy 142.094585 -281.503168) (xy 142.144185 -281.477667)
			(xy 142.196969 -281.45966) (xy 142.251812 -281.44953) (xy 142.307546 -281.447493) (xy 142.362983 -281.453593)
			(xy 142.41694 -281.467699) (xy 142.468269 -281.489511) (xy 142.515875 -281.518565) (xy 142.558743 -281.55424)
			(xy 142.59596 -281.595777) (xy 142.626733 -281.64229) (xy 142.650405 -281.692787) (xy 142.666473 -281.746194)
			(xy 142.674593 -281.80137) (xy 142.675102 -281.829256) (xy 143.396714 -281.829256) (xy 143.400785 -281.773634)
			(xy 143.412911 -281.719197) (xy 143.432834 -281.667106) (xy 143.46013 -281.618471) (xy 143.494216 -281.574328)
			(xy 143.534365 -281.535619) (xy 143.579723 -281.503168) (xy 143.629323 -281.477667) (xy 143.682107 -281.45966)
			(xy 143.73695 -281.44953) (xy 143.792684 -281.447493) (xy 143.848121 -281.453593) (xy 143.902078 -281.467699)
			(xy 143.953407 -281.489511) (xy 144.001013 -281.518565) (xy 144.043881 -281.55424) (xy 144.081098 -281.595777)
			(xy 144.111871 -281.64229) (xy 144.135543 -281.692787) (xy 144.151611 -281.746194) (xy 144.159731 -281.80137)
			(xy 144.16024 -281.829256) (xy 144.159731 -281.857142) (xy 144.151611 -281.912318) (xy 144.135543 -281.965725)
			(xy 144.111871 -282.016222) (xy 144.081098 -282.062735) (xy 144.043881 -282.104272) (xy 144.019079 -282.124912)
			(xy 154.0693 -282.124912) (xy 154.07326 -282.075858) (xy 154.085037 -282.028074) (xy 154.104328 -281.982798)
			(xy 154.130631 -281.941202) (xy 154.163266 -281.904365) (xy 154.201387 -281.87324) (xy 154.244008 -281.848633)
			(xy 154.290024 -281.831181) (xy 154.338243 -281.821337) (xy 154.387418 -281.819356) (xy 154.436273 -281.825288)
			(xy 154.483544 -281.83898) (xy 154.528006 -281.860078) (xy 154.568509 -281.888034) (xy 154.604002 -281.922126)
			(xy 154.633567 -281.96147) (xy 154.656438 -282.005047) (xy 154.672022 -282.051728) (xy 154.679917 -282.100305)
			(xy 154.680412 -282.124912) (xy 155.01926 -282.124912) (xy 155.02322 -282.075858) (xy 155.034997 -282.028074)
			(xy 155.054288 -281.982798) (xy 155.080591 -281.941202) (xy 155.113226 -281.904365) (xy 155.151347 -281.87324)
			(xy 155.193968 -281.848633) (xy 155.239984 -281.831181) (xy 155.288203 -281.821337) (xy 155.337378 -281.819356)
			(xy 155.386233 -281.825288) (xy 155.433504 -281.83898) (xy 155.477966 -281.860078) (xy 155.518469 -281.888034)
			(xy 155.553962 -281.922126) (xy 155.583527 -281.96147) (xy 155.606398 -282.005047) (xy 155.621982 -282.051728)
			(xy 155.629877 -282.100305) (xy 155.630372 -282.124912) (xy 155.629877 -282.149519) (xy 155.621982 -282.198096)
			(xy 155.606398 -282.244777) (xy 155.583527 -282.288354) (xy 155.553962 -282.327698) (xy 155.518469 -282.36179)
			(xy 155.477966 -282.389746) (xy 155.433504 -282.410844) (xy 155.386233 -282.424536) (xy 155.337378 -282.430468)
			(xy 155.288203 -282.428487) (xy 155.239984 -282.418643) (xy 155.193968 -282.401191) (xy 155.151347 -282.376584)
			(xy 155.113226 -282.345459) (xy 155.080591 -282.308622) (xy 155.054288 -282.267026) (xy 155.034997 -282.22175)
			(xy 155.02322 -282.173966) (xy 155.01926 -282.124912) (xy 154.680412 -282.124912) (xy 154.679917 -282.149519)
			(xy 154.672022 -282.198096) (xy 154.656438 -282.244777) (xy 154.633567 -282.288354) (xy 154.604002 -282.327698)
			(xy 154.568509 -282.36179) (xy 154.528006 -282.389746) (xy 154.483544 -282.410844) (xy 154.436273 -282.424536)
			(xy 154.387418 -282.430468) (xy 154.338243 -282.428487) (xy 154.290024 -282.418643) (xy 154.244008 -282.401191)
			(xy 154.201387 -282.376584) (xy 154.163266 -282.345459) (xy 154.130631 -282.308622) (xy 154.104328 -282.267026)
			(xy 154.085037 -282.22175) (xy 154.07326 -282.173966) (xy 154.0693 -282.124912) (xy 144.019079 -282.124912)
			(xy 144.001013 -282.139947) (xy 143.953407 -282.169001) (xy 143.902078 -282.190813) (xy 143.848121 -282.204919)
			(xy 143.792684 -282.211019) (xy 143.73695 -282.208982) (xy 143.682107 -282.198852) (xy 143.629323 -282.180845)
			(xy 143.579723 -282.155344) (xy 143.534365 -282.122893) (xy 143.494216 -282.084184) (xy 143.46013 -282.040041)
			(xy 143.432834 -281.991406) (xy 143.412911 -281.939315) (xy 143.400785 -281.884878) (xy 143.396714 -281.829256)
			(xy 142.675102 -281.829256) (xy 142.674593 -281.857142) (xy 142.666473 -281.912318) (xy 142.650405 -281.965725)
			(xy 142.626733 -282.016222) (xy 142.59596 -282.062735) (xy 142.558743 -282.104272) (xy 142.515875 -282.139947)
			(xy 142.468269 -282.169001) (xy 142.41694 -282.190813) (xy 142.362983 -282.204919) (xy 142.307546 -282.211019)
			(xy 142.251812 -282.208982) (xy 142.196969 -282.198852) (xy 142.144185 -282.180845) (xy 142.094585 -282.155344)
			(xy 142.049227 -282.122893) (xy 142.009078 -282.084184) (xy 141.974992 -282.040041) (xy 141.947696 -281.991406)
			(xy 141.927773 -281.939315) (xy 141.915647 -281.884878) (xy 141.911576 -281.829256) (xy 135.99414 -281.829256)
			(xy 135.99414 -284.061154) (xy 140.967204 -284.061154) (xy 140.971275 -284.005532) (xy 140.983401 -283.951095)
			(xy 141.003324 -283.899004) (xy 141.03062 -283.850369) (xy 141.064706 -283.806226) (xy 141.104855 -283.767517)
			(xy 141.150213 -283.735066) (xy 141.199813 -283.709565) (xy 141.252597 -283.691558) (xy 141.30744 -283.681428)
			(xy 141.363174 -283.679391) (xy 141.418611 -283.685491) (xy 141.472568 -283.699597) (xy 141.523897 -283.721409)
			(xy 141.571503 -283.750463) (xy 141.614371 -283.786138) (xy 141.651588 -283.827675) (xy 141.682361 -283.874188)
			(xy 141.691421 -283.893514) (xy 147.43811 -283.893514) (xy 147.438654 -283.864132) (xy 147.447683 -283.806065)
			(xy 147.465514 -283.750071) (xy 147.491725 -283.697475) (xy 147.525695 -283.649524) (xy 147.56662 -283.607352)
			(xy 147.589748 -283.589222) (xy 147.598672 -283.581742) (xy 147.609132 -283.560968) (xy 147.609814 -283.549344)
			(xy 147.611084 -283.457396) (xy 147.601178 -283.436314) (xy 147.592034 -283.428948) (xy 147.570186 -283.410742)
			(xy 147.531644 -283.368924) (xy 147.499736 -283.321849) (xy 147.475169 -283.270559) (xy 147.458486 -283.216191)
			(xy 147.450058 -283.159949) (xy 147.44954 -283.131514) (xy 147.450026 -283.104263) (xy 147.457782 -283.050315)
			(xy 147.473137 -282.99802) (xy 147.495779 -282.948443) (xy 147.525245 -282.902593) (xy 147.560936 -282.861402)
			(xy 147.602127 -282.825711) (xy 147.647977 -282.796245) (xy 147.697554 -282.773603) (xy 147.749849 -282.758248)
			(xy 147.803797 -282.750492) (xy 147.858299 -282.750492) (xy 147.912247 -282.758248) (xy 147.964542 -282.773603)
			(xy 148.014119 -282.796245) (xy 148.059969 -282.825711) (xy 148.10116 -282.861402) (xy 148.136851 -282.902593)
			(xy 148.166317 -282.948443) (xy 148.188959 -282.99802) (xy 148.204314 -283.050315) (xy 148.207845 -283.074872)
			(xy 152.169126 -283.074872) (xy 152.173086 -283.025818) (xy 152.184863 -282.978034) (xy 152.204154 -282.932758)
			(xy 152.230457 -282.891162) (xy 152.263092 -282.854325) (xy 152.301213 -282.8232) (xy 152.343834 -282.798593)
			(xy 152.38985 -282.781141) (xy 152.438069 -282.771297) (xy 152.487244 -282.769316) (xy 152.536099 -282.775248)
			(xy 152.58337 -282.78894) (xy 152.627832 -282.810038) (xy 152.668335 -282.837994) (xy 152.703828 -282.872086)
			(xy 152.733393 -282.91143) (xy 152.756264 -282.955007) (xy 152.771848 -283.001688) (xy 152.779743 -283.050265)
			(xy 152.780238 -283.074872) (xy 153.119086 -283.074872) (xy 153.123046 -283.025818) (xy 153.134823 -282.978034)
			(xy 153.154114 -282.932758) (xy 153.180417 -282.891162) (xy 153.213052 -282.854325) (xy 153.251173 -282.8232)
			(xy 153.293794 -282.798593) (xy 153.33981 -282.781141) (xy 153.388029 -282.771297) (xy 153.437204 -282.769316)
			(xy 153.486059 -282.775248) (xy 153.53333 -282.78894) (xy 153.577792 -282.810038) (xy 153.618295 -282.837994)
			(xy 153.653788 -282.872086) (xy 153.683353 -282.91143) (xy 153.706224 -282.955007) (xy 153.721808 -283.001688)
			(xy 153.729703 -283.050265) (xy 153.730198 -283.074872) (xy 153.729703 -283.099479) (xy 153.721808 -283.148056)
			(xy 153.706224 -283.194737) (xy 153.683353 -283.238314) (xy 153.653788 -283.277658) (xy 153.618295 -283.31175)
			(xy 153.577792 -283.339706) (xy 153.53333 -283.360804) (xy 153.486059 -283.374496) (xy 153.437204 -283.380428)
			(xy 153.388029 -283.378447) (xy 153.33981 -283.368603) (xy 153.293794 -283.351151) (xy 153.251173 -283.326544)
			(xy 153.213052 -283.295419) (xy 153.180417 -283.258582) (xy 153.154114 -283.216986) (xy 153.134823 -283.17171)
			(xy 153.123046 -283.123926) (xy 153.119086 -283.074872) (xy 152.780238 -283.074872) (xy 152.779743 -283.099479)
			(xy 152.771848 -283.148056) (xy 152.756264 -283.194737) (xy 152.733393 -283.238314) (xy 152.703828 -283.277658)
			(xy 152.668335 -283.31175) (xy 152.627832 -283.339706) (xy 152.58337 -283.360804) (xy 152.536099 -283.374496)
			(xy 152.487244 -283.380428) (xy 152.438069 -283.378447) (xy 152.38985 -283.368603) (xy 152.343834 -283.351151)
			(xy 152.301213 -283.326544) (xy 152.263092 -283.295419) (xy 152.230457 -283.258582) (xy 152.204154 -283.216986)
			(xy 152.184863 -283.17171) (xy 152.173086 -283.123926) (xy 152.169126 -283.074872) (xy 148.207845 -283.074872)
			(xy 148.21207 -283.104263) (xy 148.212556 -283.131514) (xy 148.212006 -283.160896) (xy 148.202975 -283.218961)
			(xy 148.185143 -283.274954) (xy 148.158933 -283.327549) (xy 148.124966 -283.375501) (xy 148.084044 -283.417674)
			(xy 148.060918 -283.435806) (xy 148.051975 -283.443267) (xy 148.041527 -283.464056) (xy 148.040852 -283.475684)
			(xy 148.039582 -283.567632) (xy 148.049488 -283.588714) (xy 148.058632 -283.59608) (xy 148.080459 -283.614309)
			(xy 148.118999 -283.656124) (xy 148.150908 -283.703195) (xy 148.175478 -283.75448) (xy 148.192166 -283.808843)
			(xy 148.200603 -283.865081) (xy 148.201126 -283.893514) (xy 148.8346 -283.893514) (xy 148.838671 -283.837892)
			(xy 148.850797 -283.783455) (xy 148.87072 -283.731364) (xy 148.898016 -283.682729) (xy 148.932102 -283.638586)
			(xy 148.972251 -283.599877) (xy 149.017609 -283.567426) (xy 149.067209 -283.541925) (xy 149.119993 -283.523918)
			(xy 149.174836 -283.513788) (xy 149.23057 -283.511751) (xy 149.286007 -283.517851) (xy 149.339964 -283.531957)
			(xy 149.391293 -283.553769) (xy 149.438899 -283.582823) (xy 149.481767 -283.618498) (xy 149.518984 -283.660035)
			(xy 149.549757 -283.706548) (xy 149.573429 -283.757045) (xy 149.589497 -283.810452) (xy 149.597617 -283.865628)
			(xy 149.598126 -283.893514) (xy 149.597617 -283.9214) (xy 149.589497 -283.976576) (xy 149.574979 -284.024832)
			(xy 154.0693 -284.024832) (xy 154.07326 -283.975778) (xy 154.085037 -283.927994) (xy 154.104328 -283.882718)
			(xy 154.130631 -283.841122) (xy 154.163266 -283.804285) (xy 154.201387 -283.77316) (xy 154.244008 -283.748553)
			(xy 154.290024 -283.731101) (xy 154.338243 -283.721257) (xy 154.387418 -283.719276) (xy 154.436273 -283.725208)
			(xy 154.483544 -283.7389) (xy 154.528006 -283.759998) (xy 154.568509 -283.787954) (xy 154.604002 -283.822046)
			(xy 154.633567 -283.86139) (xy 154.656438 -283.904967) (xy 154.672022 -283.951648) (xy 154.679917 -284.000225)
			(xy 154.680412 -284.024832) (xy 155.01926 -284.024832) (xy 155.02322 -283.975778) (xy 155.034997 -283.927994)
			(xy 155.054288 -283.882718) (xy 155.080591 -283.841122) (xy 155.113226 -283.804285) (xy 155.151347 -283.77316)
			(xy 155.193968 -283.748553) (xy 155.239984 -283.731101) (xy 155.288203 -283.721257) (xy 155.337378 -283.719276)
			(xy 155.386233 -283.725208) (xy 155.433504 -283.7389) (xy 155.477966 -283.759998) (xy 155.518469 -283.787954)
			(xy 155.553962 -283.822046) (xy 155.583527 -283.86139) (xy 155.606398 -283.904967) (xy 155.621982 -283.951648)
			(xy 155.629877 -284.000225) (xy 155.630372 -284.024832) (xy 156.91918 -284.024832) (xy 156.92314 -283.975778)
			(xy 156.934917 -283.927994) (xy 156.954208 -283.882718) (xy 156.980511 -283.841122) (xy 157.013146 -283.804285)
			(xy 157.051267 -283.77316) (xy 157.093888 -283.748553) (xy 157.139904 -283.731101) (xy 157.188123 -283.721257)
			(xy 157.237298 -283.719276) (xy 157.286153 -283.725208) (xy 157.333424 -283.7389) (xy 157.377886 -283.759998)
			(xy 157.418389 -283.787954) (xy 157.453882 -283.822046) (xy 157.483447 -283.86139) (xy 157.506318 -283.904967)
			(xy 157.521902 -283.951648) (xy 157.529797 -284.000225) (xy 157.530292 -284.024832) (xy 157.529797 -284.049439)
			(xy 157.521902 -284.098016) (xy 157.506318 -284.144697) (xy 157.483447 -284.188274) (xy 157.453882 -284.227618)
			(xy 157.418389 -284.26171) (xy 157.377886 -284.289666) (xy 157.333424 -284.310764) (xy 157.286153 -284.324456)
			(xy 157.237298 -284.330388) (xy 157.188123 -284.328407) (xy 157.139904 -284.318563) (xy 157.093888 -284.301111)
			(xy 157.051267 -284.276504) (xy 157.013146 -284.245379) (xy 156.980511 -284.208542) (xy 156.954208 -284.166946)
			(xy 156.934917 -284.12167) (xy 156.92314 -284.073886) (xy 156.91918 -284.024832) (xy 155.630372 -284.024832)
			(xy 155.629877 -284.049439) (xy 155.621982 -284.098016) (xy 155.606398 -284.144697) (xy 155.583527 -284.188274)
			(xy 155.553962 -284.227618) (xy 155.518469 -284.26171) (xy 155.477966 -284.289666) (xy 155.433504 -284.310764)
			(xy 155.386233 -284.324456) (xy 155.337378 -284.330388) (xy 155.288203 -284.328407) (xy 155.239984 -284.318563)
			(xy 155.193968 -284.301111) (xy 155.151347 -284.276504) (xy 155.113226 -284.245379) (xy 155.080591 -284.208542)
			(xy 155.054288 -284.166946) (xy 155.034997 -284.12167) (xy 155.02322 -284.073886) (xy 155.01926 -284.024832)
			(xy 154.680412 -284.024832) (xy 154.679917 -284.049439) (xy 154.672022 -284.098016) (xy 154.656438 -284.144697)
			(xy 154.633567 -284.188274) (xy 154.604002 -284.227618) (xy 154.568509 -284.26171) (xy 154.528006 -284.289666)
			(xy 154.483544 -284.310764) (xy 154.436273 -284.324456) (xy 154.387418 -284.330388) (xy 154.338243 -284.328407)
			(xy 154.290024 -284.318563) (xy 154.244008 -284.301111) (xy 154.201387 -284.276504) (xy 154.163266 -284.245379)
			(xy 154.130631 -284.208542) (xy 154.104328 -284.166946) (xy 154.085037 -284.12167) (xy 154.07326 -284.073886)
			(xy 154.0693 -284.024832) (xy 149.574979 -284.024832) (xy 149.573429 -284.029983) (xy 149.549757 -284.08048)
			(xy 149.518984 -284.126993) (xy 149.481767 -284.16853) (xy 149.438899 -284.204205) (xy 149.391293 -284.233259)
			(xy 149.339964 -284.255071) (xy 149.286007 -284.269177) (xy 149.23057 -284.275277) (xy 149.174836 -284.27324)
			(xy 149.119993 -284.26311) (xy 149.067209 -284.245103) (xy 149.017609 -284.219602) (xy 148.972251 -284.187151)
			(xy 148.932102 -284.148442) (xy 148.898016 -284.104299) (xy 148.87072 -284.055664) (xy 148.850797 -284.003573)
			(xy 148.838671 -283.949136) (xy 148.8346 -283.893514) (xy 148.201126 -283.893514) (xy 148.20064 -283.920765)
			(xy 148.192884 -283.974713) (xy 148.177529 -284.027008) (xy 148.154887 -284.076585) (xy 148.125421 -284.122435)
			(xy 148.08973 -284.163626) (xy 148.048539 -284.199317) (xy 148.002689 -284.228783) (xy 147.953112 -284.251425)
			(xy 147.900817 -284.26678) (xy 147.846869 -284.274536) (xy 147.792367 -284.274536) (xy 147.738419 -284.26678)
			(xy 147.686124 -284.251425) (xy 147.636547 -284.228783) (xy 147.590697 -284.199317) (xy 147.549506 -284.163626)
			(xy 147.513815 -284.122435) (xy 147.484349 -284.076585) (xy 147.461707 -284.027008) (xy 147.446352 -283.974713)
			(xy 147.438596 -283.920765) (xy 147.43811 -283.893514) (xy 141.691421 -283.893514) (xy 141.706033 -283.924685)
			(xy 141.722101 -283.978092) (xy 141.730221 -284.033268) (xy 141.73073 -284.061154) (xy 141.730221 -284.08904)
			(xy 141.722101 -284.144216) (xy 141.706033 -284.197623) (xy 141.682361 -284.24812) (xy 141.651588 -284.294633)
			(xy 141.614371 -284.33617) (xy 141.571503 -284.371845) (xy 141.523897 -284.400899) (xy 141.472568 -284.422711)
			(xy 141.418611 -284.436817) (xy 141.363174 -284.442917) (xy 141.30744 -284.44088) (xy 141.252597 -284.43075)
			(xy 141.199813 -284.412743) (xy 141.150213 -284.387242) (xy 141.104855 -284.354791) (xy 141.064706 -284.316082)
			(xy 141.03062 -284.271939) (xy 141.003324 -284.223304) (xy 140.983401 -284.171213) (xy 140.971275 -284.116776)
			(xy 140.967204 -284.061154) (xy 135.99414 -284.061154) (xy 135.99414 -284.852872) (xy 135.995156 -284.862524)
			(xy 135.996781 -284.869769) (xy 136.00362 -284.882941) (xy 136.008618 -284.888432) (xy 136.149842 -285.029656)
			(xy 141.911576 -285.029656) (xy 141.915647 -284.974034) (xy 141.927773 -284.919597) (xy 141.947696 -284.867506)
			(xy 141.974992 -284.818871) (xy 142.009078 -284.774728) (xy 142.049227 -284.736019) (xy 142.094585 -284.703568)
			(xy 142.144185 -284.678067) (xy 142.196969 -284.66006) (xy 142.251812 -284.64993) (xy 142.307546 -284.647893)
			(xy 142.362983 -284.653993) (xy 142.41694 -284.668099) (xy 142.468269 -284.689911) (xy 142.515875 -284.718965)
			(xy 142.558743 -284.75464) (xy 142.59596 -284.796177) (xy 142.626733 -284.84269) (xy 142.650405 -284.893187)
			(xy 142.666473 -284.946594) (xy 142.674593 -285.00177) (xy 142.675102 -285.029656) (xy 143.396714 -285.029656)
			(xy 143.400785 -284.974034) (xy 143.412911 -284.919597) (xy 143.432834 -284.867506) (xy 143.46013 -284.818871)
			(xy 143.494216 -284.774728) (xy 143.534365 -284.736019) (xy 143.579723 -284.703568) (xy 143.629323 -284.678067)
			(xy 143.682107 -284.66006) (xy 143.73695 -284.64993) (xy 143.792684 -284.647893) (xy 143.848121 -284.653993)
			(xy 143.902078 -284.668099) (xy 143.953407 -284.689911) (xy 144.001013 -284.718965) (xy 144.043881 -284.75464)
			(xy 144.081098 -284.796177) (xy 144.111871 -284.84269) (xy 144.135543 -284.893187) (xy 144.151611 -284.946594)
			(xy 144.155761 -284.974792) (xy 152.169126 -284.974792) (xy 152.173086 -284.925738) (xy 152.184863 -284.877954)
			(xy 152.204154 -284.832678) (xy 152.230457 -284.791082) (xy 152.263092 -284.754245) (xy 152.301213 -284.72312)
			(xy 152.343834 -284.698513) (xy 152.38985 -284.681061) (xy 152.438069 -284.671217) (xy 152.487244 -284.669236)
			(xy 152.536099 -284.675168) (xy 152.58337 -284.68886) (xy 152.627832 -284.709958) (xy 152.668335 -284.737914)
			(xy 152.703828 -284.772006) (xy 152.733393 -284.81135) (xy 152.756264 -284.854927) (xy 152.771848 -284.901608)
			(xy 152.779743 -284.950185) (xy 152.780238 -284.974792) (xy 153.119086 -284.974792) (xy 153.123046 -284.925738)
			(xy 153.134823 -284.877954) (xy 153.154114 -284.832678) (xy 153.180417 -284.791082) (xy 153.213052 -284.754245)
			(xy 153.251173 -284.72312) (xy 153.293794 -284.698513) (xy 153.33981 -284.681061) (xy 153.388029 -284.671217)
			(xy 153.437204 -284.669236) (xy 153.486059 -284.675168) (xy 153.53333 -284.68886) (xy 153.577792 -284.709958)
			(xy 153.618295 -284.737914) (xy 153.653788 -284.772006) (xy 153.683353 -284.81135) (xy 153.706224 -284.854927)
			(xy 153.721808 -284.901608) (xy 153.729703 -284.950185) (xy 153.730198 -284.974792) (xy 156.91918 -284.974792)
			(xy 156.92314 -284.925738) (xy 156.934917 -284.877954) (xy 156.954208 -284.832678) (xy 156.980511 -284.791082)
			(xy 157.013146 -284.754245) (xy 157.051267 -284.72312) (xy 157.093888 -284.698513) (xy 157.139904 -284.681061)
			(xy 157.188123 -284.671217) (xy 157.237298 -284.669236) (xy 157.286153 -284.675168) (xy 157.333424 -284.68886)
			(xy 157.377886 -284.709958) (xy 157.418389 -284.737914) (xy 157.453882 -284.772006) (xy 157.483447 -284.81135)
			(xy 157.506318 -284.854927) (xy 157.521902 -284.901608) (xy 157.529797 -284.950185) (xy 157.530292 -284.974792)
			(xy 157.529797 -284.999399) (xy 157.521902 -285.047976) (xy 157.506318 -285.094657) (xy 157.483447 -285.138234)
			(xy 157.453882 -285.177578) (xy 157.418389 -285.21167) (xy 157.377886 -285.239626) (xy 157.333424 -285.260724)
			(xy 157.286153 -285.274416) (xy 157.237298 -285.280348) (xy 157.188123 -285.278367) (xy 157.139904 -285.268523)
			(xy 157.093888 -285.251071) (xy 157.051267 -285.226464) (xy 157.013146 -285.195339) (xy 156.980511 -285.158502)
			(xy 156.954208 -285.116906) (xy 156.934917 -285.07163) (xy 156.92314 -285.023846) (xy 156.91918 -284.974792)
			(xy 153.730198 -284.974792) (xy 153.729703 -284.999399) (xy 153.721808 -285.047976) (xy 153.706224 -285.094657)
			(xy 153.683353 -285.138234) (xy 153.653788 -285.177578) (xy 153.618295 -285.21167) (xy 153.577792 -285.239626)
			(xy 153.53333 -285.260724) (xy 153.486059 -285.274416) (xy 153.437204 -285.280348) (xy 153.388029 -285.278367)
			(xy 153.33981 -285.268523) (xy 153.293794 -285.251071) (xy 153.251173 -285.226464) (xy 153.213052 -285.195339)
			(xy 153.180417 -285.158502) (xy 153.154114 -285.116906) (xy 153.134823 -285.07163) (xy 153.123046 -285.023846)
			(xy 153.119086 -284.974792) (xy 152.780238 -284.974792) (xy 152.779743 -284.999399) (xy 152.771848 -285.047976)
			(xy 152.756264 -285.094657) (xy 152.733393 -285.138234) (xy 152.703828 -285.177578) (xy 152.668335 -285.21167)
			(xy 152.627832 -285.239626) (xy 152.58337 -285.260724) (xy 152.536099 -285.274416) (xy 152.487244 -285.280348)
			(xy 152.438069 -285.278367) (xy 152.38985 -285.268523) (xy 152.343834 -285.251071) (xy 152.301213 -285.226464)
			(xy 152.263092 -285.195339) (xy 152.230457 -285.158502) (xy 152.204154 -285.116906) (xy 152.184863 -285.07163)
			(xy 152.173086 -285.023846) (xy 152.169126 -284.974792) (xy 144.155761 -284.974792) (xy 144.159731 -285.00177)
			(xy 144.16024 -285.029656) (xy 144.159731 -285.057542) (xy 144.151611 -285.112718) (xy 144.135543 -285.166125)
			(xy 144.111871 -285.216622) (xy 144.081098 -285.263135) (xy 144.043881 -285.304672) (xy 144.001013 -285.340347)
			(xy 143.953407 -285.369401) (xy 143.902078 -285.391213) (xy 143.848121 -285.405319) (xy 143.792684 -285.411419)
			(xy 143.73695 -285.409382) (xy 143.682107 -285.399252) (xy 143.629323 -285.381245) (xy 143.579723 -285.355744)
			(xy 143.534365 -285.323293) (xy 143.494216 -285.284584) (xy 143.46013 -285.240441) (xy 143.432834 -285.191806)
			(xy 143.412911 -285.139715) (xy 143.400785 -285.085278) (xy 143.396714 -285.029656) (xy 142.675102 -285.029656)
			(xy 142.674593 -285.057542) (xy 142.666473 -285.112718) (xy 142.650405 -285.166125) (xy 142.626733 -285.216622)
			(xy 142.59596 -285.263135) (xy 142.558743 -285.304672) (xy 142.515875 -285.340347) (xy 142.468269 -285.369401)
			(xy 142.41694 -285.391213) (xy 142.362983 -285.405319) (xy 142.307546 -285.411419) (xy 142.251812 -285.409382)
			(xy 142.196969 -285.399252) (xy 142.144185 -285.381245) (xy 142.094585 -285.355744) (xy 142.049227 -285.323293)
			(xy 142.009078 -285.284584) (xy 141.974992 -285.240441) (xy 141.947696 -285.191806) (xy 141.927773 -285.139715)
			(xy 141.915647 -285.085278) (xy 141.911576 -285.029656) (xy 136.149842 -285.029656) (xy 137.044938 -285.924752)
			(xy 154.0693 -285.924752) (xy 154.07326 -285.875698) (xy 154.085037 -285.827914) (xy 154.104328 -285.782638)
			(xy 154.130631 -285.741042) (xy 154.163266 -285.704205) (xy 154.201387 -285.67308) (xy 154.244008 -285.648473)
			(xy 154.290024 -285.631021) (xy 154.338243 -285.621177) (xy 154.387418 -285.619196) (xy 154.436273 -285.625128)
			(xy 154.483544 -285.63882) (xy 154.528006 -285.659918) (xy 154.568509 -285.687874) (xy 154.604002 -285.721966)
			(xy 154.633567 -285.76131) (xy 154.656438 -285.804887) (xy 154.672022 -285.851568) (xy 154.679917 -285.900145)
			(xy 154.680412 -285.924752) (xy 155.01926 -285.924752) (xy 155.02322 -285.875698) (xy 155.034997 -285.827914)
			(xy 155.054288 -285.782638) (xy 155.080591 -285.741042) (xy 155.113226 -285.704205) (xy 155.151347 -285.67308)
			(xy 155.193968 -285.648473) (xy 155.239984 -285.631021) (xy 155.288203 -285.621177) (xy 155.337378 -285.619196)
			(xy 155.386233 -285.625128) (xy 155.433504 -285.63882) (xy 155.477966 -285.659918) (xy 155.518469 -285.687874)
			(xy 155.553962 -285.721966) (xy 155.583527 -285.76131) (xy 155.606398 -285.804887) (xy 155.621982 -285.851568)
			(xy 155.629877 -285.900145) (xy 155.630372 -285.924752) (xy 155.629877 -285.949359) (xy 155.621982 -285.997936)
			(xy 155.606398 -286.044617) (xy 155.583527 -286.088194) (xy 155.553962 -286.127538) (xy 155.518469 -286.16163)
			(xy 155.477966 -286.189586) (xy 155.433504 -286.210684) (xy 155.386233 -286.224376) (xy 155.337378 -286.230308)
			(xy 155.288203 -286.228327) (xy 155.239984 -286.218483) (xy 155.193968 -286.201031) (xy 155.151347 -286.176424)
			(xy 155.113226 -286.145299) (xy 155.080591 -286.108462) (xy 155.054288 -286.066866) (xy 155.034997 -286.02159)
			(xy 155.02322 -285.973806) (xy 155.01926 -285.924752) (xy 154.680412 -285.924752) (xy 154.679917 -285.949359)
			(xy 154.672022 -285.997936) (xy 154.656438 -286.044617) (xy 154.633567 -286.088194) (xy 154.604002 -286.127538)
			(xy 154.568509 -286.16163) (xy 154.528006 -286.189586) (xy 154.483544 -286.210684) (xy 154.436273 -286.224376)
			(xy 154.387418 -286.230308) (xy 154.338243 -286.228327) (xy 154.290024 -286.218483) (xy 154.244008 -286.201031)
			(xy 154.201387 -286.176424) (xy 154.163266 -286.145299) (xy 154.130631 -286.108462) (xy 154.104328 -286.066866)
			(xy 154.085037 -286.02159) (xy 154.07326 -285.973806) (xy 154.0693 -285.924752) (xy 137.044938 -285.924752)
			(xy 138.133836 -287.01365) (xy 138.139337 -287.018633) (xy 138.152506 -287.025467) (xy 138.159744 -287.027112)
			(xy 138.169396 -287.028128) (xy 147.403566 -287.028128) (xy 147.414564 -287.02752) (xy 147.434509 -287.018223)
			(xy 147.448778 -287.001472) (xy 147.452334 -286.991044) (xy 147.459396 -286.967214) (xy 147.47886 -286.921481)
			(xy 147.50411 -286.87867) (xy 147.534715 -286.839508) (xy 147.570156 -286.804662) (xy 147.589748 -286.789368)
			(xy 147.590256 -286.78886) (xy 147.59468 -286.785359) (xy 147.601995 -286.776774) (xy 147.604734 -286.771842)
			(xy 147.609814 -286.761936) (xy 147.610576 -286.708596) (xy 147.611084 -286.66948) (xy 147.610999 -286.663767)
			(xy 147.608573 -286.652605) (xy 147.606258 -286.647382) (xy 147.603718 -286.642048) (xy 147.596606 -286.633158)
			(xy 147.592034 -286.629348) (xy 147.570208 -286.611118) (xy 147.531675 -286.569298) (xy 147.49977 -286.522225)
			(xy 147.475198 -286.470942) (xy 147.458503 -286.416582) (xy 147.450053 -286.360347) (xy 147.44954 -286.331914)
			(xy 147.450026 -286.304663) (xy 147.457782 -286.250715) (xy 147.473137 -286.19842) (xy 147.495779 -286.148843)
			(xy 147.525245 -286.102993) (xy 147.560936 -286.061802) (xy 147.602127 -286.026111) (xy 147.647977 -285.996645)
			(xy 147.697554 -285.974003) (xy 147.749849 -285.958648) (xy 147.803797 -285.950892) (xy 147.858299 -285.950892)
			(xy 147.912247 -285.958648) (xy 147.964542 -285.974003) (xy 148.014119 -285.996645) (xy 148.059969 -286.026111)
			(xy 148.10116 -286.061802) (xy 148.136851 -286.102993) (xy 148.166317 -286.148843) (xy 148.188959 -286.19842)
			(xy 148.204314 -286.250715) (xy 148.21207 -286.304663) (xy 148.212556 -286.331914) (xy 148.21202 -286.361317)
			(xy 148.20301 -286.41943) (xy 148.185191 -286.475471) (xy 148.158985 -286.528116) (xy 148.125012 -286.576116)
			(xy 148.084076 -286.618335) (xy 148.060918 -286.63646) (xy 148.06041 -286.636968) (xy 148.05599 -286.640472)
			(xy 148.048684 -286.649062) (xy 148.045932 -286.653986) (xy 148.040852 -286.663892) (xy 148.039836 -286.756348)
			(xy 148.039908 -286.762123) (xy 148.04235 -286.773407) (xy 148.044662 -286.7787) (xy 148.046948 -286.78378)
			(xy 148.05406 -286.79267) (xy 148.058632 -286.79648) (xy 148.081348 -286.815493) (xy 148.121194 -286.859324)
			(xy 148.153799 -286.908779) (xy 148.178383 -286.962672) (xy 148.186902 -286.991044) (xy 148.189188 -286.999172)
			(xy 148.198332 -287.012888) (xy 148.204936 -287.017714) (xy 148.211719 -287.022466) (xy 148.227395 -287.027778)
			(xy 148.23567 -287.028128) (xy 148.800566 -287.028128) (xy 148.811564 -287.02752) (xy 148.831509 -287.018223)
			(xy 148.845778 -287.001472) (xy 148.849334 -286.991044) (xy 148.857218 -286.964682) (xy 148.879517 -286.914381)
			(xy 148.908813 -286.867806) (xy 148.944497 -286.825923) (xy 148.985828 -286.789603) (xy 149.03195 -286.759598)
			(xy 149.081905 -286.736533) (xy 149.134655 -286.720884) (xy 149.189107 -286.712978) (xy 149.244129 -286.712978)
			(xy 149.298581 -286.720884) (xy 149.351331 -286.736533) (xy 149.401286 -286.759598) (xy 149.447408 -286.789603)
			(xy 149.488739 -286.825923) (xy 149.524423 -286.867806) (xy 149.553719 -286.914381) (xy 149.576018 -286.964682)
			(xy 149.583902 -286.991044) (xy 149.586188 -286.999172) (xy 149.595332 -287.012888) (xy 149.601936 -287.017714)
			(xy 149.608719 -287.022466) (xy 149.624395 -287.027778) (xy 149.63267 -287.028128) (xy 149.687026 -287.028128)
			(xy 149.69803 -287.027528) (xy 149.717988 -287.018239) (xy 149.732271 -287.001486) (xy 149.735794 -286.991044)
			(xy 149.743678 -286.964682) (xy 149.765977 -286.914381) (xy 149.795273 -286.867806) (xy 149.830957 -286.825923)
			(xy 149.872288 -286.789603) (xy 149.91841 -286.759598) (xy 149.968365 -286.736533) (xy 150.021115 -286.720884)
			(xy 150.075567 -286.712978) (xy 150.130589 -286.712978) (xy 150.185041 -286.720884) (xy 150.237791 -286.736533)
			(xy 150.287746 -286.759598) (xy 150.333868 -286.789603) (xy 150.375199 -286.825923) (xy 150.410883 -286.867806)
			(xy 150.440179 -286.914381) (xy 150.462478 -286.964682) (xy 150.470362 -286.991044) (xy 150.472648 -286.999172)
			(xy 150.481792 -287.012888) (xy 150.488396 -287.017714) (xy 150.495177 -287.022472) (xy 150.510854 -287.027797)
			(xy 150.51913 -287.028128) (xy 152.071578 -287.028128) (xy 152.075642 -287.027874) (xy 152.083252 -287.026998)
			(xy 152.097468 -287.021312) (xy 152.103582 -287.016698) (xy 152.107646 -287.012634) (xy 152.160986 -286.952182)
			(xy 152.167186 -286.943923) (xy 152.172973 -286.924121) (xy 152.172162 -286.913828) (xy 152.172162 -286.913574)
			(xy 152.170988 -286.903965) (xy 152.169718 -286.884646) (xy 152.169622 -286.874966) (xy 152.170144 -286.849711)
			(xy 152.178457 -286.799889) (xy 152.194858 -286.752115) (xy 152.218899 -286.707692) (xy 152.249923 -286.667832)
			(xy 152.287085 -286.633622) (xy 152.329371 -286.605996) (xy 152.375627 -286.585706) (xy 152.424592 -286.573306)
			(xy 152.47493 -286.569135) (xy 152.525268 -286.573306) (xy 152.574233 -286.585706) (xy 152.620489 -286.605996)
			(xy 152.662775 -286.633622) (xy 152.699937 -286.667832) (xy 152.730961 -286.707692) (xy 152.755002 -286.752115)
			(xy 152.771403 -286.799889) (xy 152.779716 -286.849711) (xy 152.780238 -286.874966) (xy 152.779812 -286.897753)
			(xy 152.773035 -286.94282) (xy 152.759642 -286.986381) (xy 152.739928 -287.02747) (xy 152.714332 -287.065176)
			(xy 152.699212 -287.08223) (xy 152.696164 -287.085278) (xy 152.69464 -287.087818) (xy 152.689988 -287.09502)
			(xy 152.685309 -287.111505) (xy 152.685496 -287.120076) (xy 152.686512 -287.126426) (xy 152.688742 -287.135783)
			(xy 152.699091 -287.15198) (xy 152.714682 -287.16322) (xy 152.733319 -287.16792) (xy 152.7429 -287.167066)
			(xy 152.743154 -287.167066) (xy 152.748996 -287.166304) (xy 152.749758 -287.166304) (xy 152.781254 -287.16478)
			(xy 153.123138 -287.16478) (xy 153.147776 -287.16605) (xy 153.157174 -287.167066) (xy 153.158698 -287.16732)
			(xy 153.167959 -287.167807) (xy 153.185818 -287.162867) (xy 153.193496 -287.157668) (xy 153.196798 -287.155128)
			(xy 153.203619 -287.148652) (xy 153.212435 -287.132058) (xy 153.214682 -287.113402) (xy 153.210059 -287.095188)
			(xy 153.204926 -287.08731) (xy 153.201878 -287.0835) (xy 153.200608 -287.081976) (xy 153.185472 -287.064969)
			(xy 153.159893 -287.027307) (xy 153.140191 -286.986264) (xy 153.126806 -286.942749) (xy 153.120033 -286.897729)
			(xy 153.119582 -286.874966) (xy 153.120104 -286.849711) (xy 153.128417 -286.799889) (xy 153.144818 -286.752115)
			(xy 153.168859 -286.707692) (xy 153.199883 -286.667832) (xy 153.237045 -286.633622) (xy 153.279331 -286.605996)
			(xy 153.325587 -286.585706) (xy 153.374552 -286.573306) (xy 153.42489 -286.569135) (xy 153.475228 -286.573306)
			(xy 153.524193 -286.585706) (xy 153.570449 -286.605996) (xy 153.612735 -286.633622) (xy 153.649897 -286.667832)
			(xy 153.680921 -286.707692) (xy 153.704962 -286.752115) (xy 153.721363 -286.799889) (xy 153.729676 -286.849711)
			(xy 153.730198 -286.874966) (xy 153.729772 -286.897753) (xy 153.722997 -286.942821) (xy 153.709605 -286.986383)
			(xy 153.689895 -287.027475) (xy 153.664302 -287.065185) (xy 153.649172 -287.08223) (xy 153.646124 -287.085278)
			(xy 153.6446 -287.087818) (xy 153.639951 -287.095021) (xy 153.635276 -287.111505) (xy 153.635456 -287.120076)
			(xy 153.636472 -287.126426) (xy 153.638701 -287.135787) (xy 153.649049 -287.151992) (xy 153.66464 -287.163244)
			(xy 153.683281 -287.167957) (xy 153.69286 -287.167066) (xy 153.693114 -287.167066) (xy 153.698956 -287.166304)
			(xy 153.699718 -287.166304) (xy 153.731214 -287.16478) (xy 154.073352 -287.16478) (xy 154.090352 -287.165279)
			(xy 154.124087 -287.169604) (xy 154.140662 -287.173416) (xy 154.141678 -287.17367) (xy 154.147774 -287.175194)
			(xy 154.601926 -287.175194)
		)
		(stroke
			(width 0)
			(type solid)
		)
		(fill yes)
		(layer "In7.Cu")
		(net "GND")
	)
	(gr_poly
		(pts
			(xy 23.652226 -256.949956) (xy 23.662104 -256.949496) (xy 23.680405 -256.942057) (xy 23.687786 -256.935478)
			(xy 23.68804 -256.935224) (xy 24.875998 -255.747266) (xy 24.883393 -255.740412) (xy 24.901992 -255.732666)
			(xy 24.912066 -255.73228) (xy 27.732482 -255.73228) (xy 27.742442 -255.731791) (xy 27.760861 -255.724197)
			(xy 27.768296 -255.717548) (xy 28.455112 -255.030986) (xy 28.45562 -255.030478) (xy 28.462211 -255.0231)
			(xy 28.469677 -255.004801) (xy 28.470098 -254.994918) (xy 28.470098 -253.938024) (xy 28.469704 -253.928502)
			(xy 28.462794 -253.910753) (xy 28.456636 -253.90348) (xy 28.403042 -253.845568) (xy 28.386024 -253.83744)
			(xy 28.376372 -253.836678) (xy 28.349375 -253.834075) (xy 28.296455 -253.822204) (xy 28.245749 -253.802958)
			(xy 28.198281 -253.776723) (xy 28.155008 -253.74403) (xy 28.116801 -253.705537) (xy 28.084432 -253.66202)
			(xy 28.058552 -253.614357) (xy 28.039685 -253.563509) (xy 28.02821 -253.510502) (xy 28.024359 -253.456403)
			(xy 28.028209 -253.402305) (xy 28.039683 -253.349297) (xy 28.05855 -253.298449) (xy 28.084428 -253.250785)
			(xy 28.116797 -253.207268) (xy 28.155003 -253.168774) (xy 28.198276 -253.13608) (xy 28.245744 -253.109845)
			(xy 28.296449 -253.090597) (xy 28.349369 -253.078726) (xy 28.376372 -253.076202) (xy 28.386024 -253.07544)
			(xy 28.403042 -253.067312) (xy 28.456636 -253.0094) (xy 28.462822 -253.002141) (xy 28.469745 -252.984386)
			(xy 28.470098 -252.974856) (xy 28.470098 -251.640086) (xy 28.469697 -251.630566) (xy 28.462778 -251.612827)
			(xy 28.456636 -251.605542) (xy 28.403042 -251.54763) (xy 28.386024 -251.539502) (xy 28.376372 -251.53874)
			(xy 28.349378 -251.536137) (xy 28.296463 -251.524267) (xy 28.245763 -251.505022) (xy 28.198299 -251.47879)
			(xy 28.15503 -251.446099) (xy 28.116828 -251.40761) (xy 28.084462 -251.364097) (xy 28.058586 -251.316439)
			(xy 28.039721 -251.265596) (xy 28.028247 -251.212593) (xy 28.024397 -251.1585) (xy 28.028247 -251.104407)
			(xy 28.039721 -251.051405) (xy 28.058586 -251.000562) (xy 28.084462 -250.952903) (xy 28.116827 -250.909391)
			(xy 28.15503 -250.870901) (xy 28.198299 -250.83821) (xy 28.245762 -250.811978) (xy 28.296463 -250.792733)
			(xy 28.349378 -250.780863) (xy 28.376372 -250.778264) (xy 28.386024 -250.777502) (xy 28.403042 -250.769374)
			(xy 28.456636 -250.711462) (xy 28.462817 -250.704202) (xy 28.469726 -250.686446) (xy 28.470098 -250.676918)
			(xy 28.470098 -232.819448) (xy 28.470531 -232.809382) (xy 28.478258 -232.790791) (xy 28.485084 -232.78338)
			(xy 33.000442 -228.268022) (xy 33.00095 -228.267514) (xy 33.007527 -228.260131) (xy 33.014966 -228.241832)
			(xy 33.015428 -228.231954) (xy 33.015428 -221.73819) (xy 33.015004 -221.72812) (xy 33.00729 -221.709516)
			(xy 33.000442 -221.702122) (xy 32.009588 -220.711268) (xy 32.002476 -220.703902) (xy 31.98368 -220.696282)
			(xy 26.727912 -220.696282) (xy 26.71918 -220.696629) (xy 26.702736 -220.702505) (xy 26.689253 -220.713602)
			(xy 26.684478 -220.72092) (xy 26.66959 -220.744711) (xy 26.633932 -220.788049) (xy 26.592308 -220.825694)
			(xy 26.545618 -220.856834) (xy 26.494869 -220.880797) (xy 26.441157 -220.897065) (xy 26.385641 -220.905288)
			(xy 26.329519 -220.905288) (xy 26.274003 -220.897065) (xy 26.220291 -220.880797) (xy 26.169542 -220.856834)
			(xy 26.122852 -220.825694) (xy 26.081228 -220.788049) (xy 26.04557 -220.744711) (xy 26.030682 -220.72092)
			(xy 26.025864 -220.713647) (xy 26.012369 -220.70261) (xy 25.995963 -220.696711) (xy 25.987248 -220.696282)
			(xy 16.985488 -220.696282) (xy 16.975418 -220.696707) (xy 16.956815 -220.704422) (xy 16.94942 -220.711268)
			(xy 16.327882 -221.332806) (xy 22.477982 -221.332806) (xy 22.482053 -221.277184) (xy 22.494179 -221.222747)
			(xy 22.514102 -221.170656) (xy 22.541398 -221.122021) (xy 22.575484 -221.077878) (xy 22.615633 -221.039169)
			(xy 22.660991 -221.006718) (xy 22.710591 -220.981217) (xy 22.763375 -220.96321) (xy 22.818218 -220.95308)
			(xy 22.873952 -220.951043) (xy 22.929389 -220.957143) (xy 22.983346 -220.971249) (xy 23.034675 -220.993061)
			(xy 23.082281 -221.022115) (xy 23.125149 -221.05779) (xy 23.162366 -221.099327) (xy 23.193139 -221.14584)
			(xy 23.216811 -221.196337) (xy 23.232879 -221.249744) (xy 23.240999 -221.30492) (xy 23.241508 -221.332806)
			(xy 23.240999 -221.360692) (xy 23.232879 -221.415868) (xy 23.216811 -221.469275) (xy 23.193139 -221.519772)
			(xy 23.162366 -221.566285) (xy 23.125149 -221.607822) (xy 23.082281 -221.643497) (xy 23.034675 -221.672551)
			(xy 22.983346 -221.694363) (xy 22.929389 -221.708469) (xy 22.873952 -221.714569) (xy 22.818218 -221.712532)
			(xy 22.763375 -221.702402) (xy 22.710591 -221.684395) (xy 22.660991 -221.658894) (xy 22.615633 -221.626443)
			(xy 22.575484 -221.587734) (xy 22.541398 -221.543591) (xy 22.514102 -221.494956) (xy 22.494179 -221.442865)
			(xy 22.482053 -221.388428) (xy 22.477982 -221.332806) (xy 16.327882 -221.332806) (xy 15.788894 -221.871794)
			(xy 15.781528 -221.878906) (xy 15.773908 -221.897702) (xy 15.773908 -222.04553) (xy 15.774401 -222.055533)
			(xy 15.782067 -222.074013) (xy 15.796219 -222.088155) (xy 15.814705 -222.095806) (xy 15.824708 -222.09633)
			(xy 15.841726 -222.09633) (xy 15.868396 -222.076518) (xy 15.873222 -222.060516) (xy 15.881595 -222.03483)
			(xy 15.90457 -221.985935) (xy 15.93421 -221.940769) (xy 15.969922 -221.900233) (xy 16.010994 -221.865137)
			(xy 16.056604 -221.836185) (xy 16.105842 -221.813952) (xy 16.157722 -221.798885) (xy 16.211208 -221.791284)
			(xy 16.23822 -221.790768) (xy 16.265471 -221.791255) (xy 16.319418 -221.799014) (xy 16.371712 -221.81437)
			(xy 16.421288 -221.837012) (xy 16.467137 -221.866479) (xy 16.508327 -221.90217) (xy 16.544019 -221.943359)
			(xy 16.566143 -221.977783) (xy 17.088569 -221.977783) (xy 17.088569 -221.923277) (xy 17.096326 -221.869327)
			(xy 17.111682 -221.817029) (xy 17.134325 -221.76745) (xy 17.163793 -221.721597) (xy 17.199486 -221.680405)
			(xy 17.240678 -221.644711) (xy 17.286531 -221.615244) (xy 17.336111 -221.592602) (xy 17.388409 -221.577246)
			(xy 17.442359 -221.569489) (xy 17.469612 -221.569026) (xy 17.499301 -221.569562) (xy 17.557961 -221.578763)
			(xy 17.614488 -221.596942) (xy 17.667516 -221.623658) (xy 17.715764 -221.658268) (xy 17.758067 -221.699935)
			(xy 17.77619 -221.723458) (xy 17.785037 -221.734575) (xy 17.807564 -221.751866) (xy 17.833986 -221.762276)
			(xy 17.862253 -221.764998) (xy 17.890176 -221.759821) (xy 17.915588 -221.747145) (xy 17.936521 -221.727955)
			(xy 17.944338 -221.716092) (xy 17.959314 -221.692619) (xy 17.995015 -221.649894) (xy 18.036544 -221.612809)
			(xy 18.083021 -221.58215) (xy 18.133458 -221.558569) (xy 18.186786 -221.542565) (xy 18.241873 -221.534478)
			(xy 18.269712 -221.533974) (xy 18.296961 -221.534497) (xy 18.350905 -221.542255) (xy 18.403196 -221.55761)
			(xy 18.452769 -221.580251) (xy 18.498616 -221.609716) (xy 18.539803 -221.645406) (xy 18.575491 -221.686594)
			(xy 18.604955 -221.732441) (xy 18.627594 -221.782015) (xy 18.642948 -221.834307) (xy 18.650704 -221.888251)
			(xy 18.650704 -221.942749) (xy 18.642948 -221.996693) (xy 18.627594 -222.048985) (xy 18.604955 -222.098559)
			(xy 18.575491 -222.144406) (xy 18.539803 -222.185594) (xy 18.498616 -222.221284) (xy 18.452769 -222.250749)
			(xy 18.403196 -222.27339) (xy 18.350905 -222.288745) (xy 18.296961 -222.296503) (xy 18.269712 -222.29699)
			(xy 18.240024 -222.29643) (xy 18.181365 -222.287233) (xy 18.124839 -222.269059) (xy 18.071811 -222.242347)
			(xy 18.023563 -222.207741) (xy 17.981258 -222.166079) (xy 17.963134 -222.142558) (xy 17.95426 -222.131463)
			(xy 17.93174 -222.114169) (xy 17.905324 -222.103756) (xy 17.877061 -222.10103) (xy 17.849142 -222.106204)
			(xy 17.823732 -222.118876) (xy 17.802802 -222.138063) (xy 17.794986 -222.149924) (xy 17.779965 -222.173367)
			(xy 17.744274 -222.216096) (xy 17.702754 -222.253186) (xy 17.656286 -222.28385) (xy 17.605855 -222.307437)
			(xy 17.552532 -222.323445) (xy 17.497449 -222.331536) (xy 17.469612 -222.332042) (xy 17.442359 -222.331571)
			(xy 17.388409 -222.323814) (xy 17.336111 -222.308458) (xy 17.286531 -222.285816) (xy 17.240678 -222.256349)
			(xy 17.199486 -222.220655) (xy 17.163793 -222.179463) (xy 17.134325 -222.13361) (xy 17.111682 -222.084031)
			(xy 17.096326 -222.031733) (xy 17.088569 -221.977783) (xy 16.566143 -221.977783) (xy 16.573486 -221.989209)
			(xy 16.596128 -222.038785) (xy 16.611485 -222.091078) (xy 16.619245 -222.145025) (xy 16.619728 -222.172276)
			(xy 16.619263 -222.199158) (xy 16.611707 -222.252388) (xy 16.596754 -222.304031) (xy 16.574702 -222.353064)
			(xy 16.545985 -222.398516) (xy 16.511174 -222.439488) (xy 16.470956 -222.475169) (xy 16.426129 -222.504852)
			(xy 16.37758 -222.527949) (xy 16.326269 -222.544004) (xy 16.273213 -222.552699) (xy 16.246348 -222.553784)
			(xy 16.237966 -222.553784) (xy 16.210978 -222.553315) (xy 16.157541 -222.545704) (xy 16.10571 -222.530638)
			(xy 16.056519 -222.508419) (xy 16.01095 -222.47949) (xy 15.969913 -222.444427) (xy 15.951708 -222.424498)
			(xy 15.951708 -222.424244) (xy 15.951454 -222.42399) (xy 15.944285 -222.416674) (xy 15.925771 -222.40795)
			(xy 15.905321 -222.407121) (xy 15.895574 -222.410274) (xy 15.806928 -222.443802) (xy 15.800578 -222.446596)
			(xy 15.792783 -222.451219) (xy 15.780833 -222.464826) (xy 15.774363 -222.481741) (xy 15.773908 -222.490792)
			(xy 15.773908 -223.147382) (xy 19.056094 -223.147382) (xy 19.060165 -223.09176) (xy 19.072291 -223.037323)
			(xy 19.092214 -222.985232) (xy 19.11951 -222.936597) (xy 19.153596 -222.892454) (xy 19.193745 -222.853745)
			(xy 19.239103 -222.821294) (xy 19.288703 -222.795793) (xy 19.341487 -222.777786) (xy 19.39633 -222.767656)
			(xy 19.452064 -222.765619) (xy 19.507501 -222.771719) (xy 19.561458 -222.785825) (xy 19.612787 -222.807637)
			(xy 19.660393 -222.836691) (xy 19.703261 -222.872366) (xy 19.740478 -222.913903) (xy 19.771251 -222.960416)
			(xy 19.794923 -223.010913) (xy 19.810991 -223.06432) (xy 19.813982 -223.084644) (xy 21.0472 -223.084644)
			(xy 21.051271 -223.029022) (xy 21.063397 -222.974585) (xy 21.08332 -222.922494) (xy 21.110616 -222.873859)
			(xy 21.144702 -222.829716) (xy 21.184851 -222.791007) (xy 21.230209 -222.758556) (xy 21.279809 -222.733055)
			(xy 21.332593 -222.715048) (xy 21.387436 -222.704918) (xy 21.44317 -222.702881) (xy 21.498607 -222.708981)
			(xy 21.552564 -222.723087) (xy 21.603893 -222.744899) (xy 21.651499 -222.773953) (xy 21.694367 -222.809628)
			(xy 21.731584 -222.851165) (xy 21.762357 -222.897678) (xy 21.786029 -222.948175) (xy 21.794456 -222.976186)
			(xy 22.880066 -222.976186) (xy 22.880621 -222.94727) (xy 22.889339 -222.8901) (xy 22.906588 -222.8349)
			(xy 22.931973 -222.782938) (xy 22.964911 -222.735403) (xy 23.004648 -222.693386) (xy 23.027132 -222.675196)
			(xy 23.034531 -222.668928) (xy 23.044317 -222.652202) (xy 23.046182 -222.642684) (xy 23.04669 -222.635064)
			(xy 23.04669 -222.555308) (xy 23.046182 -222.547688) (xy 23.044305 -222.538176) (xy 23.034515 -222.52146)
			(xy 23.027132 -222.515176) (xy 23.004644 -222.49699) (xy 22.964907 -222.454971) (xy 22.931968 -222.407435)
			(xy 22.90658 -222.355472) (xy 22.889325 -222.300273) (xy 22.880599 -222.243102) (xy 22.880066 -222.214186)
			(xy 22.880552 -222.186935) (xy 22.888308 -222.132987) (xy 22.903663 -222.080692) (xy 22.926305 -222.031115)
			(xy 22.955771 -221.985265) (xy 22.991462 -221.944074) (xy 23.032653 -221.908383) (xy 23.078503 -221.878917)
			(xy 23.12808 -221.856275) (xy 23.180375 -221.84092) (xy 23.234323 -221.833164) (xy 23.288825 -221.833164)
			(xy 23.342773 -221.84092) (xy 23.395068 -221.856275) (xy 23.444645 -221.878917) (xy 23.490495 -221.908383)
			(xy 23.531686 -221.944074) (xy 23.567377 -221.985265) (xy 23.596843 -222.031115) (xy 23.619485 -222.080692)
			(xy 23.63484 -222.132987) (xy 23.642596 -222.186935) (xy 23.643082 -222.214186) (xy 23.64256 -222.243103)
			(xy 23.633833 -222.300274) (xy 23.616576 -222.355473) (xy 23.591185 -222.407435) (xy 23.558242 -222.454969)
			(xy 23.518501 -222.496986) (xy 23.496016 -222.515176) (xy 23.488635 -222.521463) (xy 23.478837 -222.538175)
			(xy 23.476966 -222.547688) (xy 23.476458 -222.555308) (xy 23.476458 -222.635064) (xy 23.476966 -222.642684)
			(xy 23.478827 -222.6522) (xy 23.48863 -222.668913) (xy 23.496016 -222.675196) (xy 23.518501 -222.693385)
			(xy 23.558235 -222.735406) (xy 23.591174 -222.782941) (xy 23.616562 -222.834903) (xy 23.633818 -222.8901)
			(xy 23.642547 -222.94727) (xy 23.643082 -222.976186) (xy 23.642596 -223.003437) (xy 23.63484 -223.057385)
			(xy 23.619485 -223.10968) (xy 23.596843 -223.159257) (xy 23.567377 -223.205107) (xy 23.531686 -223.246298)
			(xy 23.490495 -223.281989) (xy 23.444645 -223.311455) (xy 23.395068 -223.334097) (xy 23.342773 -223.349452)
			(xy 23.288825 -223.357208) (xy 23.234323 -223.357208) (xy 23.180375 -223.349452) (xy 23.12808 -223.334097)
			(xy 23.078503 -223.311455) (xy 23.032653 -223.281989) (xy 22.991462 -223.246298) (xy 22.955771 -223.205107)
			(xy 22.926305 -223.159257) (xy 22.903663 -223.10968) (xy 22.888308 -223.057385) (xy 22.880552 -223.003437)
			(xy 22.880066 -222.976186) (xy 21.794456 -222.976186) (xy 21.802097 -223.001582) (xy 21.810217 -223.056758)
			(xy 21.810726 -223.084644) (xy 21.810217 -223.11253) (xy 21.802097 -223.167706) (xy 21.786029 -223.221113)
			(xy 21.762357 -223.27161) (xy 21.731584 -223.318123) (xy 21.694367 -223.35966) (xy 21.651499 -223.395335)
			(xy 21.603893 -223.424389) (xy 21.552564 -223.446201) (xy 21.498607 -223.460307) (xy 21.44317 -223.466407)
			(xy 21.387436 -223.46437) (xy 21.332593 -223.45424) (xy 21.279809 -223.436233) (xy 21.230209 -223.410732)
			(xy 21.184851 -223.378281) (xy 21.144702 -223.339572) (xy 21.110616 -223.295429) (xy 21.08332 -223.246794)
			(xy 21.063397 -223.194703) (xy 21.051271 -223.140266) (xy 21.0472 -223.084644) (xy 19.813982 -223.084644)
			(xy 19.819111 -223.119496) (xy 19.81962 -223.147382) (xy 19.819111 -223.175268) (xy 19.810991 -223.230444)
			(xy 19.794923 -223.283851) (xy 19.771251 -223.334348) (xy 19.740478 -223.380861) (xy 19.703261 -223.422398)
			(xy 19.660393 -223.458073) (xy 19.612787 -223.487127) (xy 19.561458 -223.508939) (xy 19.507501 -223.523045)
			(xy 19.452064 -223.529145) (xy 19.39633 -223.527108) (xy 19.341487 -223.516978) (xy 19.288703 -223.498971)
			(xy 19.239103 -223.47347) (xy 19.193745 -223.441019) (xy 19.153596 -223.40231) (xy 19.11951 -223.358167)
			(xy 19.092214 -223.309532) (xy 19.072291 -223.257441) (xy 19.060165 -223.203004) (xy 19.056094 -223.147382)
			(xy 15.773908 -223.147382) (xy 15.773908 -223.537018) (xy 16.46885 -223.537018) (xy 16.472921 -223.481396)
			(xy 16.485047 -223.426959) (xy 16.50497 -223.374868) (xy 16.532266 -223.326233) (xy 16.566352 -223.28209)
			(xy 16.606501 -223.243381) (xy 16.651859 -223.21093) (xy 16.701459 -223.185429) (xy 16.754243 -223.167422)
			(xy 16.809086 -223.157292) (xy 16.86482 -223.155255) (xy 16.920257 -223.161355) (xy 16.974214 -223.175461)
			(xy 17.025543 -223.197273) (xy 17.073149 -223.226327) (xy 17.116017 -223.262002) (xy 17.153234 -223.303539)
			(xy 17.184007 -223.350052) (xy 17.207679 -223.400549) (xy 17.223747 -223.453956) (xy 17.231867 -223.509132)
			(xy 17.232376 -223.537018) (xy 17.231867 -223.564904) (xy 17.223747 -223.62008) (xy 17.207679 -223.673487)
			(xy 17.184007 -223.723984) (xy 17.153234 -223.770497) (xy 17.116017 -223.812034) (xy 17.080533 -223.841564)
			(xy 28.472636 -223.841564) (xy 28.476707 -223.785942) (xy 28.488833 -223.731505) (xy 28.508756 -223.679414)
			(xy 28.536052 -223.630779) (xy 28.570138 -223.586636) (xy 28.610287 -223.547927) (xy 28.655645 -223.515476)
			(xy 28.705245 -223.489975) (xy 28.758029 -223.471968) (xy 28.812872 -223.461838) (xy 28.868606 -223.459801)
			(xy 28.924043 -223.465901) (xy 28.978 -223.480007) (xy 29.029329 -223.501819) (xy 29.076935 -223.530873)
			(xy 29.119803 -223.566548) (xy 29.15702 -223.608085) (xy 29.187793 -223.654598) (xy 29.211465 -223.705095)
			(xy 29.227533 -223.758502) (xy 29.235653 -223.813678) (xy 29.236162 -223.841564) (xy 29.235653 -223.86945)
			(xy 29.227533 -223.924626) (xy 29.211465 -223.978033) (xy 29.187793 -224.02853) (xy 29.15702 -224.075043)
			(xy 29.119803 -224.11658) (xy 29.076935 -224.152255) (xy 29.029329 -224.181309) (xy 28.978 -224.203121)
			(xy 28.924043 -224.217227) (xy 28.868606 -224.223327) (xy 28.812872 -224.22129) (xy 28.758029 -224.21116)
			(xy 28.705245 -224.193153) (xy 28.655645 -224.167652) (xy 28.610287 -224.135201) (xy 28.570138 -224.096492)
			(xy 28.536052 -224.052349) (xy 28.508756 -224.003714) (xy 28.488833 -223.951623) (xy 28.476707 -223.897186)
			(xy 28.472636 -223.841564) (xy 17.080533 -223.841564) (xy 17.073149 -223.847709) (xy 17.025543 -223.876763)
			(xy 16.974214 -223.898575) (xy 16.920257 -223.912681) (xy 16.86482 -223.918781) (xy 16.809086 -223.916744)
			(xy 16.754243 -223.906614) (xy 16.701459 -223.888607) (xy 16.651859 -223.863106) (xy 16.606501 -223.830655)
			(xy 16.566352 -223.791946) (xy 16.532266 -223.747803) (xy 16.50497 -223.699168) (xy 16.485047 -223.647077)
			(xy 16.472921 -223.59264) (xy 16.46885 -223.537018) (xy 15.773908 -223.537018) (xy 15.773908 -224.536)
			(xy 27.78328 -224.536) (xy 27.787351 -224.480378) (xy 27.799477 -224.425941) (xy 27.8194 -224.37385)
			(xy 27.846696 -224.325215) (xy 27.880782 -224.281072) (xy 27.920931 -224.242363) (xy 27.966289 -224.209912)
			(xy 28.015889 -224.184411) (xy 28.068673 -224.166404) (xy 28.123516 -224.156274) (xy 28.17925 -224.154237)
			(xy 28.234687 -224.160337) (xy 28.288644 -224.174443) (xy 28.339973 -224.196255) (xy 28.387579 -224.225309)
			(xy 28.430447 -224.260984) (xy 28.467664 -224.302521) (xy 28.498437 -224.349034) (xy 28.522109 -224.399531)
			(xy 28.538177 -224.452938) (xy 28.546297 -224.508114) (xy 28.546806 -224.536) (xy 30.83128 -224.536)
			(xy 30.835351 -224.480378) (xy 30.847477 -224.425941) (xy 30.8674 -224.37385) (xy 30.894696 -224.325215)
			(xy 30.928782 -224.281072) (xy 30.968931 -224.242363) (xy 31.014289 -224.209912) (xy 31.063889 -224.184411)
			(xy 31.116673 -224.166404) (xy 31.171516 -224.156274) (xy 31.22725 -224.154237) (xy 31.282687 -224.160337)
			(xy 31.336644 -224.174443) (xy 31.387973 -224.196255) (xy 31.435579 -224.225309) (xy 31.478447 -224.260984)
			(xy 31.515664 -224.302521) (xy 31.546437 -224.349034) (xy 31.570109 -224.399531) (xy 31.586177 -224.452938)
			(xy 31.594297 -224.508114) (xy 31.594806 -224.536) (xy 31.594297 -224.563886) (xy 31.586177 -224.619062)
			(xy 31.570109 -224.672469) (xy 31.546437 -224.722966) (xy 31.515664 -224.769479) (xy 31.478447 -224.811016)
			(xy 31.435579 -224.846691) (xy 31.387973 -224.875745) (xy 31.336644 -224.897557) (xy 31.282687 -224.911663)
			(xy 31.22725 -224.917763) (xy 31.171516 -224.915726) (xy 31.116673 -224.905596) (xy 31.063889 -224.887589)
			(xy 31.014289 -224.862088) (xy 30.968931 -224.829637) (xy 30.928782 -224.790928) (xy 30.894696 -224.746785)
			(xy 30.8674 -224.69815) (xy 30.847477 -224.646059) (xy 30.835351 -224.591622) (xy 30.83128 -224.536)
			(xy 28.546806 -224.536) (xy 28.546297 -224.563886) (xy 28.538177 -224.619062) (xy 28.522109 -224.672469)
			(xy 28.498437 -224.722966) (xy 28.467664 -224.769479) (xy 28.430447 -224.811016) (xy 28.387579 -224.846691)
			(xy 28.339973 -224.875745) (xy 28.288644 -224.897557) (xy 28.234687 -224.911663) (xy 28.17925 -224.917763)
			(xy 28.123516 -224.915726) (xy 28.068673 -224.905596) (xy 28.015889 -224.887589) (xy 27.966289 -224.862088)
			(xy 27.920931 -224.829637) (xy 27.880782 -224.790928) (xy 27.846696 -224.746785) (xy 27.8194 -224.69815)
			(xy 27.799477 -224.646059) (xy 27.787351 -224.591622) (xy 27.78328 -224.536) (xy 15.773908 -224.536)
			(xy 15.773908 -225.82251) (xy 18.421094 -225.82251) (xy 18.425165 -225.766888) (xy 18.437291 -225.712451)
			(xy 18.457214 -225.66036) (xy 18.48451 -225.611725) (xy 18.518596 -225.567582) (xy 18.558745 -225.528873)
			(xy 18.604103 -225.496422) (xy 18.653703 -225.470921) (xy 18.706487 -225.452914) (xy 18.76133 -225.442784)
			(xy 18.817064 -225.440747) (xy 18.872501 -225.446847) (xy 18.926458 -225.460953) (xy 18.977787 -225.482765)
			(xy 19.025393 -225.511819) (xy 19.068261 -225.547494) (xy 19.105478 -225.589031) (xy 19.136251 -225.635544)
			(xy 19.158408 -225.68281) (xy 20.720048 -225.68281) (xy 20.724119 -225.627188) (xy 20.736245 -225.572751)
			(xy 20.756168 -225.52066) (xy 20.783464 -225.472025) (xy 20.81755 -225.427882) (xy 20.857699 -225.389173)
			(xy 20.903057 -225.356722) (xy 20.952657 -225.331221) (xy 21.005441 -225.313214) (xy 21.060284 -225.303084)
			(xy 21.116018 -225.301047) (xy 21.171455 -225.307147) (xy 21.225412 -225.321253) (xy 21.276741 -225.343065)
			(xy 21.324347 -225.372119) (xy 21.367215 -225.407794) (xy 21.404432 -225.449331) (xy 21.435205 -225.495844)
			(xy 21.458877 -225.546341) (xy 21.474945 -225.599748) (xy 21.483065 -225.654924) (xy 21.483574 -225.68281)
			(xy 21.483065 -225.710696) (xy 21.474945 -225.765872) (xy 21.458877 -225.819279) (xy 21.435205 -225.869776)
			(xy 21.404432 -225.916289) (xy 21.367215 -225.957826) (xy 21.324347 -225.993501) (xy 21.276741 -226.022555)
			(xy 21.225412 -226.044367) (xy 21.171455 -226.058473) (xy 21.116018 -226.064573) (xy 21.060284 -226.062536)
			(xy 21.005441 -226.052406) (xy 20.952657 -226.034399) (xy 20.903057 -226.008898) (xy 20.857699 -225.976447)
			(xy 20.81755 -225.937738) (xy 20.783464 -225.893595) (xy 20.756168 -225.84496) (xy 20.736245 -225.792869)
			(xy 20.724119 -225.738432) (xy 20.720048 -225.68281) (xy 19.158408 -225.68281) (xy 19.159923 -225.686041)
			(xy 19.175991 -225.739448) (xy 19.184111 -225.794624) (xy 19.18462 -225.82251) (xy 19.184111 -225.850396)
			(xy 19.175991 -225.905572) (xy 19.159923 -225.958979) (xy 19.136251 -226.009476) (xy 19.105478 -226.055989)
			(xy 19.068261 -226.097526) (xy 19.025393 -226.133201) (xy 18.977787 -226.162255) (xy 18.926458 -226.184067)
			(xy 18.872501 -226.198173) (xy 18.817064 -226.204273) (xy 18.76133 -226.202236) (xy 18.706487 -226.192106)
			(xy 18.653703 -226.174099) (xy 18.604103 -226.148598) (xy 18.558745 -226.116147) (xy 18.518596 -226.077438)
			(xy 18.48451 -226.033295) (xy 18.457214 -225.98466) (xy 18.437291 -225.932569) (xy 18.425165 -225.878132)
			(xy 18.421094 -225.82251) (xy 15.773908 -225.82251) (xy 15.773908 -226.568) (xy 30.95828 -226.568)
			(xy 30.962351 -226.512378) (xy 30.974477 -226.457941) (xy 30.9944 -226.40585) (xy 31.021696 -226.357215)
			(xy 31.055782 -226.313072) (xy 31.095931 -226.274363) (xy 31.141289 -226.241912) (xy 31.190889 -226.216411)
			(xy 31.243673 -226.198404) (xy 31.298516 -226.188274) (xy 31.35425 -226.186237) (xy 31.409687 -226.192337)
			(xy 31.463644 -226.206443) (xy 31.514973 -226.228255) (xy 31.562579 -226.257309) (xy 31.605447 -226.292984)
			(xy 31.642664 -226.334521) (xy 31.673437 -226.381034) (xy 31.697109 -226.431531) (xy 31.699576 -226.43973)
			(xy 31.893 -226.43973) (xy 31.897071 -226.384108) (xy 31.909197 -226.329671) (xy 31.92912 -226.27758)
			(xy 31.956416 -226.228945) (xy 31.990502 -226.184802) (xy 32.030651 -226.146093) (xy 32.076009 -226.113642)
			(xy 32.125609 -226.088141) (xy 32.178393 -226.070134) (xy 32.233236 -226.060004) (xy 32.28897 -226.057967)
			(xy 32.344407 -226.064067) (xy 32.398364 -226.078173) (xy 32.449693 -226.099985) (xy 32.497299 -226.129039)
			(xy 32.540167 -226.164714) (xy 32.577384 -226.206251) (xy 32.608157 -226.252764) (xy 32.631829 -226.303261)
			(xy 32.647897 -226.356668) (xy 32.656017 -226.411844) (xy 32.656526 -226.43973) (xy 32.656017 -226.467616)
			(xy 32.647897 -226.522792) (xy 32.631829 -226.576199) (xy 32.608157 -226.626696) (xy 32.577384 -226.673209)
			(xy 32.540167 -226.714746) (xy 32.497299 -226.750421) (xy 32.449693 -226.779475) (xy 32.398364 -226.801287)
			(xy 32.344407 -226.815393) (xy 32.28897 -226.821493) (xy 32.233236 -226.819456) (xy 32.178393 -226.809326)
			(xy 32.125609 -226.791319) (xy 32.076009 -226.765818) (xy 32.030651 -226.733367) (xy 31.990502 -226.694658)
			(xy 31.956416 -226.650515) (xy 31.92912 -226.60188) (xy 31.909197 -226.549789) (xy 31.897071 -226.495352)
			(xy 31.893 -226.43973) (xy 31.699576 -226.43973) (xy 31.713177 -226.484938) (xy 31.721297 -226.540114)
			(xy 31.721806 -226.568) (xy 31.721297 -226.595886) (xy 31.713177 -226.651062) (xy 31.697109 -226.704469)
			(xy 31.673437 -226.754966) (xy 31.642664 -226.801479) (xy 31.605447 -226.843016) (xy 31.562579 -226.878691)
			(xy 31.514973 -226.907745) (xy 31.463644 -226.929557) (xy 31.409687 -226.943663) (xy 31.35425 -226.949763)
			(xy 31.298516 -226.947726) (xy 31.243673 -226.937596) (xy 31.190889 -226.919589) (xy 31.141289 -226.894088)
			(xy 31.095931 -226.861637) (xy 31.055782 -226.822928) (xy 31.021696 -226.778785) (xy 30.9944 -226.73015)
			(xy 30.974477 -226.678059) (xy 30.962351 -226.623622) (xy 30.95828 -226.568) (xy 15.773908 -226.568)
			(xy 15.773908 -227.965) (xy 15.918432 -227.965) (xy 15.922503 -227.909378) (xy 15.934629 -227.854941)
			(xy 15.954552 -227.80285) (xy 15.981848 -227.754215) (xy 16.015934 -227.710072) (xy 16.056083 -227.671363)
			(xy 16.101441 -227.638912) (xy 16.151041 -227.613411) (xy 16.203825 -227.595404) (xy 16.258668 -227.585274)
			(xy 16.314402 -227.583237) (xy 16.369839 -227.589337) (xy 16.423796 -227.603443) (xy 16.475125 -227.625255)
			(xy 16.522731 -227.654309) (xy 16.565599 -227.689984) (xy 16.602816 -227.731521) (xy 16.633589 -227.778034)
			(xy 16.657261 -227.828531) (xy 16.673329 -227.881938) (xy 16.681449 -227.937114) (xy 16.681958 -227.965)
			(xy 16.681449 -227.992886) (xy 16.673329 -228.048062) (xy 16.657261 -228.101469) (xy 16.633589 -228.151966)
			(xy 16.615118 -228.179884) (xy 17.914872 -228.179884) (xy 17.918943 -228.124262) (xy 17.931069 -228.069825)
			(xy 17.950992 -228.017734) (xy 17.978288 -227.969099) (xy 18.012374 -227.924956) (xy 18.052523 -227.886247)
			(xy 18.097881 -227.853796) (xy 18.147481 -227.828295) (xy 18.200265 -227.810288) (xy 18.255108 -227.800158)
			(xy 18.310842 -227.798121) (xy 18.366279 -227.804221) (xy 18.420236 -227.818327) (xy 18.471565 -227.840139)
			(xy 18.519171 -227.869193) (xy 18.562039 -227.904868) (xy 18.599256 -227.946405) (xy 18.630029 -227.992918)
			(xy 18.653701 -228.043415) (xy 18.661441 -228.06914) (xy 18.973544 -228.06914) (xy 18.977615 -228.013518)
			(xy 18.989741 -227.959081) (xy 19.009664 -227.90699) (xy 19.03696 -227.858355) (xy 19.071046 -227.814212)
			(xy 19.111195 -227.775503) (xy 19.156553 -227.743052) (xy 19.206153 -227.717551) (xy 19.258937 -227.699544)
			(xy 19.31378 -227.689414) (xy 19.369514 -227.687377) (xy 19.424951 -227.693477) (xy 19.478908 -227.707583)
			(xy 19.530237 -227.729395) (xy 19.577843 -227.758449) (xy 19.620711 -227.794124) (xy 19.657928 -227.835661)
			(xy 19.688701 -227.882174) (xy 19.712373 -227.932671) (xy 19.728441 -227.986078) (xy 19.736561 -228.041254)
			(xy 19.73707 -228.06914) (xy 19.736917 -228.077522) (xy 20.024088 -228.077522) (xy 20.028159 -228.0219)
			(xy 20.040285 -227.967463) (xy 20.060208 -227.915372) (xy 20.087504 -227.866737) (xy 20.12159 -227.822594)
			(xy 20.161739 -227.783885) (xy 20.207097 -227.751434) (xy 20.256697 -227.725933) (xy 20.309481 -227.707926)
			(xy 20.364324 -227.697796) (xy 20.420058 -227.695759) (xy 20.475495 -227.701859) (xy 20.529452 -227.715965)
			(xy 20.580781 -227.737777) (xy 20.628387 -227.766831) (xy 20.671255 -227.802506) (xy 20.708472 -227.844043)
			(xy 20.739245 -227.890556) (xy 20.762917 -227.941053) (xy 20.778985 -227.99446) (xy 20.787105 -228.049636)
			(xy 20.787614 -228.077522) (xy 20.787105 -228.105408) (xy 20.778985 -228.160584) (xy 20.762917 -228.213991)
			(xy 20.739245 -228.264488) (xy 20.708472 -228.311001) (xy 20.671255 -228.352538) (xy 20.628387 -228.388213)
			(xy 20.605993 -228.40188) (xy 21.932644 -228.40188) (xy 21.936715 -228.346258) (xy 21.948841 -228.291821)
			(xy 21.968764 -228.23973) (xy 21.99606 -228.191095) (xy 22.030146 -228.146952) (xy 22.070295 -228.108243)
			(xy 22.115653 -228.075792) (xy 22.165253 -228.050291) (xy 22.218037 -228.032284) (xy 22.27288 -228.022154)
			(xy 22.328614 -228.020117) (xy 22.384051 -228.026217) (xy 22.438008 -228.040323) (xy 22.489337 -228.062135)
			(xy 22.536943 -228.091189) (xy 22.579811 -228.126864) (xy 22.617028 -228.168401) (xy 22.647801 -228.214914)
			(xy 22.671473 -228.265411) (xy 22.687541 -228.318818) (xy 22.695661 -228.373994) (xy 22.69617 -228.40188)
			(xy 22.695661 -228.429766) (xy 22.687541 -228.484942) (xy 22.671473 -228.538349) (xy 22.647801 -228.588846)
			(xy 22.617028 -228.635359) (xy 22.581573 -228.67493) (xy 25.95575 -228.67493) (xy 25.959821 -228.619308)
			(xy 25.971947 -228.564871) (xy 25.99187 -228.51278) (xy 26.019166 -228.464145) (xy 26.053252 -228.420002)
			(xy 26.093401 -228.381293) (xy 26.138759 -228.348842) (xy 26.188359 -228.323341) (xy 26.241143 -228.305334)
			(xy 26.295986 -228.295204) (xy 26.35172 -228.293167) (xy 26.407157 -228.299267) (xy 26.461114 -228.313373)
			(xy 26.512443 -228.335185) (xy 26.560049 -228.364239) (xy 26.602917 -228.399914) (xy 26.640134 -228.441451)
			(xy 26.670907 -228.487964) (xy 26.694579 -228.538461) (xy 26.710647 -228.591868) (xy 26.718767 -228.647044)
			(xy 26.719276 -228.67493) (xy 26.718767 -228.702816) (xy 26.710647 -228.757992) (xy 26.694579 -228.811399)
			(xy 26.670907 -228.861896) (xy 26.640134 -228.908409) (xy 26.602917 -228.949946) (xy 26.560049 -228.985621)
			(xy 26.512443 -229.014675) (xy 26.461114 -229.036487) (xy 26.407157 -229.050593) (xy 26.35172 -229.056693)
			(xy 26.295986 -229.054656) (xy 26.241143 -229.044526) (xy 26.188359 -229.026519) (xy 26.138759 -229.001018)
			(xy 26.093401 -228.968567) (xy 26.053252 -228.929858) (xy 26.019166 -228.885715) (xy 25.99187 -228.83708)
			(xy 25.971947 -228.784989) (xy 25.959821 -228.730552) (xy 25.95575 -228.67493) (xy 22.581573 -228.67493)
			(xy 22.579811 -228.676896) (xy 22.536943 -228.712571) (xy 22.489337 -228.741625) (xy 22.438008 -228.763437)
			(xy 22.384051 -228.777543) (xy 22.328614 -228.783643) (xy 22.27288 -228.781606) (xy 22.218037 -228.771476)
			(xy 22.165253 -228.753469) (xy 22.115653 -228.727968) (xy 22.070295 -228.695517) (xy 22.030146 -228.656808)
			(xy 21.99606 -228.612665) (xy 21.968764 -228.56403) (xy 21.948841 -228.511939) (xy 21.936715 -228.457502)
			(xy 21.932644 -228.40188) (xy 20.605993 -228.40188) (xy 20.580781 -228.417267) (xy 20.529452 -228.439079)
			(xy 20.475495 -228.453185) (xy 20.420058 -228.459285) (xy 20.364324 -228.457248) (xy 20.309481 -228.447118)
			(xy 20.256697 -228.429111) (xy 20.207097 -228.40361) (xy 20.161739 -228.371159) (xy 20.12159 -228.33245)
			(xy 20.087504 -228.288307) (xy 20.060208 -228.239672) (xy 20.040285 -228.187581) (xy 20.028159 -228.133144)
			(xy 20.024088 -228.077522) (xy 19.736917 -228.077522) (xy 19.736561 -228.097026) (xy 19.728441 -228.152202)
			(xy 19.712373 -228.205609) (xy 19.688701 -228.256106) (xy 19.657928 -228.302619) (xy 19.620711 -228.344156)
			(xy 19.577843 -228.379831) (xy 19.530237 -228.408885) (xy 19.478908 -228.430697) (xy 19.424951 -228.444803)
			(xy 19.369514 -228.450903) (xy 19.31378 -228.448866) (xy 19.258937 -228.438736) (xy 19.206153 -228.420729)
			(xy 19.156553 -228.395228) (xy 19.111195 -228.362777) (xy 19.071046 -228.324068) (xy 19.03696 -228.279925)
			(xy 19.009664 -228.23129) (xy 18.989741 -228.179199) (xy 18.977615 -228.124762) (xy 18.973544 -228.06914)
			(xy 18.661441 -228.06914) (xy 18.669769 -228.096822) (xy 18.677889 -228.151998) (xy 18.678398 -228.179884)
			(xy 18.677889 -228.20777) (xy 18.669769 -228.262946) (xy 18.653701 -228.316353) (xy 18.630029 -228.36685)
			(xy 18.599256 -228.413363) (xy 18.562039 -228.4549) (xy 18.519171 -228.490575) (xy 18.471565 -228.519629)
			(xy 18.420236 -228.541441) (xy 18.366279 -228.555547) (xy 18.310842 -228.561647) (xy 18.255108 -228.55961)
			(xy 18.200265 -228.54948) (xy 18.147481 -228.531473) (xy 18.097881 -228.505972) (xy 18.052523 -228.473521)
			(xy 18.012374 -228.434812) (xy 17.978288 -228.390669) (xy 17.950992 -228.342034) (xy 17.931069 -228.289943)
			(xy 17.918943 -228.235506) (xy 17.914872 -228.179884) (xy 16.615118 -228.179884) (xy 16.602816 -228.198479)
			(xy 16.565599 -228.240016) (xy 16.522731 -228.275691) (xy 16.475125 -228.304745) (xy 16.423796 -228.326557)
			(xy 16.369839 -228.340663) (xy 16.314402 -228.346763) (xy 16.258668 -228.344726) (xy 16.203825 -228.334596)
			(xy 16.151041 -228.316589) (xy 16.101441 -228.291088) (xy 16.056083 -228.258637) (xy 16.015934 -228.219928)
			(xy 15.981848 -228.175785) (xy 15.954552 -228.12715) (xy 15.934629 -228.075059) (xy 15.922503 -228.020622)
			(xy 15.918432 -227.965) (xy 15.773908 -227.965) (xy 15.773908 -229.94493) (xy 22.83028 -229.94493)
			(xy 22.834351 -229.889308) (xy 22.846477 -229.834871) (xy 22.8664 -229.78278) (xy 22.893696 -229.734145)
			(xy 22.927782 -229.690002) (xy 22.967931 -229.651293) (xy 23.013289 -229.618842) (xy 23.062889 -229.593341)
			(xy 23.115673 -229.575334) (xy 23.170516 -229.565204) (xy 23.22625 -229.563167) (xy 23.281687 -229.569267)
			(xy 23.335644 -229.583373) (xy 23.386973 -229.605185) (xy 23.434579 -229.634239) (xy 23.477447 -229.669914)
			(xy 23.514664 -229.711451) (xy 23.545437 -229.757964) (xy 23.569109 -229.808461) (xy 23.585177 -229.861868)
			(xy 23.593297 -229.917044) (xy 23.593806 -229.94493) (xy 23.593297 -229.972816) (xy 23.585177 -230.027992)
			(xy 23.569109 -230.081399) (xy 23.545437 -230.131896) (xy 23.514664 -230.178409) (xy 23.477447 -230.219946)
			(xy 23.434579 -230.255621) (xy 23.386973 -230.284675) (xy 23.335644 -230.306487) (xy 23.281687 -230.320593)
			(xy 23.22625 -230.326693) (xy 23.170516 -230.324656) (xy 23.115673 -230.314526) (xy 23.062889 -230.296519)
			(xy 23.013289 -230.271018) (xy 22.967931 -230.238567) (xy 22.927782 -230.199858) (xy 22.893696 -230.155715)
			(xy 22.8664 -230.10708) (xy 22.846477 -230.054989) (xy 22.834351 -230.000552) (xy 22.83028 -229.94493)
			(xy 15.773908 -229.94493) (xy 15.773908 -231.422194) (xy 15.774126 -231.429003) (xy 15.777733 -231.442135)
			(xy 15.78102 -231.448102) (xy 15.784576 -231.454198) (xy 15.794482 -231.463596) (xy 15.800578 -231.466898)
			(xy 15.880334 -231.517952) (xy 15.906242 -231.519476) (xy 15.91818 -231.514142) (xy 15.943446 -231.502945)
			(xy 15.996398 -231.48713) (xy 16.051077 -231.479111) (xy 16.078708 -231.478582) (xy 16.078962 -231.478582)
			(xy 16.106213 -231.479068) (xy 16.160161 -231.486825) (xy 16.212455 -231.50218) (xy 16.262032 -231.524821)
			(xy 16.307882 -231.554288) (xy 16.349072 -231.589979) (xy 16.384764 -231.631169) (xy 16.41423 -231.67702)
			(xy 16.436871 -231.726597) (xy 16.452226 -231.778891) (xy 16.459982 -231.832839) (xy 16.459982 -231.887341)
			(xy 16.458495 -231.897682) (xy 16.753586 -231.897682) (xy 16.753982 -231.871481) (xy 16.761173 -231.819574)
			(xy 16.775403 -231.769141) (xy 16.796405 -231.721131) (xy 16.823782 -231.676449) (xy 16.857018 -231.635936)
			(xy 16.895489 -231.600355) (xy 16.938469 -231.570377) (xy 16.961612 -231.558084) (xy 16.961866 -231.55783)
			(xy 16.962374 -231.557576) (xy 16.967041 -231.554931) (xy 16.975244 -231.548021) (xy 16.97863 -231.54386)
			(xy 16.978884 -231.54386) (xy 16.982265 -231.539298) (xy 16.987133 -231.529042) (xy 16.988536 -231.52354)
			(xy 17.008094 -231.43591) (xy 17.005554 -231.42448) (xy 17.004217 -231.419352) (xy 16.999733 -231.409751)
			(xy 16.996664 -231.40543) (xy 16.996156 -231.404922) (xy 16.995902 -231.404668) (xy 16.980781 -231.38455)
			(xy 16.95543 -231.341071) (xy 16.936024 -231.294634) (xy 16.922901 -231.246046) (xy 16.916289 -231.196153)
			(xy 16.915892 -231.170988) (xy 16.916378 -231.143737) (xy 16.924134 -231.089789) (xy 16.939489 -231.037494)
			(xy 16.962131 -230.987917) (xy 16.991597 -230.942067) (xy 17.027288 -230.900876) (xy 17.068479 -230.865185)
			(xy 17.114329 -230.835719) (xy 17.163906 -230.813077) (xy 17.216201 -230.797722) (xy 17.270149 -230.789966)
			(xy 17.324651 -230.789966) (xy 17.378599 -230.797722) (xy 17.430894 -230.813077) (xy 17.480471 -230.835719)
			(xy 17.526321 -230.865185) (xy 17.567512 -230.900876) (xy 17.603203 -230.942067) (xy 17.632669 -230.987917)
			(xy 17.655311 -231.037494) (xy 17.670666 -231.089789) (xy 17.678422 -231.143737) (xy 17.678908 -231.170988)
			(xy 17.67849 -231.197188) (xy 17.671303 -231.249094) (xy 17.657077 -231.299527) (xy 17.636079 -231.347537)
			(xy 17.608705 -231.392219) (xy 17.575471 -231.432733) (xy 17.537002 -231.468314) (xy 17.494024 -231.498293)
			(xy 17.470882 -231.510586) (xy 17.470628 -231.51084) (xy 17.47012 -231.511094) (xy 17.465444 -231.513725)
			(xy 17.457246 -231.520644) (xy 17.453864 -231.52481) (xy 17.45361 -231.52481) (xy 17.450236 -231.529376)
			(xy 17.445364 -231.539629) (xy 17.443958 -231.54513) (xy 17.4244 -231.63276) (xy 17.42694 -231.64419)
			(xy 17.428286 -231.649316) (xy 17.432763 -231.658918) (xy 17.43583 -231.66324) (xy 17.436338 -231.663748)
			(xy 17.436592 -231.664002) (xy 17.451699 -231.684131) (xy 17.477052 -231.727606) (xy 17.496461 -231.774041)
			(xy 17.509588 -231.822627) (xy 17.516203 -231.872518) (xy 17.516602 -231.897682) (xy 17.516116 -231.924933)
			(xy 17.512475 -231.95026) (xy 17.786094 -231.95026) (xy 17.790165 -231.894638) (xy 17.802291 -231.840201)
			(xy 17.822214 -231.78811) (xy 17.84951 -231.739475) (xy 17.883596 -231.695332) (xy 17.923745 -231.656623)
			(xy 17.969103 -231.624172) (xy 18.018703 -231.598671) (xy 18.071487 -231.580664) (xy 18.12633 -231.570534)
			(xy 18.182064 -231.568497) (xy 18.237501 -231.574597) (xy 18.291458 -231.588703) (xy 18.342787 -231.610515)
			(xy 18.390393 -231.639569) (xy 18.433261 -231.675244) (xy 18.470478 -231.716781) (xy 18.501251 -231.763294)
			(xy 18.524923 -231.813791) (xy 18.540991 -231.867198) (xy 18.549111 -231.922374) (xy 18.54962 -231.95026)
			(xy 18.549111 -231.978146) (xy 18.540991 -232.033322) (xy 18.524923 -232.086729) (xy 18.501251 -232.137226)
			(xy 18.470478 -232.183739) (xy 18.433261 -232.225276) (xy 18.390393 -232.260951) (xy 18.342787 -232.290005)
			(xy 18.291458 -232.311817) (xy 18.237501 -232.325923) (xy 18.182064 -232.332023) (xy 18.12633 -232.329986)
			(xy 18.071487 -232.319856) (xy 18.018703 -232.301849) (xy 17.969103 -232.276348) (xy 17.923745 -232.243897)
			(xy 17.883596 -232.205188) (xy 17.84951 -232.161045) (xy 17.822214 -232.11241) (xy 17.802291 -232.060319)
			(xy 17.790165 -232.005882) (xy 17.786094 -231.95026) (xy 17.512475 -231.95026) (xy 17.50836 -231.978881)
			(xy 17.493005 -232.031176) (xy 17.470363 -232.080753) (xy 17.440897 -232.126603) (xy 17.405206 -232.167794)
			(xy 17.364015 -232.203485) (xy 17.318165 -232.232951) (xy 17.268588 -232.255593) (xy 17.216293 -232.270948)
			(xy 17.162345 -232.278704) (xy 17.107843 -232.278704) (xy 17.053895 -232.270948) (xy 17.0016 -232.255593)
			(xy 16.952023 -232.232951) (xy 16.906173 -232.203485) (xy 16.864982 -232.167794) (xy 16.829291 -232.126603)
			(xy 16.799825 -232.080753) (xy 16.777183 -232.031176) (xy 16.761828 -231.978881) (xy 16.754072 -231.924933)
			(xy 16.753586 -231.897682) (xy 16.458495 -231.897682) (xy 16.452226 -231.941289) (xy 16.436871 -231.993583)
			(xy 16.41423 -232.04316) (xy 16.384764 -232.089011) (xy 16.349072 -232.130201) (xy 16.307882 -232.165892)
			(xy 16.262032 -232.195359) (xy 16.212455 -232.218) (xy 16.160161 -232.233355) (xy 16.106213 -232.241112)
			(xy 16.078962 -232.241598) (xy 16.078454 -232.241598) (xy 16.050864 -232.241076) (xy 15.996268 -232.233052)
			(xy 15.943402 -232.217235) (xy 15.91818 -232.206038) (xy 15.906242 -232.200704) (xy 15.880334 -232.202228)
			(xy 15.7861 -232.262426) (xy 15.773908 -232.285032) (xy 15.773908 -240.318036) (xy 19.174206 -240.318036)
			(xy 19.174692 -240.290785) (xy 19.182448 -240.236837) (xy 19.197803 -240.184542) (xy 19.220445 -240.134965)
			(xy 19.249911 -240.089115) (xy 19.285602 -240.047924) (xy 19.326793 -240.012233) (xy 19.372643 -239.982767)
			(xy 19.42222 -239.960125) (xy 19.474515 -239.94477) (xy 19.528463 -239.937014) (xy 19.582965 -239.937014)
			(xy 19.636913 -239.94477) (xy 19.689208 -239.960125) (xy 19.738785 -239.982767) (xy 19.784635 -240.012233)
			(xy 19.825826 -240.047924) (xy 19.861517 -240.089115) (xy 19.890983 -240.134965) (xy 19.913625 -240.184542)
			(xy 19.92898 -240.236837) (xy 19.936736 -240.290785) (xy 19.936986 -240.304828) (xy 20.088604 -240.304828)
			(xy 20.092675 -240.249206) (xy 20.104801 -240.194769) (xy 20.124724 -240.142678) (xy 20.15202 -240.094043)
			(xy 20.186106 -240.0499) (xy 20.226255 -240.011191) (xy 20.271613 -239.97874) (xy 20.321213 -239.953239)
			(xy 20.373997 -239.935232) (xy 20.42884 -239.925102) (xy 20.484574 -239.923065) (xy 20.540011 -239.929165)
			(xy 20.593968 -239.943271) (xy 20.645297 -239.965083) (xy 20.692903 -239.994137) (xy 20.735771 -240.029812)
			(xy 20.772988 -240.071349) (xy 20.803761 -240.117862) (xy 20.827433 -240.168359) (xy 20.843501 -240.221766)
			(xy 20.851621 -240.276942) (xy 20.85213 -240.304828) (xy 20.851621 -240.332714) (xy 20.843501 -240.38789)
			(xy 20.827433 -240.441297) (xy 20.803761 -240.491794) (xy 20.772988 -240.538307) (xy 20.735771 -240.579844)
			(xy 20.692903 -240.615519) (xy 20.645297 -240.644573) (xy 20.593968 -240.666385) (xy 20.540011 -240.680491)
			(xy 20.484574 -240.686591) (xy 20.42884 -240.684554) (xy 20.373997 -240.674424) (xy 20.321213 -240.656417)
			(xy 20.271613 -240.630916) (xy 20.226255 -240.598465) (xy 20.186106 -240.559756) (xy 20.15202 -240.515613)
			(xy 20.124724 -240.466978) (xy 20.104801 -240.414887) (xy 20.092675 -240.36045) (xy 20.088604 -240.304828)
			(xy 19.936986 -240.304828) (xy 19.937222 -240.318036) (xy 19.937222 -240.31829) (xy 19.936768 -240.345461)
			(xy 19.92906 -240.399252) (xy 19.913783 -240.451401) (xy 19.891249 -240.50085) (xy 19.861916 -240.546594)
			(xy 19.844512 -240.567464) (xy 19.836015 -240.578111) (xy 19.824331 -240.602702) (xy 19.819566 -240.629508)
			(xy 19.82206 -240.656619) (xy 19.831636 -240.682105) (xy 19.84761 -240.704151) (xy 19.868847 -240.721188)
			(xy 19.893833 -240.732001) (xy 19.90725 -240.734342) (xy 19.934252 -240.738602) (xy 19.986754 -240.753823)
			(xy 20.036546 -240.776381) (xy 20.08261 -240.805814) (xy 20.124 -240.84152) (xy 20.159872 -240.882768)
			(xy 20.189489 -240.928713) (xy 20.212246 -240.978415) (xy 20.227676 -241.030856) (xy 20.235464 -241.084962)
			(xy 20.235926 -241.112294) (xy 20.23544 -241.139545) (xy 20.227684 -241.193493) (xy 20.212329 -241.245788)
			(xy 20.189687 -241.295365) (xy 20.160221 -241.341215) (xy 20.12453 -241.382406) (xy 20.083339 -241.418097)
			(xy 20.037489 -241.447563) (xy 19.987912 -241.470205) (xy 19.935617 -241.48556) (xy 19.881669 -241.493316)
			(xy 19.827167 -241.493316) (xy 19.773219 -241.48556) (xy 19.720924 -241.470205) (xy 19.671347 -241.447563)
			(xy 19.625497 -241.418097) (xy 19.584306 -241.382406) (xy 19.548615 -241.341215) (xy 19.519149 -241.295365)
			(xy 19.496507 -241.245788) (xy 19.481152 -241.193493) (xy 19.473396 -241.139545) (xy 19.47291 -241.112294)
			(xy 19.47291 -241.11204) (xy 19.473398 -241.084871) (xy 19.481101 -241.031082) (xy 19.49637 -240.978933)
			(xy 19.518896 -240.929484) (xy 19.548221 -240.883738) (xy 19.56562 -240.862866) (xy 19.574243 -240.85231)
			(xy 19.585933 -240.827695) (xy 19.590695 -240.800865) (xy 19.588189 -240.77373) (xy 19.578595 -240.748225)
			(xy 19.562594 -240.726167) (xy 19.541329 -240.709128) (xy 19.516313 -240.698321) (xy 19.502882 -240.695988)
			(xy 19.475876 -240.691752) (xy 19.423376 -240.676524) (xy 19.373586 -240.65396) (xy 19.327525 -240.624522)
			(xy 19.286137 -240.588813) (xy 19.250267 -240.547563) (xy 19.22065 -240.501617) (xy 19.197893 -240.451915)
			(xy 19.182461 -240.399474) (xy 19.17467 -240.345368) (xy 19.174206 -240.318036) (xy 15.773908 -240.318036)
			(xy 15.773908 -242.168934) (xy 19.00631 -242.168934) (xy 19.010381 -242.113312) (xy 19.022507 -242.058875)
			(xy 19.04243 -242.006784) (xy 19.069726 -241.958149) (xy 19.103812 -241.914006) (xy 19.143961 -241.875297)
			(xy 19.189319 -241.842846) (xy 19.238919 -241.817345) (xy 19.291703 -241.799338) (xy 19.346546 -241.789208)
			(xy 19.40228 -241.787171) (xy 19.457717 -241.793271) (xy 19.511674 -241.807377) (xy 19.563003 -241.829189)
			(xy 19.610609 -241.858243) (xy 19.653477 -241.893918) (xy 19.690694 -241.935455) (xy 19.721467 -241.981968)
			(xy 19.745139 -242.032465) (xy 19.761207 -242.085872) (xy 19.769327 -242.141048) (xy 19.769836 -242.168934)
			(xy 19.769327 -242.19682) (xy 19.761207 -242.251996) (xy 19.745139 -242.305403) (xy 19.721467 -242.3559)
			(xy 19.690694 -242.402413) (xy 19.653477 -242.44395) (xy 19.610609 -242.479625) (xy 19.563003 -242.508679)
			(xy 19.511674 -242.530491) (xy 19.457717 -242.544597) (xy 19.40228 -242.550697) (xy 19.346546 -242.54866)
			(xy 19.291703 -242.53853) (xy 19.238919 -242.520523) (xy 19.189319 -242.495022) (xy 19.143961 -242.462571)
			(xy 19.103812 -242.423862) (xy 19.069726 -242.379719) (xy 19.04243 -242.331084) (xy 19.022507 -242.278993)
			(xy 19.010381 -242.224556) (xy 19.00631 -242.168934) (xy 15.773908 -242.168934) (xy 15.773908 -251.158502)
			(xy 23.960326 -251.158502) (xy 23.964397 -251.10288) (xy 23.976523 -251.048443) (xy 23.996446 -250.996352)
			(xy 24.023742 -250.947717) (xy 24.057828 -250.903574) (xy 24.097977 -250.864865) (xy 24.143335 -250.832414)
			(xy 24.192935 -250.806913) (xy 24.245719 -250.788906) (xy 24.300562 -250.778776) (xy 24.356296 -250.776739)
			(xy 24.411733 -250.782839) (xy 24.46569 -250.796945) (xy 24.517019 -250.818757) (xy 24.564625 -250.847811)
			(xy 24.607493 -250.883486) (xy 24.64471 -250.925023) (xy 24.675483 -250.971536) (xy 24.699155 -251.022033)
			(xy 24.715223 -251.07544) (xy 24.723343 -251.130616) (xy 24.723792 -251.1552) (xy 25.068782 -251.1552)
			(xy 25.072853 -251.099578) (xy 25.084979 -251.045141) (xy 25.104902 -250.99305) (xy 25.132198 -250.944415)
			(xy 25.166284 -250.900272) (xy 25.206433 -250.861563) (xy 25.251791 -250.829112) (xy 25.301391 -250.803611)
			(xy 25.354175 -250.785604) (xy 25.409018 -250.775474) (xy 25.464752 -250.773437) (xy 25.520189 -250.779537)
			(xy 25.574146 -250.793643) (xy 25.625475 -250.815455) (xy 25.673081 -250.844509) (xy 25.715949 -250.880184)
			(xy 25.753166 -250.921721) (xy 25.783939 -250.968234) (xy 25.807611 -251.018731) (xy 25.823679 -251.072138)
			(xy 25.831799 -251.127314) (xy 25.832308 -251.1552) (xy 25.832248 -251.158502) (xy 25.992326 -251.158502)
			(xy 25.996397 -251.10288) (xy 26.008523 -251.048443) (xy 26.028446 -250.996352) (xy 26.055742 -250.947717)
			(xy 26.089828 -250.903574) (xy 26.129977 -250.864865) (xy 26.175335 -250.832414) (xy 26.224935 -250.806913)
			(xy 26.277719 -250.788906) (xy 26.332562 -250.778776) (xy 26.388296 -250.776739) (xy 26.443733 -250.782839)
			(xy 26.49769 -250.796945) (xy 26.549019 -250.818757) (xy 26.596625 -250.847811) (xy 26.639493 -250.883486)
			(xy 26.67671 -250.925023) (xy 26.707483 -250.971536) (xy 26.731155 -251.022033) (xy 26.747223 -251.07544)
			(xy 26.755343 -251.130616) (xy 26.755852 -251.158502) (xy 27.008326 -251.158502) (xy 27.012397 -251.10288)
			(xy 27.024523 -251.048443) (xy 27.044446 -250.996352) (xy 27.071742 -250.947717) (xy 27.105828 -250.903574)
			(xy 27.145977 -250.864865) (xy 27.191335 -250.832414) (xy 27.240935 -250.806913) (xy 27.293719 -250.788906)
			(xy 27.348562 -250.778776) (xy 27.404296 -250.776739) (xy 27.459733 -250.782839) (xy 27.51369 -250.796945)
			(xy 27.565019 -250.818757) (xy 27.612625 -250.847811) (xy 27.655493 -250.883486) (xy 27.69271 -250.925023)
			(xy 27.723483 -250.971536) (xy 27.747155 -251.022033) (xy 27.763223 -251.07544) (xy 27.771343 -251.130616)
			(xy 27.771852 -251.158502) (xy 27.771343 -251.186388) (xy 27.763223 -251.241564) (xy 27.747155 -251.294971)
			(xy 27.723483 -251.345468) (xy 27.69271 -251.391981) (xy 27.655493 -251.433518) (xy 27.612625 -251.469193)
			(xy 27.565019 -251.498247) (xy 27.51369 -251.520059) (xy 27.459733 -251.534165) (xy 27.404296 -251.540265)
			(xy 27.348562 -251.538228) (xy 27.293719 -251.528098) (xy 27.240935 -251.510091) (xy 27.191335 -251.48459)
			(xy 27.145977 -251.452139) (xy 27.105828 -251.41343) (xy 27.071742 -251.369287) (xy 27.044446 -251.320652)
			(xy 27.024523 -251.268561) (xy 27.012397 -251.214124) (xy 27.008326 -251.158502) (xy 26.755852 -251.158502)
			(xy 26.755343 -251.186388) (xy 26.747223 -251.241564) (xy 26.731155 -251.294971) (xy 26.707483 -251.345468)
			(xy 26.67671 -251.391981) (xy 26.639493 -251.433518) (xy 26.596625 -251.469193) (xy 26.549019 -251.498247)
			(xy 26.49769 -251.520059) (xy 26.443733 -251.534165) (xy 26.388296 -251.540265) (xy 26.332562 -251.538228)
			(xy 26.277719 -251.528098) (xy 26.224935 -251.510091) (xy 26.175335 -251.48459) (xy 26.129977 -251.452139)
			(xy 26.089828 -251.41343) (xy 26.055742 -251.369287) (xy 26.028446 -251.320652) (xy 26.008523 -251.268561)
			(xy 25.996397 -251.214124) (xy 25.992326 -251.158502) (xy 25.832248 -251.158502) (xy 25.831799 -251.183086)
			(xy 25.823679 -251.238262) (xy 25.807611 -251.291669) (xy 25.783939 -251.342166) (xy 25.753166 -251.388679)
			(xy 25.715949 -251.430216) (xy 25.673081 -251.465891) (xy 25.625475 -251.494945) (xy 25.574146 -251.516757)
			(xy 25.520189 -251.530863) (xy 25.464752 -251.536963) (xy 25.409018 -251.534926) (xy 25.354175 -251.524796)
			(xy 25.301391 -251.506789) (xy 25.251791 -251.481288) (xy 25.206433 -251.448837) (xy 25.166284 -251.410128)
			(xy 25.132198 -251.365985) (xy 25.104902 -251.31735) (xy 25.084979 -251.265259) (xy 25.072853 -251.210822)
			(xy 25.068782 -251.1552) (xy 24.723792 -251.1552) (xy 24.723852 -251.158502) (xy 24.723343 -251.186388)
			(xy 24.715223 -251.241564) (xy 24.699155 -251.294971) (xy 24.675483 -251.345468) (xy 24.64471 -251.391981)
			(xy 24.607493 -251.433518) (xy 24.564625 -251.469193) (xy 24.517019 -251.498247) (xy 24.46569 -251.520059)
			(xy 24.411733 -251.534165) (xy 24.356296 -251.540265) (xy 24.300562 -251.538228) (xy 24.245719 -251.528098)
			(xy 24.192935 -251.510091) (xy 24.143335 -251.48459) (xy 24.097977 -251.452139) (xy 24.057828 -251.41343)
			(xy 24.023742 -251.369287) (xy 23.996446 -251.320652) (xy 23.976523 -251.268561) (xy 23.964397 -251.214124)
			(xy 23.960326 -251.158502) (xy 15.773908 -251.158502) (xy 15.773908 -253.357888) (xy 15.774381 -253.367759)
			(xy 15.781843 -253.386039) (xy 15.788386 -253.393448) (xy 15.78864 -253.393702) (xy 15.851378 -253.45644)
			(xy 23.960326 -253.45644) (xy 23.964397 -253.400818) (xy 23.976523 -253.346381) (xy 23.996446 -253.29429)
			(xy 24.023742 -253.245655) (xy 24.057828 -253.201512) (xy 24.097977 -253.162803) (xy 24.143335 -253.130352)
			(xy 24.192935 -253.104851) (xy 24.245719 -253.086844) (xy 24.300562 -253.076714) (xy 24.356296 -253.074677)
			(xy 24.411733 -253.080777) (xy 24.46569 -253.094883) (xy 24.517019 -253.116695) (xy 24.564625 -253.145749)
			(xy 24.607493 -253.181424) (xy 24.64471 -253.222961) (xy 24.675483 -253.269474) (xy 24.699155 -253.319971)
			(xy 24.715223 -253.373378) (xy 24.723343 -253.428554) (xy 24.723852 -253.45644) (xy 24.976326 -253.45644)
			(xy 24.980397 -253.400818) (xy 24.992523 -253.346381) (xy 25.012446 -253.29429) (xy 25.039742 -253.245655)
			(xy 25.073828 -253.201512) (xy 25.113977 -253.162803) (xy 25.159335 -253.130352) (xy 25.208935 -253.104851)
			(xy 25.261719 -253.086844) (xy 25.316562 -253.076714) (xy 25.372296 -253.074677) (xy 25.427733 -253.080777)
			(xy 25.48169 -253.094883) (xy 25.533019 -253.116695) (xy 25.580625 -253.145749) (xy 25.623493 -253.181424)
			(xy 25.66071 -253.222961) (xy 25.691483 -253.269474) (xy 25.715155 -253.319971) (xy 25.731223 -253.373378)
			(xy 25.739343 -253.428554) (xy 25.739852 -253.45644) (xy 25.992326 -253.45644) (xy 25.996397 -253.400818)
			(xy 26.008523 -253.346381) (xy 26.028446 -253.29429) (xy 26.055742 -253.245655) (xy 26.089828 -253.201512)
			(xy 26.129977 -253.162803) (xy 26.175335 -253.130352) (xy 26.224935 -253.104851) (xy 26.277719 -253.086844)
			(xy 26.332562 -253.076714) (xy 26.388296 -253.074677) (xy 26.443733 -253.080777) (xy 26.49769 -253.094883)
			(xy 26.549019 -253.116695) (xy 26.596625 -253.145749) (xy 26.639493 -253.181424) (xy 26.67671 -253.222961)
			(xy 26.707483 -253.269474) (xy 26.731155 -253.319971) (xy 26.747223 -253.373378) (xy 26.755343 -253.428554)
			(xy 26.755852 -253.45644) (xy 27.008326 -253.45644) (xy 27.012397 -253.400818) (xy 27.024523 -253.346381)
			(xy 27.044446 -253.29429) (xy 27.071742 -253.245655) (xy 27.105828 -253.201512) (xy 27.145977 -253.162803)
			(xy 27.191335 -253.130352) (xy 27.240935 -253.104851) (xy 27.293719 -253.086844) (xy 27.348562 -253.076714)
			(xy 27.404296 -253.074677) (xy 27.459733 -253.080777) (xy 27.51369 -253.094883) (xy 27.565019 -253.116695)
			(xy 27.612625 -253.145749) (xy 27.655493 -253.181424) (xy 27.69271 -253.222961) (xy 27.723483 -253.269474)
			(xy 27.747155 -253.319971) (xy 27.763223 -253.373378) (xy 27.771343 -253.428554) (xy 27.771852 -253.45644)
			(xy 27.771343 -253.484326) (xy 27.763223 -253.539502) (xy 27.747155 -253.592909) (xy 27.723483 -253.643406)
			(xy 27.69271 -253.689919) (xy 27.655493 -253.731456) (xy 27.612625 -253.767131) (xy 27.565019 -253.796185)
			(xy 27.51369 -253.817997) (xy 27.459733 -253.832103) (xy 27.404296 -253.838203) (xy 27.348562 -253.836166)
			(xy 27.293719 -253.826036) (xy 27.240935 -253.808029) (xy 27.191335 -253.782528) (xy 27.145977 -253.750077)
			(xy 27.105828 -253.711368) (xy 27.071742 -253.667225) (xy 27.044446 -253.61859) (xy 27.024523 -253.566499)
			(xy 27.012397 -253.512062) (xy 27.008326 -253.45644) (xy 26.755852 -253.45644) (xy 26.755343 -253.484326)
			(xy 26.747223 -253.539502) (xy 26.731155 -253.592909) (xy 26.707483 -253.643406) (xy 26.67671 -253.689919)
			(xy 26.639493 -253.731456) (xy 26.596625 -253.767131) (xy 26.549019 -253.796185) (xy 26.49769 -253.817997)
			(xy 26.443733 -253.832103) (xy 26.388296 -253.838203) (xy 26.332562 -253.836166) (xy 26.277719 -253.826036)
			(xy 26.224935 -253.808029) (xy 26.175335 -253.782528) (xy 26.129977 -253.750077) (xy 26.089828 -253.711368)
			(xy 26.055742 -253.667225) (xy 26.028446 -253.61859) (xy 26.008523 -253.566499) (xy 25.996397 -253.512062)
			(xy 25.992326 -253.45644) (xy 25.739852 -253.45644) (xy 25.739343 -253.484326) (xy 25.731223 -253.539502)
			(xy 25.715155 -253.592909) (xy 25.691483 -253.643406) (xy 25.66071 -253.689919) (xy 25.623493 -253.731456)
			(xy 25.580625 -253.767131) (xy 25.533019 -253.796185) (xy 25.48169 -253.817997) (xy 25.427733 -253.832103)
			(xy 25.372296 -253.838203) (xy 25.316562 -253.836166) (xy 25.261719 -253.826036) (xy 25.208935 -253.808029)
			(xy 25.159335 -253.782528) (xy 25.113977 -253.750077) (xy 25.073828 -253.711368) (xy 25.039742 -253.667225)
			(xy 25.012446 -253.61859) (xy 24.992523 -253.566499) (xy 24.980397 -253.512062) (xy 24.976326 -253.45644)
			(xy 24.723852 -253.45644) (xy 24.723343 -253.484326) (xy 24.715223 -253.539502) (xy 24.699155 -253.592909)
			(xy 24.675483 -253.643406) (xy 24.64471 -253.689919) (xy 24.607493 -253.731456) (xy 24.564625 -253.767131)
			(xy 24.517019 -253.796185) (xy 24.46569 -253.817997) (xy 24.411733 -253.832103) (xy 24.356296 -253.838203)
			(xy 24.300562 -253.836166) (xy 24.245719 -253.826036) (xy 24.192935 -253.808029) (xy 24.143335 -253.782528)
			(xy 24.097977 -253.750077) (xy 24.057828 -253.711368) (xy 24.023742 -253.667225) (xy 23.996446 -253.61859)
			(xy 23.976523 -253.566499) (xy 23.964397 -253.512062) (xy 23.960326 -253.45644) (xy 15.851378 -253.45644)
			(xy 18.305526 -255.910588) (xy 21.87651 -255.910588) (xy 21.880581 -255.854966) (xy 21.892707 -255.800529)
			(xy 21.91263 -255.748438) (xy 21.939926 -255.699803) (xy 21.974012 -255.65566) (xy 22.014161 -255.616951)
			(xy 22.059519 -255.5845) (xy 22.109119 -255.558999) (xy 22.161903 -255.540992) (xy 22.216746 -255.530862)
			(xy 22.27248 -255.528825) (xy 22.327917 -255.534925) (xy 22.381874 -255.549031) (xy 22.433203 -255.570843)
			(xy 22.480809 -255.599897) (xy 22.523677 -255.635572) (xy 22.558963 -255.674954) (xy 22.765453 -255.674954)
			(xy 22.765453 -255.620446) (xy 22.773211 -255.566494) (xy 22.788567 -255.514195) (xy 22.811211 -255.464614)
			(xy 22.84068 -255.41876) (xy 22.876375 -255.377567) (xy 22.91757 -255.341873) (xy 22.963424 -255.312405)
			(xy 23.013006 -255.289763) (xy 23.065306 -255.274408) (xy 23.119258 -255.266653) (xy 23.146512 -255.26619)
			(xy 23.176121 -255.266801) (xy 23.23463 -255.275939) (xy 23.291025 -255.29401) (xy 23.343949 -255.320578)
			(xy 23.392131 -255.355006) (xy 23.434414 -255.396466) (xy 23.469782 -255.443963) (xy 23.484078 -255.469898)
			(xy 23.491605 -255.482931) (xy 23.512833 -255.504246) (xy 23.539345 -255.518463) (xy 23.568845 -255.524353)
			(xy 23.598783 -255.521405) (xy 23.626568 -255.509874) (xy 23.649797 -255.490759) (xy 23.658576 -255.478534)
			(xy 23.673758 -255.456285) (xy 23.709456 -255.415951) (xy 23.750471 -255.381036) (xy 23.795986 -255.352233)
			(xy 23.845098 -255.330115) (xy 23.896832 -255.31512) (xy 23.95016 -255.307547) (xy 23.977092 -255.307084)
			(xy 24.004345 -255.307563) (xy 24.058295 -255.315319) (xy 24.110593 -255.330674) (xy 24.160173 -255.353315)
			(xy 24.206026 -255.382782) (xy 24.247219 -255.418475) (xy 24.282913 -255.459667) (xy 24.312381 -255.50552)
			(xy 24.335024 -255.555099) (xy 24.35038 -255.607397) (xy 24.358137 -255.661347) (xy 24.358137 -255.715853)
			(xy 24.35038 -255.769803) (xy 24.335024 -255.822101) (xy 24.312381 -255.87168) (xy 24.282913 -255.917533)
			(xy 24.247219 -255.958725) (xy 24.206026 -255.994418) (xy 24.160173 -256.023885) (xy 24.110593 -256.046526)
			(xy 24.058295 -256.061881) (xy 24.004345 -256.069637) (xy 23.977092 -256.0701) (xy 23.947483 -256.06949)
			(xy 23.888973 -256.060353) (xy 23.832579 -256.042282) (xy 23.779655 -256.015714) (xy 23.731472 -255.981286)
			(xy 23.68919 -255.939825) (xy 23.653822 -255.892327) (xy 23.639526 -255.866392) (xy 23.631993 -255.853363)
			(xy 23.610765 -255.83205) (xy 23.584256 -255.817834) (xy 23.554757 -255.811945) (xy 23.524821 -255.814892)
			(xy 23.497037 -255.82642) (xy 23.473808 -255.845532) (xy 23.465028 -255.857756) (xy 23.44984 -255.88)
			(xy 23.414143 -255.920335) (xy 23.37313 -255.955251) (xy 23.327616 -255.984055) (xy 23.278504 -256.006174)
			(xy 23.226771 -256.021169) (xy 23.173443 -256.028743) (xy 23.146512 -256.029206) (xy 23.119258 -256.028747)
			(xy 23.065306 -256.020992) (xy 23.013006 -256.005637) (xy 22.963424 -255.982995) (xy 22.91757 -255.953527)
			(xy 22.876375 -255.917833) (xy 22.84068 -255.87664) (xy 22.811211 -255.830786) (xy 22.788567 -255.781205)
			(xy 22.773211 -255.728906) (xy 22.765453 -255.674954) (xy 22.558963 -255.674954) (xy 22.560894 -255.677109)
			(xy 22.591667 -255.723622) (xy 22.615339 -255.774119) (xy 22.631407 -255.827526) (xy 22.639527 -255.882702)
			(xy 22.640036 -255.910588) (xy 22.639527 -255.938474) (xy 22.631407 -255.99365) (xy 22.615339 -256.047057)
			(xy 22.591667 -256.097554) (xy 22.560894 -256.144067) (xy 22.523677 -256.185604) (xy 22.480809 -256.221279)
			(xy 22.433203 -256.250333) (xy 22.381874 -256.272145) (xy 22.327917 -256.286251) (xy 22.27248 -256.292351)
			(xy 22.216746 -256.290314) (xy 22.161903 -256.280184) (xy 22.109119 -256.262177) (xy 22.059519 -256.236676)
			(xy 22.014161 -256.204225) (xy 21.974012 -256.165516) (xy 21.939926 -256.121373) (xy 21.91263 -256.072738)
			(xy 21.892707 -256.020647) (xy 21.880581 -255.96621) (xy 21.87651 -255.910588) (xy 18.305526 -255.910588)
			(xy 19.329908 -256.93497) (xy 19.330416 -256.935478) (xy 19.337796 -256.942064) (xy 19.356095 -256.949523)
			(xy 19.365976 -256.949956)
		)
		(stroke
			(width 0)
			(type solid)
		)
		(fill yes)
		(layer "In7.Cu")
		(net "P1V8_PEX")
	)
	(gr_poly
		(pts
			(xy 255.697482 -256.514854) (xy 255.707545 -256.514415) (xy 255.726123 -256.506674) (xy 255.73355 -256.499868)
			(xy 256.03835 -256.195068) (xy 256.046391 -256.185999) (xy 256.05367 -256.162919) (xy 256.05232 -256.150872)
			(xy 256.036572 -256.056892) (xy 256.02184 -256.037334) (xy 256.010664 -256.032) (xy 255.986828 -256.019937)
			(xy 255.942485 -255.990144) (xy 255.902727 -255.954463) (xy 255.868329 -255.913589) (xy 255.839963 -255.86832)
			(xy 255.818182 -255.819539) (xy 255.803412 -255.7682) (xy 255.795941 -255.715303) (xy 255.795526 -255.688592)
			(xy 255.79599 -255.66134) (xy 255.803748 -255.607392) (xy 255.819105 -255.555097) (xy 255.841748 -255.50552)
			(xy 255.871217 -255.459671) (xy 255.906911 -255.418482) (xy 255.948104 -255.382792) (xy 255.993957 -255.353328)
			(xy 256.043537 -255.33069) (xy 256.095833 -255.315339) (xy 256.149782 -255.307587) (xy 256.177034 -255.307084)
			(xy 256.203746 -255.307527) (xy 256.256649 -255.314971) (xy 256.307996 -255.329723) (xy 256.356783 -255.351493)
			(xy 256.402055 -255.379858) (xy 256.442928 -255.41426) (xy 256.478601 -255.454029) (xy 256.508378 -255.498385)
			(xy 256.520442 -255.522222) (xy 256.525776 -255.533398) (xy 256.545334 -255.54813) (xy 256.639314 -255.563878)
			(xy 256.651357 -255.565206) (xy 256.674431 -255.557928) (xy 256.68351 -255.549908) (xy 257.25374 -254.979678)
			(xy 257.260589 -254.972281) (xy 257.268325 -254.953682) (xy 257.268726 -254.94361) (xy 257.268726 -253.722886)
			(xy 257.268366 -253.714437) (xy 257.262777 -253.698485) (xy 257.257804 -253.691644) (xy 257.242499 -253.671429)
			(xy 257.216805 -253.627718) (xy 257.197139 -253.580984) (xy 257.183848 -253.532053) (xy 257.177167 -253.481792)
			(xy 257.176778 -253.45644) (xy 257.177202 -253.431093) (xy 257.183924 -253.380846) (xy 257.197229 -253.331929)
			(xy 257.216885 -253.285201) (xy 257.242545 -253.24148) (xy 257.257804 -253.221236) (xy 257.262806 -253.214411)
			(xy 257.268394 -253.198449) (xy 257.268726 -253.189994) (xy 257.268726 -251.424948) (xy 257.268376 -251.416495)
			(xy 257.262802 -251.400531) (xy 257.257804 -251.393706) (xy 257.242501 -251.37349) (xy 257.216812 -251.329778)
			(xy 257.19715 -251.283044) (xy 257.183863 -251.234114) (xy 257.177188 -251.183853) (xy 257.176778 -251.158502)
			(xy 257.177198 -251.133154) (xy 257.183912 -251.082903) (xy 257.197211 -251.033982) (xy 257.216861 -250.987248)
			(xy 257.242516 -250.943522) (xy 257.257804 -250.923298) (xy 257.262801 -250.916471) (xy 257.268377 -250.900509)
			(xy 257.268726 -250.892056) (xy 257.268726 -249.27687) (xy 257.268379 -249.268416) (xy 257.262811 -249.252448)
			(xy 257.257804 -249.245628) (xy 257.2425 -249.225413) (xy 257.216808 -249.181701) (xy 257.197143 -249.134967)
			(xy 257.183854 -249.086037) (xy 257.177176 -249.035776) (xy 257.176778 -249.010424) (xy 257.177203 -248.985077)
			(xy 257.183927 -248.934832) (xy 257.197234 -248.885916) (xy 257.216891 -248.839188) (xy 257.242552 -248.795469)
			(xy 257.257804 -248.77522) (xy 257.262804 -248.768394) (xy 257.268387 -248.752432) (xy 257.268726 -248.743978)
			(xy 257.268726 -242.851178) (xy 257.268231 -242.840337) (xy 257.259286 -242.820589) (xy 257.251454 -242.813078)
			(xy 257.185668 -242.75542) (xy 257.16484 -242.74907) (xy 257.153664 -242.750594) (xy 257.141212 -242.752138)
			(xy 257.116173 -242.753789) (xy 257.103626 -242.753896) (xy 257.076373 -242.753434) (xy 257.022421 -242.745681)
			(xy 256.970121 -242.730327) (xy 256.92054 -242.707687) (xy 256.874685 -242.678221) (xy 256.83349 -242.642528)
			(xy 256.797795 -242.601336) (xy 256.768325 -242.555483) (xy 256.745682 -242.505903) (xy 256.730325 -242.453605)
			(xy 256.722567 -242.399653) (xy 256.722567 -242.345147) (xy 256.730325 -242.291195) (xy 256.745682 -242.238897)
			(xy 256.768325 -242.189317) (xy 256.797795 -242.143464) (xy 256.83349 -242.102272) (xy 256.874685 -242.066579)
			(xy 256.92054 -242.037113) (xy 256.970121 -242.014473) (xy 257.022421 -241.999119) (xy 257.076373 -241.991366)
			(xy 257.103626 -241.99088) (xy 257.116173 -241.990981) (xy 257.141213 -241.992631) (xy 257.153664 -241.994182)
			(xy 257.16484 -241.995706) (xy 257.185668 -241.989356) (xy 257.251454 -241.931698) (xy 257.259258 -241.924165)
			(xy 257.268216 -241.904432) (xy 257.268726 -241.893598) (xy 257.268726 -241.313462) (xy 257.268235 -241.303091)
			(xy 257.260051 -241.28403) (xy 257.245022 -241.269732) (xy 257.235452 -241.26571) (xy 257.130804 -241.227356)
			(xy 257.10007 -241.23523) (xy 257.089656 -241.247676) (xy 257.071439 -241.268379) (xy 257.030066 -241.304839)
			(xy 256.983875 -241.334963) (xy 256.933829 -241.358123) (xy 256.880969 -241.373839) (xy 256.826399 -241.381781)
			(xy 256.798826 -241.382296) (xy 256.772853 -241.381852) (xy 256.721389 -241.374792) (xy 256.671359 -241.360811)
			(xy 256.62369 -241.34017) (xy 256.579263 -241.31325) (xy 256.538901 -241.280549) (xy 256.503351 -241.242673)
			(xy 256.48793 -241.221768) (xy 256.48031 -241.212268) (xy 256.458688 -241.201141) (xy 256.446528 -241.200432)
			(xy 256.363724 -241.200432) (xy 256.351559 -241.201119) (xy 256.329926 -241.21225) (xy 256.322322 -241.221768)
			(xy 256.306927 -241.242694) (xy 256.271379 -241.280577) (xy 256.231015 -241.313282) (xy 256.186584 -241.340202)
			(xy 256.138908 -241.360838) (xy 256.088871 -241.374809) (xy 256.037401 -241.381854) (xy 256.011426 -241.382296)
			(xy 255.984166 -241.381835) (xy 255.930201 -241.374079) (xy 255.87789 -241.358723) (xy 255.828296 -241.336078)
			(xy 255.782429 -241.306605) (xy 255.741224 -241.270905) (xy 255.70552 -241.229703) (xy 255.69037 -241.207036)
			(xy 255.685513 -241.200081) (xy 255.672186 -241.189599) (xy 255.656174 -241.184023) (xy 255.647698 -241.183668)
			(xy 255.562354 -241.183668) (xy 255.553869 -241.183981) (xy 255.537836 -241.189539) (xy 255.52452 -241.200058)
			(xy 255.519682 -241.207036) (xy 255.504526 -241.229697) (xy 255.468811 -241.270883) (xy 255.427602 -241.306572)
			(xy 255.381737 -241.336039) (xy 255.332148 -241.358684) (xy 255.279842 -241.374048) (xy 255.225883 -241.381818)
			(xy 255.198626 -241.382296) (xy 255.171373 -241.381834) (xy 255.117421 -241.374081) (xy 255.065121 -241.358727)
			(xy 255.01554 -241.336087) (xy 254.969685 -241.306621) (xy 254.92849 -241.270928) (xy 254.892795 -241.229736)
			(xy 254.863325 -241.183883) (xy 254.840682 -241.134303) (xy 254.825325 -241.082005) (xy 254.817567 -241.028053)
			(xy 254.817567 -240.973547) (xy 254.825325 -240.919595) (xy 254.840682 -240.867297) (xy 254.863325 -240.817717)
			(xy 254.892795 -240.771864) (xy 254.92849 -240.730672) (xy 254.969685 -240.694979) (xy 255.01554 -240.665513)
			(xy 255.065121 -240.642873) (xy 255.117421 -240.627519) (xy 255.171373 -240.619766) (xy 255.198626 -240.61928)
			(xy 255.225888 -240.619738) (xy 255.279857 -240.627487) (xy 255.332174 -240.642838) (xy 255.381775 -240.665479)
			(xy 255.427648 -240.694948) (xy 255.46886 -240.730645) (xy 255.504572 -240.771845) (xy 255.519682 -240.79454)
			(xy 255.524535 -240.801503) (xy 255.537859 -240.812002) (xy 255.553874 -240.817596) (xy 255.562354 -240.817908)
			(xy 255.647698 -240.817908) (xy 255.656186 -240.817602) (xy 255.672229 -240.812052) (xy 255.685554 -240.801535)
			(xy 255.69037 -240.79454) (xy 255.705524 -240.771878) (xy 255.741237 -240.730689) (xy 255.782446 -240.694999)
			(xy 255.828311 -240.665532) (xy 255.877902 -240.642888) (xy 255.930209 -240.627528) (xy 255.984168 -240.619764)
			(xy 256.011426 -240.61928) (xy 256.037401 -240.619721) (xy 256.088869 -240.626775) (xy 256.138904 -240.64075)
			(xy 256.186579 -240.661387) (xy 256.231012 -240.688303) (xy 256.27138 -240.721001) (xy 256.306937 -240.758875)
			(xy 256.322322 -240.779808) (xy 256.329937 -240.78932) (xy 256.351559 -240.800473) (xy 256.363724 -240.801144)
			(xy 256.446528 -240.801144) (xy 256.458686 -240.800446) (xy 256.480297 -240.789298) (xy 256.48793 -240.779808)
			(xy 256.503324 -240.758881) (xy 256.53887 -240.720995) (xy 256.579233 -240.68829) (xy 256.623665 -240.66137)
			(xy 256.671342 -240.640736) (xy 256.721379 -240.626769) (xy 256.772851 -240.619729) (xy 256.798826 -240.61928)
			(xy 256.826399 -240.619768) (xy 256.88097 -240.627714) (xy 256.933828 -240.643436) (xy 256.983871 -240.666605)
			(xy 257.030056 -240.696741) (xy 257.071419 -240.733213) (xy 257.089656 -240.7539) (xy 257.10007 -240.766346)
			(xy 257.130804 -240.77422) (xy 257.235452 -240.735866) (xy 257.245016 -240.73183) (xy 257.260059 -240.717554)
			(xy 257.26821 -240.698485) (xy 257.268726 -240.688114) (xy 257.268726 -236.07268) (xy 257.269153 -236.062612)
			(xy 257.276876 -236.044015) (xy 257.283712 -236.036612) (xy 258.183888 -235.136436) (xy 258.191284 -235.129584)
			(xy 258.209882 -235.121839) (xy 258.219956 -235.12145) (xy 262.983472 -235.12145) (xy 262.993535 -235.121888)
			(xy 263.012116 -235.129626) (xy 263.01954 -235.136436) (xy 263.99744 -236.114336) (xy 264.004287 -236.121734)
			(xy 264.012018 -236.140332) (xy 264.012426 -236.150404) (xy 264.012426 -236.631226) (xy 269.035274 -236.631226)
			(xy 269.039345 -236.575604) (xy 269.051471 -236.521167) (xy 269.071394 -236.469076) (xy 269.09869 -236.420441)
			(xy 269.132776 -236.376298) (xy 269.172925 -236.337589) (xy 269.218283 -236.305138) (xy 269.267883 -236.279637)
			(xy 269.320667 -236.26163) (xy 269.37551 -236.2515) (xy 269.431244 -236.249463) (xy 269.486681 -236.255563)
			(xy 269.540638 -236.269669) (xy 269.591967 -236.291481) (xy 269.639573 -236.320535) (xy 269.682441 -236.35621)
			(xy 269.719658 -236.397747) (xy 269.750431 -236.44426) (xy 269.774103 -236.494757) (xy 269.790171 -236.548164)
			(xy 269.798291 -236.60334) (xy 269.7988 -236.631226) (xy 269.798291 -236.659112) (xy 269.790171 -236.714288)
			(xy 269.784796 -236.732154) (xy 270.605941 -236.732154) (xy 270.605941 -236.677646) (xy 270.613698 -236.623692)
			(xy 270.629056 -236.571391) (xy 270.6517 -236.521808) (xy 270.68117 -236.475953) (xy 270.716866 -236.434758)
			(xy 270.758062 -236.399063) (xy 270.803919 -236.369594) (xy 270.853502 -236.346952) (xy 270.905803 -236.331596)
			(xy 270.959758 -236.32384) (xy 270.987012 -236.323378) (xy 271.015125 -236.323829) (xy 271.070744 -236.33207)
			(xy 271.124551 -236.348385) (xy 271.17538 -236.372422) (xy 271.22213 -236.40366) (xy 271.263788 -236.441422)
			(xy 271.299452 -236.48489) (xy 271.328349 -236.533122) (xy 271.349853 -236.585073) (xy 271.363498 -236.639618)
			(xy 271.366742 -236.667548) (xy 271.368574 -236.681793) (xy 271.379204 -236.708463) (xy 271.396837 -236.73112)
			(xy 271.420081 -236.747972) (xy 271.447098 -236.757688) (xy 271.475751 -236.759499) (xy 271.503776 -236.753261)
			(xy 271.516602 -236.746796) (xy 271.544887 -236.732019) (xy 271.605163 -236.711073) (xy 271.668084 -236.700452)
			(xy 271.69999 -236.699806) (xy 271.727244 -236.70024) (xy 271.781198 -236.707996) (xy 271.833499 -236.723352)
			(xy 271.883083 -236.745995) (xy 271.928939 -236.775464) (xy 271.970134 -236.811159) (xy 272.00583 -236.852353)
			(xy 272.0353 -236.898209) (xy 272.057944 -236.947791) (xy 272.073302 -237.000092) (xy 272.081059 -237.054046)
			(xy 272.081059 -237.108554) (xy 272.073302 -237.162508) (xy 272.057944 -237.214809) (xy 272.0353 -237.264391)
			(xy 272.00583 -237.310247) (xy 271.970134 -237.351441) (xy 271.928939 -237.387136) (xy 271.883083 -237.416605)
			(xy 271.833499 -237.439248) (xy 271.781198 -237.454604) (xy 271.727244 -237.46236) (xy 271.69999 -237.462822)
			(xy 271.671877 -237.462369) (xy 271.616258 -237.454129) (xy 271.562451 -237.437813) (xy 271.511622 -237.413777)
			(xy 271.464872 -237.382539) (xy 271.423214 -237.344777) (xy 271.38755 -237.30131) (xy 271.358653 -237.253078)
			(xy 271.337149 -237.201127) (xy 271.323504 -237.146582) (xy 271.32026 -237.118652) (xy 271.318425 -237.104408)
			(xy 271.307796 -237.077738) (xy 271.290162 -237.055081) (xy 271.266919 -237.038229) (xy 271.239903 -237.028513)
			(xy 271.21125 -237.026702) (xy 271.183226 -237.032939) (xy 271.1704 -237.039404) (xy 271.142115 -237.054181)
			(xy 271.081839 -237.075126) (xy 271.018918 -237.085748) (xy 270.987012 -237.086394) (xy 270.959758 -237.08596)
			(xy 270.905803 -237.078204) (xy 270.853502 -237.062848) (xy 270.803919 -237.040206) (xy 270.758062 -237.010737)
			(xy 270.716866 -236.975042) (xy 270.68117 -236.933847) (xy 270.6517 -236.887992) (xy 270.629056 -236.838409)
			(xy 270.613698 -236.786108) (xy 270.605941 -236.732154) (xy 269.784796 -236.732154) (xy 269.774103 -236.767695)
			(xy 269.750431 -236.818192) (xy 269.719658 -236.864705) (xy 269.682441 -236.906242) (xy 269.639573 -236.941917)
			(xy 269.591967 -236.970971) (xy 269.540638 -236.992783) (xy 269.486681 -237.006889) (xy 269.431244 -237.012989)
			(xy 269.37551 -237.010952) (xy 269.320667 -237.000822) (xy 269.267883 -236.982815) (xy 269.218283 -236.957314)
			(xy 269.172925 -236.924863) (xy 269.132776 -236.886154) (xy 269.09869 -236.842011) (xy 269.071394 -236.793376)
			(xy 269.051471 -236.741285) (xy 269.039345 -236.686848) (xy 269.035274 -236.631226) (xy 264.012426 -236.631226)
			(xy 264.012426 -249.00382) (xy 270.384268 -249.00382) (xy 270.388339 -248.948198) (xy 270.400465 -248.893761)
			(xy 270.420388 -248.84167) (xy 270.447684 -248.793035) (xy 270.48177 -248.748892) (xy 270.521919 -248.710183)
			(xy 270.567277 -248.677732) (xy 270.616877 -248.652231) (xy 270.669661 -248.634224) (xy 270.724504 -248.624094)
			(xy 270.780238 -248.622057) (xy 270.835675 -248.628157) (xy 270.889632 -248.642263) (xy 270.940961 -248.664075)
			(xy 270.988567 -248.693129) (xy 271.031435 -248.728804) (xy 271.068652 -248.770341) (xy 271.099425 -248.816854)
			(xy 271.123097 -248.867351) (xy 271.139165 -248.920758) (xy 271.14395 -248.953274) (xy 271.29816 -248.953274)
			(xy 271.302231 -248.897652) (xy 271.314357 -248.843215) (xy 271.33428 -248.791124) (xy 271.361576 -248.742489)
			(xy 271.395662 -248.698346) (xy 271.435811 -248.659637) (xy 271.481169 -248.627186) (xy 271.530769 -248.601685)
			(xy 271.583553 -248.583678) (xy 271.638396 -248.573548) (xy 271.69413 -248.571511) (xy 271.749567 -248.577611)
			(xy 271.803524 -248.591717) (xy 271.854853 -248.613529) (xy 271.902459 -248.642583) (xy 271.945327 -248.678258)
			(xy 271.982544 -248.719795) (xy 272.013317 -248.766308) (xy 272.036989 -248.816805) (xy 272.053057 -248.870212)
			(xy 272.061177 -248.925388) (xy 272.061686 -248.953274) (xy 272.061177 -248.98116) (xy 272.053057 -249.036336)
			(xy 272.036989 -249.089743) (xy 272.013317 -249.14024) (xy 271.982544 -249.186753) (xy 271.945327 -249.22829)
			(xy 271.902459 -249.263965) (xy 271.854853 -249.293019) (xy 271.803524 -249.314831) (xy 271.749567 -249.328937)
			(xy 271.69413 -249.335037) (xy 271.638396 -249.333) (xy 271.583553 -249.32287) (xy 271.530769 -249.304863)
			(xy 271.481169 -249.279362) (xy 271.435811 -249.246911) (xy 271.395662 -249.208202) (xy 271.361576 -249.164059)
			(xy 271.33428 -249.115424) (xy 271.314357 -249.063333) (xy 271.302231 -249.008896) (xy 271.29816 -248.953274)
			(xy 271.14395 -248.953274) (xy 271.147285 -248.975934) (xy 271.147794 -249.00382) (xy 271.147285 -249.031706)
			(xy 271.139165 -249.086882) (xy 271.123097 -249.140289) (xy 271.099425 -249.190786) (xy 271.068652 -249.237299)
			(xy 271.031435 -249.278836) (xy 270.988567 -249.314511) (xy 270.940961 -249.343565) (xy 270.889632 -249.365377)
			(xy 270.835675 -249.379483) (xy 270.780238 -249.385583) (xy 270.724504 -249.383546) (xy 270.669661 -249.373416)
			(xy 270.616877 -249.355409) (xy 270.567277 -249.329908) (xy 270.521919 -249.297457) (xy 270.48177 -249.258748)
			(xy 270.447684 -249.214605) (xy 270.420388 -249.16597) (xy 270.400465 -249.113879) (xy 270.388339 -249.059442)
			(xy 270.384268 -249.00382) (xy 264.012426 -249.00382) (xy 264.012426 -251.026676) (xy 264.01522 -251.034804)
			(xy 264.024861 -251.064814) (xy 264.035203 -251.126987) (xy 264.035794 -251.158502) (xy 264.288268 -251.158502)
			(xy 264.292339 -251.10288) (xy 264.304465 -251.048443) (xy 264.324388 -250.996352) (xy 264.351684 -250.947717)
			(xy 264.38577 -250.903574) (xy 264.425919 -250.864865) (xy 264.471277 -250.832414) (xy 264.520877 -250.806913)
			(xy 264.573661 -250.788906) (xy 264.628504 -250.778776) (xy 264.684238 -250.776739) (xy 264.739675 -250.782839)
			(xy 264.793632 -250.796945) (xy 264.844961 -250.818757) (xy 264.892567 -250.847811) (xy 264.935435 -250.883486)
			(xy 264.972652 -250.925023) (xy 265.003425 -250.971536) (xy 265.027097 -251.022033) (xy 265.043165 -251.07544)
			(xy 265.051285 -251.130616) (xy 265.051794 -251.158502) (xy 265.304268 -251.158502) (xy 265.308339 -251.10288)
			(xy 265.320465 -251.048443) (xy 265.340388 -250.996352) (xy 265.367684 -250.947717) (xy 265.40177 -250.903574)
			(xy 265.441919 -250.864865) (xy 265.487277 -250.832414) (xy 265.536877 -250.806913) (xy 265.589661 -250.788906)
			(xy 265.644504 -250.778776) (xy 265.700238 -250.776739) (xy 265.755675 -250.782839) (xy 265.809632 -250.796945)
			(xy 265.860961 -250.818757) (xy 265.908567 -250.847811) (xy 265.951435 -250.883486) (xy 265.988652 -250.925023)
			(xy 266.019425 -250.971536) (xy 266.043097 -251.022033) (xy 266.059165 -251.07544) (xy 266.067285 -251.130616)
			(xy 266.067794 -251.158502) (xy 266.320268 -251.158502) (xy 266.324339 -251.10288) (xy 266.336465 -251.048443)
			(xy 266.356388 -250.996352) (xy 266.383684 -250.947717) (xy 266.41777 -250.903574) (xy 266.457919 -250.864865)
			(xy 266.503277 -250.832414) (xy 266.552877 -250.806913) (xy 266.605661 -250.788906) (xy 266.660504 -250.778776)
			(xy 266.716238 -250.776739) (xy 266.771675 -250.782839) (xy 266.825632 -250.796945) (xy 266.876961 -250.818757)
			(xy 266.924567 -250.847811) (xy 266.967435 -250.883486) (xy 267.004652 -250.925023) (xy 267.035425 -250.971536)
			(xy 267.059097 -251.022033) (xy 267.075165 -251.07544) (xy 267.083285 -251.130616) (xy 267.083794 -251.158502)
			(xy 267.336268 -251.158502) (xy 267.340339 -251.10288) (xy 267.352465 -251.048443) (xy 267.372388 -250.996352)
			(xy 267.399684 -250.947717) (xy 267.43377 -250.903574) (xy 267.473919 -250.864865) (xy 267.519277 -250.832414)
			(xy 267.568877 -250.806913) (xy 267.621661 -250.788906) (xy 267.676504 -250.778776) (xy 267.732238 -250.776739)
			(xy 267.787675 -250.782839) (xy 267.841632 -250.796945) (xy 267.892961 -250.818757) (xy 267.940567 -250.847811)
			(xy 267.983435 -250.883486) (xy 268.020652 -250.925023) (xy 268.051425 -250.971536) (xy 268.075097 -251.022033)
			(xy 268.091165 -251.07544) (xy 268.099285 -251.130616) (xy 268.099794 -251.158502) (xy 268.352268 -251.158502)
			(xy 268.356339 -251.10288) (xy 268.368465 -251.048443) (xy 268.388388 -250.996352) (xy 268.415684 -250.947717)
			(xy 268.44977 -250.903574) (xy 268.489919 -250.864865) (xy 268.535277 -250.832414) (xy 268.584877 -250.806913)
			(xy 268.637661 -250.788906) (xy 268.692504 -250.778776) (xy 268.748238 -250.776739) (xy 268.803675 -250.782839)
			(xy 268.857632 -250.796945) (xy 268.908961 -250.818757) (xy 268.956567 -250.847811) (xy 268.999435 -250.883486)
			(xy 269.036652 -250.925023) (xy 269.067425 -250.971536) (xy 269.091097 -251.022033) (xy 269.107165 -251.07544)
			(xy 269.115285 -251.130616) (xy 269.115794 -251.158502) (xy 269.368268 -251.158502) (xy 269.372339 -251.10288)
			(xy 269.384465 -251.048443) (xy 269.404388 -250.996352) (xy 269.431684 -250.947717) (xy 269.46577 -250.903574)
			(xy 269.505919 -250.864865) (xy 269.551277 -250.832414) (xy 269.600877 -250.806913) (xy 269.653661 -250.788906)
			(xy 269.708504 -250.778776) (xy 269.764238 -250.776739) (xy 269.819675 -250.782839) (xy 269.873632 -250.796945)
			(xy 269.924961 -250.818757) (xy 269.972567 -250.847811) (xy 270.015435 -250.883486) (xy 270.052652 -250.925023)
			(xy 270.083425 -250.971536) (xy 270.107097 -251.022033) (xy 270.123165 -251.07544) (xy 270.131285 -251.130616)
			(xy 270.131609 -251.148342) (xy 270.337024 -251.148342) (xy 270.341095 -251.09272) (xy 270.353221 -251.038283)
			(xy 270.373144 -250.986192) (xy 270.40044 -250.937557) (xy 270.434526 -250.893414) (xy 270.474675 -250.854705)
			(xy 270.520033 -250.822254) (xy 270.569633 -250.796753) (xy 270.622417 -250.778746) (xy 270.67726 -250.768616)
			(xy 270.732994 -250.766579) (xy 270.788431 -250.772679) (xy 270.842388 -250.786785) (xy 270.893717 -250.808597)
			(xy 270.941323 -250.837651) (xy 270.984191 -250.873326) (xy 271.021408 -250.914863) (xy 271.052181 -250.961376)
			(xy 271.075853 -251.011873) (xy 271.091921 -251.06528) (xy 271.100041 -251.120456) (xy 271.10055 -251.148342)
			(xy 271.100365 -251.158502) (xy 271.400268 -251.158502) (xy 271.404339 -251.10288) (xy 271.416465 -251.048443)
			(xy 271.436388 -250.996352) (xy 271.463684 -250.947717) (xy 271.49777 -250.903574) (xy 271.537919 -250.864865)
			(xy 271.583277 -250.832414) (xy 271.632877 -250.806913) (xy 271.685661 -250.788906) (xy 271.740504 -250.778776)
			(xy 271.796238 -250.776739) (xy 271.851675 -250.782839) (xy 271.905632 -250.796945) (xy 271.956961 -250.818757)
			(xy 272.004567 -250.847811) (xy 272.047435 -250.883486) (xy 272.084652 -250.925023) (xy 272.115425 -250.971536)
			(xy 272.139097 -251.022033) (xy 272.155165 -251.07544) (xy 272.163285 -251.130616) (xy 272.163794 -251.158502)
			(xy 272.416268 -251.158502) (xy 272.420339 -251.10288) (xy 272.432465 -251.048443) (xy 272.452388 -250.996352)
			(xy 272.479684 -250.947717) (xy 272.51377 -250.903574) (xy 272.553919 -250.864865) (xy 272.599277 -250.832414)
			(xy 272.648877 -250.806913) (xy 272.701661 -250.788906) (xy 272.756504 -250.778776) (xy 272.812238 -250.776739)
			(xy 272.867675 -250.782839) (xy 272.921632 -250.796945) (xy 272.972961 -250.818757) (xy 273.020567 -250.847811)
			(xy 273.063435 -250.883486) (xy 273.100652 -250.925023) (xy 273.131425 -250.971536) (xy 273.155097 -251.022033)
			(xy 273.171165 -251.07544) (xy 273.179285 -251.130616) (xy 273.179794 -251.158502) (xy 273.179285 -251.186388)
			(xy 273.171165 -251.241564) (xy 273.155097 -251.294971) (xy 273.131425 -251.345468) (xy 273.100652 -251.391981)
			(xy 273.063435 -251.433518) (xy 273.020567 -251.469193) (xy 272.972961 -251.498247) (xy 272.921632 -251.520059)
			(xy 272.867675 -251.534165) (xy 272.812238 -251.540265) (xy 272.756504 -251.538228) (xy 272.701661 -251.528098)
			(xy 272.648877 -251.510091) (xy 272.599277 -251.48459) (xy 272.553919 -251.452139) (xy 272.51377 -251.41343)
			(xy 272.479684 -251.369287) (xy 272.452388 -251.320652) (xy 272.432465 -251.268561) (xy 272.420339 -251.214124)
			(xy 272.416268 -251.158502) (xy 272.163794 -251.158502) (xy 272.163285 -251.186388) (xy 272.155165 -251.241564)
			(xy 272.139097 -251.294971) (xy 272.115425 -251.345468) (xy 272.084652 -251.391981) (xy 272.047435 -251.433518)
			(xy 272.004567 -251.469193) (xy 271.956961 -251.498247) (xy 271.905632 -251.520059) (xy 271.851675 -251.534165)
			(xy 271.796238 -251.540265) (xy 271.740504 -251.538228) (xy 271.685661 -251.528098) (xy 271.632877 -251.510091)
			(xy 271.583277 -251.48459) (xy 271.537919 -251.452139) (xy 271.49777 -251.41343) (xy 271.463684 -251.369287)
			(xy 271.436388 -251.320652) (xy 271.416465 -251.268561) (xy 271.404339 -251.214124) (xy 271.400268 -251.158502)
			(xy 271.100365 -251.158502) (xy 271.100041 -251.176228) (xy 271.091921 -251.231404) (xy 271.075853 -251.284811)
			(xy 271.052181 -251.335308) (xy 271.021408 -251.381821) (xy 270.984191 -251.423358) (xy 270.941323 -251.459033)
			(xy 270.893717 -251.488087) (xy 270.842388 -251.509899) (xy 270.788431 -251.524005) (xy 270.732994 -251.530105)
			(xy 270.67726 -251.528068) (xy 270.622417 -251.517938) (xy 270.569633 -251.499931) (xy 270.520033 -251.47443)
			(xy 270.474675 -251.441979) (xy 270.434526 -251.40327) (xy 270.40044 -251.359127) (xy 270.373144 -251.310492)
			(xy 270.353221 -251.258401) (xy 270.341095 -251.203964) (xy 270.337024 -251.148342) (xy 270.131609 -251.148342)
			(xy 270.131794 -251.158502) (xy 270.131285 -251.186388) (xy 270.123165 -251.241564) (xy 270.107097 -251.294971)
			(xy 270.083425 -251.345468) (xy 270.052652 -251.391981) (xy 270.015435 -251.433518) (xy 269.972567 -251.469193)
			(xy 269.924961 -251.498247) (xy 269.873632 -251.520059) (xy 269.819675 -251.534165) (xy 269.764238 -251.540265)
			(xy 269.708504 -251.538228) (xy 269.653661 -251.528098) (xy 269.600877 -251.510091) (xy 269.551277 -251.48459)
			(xy 269.505919 -251.452139) (xy 269.46577 -251.41343) (xy 269.431684 -251.369287) (xy 269.404388 -251.320652)
			(xy 269.384465 -251.268561) (xy 269.372339 -251.214124) (xy 269.368268 -251.158502) (xy 269.115794 -251.158502)
			(xy 269.115285 -251.186388) (xy 269.107165 -251.241564) (xy 269.091097 -251.294971) (xy 269.067425 -251.345468)
			(xy 269.036652 -251.391981) (xy 268.999435 -251.433518) (xy 268.956567 -251.469193) (xy 268.908961 -251.498247)
			(xy 268.857632 -251.520059) (xy 268.803675 -251.534165) (xy 268.748238 -251.540265) (xy 268.692504 -251.538228)
			(xy 268.637661 -251.528098) (xy 268.584877 -251.510091) (xy 268.535277 -251.48459) (xy 268.489919 -251.452139)
			(xy 268.44977 -251.41343) (xy 268.415684 -251.369287) (xy 268.388388 -251.320652) (xy 268.368465 -251.268561)
			(xy 268.356339 -251.214124) (xy 268.352268 -251.158502) (xy 268.099794 -251.158502) (xy 268.099285 -251.186388)
			(xy 268.091165 -251.241564) (xy 268.075097 -251.294971) (xy 268.051425 -251.345468) (xy 268.020652 -251.391981)
			(xy 267.983435 -251.433518) (xy 267.940567 -251.469193) (xy 267.892961 -251.498247) (xy 267.841632 -251.520059)
			(xy 267.787675 -251.534165) (xy 267.732238 -251.540265) (xy 267.676504 -251.538228) (xy 267.621661 -251.528098)
			(xy 267.568877 -251.510091) (xy 267.519277 -251.48459) (xy 267.473919 -251.452139) (xy 267.43377 -251.41343)
			(xy 267.399684 -251.369287) (xy 267.372388 -251.320652) (xy 267.352465 -251.268561) (xy 267.340339 -251.214124)
			(xy 267.336268 -251.158502) (xy 267.083794 -251.158502) (xy 267.083285 -251.186388) (xy 267.075165 -251.241564)
			(xy 267.059097 -251.294971) (xy 267.035425 -251.345468) (xy 267.004652 -251.391981) (xy 266.967435 -251.433518)
			(xy 266.924567 -251.469193) (xy 266.876961 -251.498247) (xy 266.825632 -251.520059) (xy 266.771675 -251.534165)
			(xy 266.716238 -251.540265) (xy 266.660504 -251.538228) (xy 266.605661 -251.528098) (xy 266.552877 -251.510091)
			(xy 266.503277 -251.48459) (xy 266.457919 -251.452139) (xy 266.41777 -251.41343) (xy 266.383684 -251.369287)
			(xy 266.356388 -251.320652) (xy 266.336465 -251.268561) (xy 266.324339 -251.214124) (xy 266.320268 -251.158502)
			(xy 266.067794 -251.158502) (xy 266.067285 -251.186388) (xy 266.059165 -251.241564) (xy 266.043097 -251.294971)
			(xy 266.019425 -251.345468) (xy 265.988652 -251.391981) (xy 265.951435 -251.433518) (xy 265.908567 -251.469193)
			(xy 265.860961 -251.498247) (xy 265.809632 -251.520059) (xy 265.755675 -251.534165) (xy 265.700238 -251.540265)
			(xy 265.644504 -251.538228) (xy 265.589661 -251.528098) (xy 265.536877 -251.510091) (xy 265.487277 -251.48459)
			(xy 265.441919 -251.452139) (xy 265.40177 -251.41343) (xy 265.367684 -251.369287) (xy 265.340388 -251.320652)
			(xy 265.320465 -251.268561) (xy 265.308339 -251.214124) (xy 265.304268 -251.158502) (xy 265.051794 -251.158502)
			(xy 265.051285 -251.186388) (xy 265.043165 -251.241564) (xy 265.027097 -251.294971) (xy 265.003425 -251.345468)
			(xy 264.972652 -251.391981) (xy 264.935435 -251.433518) (xy 264.892567 -251.469193) (xy 264.844961 -251.498247)
			(xy 264.793632 -251.520059) (xy 264.739675 -251.534165) (xy 264.684238 -251.540265) (xy 264.628504 -251.538228)
			(xy 264.573661 -251.528098) (xy 264.520877 -251.510091) (xy 264.471277 -251.48459) (xy 264.425919 -251.452139)
			(xy 264.38577 -251.41343) (xy 264.351684 -251.369287) (xy 264.324388 -251.320652) (xy 264.304465 -251.268561)
			(xy 264.292339 -251.214124) (xy 264.288268 -251.158502) (xy 264.035794 -251.158502) (xy 264.035145 -251.190012)
			(xy 264.024806 -251.252177) (xy 264.01522 -251.2822) (xy 264.012426 -251.290328) (xy 264.012426 -253.324614)
			(xy 264.01522 -253.332742) (xy 264.024858 -253.362752) (xy 264.035194 -253.424926) (xy 264.035794 -253.45644)
			(xy 271.400268 -253.45644) (xy 271.404339 -253.400818) (xy 271.416465 -253.346381) (xy 271.436388 -253.29429)
			(xy 271.463684 -253.245655) (xy 271.49777 -253.201512) (xy 271.537919 -253.162803) (xy 271.583277 -253.130352)
			(xy 271.632877 -253.104851) (xy 271.685661 -253.086844) (xy 271.740504 -253.076714) (xy 271.796238 -253.074677)
			(xy 271.851675 -253.080777) (xy 271.905632 -253.094883) (xy 271.956961 -253.116695) (xy 272.004567 -253.145749)
			(xy 272.047435 -253.181424) (xy 272.084652 -253.222961) (xy 272.115425 -253.269474) (xy 272.139097 -253.319971)
			(xy 272.155165 -253.373378) (xy 272.163285 -253.428554) (xy 272.163794 -253.45644) (xy 272.163285 -253.484326)
			(xy 272.155165 -253.539502) (xy 272.139097 -253.592909) (xy 272.115425 -253.643406) (xy 272.084652 -253.689919)
			(xy 272.047435 -253.731456) (xy 272.004567 -253.767131) (xy 271.956961 -253.796185) (xy 271.905632 -253.817997)
			(xy 271.851675 -253.832103) (xy 271.796238 -253.838203) (xy 271.740504 -253.836166) (xy 271.685661 -253.826036)
			(xy 271.632877 -253.808029) (xy 271.583277 -253.782528) (xy 271.537919 -253.750077) (xy 271.49777 -253.711368)
			(xy 271.463684 -253.667225) (xy 271.436388 -253.61859) (xy 271.416465 -253.566499) (xy 271.404339 -253.512062)
			(xy 271.400268 -253.45644) (xy 264.035794 -253.45644) (xy 264.035142 -253.487949) (xy 264.024797 -253.550112)
			(xy 264.01522 -253.580138) (xy 264.012426 -253.588266) (xy 264.012426 -254.865886) (xy 264.012865 -254.875949)
			(xy 264.020605 -254.894528) (xy 264.027412 -254.901954) (xy 264.850118 -255.72466) (xy 264.857516 -255.731508)
			(xy 264.876114 -255.739242) (xy 264.886186 -255.739646) (xy 272.90522 -255.739646) (xy 272.915287 -255.739218)
			(xy 272.933881 -255.731492) (xy 272.941288 -255.72466) (xy 274.010374 -254.655574) (xy 274.017932 -254.647258)
			(xy 274.02559 -254.62616) (xy 274.025106 -254.614934) (xy 272.560034 -238.614204) (xy 272.559272 -238.609378)
			(xy 269.494254 -222.400622) (xy 269.49261 -222.393192) (xy 269.485503 -222.379744) (xy 269.480284 -222.374206)
			(xy 268.522958 -221.41688) (xy 268.515561 -221.410031) (xy 268.496962 -221.4023) (xy 268.48689 -221.401894)
			(xy 265.98372 -221.401894) (xy 265.9727 -221.40243) (xy 265.952677 -221.411643) (xy 265.945112 -221.419674)
			(xy 265.887454 -221.48673) (xy 265.881612 -221.508066) (xy 265.883136 -221.518988) (xy 265.885264 -221.533499)
			(xy 265.887552 -221.562742) (xy 265.887708 -221.577408) (xy 265.88724 -221.604399) (xy 265.879632 -221.657842)
			(xy 265.864568 -221.70968) (xy 265.842349 -221.758877) (xy 265.813418 -221.804452) (xy 265.778353 -221.845495)
			(xy 265.737855 -221.881187) (xy 265.69273 -221.910816) (xy 265.643881 -221.933789) (xy 265.618214 -221.942152)
			(xy 265.613065 -221.943848) (xy 265.603581 -221.949094) (xy 265.599418 -221.952566) (xy 265.581106 -221.968222)
			(xy 265.540812 -221.99463) (xy 265.497124 -222.014938) (xy 265.45096 -222.028718) (xy 265.403289 -222.035681)
			(xy 265.3792 -222.036132) (xy 265.259312 -222.036132) (xy 265.249324 -222.036668) (xy 265.230892 -222.044382)
			(xy 265.223498 -222.051118) (xy 263.927082 -223.347534) (xy 267.562582 -223.347534) (xy 267.566653 -223.291912)
			(xy 267.578779 -223.237475) (xy 267.598702 -223.185384) (xy 267.625998 -223.136749) (xy 267.660084 -223.092606)
			(xy 267.700233 -223.053897) (xy 267.745591 -223.021446) (xy 267.795191 -222.995945) (xy 267.847975 -222.977938)
			(xy 267.902818 -222.967808) (xy 267.958552 -222.965771) (xy 268.013989 -222.971871) (xy 268.067946 -222.985977)
			(xy 268.119275 -223.007789) (xy 268.166881 -223.036843) (xy 268.209749 -223.072518) (xy 268.246966 -223.114055)
			(xy 268.277739 -223.160568) (xy 268.301411 -223.211065) (xy 268.317479 -223.264472) (xy 268.325599 -223.319648)
			(xy 268.326108 -223.347534) (xy 268.325599 -223.37542) (xy 268.317479 -223.430596) (xy 268.301411 -223.484003)
			(xy 268.277739 -223.5345) (xy 268.246966 -223.581013) (xy 268.209749 -223.62255) (xy 268.166881 -223.658225)
			(xy 268.119275 -223.687279) (xy 268.067946 -223.709091) (xy 268.013989 -223.723197) (xy 267.958552 -223.729297)
			(xy 267.902818 -223.72726) (xy 267.847975 -223.71713) (xy 267.795191 -223.699123) (xy 267.745591 -223.673622)
			(xy 267.700233 -223.641171) (xy 267.660084 -223.602462) (xy 267.625998 -223.558319) (xy 267.598702 -223.509684)
			(xy 267.578779 -223.457593) (xy 267.566653 -223.403156) (xy 267.562582 -223.347534) (xy 263.927082 -223.347534)
			(xy 263.341358 -223.933258) (xy 263.335262 -223.943418) (xy 263.33323 -223.94926) (xy 263.32476 -223.974334)
			(xy 263.300992 -224.021617) (xy 263.270016 -224.064525) (xy 263.251696 -224.083626) (xy 262.238236 -225.097086)
			(xy 263.196068 -225.097086) (xy 263.200139 -225.041464) (xy 263.212265 -224.987027) (xy 263.232188 -224.934936)
			(xy 263.259484 -224.886301) (xy 263.29357 -224.842158) (xy 263.333719 -224.803449) (xy 263.379077 -224.770998)
			(xy 263.428677 -224.745497) (xy 263.481461 -224.72749) (xy 263.536304 -224.71736) (xy 263.592038 -224.715323)
			(xy 263.647475 -224.721423) (xy 263.701432 -224.735529) (xy 263.752761 -224.757341) (xy 263.800367 -224.786395)
			(xy 263.843235 -224.82207) (xy 263.880452 -224.863607) (xy 263.911225 -224.91012) (xy 263.934897 -224.960617)
			(xy 263.950965 -225.014024) (xy 263.959085 -225.0692) (xy 263.959594 -225.097086) (xy 263.959085 -225.124972)
			(xy 263.950965 -225.180148) (xy 263.934897 -225.233555) (xy 263.911225 -225.284052) (xy 263.880452 -225.330565)
			(xy 263.843235 -225.372102) (xy 263.800367 -225.407777) (xy 263.752761 -225.436831) (xy 263.701432 -225.458643)
			(xy 263.698957 -225.45929) (xy 268.389352 -225.45929) (xy 268.393423 -225.403668) (xy 268.405549 -225.349231)
			(xy 268.425472 -225.29714) (xy 268.452768 -225.248505) (xy 268.486854 -225.204362) (xy 268.527003 -225.165653)
			(xy 268.572361 -225.133202) (xy 268.621961 -225.107701) (xy 268.674745 -225.089694) (xy 268.729588 -225.079564)
			(xy 268.785322 -225.077527) (xy 268.840759 -225.083627) (xy 268.894716 -225.097733) (xy 268.946045 -225.119545)
			(xy 268.993651 -225.148599) (xy 269.036519 -225.184274) (xy 269.073736 -225.225811) (xy 269.104509 -225.272324)
			(xy 269.128181 -225.322821) (xy 269.144249 -225.376228) (xy 269.152369 -225.431404) (xy 269.152878 -225.45929)
			(xy 269.152369 -225.487176) (xy 269.144249 -225.542352) (xy 269.128181 -225.595759) (xy 269.104509 -225.646256)
			(xy 269.073736 -225.692769) (xy 269.036519 -225.734306) (xy 268.993651 -225.769981) (xy 268.946045 -225.799035)
			(xy 268.894716 -225.820847) (xy 268.840759 -225.834953) (xy 268.785322 -225.841053) (xy 268.729588 -225.839016)
			(xy 268.674745 -225.828886) (xy 268.621961 -225.810879) (xy 268.572361 -225.785378) (xy 268.527003 -225.752927)
			(xy 268.486854 -225.714218) (xy 268.452768 -225.670075) (xy 268.425472 -225.62144) (xy 268.405549 -225.569349)
			(xy 268.393423 -225.514912) (xy 268.389352 -225.45929) (xy 263.698957 -225.45929) (xy 263.647475 -225.472749)
			(xy 263.592038 -225.478849) (xy 263.536304 -225.476812) (xy 263.481461 -225.466682) (xy 263.428677 -225.448675)
			(xy 263.379077 -225.423174) (xy 263.333719 -225.390723) (xy 263.29357 -225.352014) (xy 263.259484 -225.307871)
			(xy 263.232188 -225.259236) (xy 263.212265 -225.207145) (xy 263.200139 -225.152708) (xy 263.196068 -225.097086)
			(xy 262.238236 -225.097086) (xy 260.995922 -226.3394) (xy 266.392912 -226.3394) (xy 266.396983 -226.283778)
			(xy 266.409109 -226.229341) (xy 266.429032 -226.17725) (xy 266.456328 -226.128615) (xy 266.490414 -226.084472)
			(xy 266.530563 -226.045763) (xy 266.575921 -226.013312) (xy 266.625521 -225.987811) (xy 266.678305 -225.969804)
			(xy 266.733148 -225.959674) (xy 266.788882 -225.957637) (xy 266.844319 -225.963737) (xy 266.898276 -225.977843)
			(xy 266.949605 -225.999655) (xy 266.997211 -226.028709) (xy 267.040079 -226.064384) (xy 267.077296 -226.105921)
			(xy 267.108069 -226.152434) (xy 267.131741 -226.202931) (xy 267.147809 -226.256338) (xy 267.155929 -226.311514)
			(xy 267.156438 -226.3394) (xy 267.155929 -226.367286) (xy 267.147809 -226.422462) (xy 267.131741 -226.475869)
			(xy 267.108069 -226.526366) (xy 267.077296 -226.572879) (xy 267.040079 -226.614416) (xy 266.997211 -226.650091)
			(xy 266.949605 -226.679145) (xy 266.898276 -226.700957) (xy 266.844319 -226.715063) (xy 266.788882 -226.721163)
			(xy 266.733148 -226.719126) (xy 266.678305 -226.708996) (xy 266.625521 -226.690989) (xy 266.575921 -226.665488)
			(xy 266.530563 -226.633037) (xy 266.490414 -226.594328) (xy 266.456328 -226.550185) (xy 266.429032 -226.50155)
			(xy 266.409109 -226.449459) (xy 266.396983 -226.395022) (xy 266.392912 -226.3394) (xy 260.995922 -226.3394)
			(xy 260.694424 -226.640898) (xy 260.687575 -226.648295) (xy 260.679836 -226.666893) (xy 260.679438 -226.676966)
			(xy 260.679438 -227.698046) (xy 260.679005 -227.708111) (xy 260.671272 -227.726698) (xy 260.664452 -227.734114)
			(xy 259.147056 -229.25151) (xy 263.272522 -229.25151) (xy 263.276593 -229.195888) (xy 263.288719 -229.141451)
			(xy 263.308642 -229.08936) (xy 263.335938 -229.040725) (xy 263.370024 -228.996582) (xy 263.410173 -228.957873)
			(xy 263.455531 -228.925422) (xy 263.505131 -228.899921) (xy 263.557915 -228.881914) (xy 263.612758 -228.871784)
			(xy 263.668492 -228.869747) (xy 263.723929 -228.875847) (xy 263.777886 -228.889953) (xy 263.829215 -228.911765)
			(xy 263.876821 -228.940819) (xy 263.919689 -228.976494) (xy 263.956906 -229.018031) (xy 263.987679 -229.064544)
			(xy 264.011351 -229.115041) (xy 264.027419 -229.168448) (xy 264.035539 -229.223624) (xy 264.036048 -229.25151)
			(xy 264.035539 -229.279396) (xy 264.027419 -229.334572) (xy 264.011351 -229.387979) (xy 263.987679 -229.438476)
			(xy 263.956906 -229.484989) (xy 263.919689 -229.526526) (xy 263.876821 -229.562201) (xy 263.829215 -229.591255)
			(xy 263.777886 -229.613067) (xy 263.723929 -229.627173) (xy 263.668492 -229.633273) (xy 263.612758 -229.631236)
			(xy 263.557915 -229.621106) (xy 263.505131 -229.603099) (xy 263.455531 -229.577598) (xy 263.410173 -229.545147)
			(xy 263.370024 -229.506438) (xy 263.335938 -229.462295) (xy 263.308642 -229.41366) (xy 263.288719 -229.361569)
			(xy 263.276593 -229.307132) (xy 263.272522 -229.25151) (xy 259.147056 -229.25151) (xy 257.514344 -230.884222)
			(xy 257.507419 -230.89186) (xy 257.499806 -230.910999) (xy 257.499612 -230.921306) (xy 257.501644 -231.00538)
			(xy 257.51028 -231.024176) (xy 257.518154 -231.031288) (xy 257.5375 -231.04946) (xy 257.571486 -231.09023)
			(xy 257.599496 -231.135315) (xy 257.620991 -231.183846) (xy 257.635556 -231.234886) (xy 257.64291 -231.287451)
			(xy 257.643376 -231.31399) (xy 257.642913 -231.341242) (xy 257.635157 -231.395193) (xy 257.619802 -231.44749)
			(xy 257.597159 -231.497069) (xy 257.567691 -231.542921) (xy 257.531997 -231.584113) (xy 257.490804 -231.619804)
			(xy 257.44495 -231.64927) (xy 257.395369 -231.67191) (xy 257.343071 -231.687262) (xy 257.289121 -231.695015)
			(xy 257.261868 -231.695498) (xy 257.23533 -231.695039) (xy 257.182766 -231.687681) (xy 257.131729 -231.673111)
			(xy 257.083202 -231.651611) (xy 257.038122 -231.623595) (xy 256.997359 -231.589603) (xy 256.979166 -231.570276)
			(xy 256.972054 -231.562402) (xy 256.953258 -231.553766) (xy 256.869184 -231.551734) (xy 256.858878 -231.551946)
			(xy 256.839736 -231.559542) (xy 256.8321 -231.566466) (xy 255.334516 -233.06405) (xy 258.296408 -233.06405)
			(xy 258.300479 -233.008428) (xy 258.312605 -232.953991) (xy 258.332528 -232.9019) (xy 258.359824 -232.853265)
			(xy 258.39391 -232.809122) (xy 258.434059 -232.770413) (xy 258.479417 -232.737962) (xy 258.529017 -232.712461)
			(xy 258.581801 -232.694454) (xy 258.636644 -232.684324) (xy 258.692378 -232.682287) (xy 258.747815 -232.688387)
			(xy 258.801772 -232.702493) (xy 258.853101 -232.724305) (xy 258.900707 -232.753359) (xy 258.943575 -232.789034)
			(xy 258.980792 -232.830571) (xy 259.011565 -232.877084) (xy 259.035237 -232.927581) (xy 259.051305 -232.980988)
			(xy 259.059425 -233.036164) (xy 259.059934 -233.06405) (xy 259.059498 -233.087926) (xy 259.293866 -233.087926)
			(xy 259.297937 -233.032304) (xy 259.310063 -232.977867) (xy 259.329986 -232.925776) (xy 259.357282 -232.877141)
			(xy 259.391368 -232.832998) (xy 259.431517 -232.794289) (xy 259.476875 -232.761838) (xy 259.526475 -232.736337)
			(xy 259.579259 -232.71833) (xy 259.634102 -232.7082) (xy 259.689836 -232.706163) (xy 259.745273 -232.712263)
			(xy 259.79923 -232.726369) (xy 259.850559 -232.748181) (xy 259.898165 -232.777235) (xy 259.941033 -232.81291)
			(xy 259.97825 -232.854447) (xy 260.009023 -232.90096) (xy 260.032695 -232.951457) (xy 260.048763 -233.004864)
			(xy 260.056883 -233.06004) (xy 260.057392 -233.087926) (xy 260.057165 -233.100372) (xy 261.128762 -233.100372)
			(xy 261.132833 -233.04475) (xy 261.144959 -232.990313) (xy 261.164882 -232.938222) (xy 261.192178 -232.889587)
			(xy 261.226264 -232.845444) (xy 261.266413 -232.806735) (xy 261.311771 -232.774284) (xy 261.361371 -232.748783)
			(xy 261.414155 -232.730776) (xy 261.468998 -232.720646) (xy 261.524732 -232.718609) (xy 261.580169 -232.724709)
			(xy 261.634126 -232.738815) (xy 261.685455 -232.760627) (xy 261.733061 -232.789681) (xy 261.775929 -232.825356)
			(xy 261.813146 -232.866893) (xy 261.843919 -232.913406) (xy 261.867591 -232.963903) (xy 261.883659 -233.01731)
			(xy 261.891779 -233.072486) (xy 261.892288 -233.100372) (xy 261.891779 -233.128258) (xy 261.883659 -233.183434)
			(xy 261.867591 -233.236841) (xy 261.843919 -233.287338) (xy 261.813146 -233.333851) (xy 261.775929 -233.375388)
			(xy 261.733061 -233.411063) (xy 261.685455 -233.440117) (xy 261.634126 -233.461929) (xy 261.580169 -233.476035)
			(xy 261.524732 -233.482135) (xy 261.468998 -233.480098) (xy 261.414155 -233.469968) (xy 261.361371 -233.451961)
			(xy 261.311771 -233.42646) (xy 261.266413 -233.394009) (xy 261.226264 -233.3553) (xy 261.192178 -233.311157)
			(xy 261.164882 -233.262522) (xy 261.144959 -233.210431) (xy 261.132833 -233.155994) (xy 261.128762 -233.100372)
			(xy 260.057165 -233.100372) (xy 260.056883 -233.115812) (xy 260.048763 -233.170988) (xy 260.032695 -233.224395)
			(xy 260.009023 -233.274892) (xy 259.97825 -233.321405) (xy 259.941033 -233.362942) (xy 259.898165 -233.398617)
			(xy 259.850559 -233.427671) (xy 259.79923 -233.449483) (xy 259.745273 -233.463589) (xy 259.689836 -233.469689)
			(xy 259.634102 -233.467652) (xy 259.579259 -233.457522) (xy 259.526475 -233.439515) (xy 259.476875 -233.414014)
			(xy 259.431517 -233.381563) (xy 259.391368 -233.342854) (xy 259.357282 -233.298711) (xy 259.329986 -233.250076)
			(xy 259.310063 -233.197985) (xy 259.297937 -233.143548) (xy 259.293866 -233.087926) (xy 259.059498 -233.087926)
			(xy 259.059425 -233.091936) (xy 259.051305 -233.147112) (xy 259.035237 -233.200519) (xy 259.011565 -233.251016)
			(xy 258.980792 -233.297529) (xy 258.943575 -233.339066) (xy 258.900707 -233.374741) (xy 258.853101 -233.403795)
			(xy 258.801772 -233.425607) (xy 258.747815 -233.439713) (xy 258.692378 -233.445813) (xy 258.636644 -233.443776)
			(xy 258.581801 -233.433646) (xy 258.529017 -233.415639) (xy 258.479417 -233.390138) (xy 258.434059 -233.357687)
			(xy 258.39391 -233.318978) (xy 258.359824 -233.274835) (xy 258.332528 -233.2262) (xy 258.312605 -233.174109)
			(xy 258.300479 -233.119672) (xy 258.296408 -233.06405) (xy 255.334516 -233.06405) (xy 253.703836 -234.69473)
			(xy 254.876044 -234.69473) (xy 254.880115 -234.639108) (xy 254.892241 -234.584671) (xy 254.912164 -234.53258)
			(xy 254.93946 -234.483945) (xy 254.973546 -234.439802) (xy 255.013695 -234.401093) (xy 255.059053 -234.368642)
			(xy 255.108653 -234.343141) (xy 255.161437 -234.325134) (xy 255.21628 -234.315004) (xy 255.272014 -234.312967)
			(xy 255.327451 -234.319067) (xy 255.381408 -234.333173) (xy 255.432737 -234.354985) (xy 255.480343 -234.384039)
			(xy 255.523211 -234.419714) (xy 255.560428 -234.461251) (xy 255.591201 -234.507764) (xy 255.614873 -234.558261)
			(xy 255.630941 -234.611668) (xy 255.639061 -234.666844) (xy 255.63957 -234.69473) (xy 255.639514 -234.697778)
			(xy 255.887472 -234.697778) (xy 255.891543 -234.642156) (xy 255.903669 -234.587719) (xy 255.923592 -234.535628)
			(xy 255.950888 -234.486993) (xy 255.984974 -234.44285) (xy 256.025123 -234.404141) (xy 256.070481 -234.37169)
			(xy 256.120081 -234.346189) (xy 256.172865 -234.328182) (xy 256.227708 -234.318052) (xy 256.283442 -234.316015)
			(xy 256.338879 -234.322115) (xy 256.392836 -234.336221) (xy 256.444165 -234.358033) (xy 256.491771 -234.387087)
			(xy 256.534639 -234.422762) (xy 256.571856 -234.464299) (xy 256.602629 -234.510812) (xy 256.626301 -234.561309)
			(xy 256.642369 -234.614716) (xy 256.650489 -234.669892) (xy 256.650998 -234.697778) (xy 256.650489 -234.725664)
			(xy 256.642369 -234.78084) (xy 256.626301 -234.834247) (xy 256.602629 -234.884744) (xy 256.571856 -234.931257)
			(xy 256.534639 -234.972794) (xy 256.491771 -235.008469) (xy 256.444165 -235.037523) (xy 256.392836 -235.059335)
			(xy 256.338879 -235.073441) (xy 256.283442 -235.079541) (xy 256.227708 -235.077504) (xy 256.172865 -235.067374)
			(xy 256.120081 -235.049367) (xy 256.070481 -235.023866) (xy 256.025123 -234.991415) (xy 255.984974 -234.952706)
			(xy 255.950888 -234.908563) (xy 255.923592 -234.859928) (xy 255.903669 -234.807837) (xy 255.891543 -234.7534)
			(xy 255.887472 -234.697778) (xy 255.639514 -234.697778) (xy 255.639061 -234.722616) (xy 255.630941 -234.777792)
			(xy 255.614873 -234.831199) (xy 255.591201 -234.881696) (xy 255.560428 -234.928209) (xy 255.523211 -234.969746)
			(xy 255.480343 -235.005421) (xy 255.432737 -235.034475) (xy 255.381408 -235.056287) (xy 255.327451 -235.070393)
			(xy 255.272014 -235.076493) (xy 255.21628 -235.074456) (xy 255.161437 -235.064326) (xy 255.108653 -235.046319)
			(xy 255.059053 -235.020818) (xy 255.013695 -234.988367) (xy 254.973546 -234.949658) (xy 254.93946 -234.905515)
			(xy 254.912164 -234.85688) (xy 254.892241 -234.804789) (xy 254.880115 -234.750352) (xy 254.876044 -234.69473)
			(xy 253.703836 -234.69473) (xy 245.734078 -242.664488) (xy 254.886458 -242.664488) (xy 254.890529 -242.608866)
			(xy 254.902655 -242.554429) (xy 254.922578 -242.502338) (xy 254.949874 -242.453703) (xy 254.98396 -242.40956)
			(xy 255.024109 -242.370851) (xy 255.069467 -242.3384) (xy 255.119067 -242.312899) (xy 255.171851 -242.294892)
			(xy 255.226694 -242.284762) (xy 255.282428 -242.282725) (xy 255.337865 -242.288825) (xy 255.391822 -242.302931)
			(xy 255.443151 -242.324743) (xy 255.490757 -242.353797) (xy 255.533625 -242.389472) (xy 255.570842 -242.431009)
			(xy 255.601615 -242.477522) (xy 255.625287 -242.528019) (xy 255.641355 -242.581426) (xy 255.649475 -242.636602)
			(xy 255.649984 -242.664488) (xy 255.649475 -242.692374) (xy 255.641355 -242.74755) (xy 255.625287 -242.800957)
			(xy 255.601615 -242.851454) (xy 255.570842 -242.897967) (xy 255.533625 -242.939504) (xy 255.490757 -242.975179)
			(xy 255.443151 -243.004233) (xy 255.391822 -243.026045) (xy 255.337865 -243.040151) (xy 255.282428 -243.046251)
			(xy 255.226694 -243.044214) (xy 255.171851 -243.034084) (xy 255.119067 -243.016077) (xy 255.069467 -242.990576)
			(xy 255.024109 -242.958125) (xy 254.98396 -242.919416) (xy 254.949874 -242.875273) (xy 254.922578 -242.826638)
			(xy 254.902655 -242.774547) (xy 254.890529 -242.72011) (xy 254.886458 -242.664488) (xy 245.734078 -242.664488)
			(xy 243.40947 -244.989096) (xy 243.40207 -244.995938) (xy 243.383472 -245.003662) (xy 243.373402 -245.004082)
			(xy 243.332 -245.004082) (xy 243.321929 -245.004505) (xy 243.303323 -245.012217) (xy 243.295932 -245.019068)
			(xy 242.29949 -246.01551) (xy 249.35764 -246.01551) (xy 249.361711 -245.959888) (xy 249.373837 -245.905451)
			(xy 249.39376 -245.85336) (xy 249.421056 -245.804725) (xy 249.455142 -245.760582) (xy 249.495291 -245.721873)
			(xy 249.540649 -245.689422) (xy 249.590249 -245.663921) (xy 249.643033 -245.645914) (xy 249.697876 -245.635784)
			(xy 249.75361 -245.633747) (xy 249.809047 -245.639847) (xy 249.863004 -245.653953) (xy 249.914333 -245.675765)
			(xy 249.961939 -245.704819) (xy 250.004807 -245.740494) (xy 250.042024 -245.782031) (xy 250.072797 -245.828544)
			(xy 250.096469 -245.879041) (xy 250.112537 -245.932448) (xy 250.120657 -245.987624) (xy 250.121166 -246.01551)
			(xy 250.120657 -246.043396) (xy 250.112537 -246.098572) (xy 250.096469 -246.151979) (xy 250.072797 -246.202476)
			(xy 250.042024 -246.248989) (xy 250.004807 -246.290526) (xy 249.961939 -246.326201) (xy 249.914333 -246.355255)
			(xy 249.863004 -246.377067) (xy 249.809047 -246.391173) (xy 249.75361 -246.397273) (xy 249.697876 -246.395236)
			(xy 249.643033 -246.385106) (xy 249.590249 -246.367099) (xy 249.540649 -246.341598) (xy 249.495291 -246.309147)
			(xy 249.455142 -246.270438) (xy 249.421056 -246.226295) (xy 249.39376 -246.17766) (xy 249.373837 -246.125569)
			(xy 249.361711 -246.071132) (xy 249.35764 -246.01551) (xy 242.29949 -246.01551) (xy 239.923066 -248.391934)
			(xy 240.834416 -248.391934) (xy 240.838487 -248.336312) (xy 240.850613 -248.281875) (xy 240.870536 -248.229784)
			(xy 240.897832 -248.181149) (xy 240.931918 -248.137006) (xy 240.972067 -248.098297) (xy 241.017425 -248.065846)
			(xy 241.067025 -248.040345) (xy 241.119809 -248.022338) (xy 241.174652 -248.012208) (xy 241.230386 -248.010171)
			(xy 241.285823 -248.016271) (xy 241.33978 -248.030377) (xy 241.391109 -248.052189) (xy 241.438715 -248.081243)
			(xy 241.481583 -248.116918) (xy 241.5188 -248.158455) (xy 241.549573 -248.204968) (xy 241.573245 -248.255465)
			(xy 241.589313 -248.308872) (xy 241.597433 -248.364048) (xy 241.597942 -248.391934) (xy 242.866416 -248.391934)
			(xy 242.870487 -248.336312) (xy 242.882613 -248.281875) (xy 242.902536 -248.229784) (xy 242.929832 -248.181149)
			(xy 242.963918 -248.137006) (xy 243.004067 -248.098297) (xy 243.049425 -248.065846) (xy 243.099025 -248.040345)
			(xy 243.151809 -248.022338) (xy 243.206652 -248.012208) (xy 243.262386 -248.010171) (xy 243.317823 -248.016271)
			(xy 243.37178 -248.030377) (xy 243.423109 -248.052189) (xy 243.470715 -248.081243) (xy 243.513583 -248.116918)
			(xy 243.5508 -248.158455) (xy 243.581573 -248.204968) (xy 243.605245 -248.255465) (xy 243.621313 -248.308872)
			(xy 243.629433 -248.364048) (xy 243.629942 -248.391934) (xy 243.629433 -248.41982) (xy 243.621313 -248.474996)
			(xy 243.605245 -248.528403) (xy 243.581573 -248.5789) (xy 243.5508 -248.625413) (xy 243.513583 -248.66695)
			(xy 243.470715 -248.702625) (xy 243.423109 -248.731679) (xy 243.37178 -248.753491) (xy 243.317823 -248.767597)
			(xy 243.262386 -248.773697) (xy 243.206652 -248.77166) (xy 243.151809 -248.76153) (xy 243.099025 -248.743523)
			(xy 243.049425 -248.718022) (xy 243.004067 -248.685571) (xy 242.963918 -248.646862) (xy 242.929832 -248.602719)
			(xy 242.902536 -248.554084) (xy 242.882613 -248.501993) (xy 242.870487 -248.447556) (xy 242.866416 -248.391934)
			(xy 241.597942 -248.391934) (xy 241.597433 -248.41982) (xy 241.589313 -248.474996) (xy 241.573245 -248.528403)
			(xy 241.549573 -248.5789) (xy 241.5188 -248.625413) (xy 241.481583 -248.66695) (xy 241.438715 -248.702625)
			(xy 241.391109 -248.731679) (xy 241.33978 -248.753491) (xy 241.285823 -248.767597) (xy 241.230386 -248.773697)
			(xy 241.174652 -248.77166) (xy 241.119809 -248.76153) (xy 241.067025 -248.743523) (xy 241.017425 -248.718022)
			(xy 240.972067 -248.685571) (xy 240.931918 -248.646862) (xy 240.897832 -248.602719) (xy 240.870536 -248.554084)
			(xy 240.850613 -248.501993) (xy 240.838487 -248.447556) (xy 240.834416 -248.391934) (xy 239.923066 -248.391934)
			(xy 239.417352 -248.897648) (xy 239.410508 -248.905047) (xy 239.402782 -248.923645) (xy 239.402366 -248.933716)
			(xy 239.402366 -249.476514) (xy 239.818416 -249.476514) (xy 239.822487 -249.420892) (xy 239.834613 -249.366455)
			(xy 239.854536 -249.314364) (xy 239.881832 -249.265729) (xy 239.915918 -249.221586) (xy 239.956067 -249.182877)
			(xy 240.001425 -249.150426) (xy 240.051025 -249.124925) (xy 240.103809 -249.106918) (xy 240.158652 -249.096788)
			(xy 240.214386 -249.094751) (xy 240.269823 -249.100851) (xy 240.32378 -249.114957) (xy 240.375109 -249.136769)
			(xy 240.422715 -249.165823) (xy 240.465583 -249.201498) (xy 240.5028 -249.243035) (xy 240.533573 -249.289548)
			(xy 240.557245 -249.340045) (xy 240.573313 -249.393452) (xy 240.581433 -249.448628) (xy 240.581942 -249.476514)
			(xy 241.850416 -249.476514) (xy 241.854487 -249.420892) (xy 241.866613 -249.366455) (xy 241.886536 -249.314364)
			(xy 241.913832 -249.265729) (xy 241.947918 -249.221586) (xy 241.988067 -249.182877) (xy 242.033425 -249.150426)
			(xy 242.083025 -249.124925) (xy 242.135809 -249.106918) (xy 242.190652 -249.096788) (xy 242.246386 -249.094751)
			(xy 242.301823 -249.100851) (xy 242.35578 -249.114957) (xy 242.407109 -249.136769) (xy 242.454715 -249.165823)
			(xy 242.497583 -249.201498) (xy 242.5348 -249.243035) (xy 242.565573 -249.289548) (xy 242.589245 -249.340045)
			(xy 242.605313 -249.393452) (xy 242.613433 -249.448628) (xy 242.613942 -249.476514) (xy 244.898416 -249.476514)
			(xy 244.902487 -249.420892) (xy 244.914613 -249.366455) (xy 244.934536 -249.314364) (xy 244.961832 -249.265729)
			(xy 244.995918 -249.221586) (xy 245.036067 -249.182877) (xy 245.081425 -249.150426) (xy 245.131025 -249.124925)
			(xy 245.183809 -249.106918) (xy 245.238652 -249.096788) (xy 245.294386 -249.094751) (xy 245.349823 -249.100851)
			(xy 245.40378 -249.114957) (xy 245.455109 -249.136769) (xy 245.502715 -249.165823) (xy 245.545583 -249.201498)
			(xy 245.5828 -249.243035) (xy 245.613573 -249.289548) (xy 245.637245 -249.340045) (xy 245.653313 -249.393452)
			(xy 245.661433 -249.448628) (xy 245.661942 -249.476514) (xy 245.661433 -249.5044) (xy 245.653313 -249.559576)
			(xy 245.637245 -249.612983) (xy 245.613573 -249.66348) (xy 245.5828 -249.709993) (xy 245.545583 -249.75153)
			(xy 245.502715 -249.787205) (xy 245.455109 -249.816259) (xy 245.40378 -249.838071) (xy 245.349823 -249.852177)
			(xy 245.294386 -249.858277) (xy 245.238652 -249.85624) (xy 245.183809 -249.84611) (xy 245.131025 -249.828103)
			(xy 245.081425 -249.802602) (xy 245.036067 -249.770151) (xy 244.995918 -249.731442) (xy 244.961832 -249.687299)
			(xy 244.934536 -249.638664) (xy 244.914613 -249.586573) (xy 244.902487 -249.532136) (xy 244.898416 -249.476514)
			(xy 242.613942 -249.476514) (xy 242.613433 -249.5044) (xy 242.605313 -249.559576) (xy 242.589245 -249.612983)
			(xy 242.565573 -249.66348) (xy 242.5348 -249.709993) (xy 242.497583 -249.75153) (xy 242.454715 -249.787205)
			(xy 242.407109 -249.816259) (xy 242.35578 -249.838071) (xy 242.301823 -249.852177) (xy 242.246386 -249.858277)
			(xy 242.190652 -249.85624) (xy 242.135809 -249.84611) (xy 242.083025 -249.828103) (xy 242.033425 -249.802602)
			(xy 241.988067 -249.770151) (xy 241.947918 -249.731442) (xy 241.913832 -249.687299) (xy 241.886536 -249.638664)
			(xy 241.866613 -249.586573) (xy 241.854487 -249.532136) (xy 241.850416 -249.476514) (xy 240.581942 -249.476514)
			(xy 240.581433 -249.5044) (xy 240.573313 -249.559576) (xy 240.557245 -249.612983) (xy 240.533573 -249.66348)
			(xy 240.5028 -249.709993) (xy 240.465583 -249.75153) (xy 240.422715 -249.787205) (xy 240.375109 -249.816259)
			(xy 240.32378 -249.838071) (xy 240.269823 -249.852177) (xy 240.214386 -249.858277) (xy 240.158652 -249.85624)
			(xy 240.103809 -249.84611) (xy 240.051025 -249.828103) (xy 240.001425 -249.802602) (xy 239.956067 -249.770151)
			(xy 239.915918 -249.731442) (xy 239.881832 -249.687299) (xy 239.854536 -249.638664) (xy 239.834613 -249.586573)
			(xy 239.822487 -249.532136) (xy 239.818416 -249.476514) (xy 239.402366 -249.476514) (xy 239.402366 -251.857256)
			(xy 240.834416 -251.857256) (xy 240.838487 -251.801634) (xy 240.850613 -251.747197) (xy 240.870536 -251.695106)
			(xy 240.897832 -251.646471) (xy 240.931918 -251.602328) (xy 240.972067 -251.563619) (xy 241.017425 -251.531168)
			(xy 241.067025 -251.505667) (xy 241.119809 -251.48766) (xy 241.174652 -251.47753) (xy 241.230386 -251.475493)
			(xy 241.285823 -251.481593) (xy 241.33978 -251.495699) (xy 241.391109 -251.517511) (xy 241.438715 -251.546565)
			(xy 241.481583 -251.58224) (xy 241.5188 -251.623777) (xy 241.549573 -251.67029) (xy 241.573245 -251.720787)
			(xy 241.589313 -251.774194) (xy 241.597433 -251.82937) (xy 241.597942 -251.857256) (xy 241.850416 -251.857256)
			(xy 241.854487 -251.801634) (xy 241.866613 -251.747197) (xy 241.886536 -251.695106) (xy 241.913832 -251.646471)
			(xy 241.947918 -251.602328) (xy 241.988067 -251.563619) (xy 242.033425 -251.531168) (xy 242.083025 -251.505667)
			(xy 242.135809 -251.48766) (xy 242.190652 -251.47753) (xy 242.246386 -251.475493) (xy 242.301823 -251.481593)
			(xy 242.35578 -251.495699) (xy 242.407109 -251.517511) (xy 242.454715 -251.546565) (xy 242.497583 -251.58224)
			(xy 242.5348 -251.623777) (xy 242.565573 -251.67029) (xy 242.589245 -251.720787) (xy 242.605313 -251.774194)
			(xy 242.613433 -251.82937) (xy 242.613942 -251.857256) (xy 243.882416 -251.857256) (xy 243.886487 -251.801634)
			(xy 243.898613 -251.747197) (xy 243.918536 -251.695106) (xy 243.945832 -251.646471) (xy 243.979918 -251.602328)
			(xy 244.020067 -251.563619) (xy 244.065425 -251.531168) (xy 244.115025 -251.505667) (xy 244.167809 -251.48766)
			(xy 244.222652 -251.47753) (xy 244.278386 -251.475493) (xy 244.333823 -251.481593) (xy 244.38778 -251.495699)
			(xy 244.439109 -251.517511) (xy 244.486715 -251.546565) (xy 244.529583 -251.58224) (xy 244.5668 -251.623777)
			(xy 244.597573 -251.67029) (xy 244.621245 -251.720787) (xy 244.637313 -251.774194) (xy 244.645433 -251.82937)
			(xy 244.645942 -251.857256) (xy 244.79758 -251.857256) (xy 244.798039 -251.82563) (xy 244.80625 -251.762914)
			(xy 244.822578 -251.701807) (xy 244.846743 -251.643355) (xy 244.878333 -251.588557) (xy 244.916805 -251.538352)
			(xy 244.938804 -251.515626) (xy 247.790462 -248.663968) (xy 247.813227 -248.642014) (xy 247.863431 -248.603554)
			(xy 247.918224 -248.571972) (xy 247.976668 -248.547807) (xy 248.037765 -248.531472) (xy 248.10047 -248.523247)
			(xy 248.132092 -248.522744) (xy 255.580388 -248.522744) (xy 255.612004 -248.523242) (xy 255.674695 -248.531494)
			(xy 255.735772 -248.547858) (xy 255.794191 -248.572055) (xy 255.848952 -248.60367) (xy 255.899118 -248.642162)
			(xy 255.94383 -248.686873) (xy 255.982324 -248.737038) (xy 256.01394 -248.791798) (xy 256.038138 -248.850216)
			(xy 256.054504 -248.911293) (xy 256.062757 -248.973984) (xy 256.062757 -249.037216) (xy 256.054504 -249.099907)
			(xy 256.038138 -249.160984) (xy 256.01394 -249.219402) (xy 255.982324 -249.274162) (xy 255.94383 -249.324327)
			(xy 255.899118 -249.369038) (xy 255.848952 -249.40753) (xy 255.794191 -249.439145) (xy 255.735772 -249.463342)
			(xy 255.674695 -249.479706) (xy 255.612004 -249.487958) (xy 255.580388 -249.488452) (xy 248.353072 -249.488452)
			(xy 248.343068 -249.488915) (xy 248.324605 -249.496632) (xy 248.317258 -249.503438) (xy 246.646857 -251.173996)
			(xy 256.047238 -251.173996) (xy 256.051309 -251.118374) (xy 256.063435 -251.063937) (xy 256.083358 -251.011846)
			(xy 256.110654 -250.963211) (xy 256.14474 -250.919068) (xy 256.184889 -250.880359) (xy 256.230247 -250.847908)
			(xy 256.279847 -250.822407) (xy 256.332631 -250.8044) (xy 256.387474 -250.79427) (xy 256.443208 -250.792233)
			(xy 256.498645 -250.798333) (xy 256.552602 -250.812439) (xy 256.603931 -250.834251) (xy 256.651537 -250.863305)
			(xy 256.694405 -250.89898) (xy 256.731622 -250.940517) (xy 256.762395 -250.98703) (xy 256.786067 -251.037527)
			(xy 256.802135 -251.090934) (xy 256.810255 -251.14611) (xy 256.810764 -251.173996) (xy 256.810255 -251.201882)
			(xy 256.802135 -251.257058) (xy 256.786067 -251.310465) (xy 256.762395 -251.360962) (xy 256.731622 -251.407475)
			(xy 256.694405 -251.449012) (xy 256.651537 -251.484687) (xy 256.603931 -251.513741) (xy 256.552602 -251.535553)
			(xy 256.498645 -251.549659) (xy 256.443208 -251.555759) (xy 256.387474 -251.553722) (xy 256.332631 -251.543592)
			(xy 256.279847 -251.525585) (xy 256.230247 -251.500084) (xy 256.184889 -251.467633) (xy 256.14474 -251.428924)
			(xy 256.110654 -251.384781) (xy 256.083358 -251.336146) (xy 256.063435 -251.284055) (xy 256.051309 -251.229618)
			(xy 256.047238 -251.173996) (xy 246.646857 -251.173996) (xy 245.622064 -252.198886) (xy 245.599323 -252.220877)
			(xy 245.549128 -252.259382) (xy 245.494339 -252.291007) (xy 245.435892 -252.315213) (xy 245.374785 -252.331586)
			(xy 245.312065 -252.339845) (xy 245.280434 -252.340364) (xy 245.248809 -252.339827) (xy 245.1861 -252.331573)
			(xy 245.125006 -252.315201) (xy 245.066573 -252.290992) (xy 245.011801 -252.259361) (xy 244.961628 -252.220848)
			(xy 244.916913 -252.176114) (xy 244.878423 -252.125924) (xy 244.846815 -252.071139) (xy 244.822631 -252.012695)
			(xy 244.806286 -251.951593) (xy 244.798059 -251.888881) (xy 244.79758 -251.857256) (xy 244.645942 -251.857256)
			(xy 244.645433 -251.885142) (xy 244.637313 -251.940318) (xy 244.621245 -251.993725) (xy 244.597573 -252.044222)
			(xy 244.5668 -252.090735) (xy 244.529583 -252.132272) (xy 244.486715 -252.167947) (xy 244.439109 -252.197001)
			(xy 244.38778 -252.218813) (xy 244.333823 -252.232919) (xy 244.278386 -252.239019) (xy 244.222652 -252.236982)
			(xy 244.167809 -252.226852) (xy 244.115025 -252.208845) (xy 244.065425 -252.183344) (xy 244.020067 -252.150893)
			(xy 243.979918 -252.112184) (xy 243.945832 -252.068041) (xy 243.918536 -252.019406) (xy 243.898613 -251.967315)
			(xy 243.886487 -251.912878) (xy 243.882416 -251.857256) (xy 242.613942 -251.857256) (xy 242.613433 -251.885142)
			(xy 242.605313 -251.940318) (xy 242.589245 -251.993725) (xy 242.565573 -252.044222) (xy 242.5348 -252.090735)
			(xy 242.497583 -252.132272) (xy 242.454715 -252.167947) (xy 242.407109 -252.197001) (xy 242.35578 -252.218813)
			(xy 242.301823 -252.232919) (xy 242.246386 -252.239019) (xy 242.190652 -252.236982) (xy 242.135809 -252.226852)
			(xy 242.083025 -252.208845) (xy 242.033425 -252.183344) (xy 241.988067 -252.150893) (xy 241.947918 -252.112184)
			(xy 241.913832 -252.068041) (xy 241.886536 -252.019406) (xy 241.866613 -251.967315) (xy 241.854487 -251.912878)
			(xy 241.850416 -251.857256) (xy 241.597942 -251.857256) (xy 241.597433 -251.885142) (xy 241.589313 -251.940318)
			(xy 241.573245 -251.993725) (xy 241.549573 -252.044222) (xy 241.5188 -252.090735) (xy 241.481583 -252.132272)
			(xy 241.438715 -252.167947) (xy 241.391109 -252.197001) (xy 241.33978 -252.218813) (xy 241.285823 -252.232919)
			(xy 241.230386 -252.239019) (xy 241.174652 -252.236982) (xy 241.119809 -252.226852) (xy 241.067025 -252.208845)
			(xy 241.017425 -252.183344) (xy 240.972067 -252.150893) (xy 240.931918 -252.112184) (xy 240.897832 -252.068041)
			(xy 240.870536 -252.019406) (xy 240.850613 -251.967315) (xy 240.838487 -251.912878) (xy 240.834416 -251.857256)
			(xy 239.402366 -251.857256) (xy 239.402366 -253.620778) (xy 253.587248 -253.620778) (xy 253.591319 -253.565156)
			(xy 253.603445 -253.510719) (xy 253.623368 -253.458628) (xy 253.650664 -253.409993) (xy 253.68475 -253.36585)
			(xy 253.724899 -253.327141) (xy 253.770257 -253.29469) (xy 253.819857 -253.269189) (xy 253.872641 -253.251182)
			(xy 253.927484 -253.241052) (xy 253.983218 -253.239015) (xy 254.038655 -253.245115) (xy 254.092612 -253.259221)
			(xy 254.143941 -253.281033) (xy 254.191547 -253.310087) (xy 254.234415 -253.345762) (xy 254.271632 -253.387299)
			(xy 254.302405 -253.433812) (xy 254.326077 -253.484309) (xy 254.342145 -253.537716) (xy 254.350265 -253.592892)
			(xy 254.350774 -253.620778) (xy 254.350265 -253.648664) (xy 254.342145 -253.70384) (xy 254.326077 -253.757247)
			(xy 254.302405 -253.807744) (xy 254.271632 -253.854257) (xy 254.234415 -253.895794) (xy 254.191547 -253.931469)
			(xy 254.143941 -253.960523) (xy 254.092612 -253.982335) (xy 254.038655 -253.996441) (xy 253.983218 -254.002541)
			(xy 253.927484 -254.000504) (xy 253.872641 -253.990374) (xy 253.819857 -253.972367) (xy 253.770257 -253.946866)
			(xy 253.724899 -253.914415) (xy 253.68475 -253.875706) (xy 253.650664 -253.831563) (xy 253.623368 -253.782928)
			(xy 253.603445 -253.730837) (xy 253.591319 -253.6764) (xy 253.587248 -253.620778) (xy 239.402366 -253.620778)
			(xy 239.402366 -255.910588) (xy 254.076452 -255.910588) (xy 254.080523 -255.854966) (xy 254.092649 -255.800529)
			(xy 254.112572 -255.748438) (xy 254.139868 -255.699803) (xy 254.173954 -255.65566) (xy 254.214103 -255.616951)
			(xy 254.259461 -255.5845) (xy 254.309061 -255.558999) (xy 254.361845 -255.540992) (xy 254.416688 -255.530862)
			(xy 254.472422 -255.528825) (xy 254.527859 -255.534925) (xy 254.581816 -255.549031) (xy 254.633145 -255.570843)
			(xy 254.680751 -255.599897) (xy 254.723619 -255.635572) (xy 254.760836 -255.677109) (xy 254.791609 -255.723622)
			(xy 254.815281 -255.774119) (xy 254.831349 -255.827526) (xy 254.839469 -255.882702) (xy 254.839978 -255.910588)
			(xy 254.839469 -255.938474) (xy 254.831349 -255.99365) (xy 254.815281 -256.047057) (xy 254.791609 -256.097554)
			(xy 254.760836 -256.144067) (xy 254.723619 -256.185604) (xy 254.680751 -256.221279) (xy 254.633145 -256.250333)
			(xy 254.581816 -256.272145) (xy 254.527859 -256.286251) (xy 254.472422 -256.292351) (xy 254.416688 -256.290314)
			(xy 254.361845 -256.280184) (xy 254.309061 -256.262177) (xy 254.259461 -256.236676) (xy 254.214103 -256.204225)
			(xy 254.173954 -256.165516) (xy 254.139868 -256.121373) (xy 254.112572 -256.072738) (xy 254.092649 -256.020647)
			(xy 254.080523 -255.96621) (xy 254.076452 -255.910588) (xy 239.402366 -255.910588) (xy 239.402366 -255.99009)
			(xy 239.402789 -256.00016) (xy 239.410508 -256.01876) (xy 239.417352 -256.026158) (xy 239.891062 -256.499868)
			(xy 239.898462 -256.506708) (xy 239.917061 -256.514425) (xy 239.92713 -256.514854)
		)
		(stroke
			(width 0)
			(type solid)
		)
		(fill yes)
		(layer "In7.Cu")
		(net "GND")
	)
	(gr_poly
		(pts
			(xy 366.02162 -339.650832) (xy 366.032377 -339.64966) (xy 366.05398 -339.648389) (xy 366.0648 -339.648292)
			(xy 366.07562 -339.64839) (xy 366.097223 -339.649663) (xy 366.10798 -339.650832) (xy 366.111028 -339.651086)
			(xy 367.074958 -339.651086) (xy 367.083862 -339.650657) (xy 367.100573 -339.64449) (xy 367.114175 -339.632989)
			(xy 367.1189 -339.625432) (xy 367.1697 -339.53704) (xy 367.169446 -339.509862) (xy 367.162588 -339.498178)
			(xy 367.150107 -339.476115) (xy 367.130446 -339.429392) (xy 367.117148 -339.380476) (xy 367.110448 -339.33023)
			(xy 367.11001 -339.304884) (xy 367.110496 -339.277633) (xy 367.118252 -339.223685) (xy 367.133607 -339.17139)
			(xy 367.156249 -339.121813) (xy 367.185715 -339.075963) (xy 367.221406 -339.034772) (xy 367.262597 -338.999081)
			(xy 367.308447 -338.969615) (xy 367.358024 -338.946973) (xy 367.410319 -338.931618) (xy 367.464267 -338.923862)
			(xy 367.518769 -338.923862) (xy 367.572717 -338.931618) (xy 367.625012 -338.946973) (xy 367.674589 -338.969615)
			(xy 367.720439 -338.999081) (xy 367.76163 -339.034772) (xy 367.797321 -339.075963) (xy 367.826787 -339.121813)
			(xy 367.849429 -339.17139) (xy 367.864784 -339.223685) (xy 367.87254 -339.277633) (xy 367.873026 -339.304884)
			(xy 367.872613 -339.330231) (xy 367.865905 -339.380479) (xy 367.852605 -339.429397) (xy 367.832948 -339.476124)
			(xy 367.820448 -339.498178) (xy 367.81359 -339.509862) (xy 367.813336 -339.53704) (xy 367.864136 -339.625432)
			(xy 367.868839 -339.633013) (xy 367.882434 -339.644548) (xy 367.899164 -339.650712) (xy 367.908078 -339.651086)
			(xy 371.973602 -339.651086) (xy 371.983672 -339.650662) (xy 372.002274 -339.642946) (xy 372.00967 -339.6361)
			(xy 388.597648 -323.048122) (xy 388.605048 -323.041281) (xy 388.623646 -323.03356) (xy 388.633716 -323.033136)
			(xy 393.819888 -323.033136) (xy 393.82858 -323.032791) (xy 393.84495 -323.026948) (xy 393.851892 -323.021706)
			(xy 396.943326 -320.512948) (xy 396.947136 -320.509392) (xy 397.842994 -319.613534) (xy 397.849795 -319.606186)
			(xy 397.857505 -319.587723) (xy 397.85798 -319.57772) (xy 397.85798 -318.46266) (xy 397.857435 -318.452676)
			(xy 397.849709 -318.434256) (xy 397.842994 -318.426846) (xy 397.504158 -318.08801) (xy 397.487648 -318.080644)
			(xy 397.47825 -318.079882) (xy 397.452631 -318.077759) (xy 397.402458 -318.066576) (xy 397.354627 -318.047744)
			(xy 397.3322 -318.035178) (xy 397.326292 -318.031913) (xy 397.313291 -318.028299) (xy 397.306546 -318.028066)
			(xy 396.676118 -318.028066) (xy 396.666974 -318.031876) (xy 396.644593 -318.04069) (xy 396.597831 -318.051954)
			(xy 396.54988 -318.05574) (xy 396.501929 -318.051954) (xy 396.455167 -318.04069) (xy 396.432786 -318.031876)
			(xy 396.423642 -318.028066) (xy 395.793214 -318.028066) (xy 395.78647 -318.028314) (xy 395.773473 -318.031926)
			(xy 395.76756 -318.035178) (xy 395.741959 -318.049471) (xy 395.686955 -318.069764) (xy 395.629235 -318.080038)
			(xy 395.59992 -318.080644) (xy 395.570606 -318.080035) (xy 395.512888 -318.069752) (xy 395.457882 -318.049469)
			(xy 395.43228 -318.035178) (xy 395.426371 -318.031916) (xy 395.413371 -318.028307) (xy 395.406626 -318.028066)
			(xy 394.776198 -318.028066) (xy 394.767054 -318.031876) (xy 394.744673 -318.04069) (xy 394.697911 -318.051954)
			(xy 394.64996 -318.05574) (xy 394.602009 -318.051954) (xy 394.555247 -318.04069) (xy 394.532866 -318.031876)
			(xy 394.523722 -318.028066) (xy 393.893294 -318.028066) (xy 393.886547 -318.028303) (xy 393.87354 -318.031898)
			(xy 393.86764 -318.035178) (xy 393.842038 -318.049469) (xy 393.787035 -318.069759) (xy 393.729314 -318.08003)
			(xy 393.7 -318.080644) (xy 393.670687 -318.080033) (xy 393.61297 -318.069747) (xy 393.557966 -318.049461)
			(xy 393.53236 -318.035178) (xy 393.526451 -318.031918) (xy 393.51345 -318.028314) (xy 393.506706 -318.028066)
			(xy 392.876024 -318.028066) (xy 392.86688 -318.031876) (xy 392.844499 -318.04069) (xy 392.797737 -318.051954)
			(xy 392.749786 -318.05574) (xy 392.701835 -318.051954) (xy 392.655073 -318.04069) (xy 392.632692 -318.031876)
			(xy 392.623548 -318.028066) (xy 391.99312 -318.028066) (xy 391.986376 -318.028313) (xy 391.973378 -318.031924)
			(xy 391.967466 -318.035178) (xy 391.941865 -318.049471) (xy 391.886861 -318.069765) (xy 391.829141 -318.08004)
			(xy 391.799826 -318.080644) (xy 391.770512 -318.080035) (xy 391.712793 -318.069753) (xy 391.657786 -318.049471)
			(xy 391.632186 -318.035178) (xy 391.626278 -318.031915) (xy 391.613277 -318.028305) (xy 391.606532 -318.028066)
			(xy 390.976104 -318.028066) (xy 390.96696 -318.031876) (xy 390.944579 -318.04069) (xy 390.897817 -318.051954)
			(xy 390.849866 -318.05574) (xy 390.801915 -318.051954) (xy 390.755153 -318.04069) (xy 390.732772 -318.031876)
			(xy 390.723628 -318.028066) (xy 390.0932 -318.028066) (xy 390.086453 -318.028303) (xy 390.073445 -318.031896)
			(xy 390.067546 -318.035178) (xy 390.041945 -318.04947) (xy 389.986941 -318.069761) (xy 389.92922 -318.080032)
			(xy 389.899906 -318.080644) (xy 389.870592 -318.080034) (xy 389.812875 -318.069748) (xy 389.75787 -318.049463)
			(xy 389.732266 -318.035178) (xy 389.726357 -318.031917) (xy 389.713356 -318.028312) (xy 389.706612 -318.028066)
			(xy 389.076184 -318.028066) (xy 389.06704 -318.031876) (xy 389.044659 -318.04069) (xy 388.997897 -318.051954)
			(xy 388.949946 -318.05574) (xy 388.901995 -318.051954) (xy 388.855233 -318.04069) (xy 388.832852 -318.031876)
			(xy 388.823708 -318.028066) (xy 388.19328 -318.028066) (xy 388.186534 -318.028305) (xy 388.173528 -318.031903)
			(xy 388.167626 -318.035178) (xy 388.142026 -318.049476) (xy 388.087023 -318.06978) (xy 388.029302 -318.080066)
			(xy 387.999986 -318.080644) (xy 387.970673 -318.080032) (xy 387.912957 -318.069744) (xy 387.857954 -318.049456)
			(xy 387.832346 -318.035178) (xy 387.826437 -318.03192) (xy 387.813436 -318.02832) (xy 387.806692 -318.028066)
			(xy 387.176264 -318.028066) (xy 387.16712 -318.031876) (xy 387.144739 -318.04069) (xy 387.097977 -318.051954)
			(xy 387.050026 -318.05574) (xy 387.002075 -318.051954) (xy 386.955313 -318.04069) (xy 386.932932 -318.031876)
			(xy 386.923788 -318.028066) (xy 386.293106 -318.028066) (xy 386.286359 -318.028302) (xy 386.27335 -318.031894)
			(xy 386.267452 -318.035178) (xy 386.241851 -318.04947) (xy 386.186847 -318.069762) (xy 386.129126 -318.080035)
			(xy 386.099812 -318.080644) (xy 386.070498 -318.080034) (xy 386.012781 -318.06975) (xy 385.957775 -318.049465)
			(xy 385.932172 -318.035178) (xy 385.926263 -318.031917) (xy 385.913262 -318.02831) (xy 385.906518 -318.028066)
			(xy 385.343146 -318.028066) (xy 385.336401 -318.02831) (xy 385.3234 -318.031914) (xy 385.317492 -318.035178)
			(xy 385.291891 -318.049473) (xy 385.236888 -318.069772) (xy 385.179167 -318.080051) (xy 385.149852 -318.080644)
			(xy 385.120537 -318.080037) (xy 385.062817 -318.06976) (xy 385.007807 -318.049481) (xy 384.982212 -318.035178)
			(xy 384.976302 -318.031924) (xy 384.963301 -318.028332) (xy 384.956558 -318.028066) (xy 384.472434 -318.028066)
			(xy 384.462371 -318.028503) (xy 384.44379 -318.036242) (xy 384.436366 -318.043052) (xy 383.982468 -318.49695)
			(xy 383.97507 -318.503797) (xy 383.956471 -318.511527) (xy 383.9464 -318.511936) (xy 382.229106 -318.511936)
			(xy 382.220373 -318.512284) (xy 382.203927 -318.518158) (xy 382.190438 -318.529249) (xy 382.185672 -318.536574)
			(xy 382.133856 -318.622934) (xy 382.133094 -318.64935) (xy 382.139698 -318.661288) (xy 382.160074 -318.699896)
			(xy 386.744222 -318.699896) (xy 386.748182 -318.650842) (xy 386.759959 -318.603058) (xy 386.77925 -318.557782)
			(xy 386.805553 -318.516186) (xy 386.838188 -318.479349) (xy 386.876309 -318.448224) (xy 386.91893 -318.423617)
			(xy 386.964946 -318.406165) (xy 387.013165 -318.396321) (xy 387.06234 -318.39434) (xy 387.111195 -318.400272)
			(xy 387.158466 -318.413964) (xy 387.202928 -318.435062) (xy 387.243431 -318.463018) (xy 387.278924 -318.49711)
			(xy 387.308489 -318.536454) (xy 387.33136 -318.580031) (xy 387.346944 -318.626712) (xy 387.354839 -318.675289)
			(xy 387.355334 -318.699896) (xy 388.644142 -318.699896) (xy 388.648102 -318.650842) (xy 388.659879 -318.603058)
			(xy 388.67917 -318.557782) (xy 388.705473 -318.516186) (xy 388.738108 -318.479349) (xy 388.776229 -318.448224)
			(xy 388.81885 -318.423617) (xy 388.864866 -318.406165) (xy 388.913085 -318.396321) (xy 388.96226 -318.39434)
			(xy 389.011115 -318.400272) (xy 389.058386 -318.413964) (xy 389.102848 -318.435062) (xy 389.143351 -318.463018)
			(xy 389.178844 -318.49711) (xy 389.208409 -318.536454) (xy 389.23128 -318.580031) (xy 389.246864 -318.626712)
			(xy 389.254759 -318.675289) (xy 389.255254 -318.699896) (xy 390.544062 -318.699896) (xy 390.548022 -318.650842)
			(xy 390.559799 -318.603058) (xy 390.57909 -318.557782) (xy 390.605393 -318.516186) (xy 390.638028 -318.479349)
			(xy 390.676149 -318.448224) (xy 390.71877 -318.423617) (xy 390.764786 -318.406165) (xy 390.813005 -318.396321)
			(xy 390.86218 -318.39434) (xy 390.911035 -318.400272) (xy 390.958306 -318.413964) (xy 391.002768 -318.435062)
			(xy 391.043271 -318.463018) (xy 391.078764 -318.49711) (xy 391.108329 -318.536454) (xy 391.1312 -318.580031)
			(xy 391.146784 -318.626712) (xy 391.154679 -318.675289) (xy 391.155174 -318.699896) (xy 392.443982 -318.699896)
			(xy 392.447942 -318.650842) (xy 392.459719 -318.603058) (xy 392.47901 -318.557782) (xy 392.505313 -318.516186)
			(xy 392.537948 -318.479349) (xy 392.576069 -318.448224) (xy 392.61869 -318.423617) (xy 392.664706 -318.406165)
			(xy 392.712925 -318.396321) (xy 392.7621 -318.39434) (xy 392.810955 -318.400272) (xy 392.858226 -318.413964)
			(xy 392.902688 -318.435062) (xy 392.943191 -318.463018) (xy 392.978684 -318.49711) (xy 393.008249 -318.536454)
			(xy 393.03112 -318.580031) (xy 393.046704 -318.626712) (xy 393.054599 -318.675289) (xy 393.055094 -318.699896)
			(xy 394.344156 -318.699896) (xy 394.348116 -318.650842) (xy 394.359893 -318.603058) (xy 394.379184 -318.557782)
			(xy 394.405487 -318.516186) (xy 394.438122 -318.479349) (xy 394.476243 -318.448224) (xy 394.518864 -318.423617)
			(xy 394.56488 -318.406165) (xy 394.613099 -318.396321) (xy 394.662274 -318.39434) (xy 394.711129 -318.400272)
			(xy 394.7584 -318.413964) (xy 394.802862 -318.435062) (xy 394.843365 -318.463018) (xy 394.878858 -318.49711)
			(xy 394.908423 -318.536454) (xy 394.931294 -318.580031) (xy 394.946878 -318.626712) (xy 394.954773 -318.675289)
			(xy 394.955268 -318.699896) (xy 396.244076 -318.699896) (xy 396.248036 -318.650842) (xy 396.259813 -318.603058)
			(xy 396.279104 -318.557782) (xy 396.305407 -318.516186) (xy 396.338042 -318.479349) (xy 396.376163 -318.448224)
			(xy 396.418784 -318.423617) (xy 396.4648 -318.406165) (xy 396.513019 -318.396321) (xy 396.562194 -318.39434)
			(xy 396.611049 -318.400272) (xy 396.65832 -318.413964) (xy 396.702782 -318.435062) (xy 396.743285 -318.463018)
			(xy 396.778778 -318.49711) (xy 396.808343 -318.536454) (xy 396.831214 -318.580031) (xy 396.846798 -318.626712)
			(xy 396.854693 -318.675289) (xy 396.855188 -318.699896) (xy 396.854693 -318.724503) (xy 396.846798 -318.77308)
			(xy 396.831214 -318.819761) (xy 396.808343 -318.863338) (xy 396.778778 -318.902682) (xy 396.743285 -318.936774)
			(xy 396.702782 -318.96473) (xy 396.65832 -318.985828) (xy 396.611049 -318.99952) (xy 396.562194 -319.005452)
			(xy 396.513019 -319.003471) (xy 396.4648 -318.993627) (xy 396.418784 -318.976175) (xy 396.376163 -318.951568)
			(xy 396.338042 -318.920443) (xy 396.305407 -318.883606) (xy 396.279104 -318.84201) (xy 396.259813 -318.796734)
			(xy 396.248036 -318.74895) (xy 396.244076 -318.699896) (xy 394.955268 -318.699896) (xy 394.954773 -318.724503)
			(xy 394.946878 -318.77308) (xy 394.931294 -318.819761) (xy 394.908423 -318.863338) (xy 394.878858 -318.902682)
			(xy 394.843365 -318.936774) (xy 394.802862 -318.96473) (xy 394.7584 -318.985828) (xy 394.711129 -318.99952)
			(xy 394.662274 -319.005452) (xy 394.613099 -319.003471) (xy 394.56488 -318.993627) (xy 394.518864 -318.976175)
			(xy 394.476243 -318.951568) (xy 394.438122 -318.920443) (xy 394.405487 -318.883606) (xy 394.379184 -318.84201)
			(xy 394.359893 -318.796734) (xy 394.348116 -318.74895) (xy 394.344156 -318.699896) (xy 393.055094 -318.699896)
			(xy 393.054599 -318.724503) (xy 393.046704 -318.77308) (xy 393.03112 -318.819761) (xy 393.008249 -318.863338)
			(xy 392.978684 -318.902682) (xy 392.943191 -318.936774) (xy 392.902688 -318.96473) (xy 392.858226 -318.985828)
			(xy 392.810955 -318.99952) (xy 392.7621 -319.005452) (xy 392.712925 -319.003471) (xy 392.664706 -318.993627)
			(xy 392.61869 -318.976175) (xy 392.576069 -318.951568) (xy 392.537948 -318.920443) (xy 392.505313 -318.883606)
			(xy 392.47901 -318.84201) (xy 392.459719 -318.796734) (xy 392.447942 -318.74895) (xy 392.443982 -318.699896)
			(xy 391.155174 -318.699896) (xy 391.154679 -318.724503) (xy 391.146784 -318.77308) (xy 391.1312 -318.819761)
			(xy 391.108329 -318.863338) (xy 391.078764 -318.902682) (xy 391.043271 -318.936774) (xy 391.002768 -318.96473)
			(xy 390.958306 -318.985828) (xy 390.911035 -318.99952) (xy 390.86218 -319.005452) (xy 390.813005 -319.003471)
			(xy 390.764786 -318.993627) (xy 390.71877 -318.976175) (xy 390.676149 -318.951568) (xy 390.638028 -318.920443)
			(xy 390.605393 -318.883606) (xy 390.57909 -318.84201) (xy 390.559799 -318.796734) (xy 390.548022 -318.74895)
			(xy 390.544062 -318.699896) (xy 389.255254 -318.699896) (xy 389.254759 -318.724503) (xy 389.246864 -318.77308)
			(xy 389.23128 -318.819761) (xy 389.208409 -318.863338) (xy 389.178844 -318.902682) (xy 389.143351 -318.936774)
			(xy 389.102848 -318.96473) (xy 389.058386 -318.985828) (xy 389.011115 -318.99952) (xy 388.96226 -319.005452)
			(xy 388.913085 -319.003471) (xy 388.864866 -318.993627) (xy 388.81885 -318.976175) (xy 388.776229 -318.951568)
			(xy 388.738108 -318.920443) (xy 388.705473 -318.883606) (xy 388.67917 -318.84201) (xy 388.659879 -318.796734)
			(xy 388.648102 -318.74895) (xy 388.644142 -318.699896) (xy 387.355334 -318.699896) (xy 387.354839 -318.724503)
			(xy 387.346944 -318.77308) (xy 387.33136 -318.819761) (xy 387.308489 -318.863338) (xy 387.278924 -318.902682)
			(xy 387.243431 -318.936774) (xy 387.202928 -318.96473) (xy 387.158466 -318.985828) (xy 387.111195 -318.99952)
			(xy 387.06234 -319.005452) (xy 387.013165 -319.003471) (xy 386.964946 -318.993627) (xy 386.91893 -318.976175)
			(xy 386.876309 -318.951568) (xy 386.838188 -318.920443) (xy 386.805553 -318.883606) (xy 386.77925 -318.84201)
			(xy 386.759959 -318.796734) (xy 386.748182 -318.74895) (xy 386.744222 -318.699896) (xy 382.160074 -318.699896)
			(xy 382.185037 -318.747195) (xy 382.269502 -318.922145) (xy 382.346744 -319.100401) (xy 382.416636 -319.281666)
			(xy 382.479059 -319.465636) (xy 382.53391 -319.652004) (xy 382.581097 -319.840458) (xy 382.620541 -320.030684)
			(xy 382.652176 -320.222363) (xy 382.67595 -320.415175) (xy 382.691821 -320.608798) (xy 382.699765 -320.802908)
			(xy 382.700276 -320.900044) (xy 382.699782 -320.996959) (xy 382.691876 -321.190627) (xy 382.676077 -321.383811)
			(xy 382.652412 -321.57619) (xy 382.620919 -321.767444) (xy 382.581652 -321.957254) (xy 382.534675 -322.145304)
			(xy 382.480067 -322.331282) (xy 382.417918 -322.514877) (xy 382.348333 -322.695785) (xy 382.271427 -322.873704)
			(xy 382.187328 -323.048338) (xy 382.096175 -323.219397) (xy 381.998121 -323.386595) (xy 381.893329 -323.549654)
			(xy 381.781974 -323.708304) (xy 381.66424 -323.862279) (xy 381.540323 -324.011324) (xy 381.41043 -324.155191)
			(xy 381.274777 -324.29364) (xy 381.13359 -324.42644) (xy 380.987104 -324.553371) (xy 380.835562 -324.674222)
			(xy 380.679217 -324.788791) (xy 380.518329 -324.896887) (xy 380.353166 -324.998331) (xy 380.184002 -325.092954)
			(xy 380.01112 -325.180598) (xy 379.834807 -325.261118) (xy 379.655356 -325.334379) (xy 379.473066 -325.400259)
			(xy 379.288241 -325.458649) (xy 379.101188 -325.509452) (xy 378.912219 -325.552583) (xy 378.721647 -325.587971)
			(xy 378.529791 -325.615555) (xy 378.336969 -325.635292) (xy 378.143503 -325.647147) (xy 377.949714 -325.651101)
			(xy 377.755925 -325.647147) (xy 377.562459 -325.635292) (xy 377.369637 -325.615555) (xy 377.177781 -325.587971)
			(xy 376.987209 -325.552583) (xy 376.79824 -325.509452) (xy 376.611187 -325.458649) (xy 376.426362 -325.400259)
			(xy 376.244072 -325.334379) (xy 376.064621 -325.261118) (xy 375.888308 -325.180598) (xy 375.715426 -325.092954)
			(xy 375.546262 -324.998331) (xy 375.381099 -324.896887) (xy 375.220211 -324.788791) (xy 375.063866 -324.674222)
			(xy 374.912324 -324.553371) (xy 374.765838 -324.42644) (xy 374.624651 -324.29364) (xy 374.488998 -324.155191)
			(xy 374.359105 -324.011324) (xy 374.235188 -323.862279) (xy 374.117454 -323.708304) (xy 374.006099 -323.549654)
			(xy 373.901307 -323.386595) (xy 373.803253 -323.219397) (xy 373.7121 -323.048338) (xy 373.628001 -322.873704)
			(xy 373.551095 -322.695785) (xy 373.48151 -322.514877) (xy 373.419361 -322.331282) (xy 373.364753 -322.145304)
			(xy 373.317776 -321.957254) (xy 373.278509 -321.767444) (xy 373.247016 -321.57619) (xy 373.223351 -321.383811)
			(xy 373.207552 -321.190627) (xy 373.199646 -320.996959) (xy 373.199152 -320.900044) (xy 373.199643 -320.802907)
			(xy 373.207584 -320.608797) (xy 373.223453 -320.415173) (xy 373.247225 -320.22236) (xy 373.27886 -320.03068)
			(xy 373.318304 -319.840453) (xy 373.365493 -319.651998) (xy 373.420346 -319.46563) (xy 373.482772 -319.28166)
			(xy 373.552668 -319.100396) (xy 373.629915 -318.922141) (xy 373.714386 -318.747193) (xy 373.75973 -318.661288)
			(xy 373.766334 -318.64935) (xy 373.765572 -318.622934) (xy 373.713756 -318.536574) (xy 373.708941 -318.529298)
			(xy 373.695447 -318.518256) (xy 373.679038 -318.512358) (xy 373.670322 -318.511936) (xy 372.439438 -318.511936)
			(xy 372.429374 -318.5115) (xy 372.410792 -318.503762) (xy 372.40337 -318.49695) (xy 372.377716 -318.471296)
			(xy 372.370313 -318.464463) (xy 372.351715 -318.45676) (xy 372.341648 -318.45631) (xy 331.486002 -318.45631)
			(xy 331.475932 -318.456733) (xy 331.457328 -318.464448) (xy 331.449934 -318.471296) (xy 330.401168 -319.520062)
			(xy 330.394324 -319.52746) (xy 330.386601 -319.54606) (xy 330.386182 -319.55613) (xy 330.386182 -320.08064)
			(xy 338.422996 -320.08064) (xy 338.423507 -320.051722) (xy 338.432232 -319.994549) (xy 338.449489 -319.939349)
			(xy 338.474882 -319.887386) (xy 338.507829 -319.839853) (xy 338.547574 -319.797838) (xy 338.570062 -319.77965)
			(xy 338.578807 -319.772073) (xy 338.588997 -319.751325) (xy 338.58962 -319.739772) (xy 338.58962 -319.659508)
			(xy 338.589038 -319.647942) (xy 338.578851 -319.627171) (xy 338.570062 -319.61963) (xy 338.547585 -319.601432)
			(xy 338.507851 -319.559412) (xy 338.474912 -319.511879) (xy 338.449523 -319.459919) (xy 338.432265 -319.404723)
			(xy 338.423533 -319.347555) (xy 338.422996 -319.31864) (xy 338.423493 -319.291388) (xy 338.431244 -319.237438)
			(xy 338.446595 -319.185141) (xy 338.469233 -319.13556) (xy 338.498698 -319.089707) (xy 338.534388 -319.048514)
			(xy 338.575578 -319.012819) (xy 338.621429 -318.983351) (xy 338.671007 -318.960708) (xy 338.723303 -318.945352)
			(xy 338.777252 -318.937595) (xy 338.804504 -318.937132) (xy 338.833422 -318.937635) (xy 338.890594 -318.946366)
			(xy 338.945794 -318.963626) (xy 338.997756 -318.98902) (xy 339.045289 -319.021967) (xy 339.087305 -319.061711)
			(xy 339.105494 -319.084198) (xy 339.113063 -319.092952) (xy 339.133816 -319.10314) (xy 339.145372 -319.103756)
			(xy 339.225636 -319.103756) (xy 339.237201 -319.103164) (xy 339.257974 -319.092986) (xy 339.265514 -319.084198)
			(xy 339.282267 -319.063415) (xy 339.320621 -319.026285) (xy 339.363775 -318.994863) (xy 339.410889 -318.969764)
			(xy 339.461041 -318.951478) (xy 339.513252 -318.940361) (xy 339.566504 -318.936631) (xy 339.619756 -318.940361)
			(xy 339.671967 -318.951478) (xy 339.722119 -318.969764) (xy 339.769233 -318.994863) (xy 339.812387 -319.026285)
			(xy 339.850741 -319.063415) (xy 339.867494 -319.084198) (xy 339.875063 -319.092952) (xy 339.895816 -319.10314)
			(xy 339.907372 -319.103756) (xy 339.987636 -319.103756) (xy 339.999201 -319.103164) (xy 340.019974 -319.092986)
			(xy 340.027514 -319.084198) (xy 340.044267 -319.063415) (xy 340.082621 -319.026285) (xy 340.125775 -318.994863)
			(xy 340.172889 -318.969764) (xy 340.223041 -318.951478) (xy 340.275252 -318.940361) (xy 340.328504 -318.936631)
			(xy 340.381756 -318.940361) (xy 340.433967 -318.951478) (xy 340.484119 -318.969764) (xy 340.531233 -318.994863)
			(xy 340.574387 -319.026285) (xy 340.612741 -319.063415) (xy 340.629494 -319.084198) (xy 340.637063 -319.092952)
			(xy 340.657816 -319.10314) (xy 340.669372 -319.103756) (xy 340.749636 -319.103756) (xy 340.761201 -319.103164)
			(xy 340.781974 -319.092986) (xy 340.789514 -319.084198) (xy 340.806267 -319.063415) (xy 340.844621 -319.026285)
			(xy 340.887775 -318.994863) (xy 340.934889 -318.969764) (xy 340.985041 -318.951478) (xy 341.037252 -318.940361)
			(xy 341.090504 -318.936631) (xy 341.143756 -318.940361) (xy 341.195967 -318.951478) (xy 341.246119 -318.969764)
			(xy 341.293233 -318.994863) (xy 341.336387 -319.026285) (xy 341.374741 -319.063415) (xy 341.391494 -319.084198)
			(xy 341.399063 -319.092952) (xy 341.419816 -319.10314) (xy 341.431372 -319.103756) (xy 341.511636 -319.103756)
			(xy 341.523201 -319.103164) (xy 341.543974 -319.092986) (xy 341.551514 -319.084198) (xy 341.568267 -319.063415)
			(xy 341.606621 -319.026285) (xy 341.649775 -318.994863) (xy 341.696889 -318.969764) (xy 341.747041 -318.951478)
			(xy 341.799252 -318.940361) (xy 341.852504 -318.936631) (xy 341.905756 -318.940361) (xy 341.957967 -318.951478)
			(xy 342.008119 -318.969764) (xy 342.055233 -318.994863) (xy 342.098387 -319.026285) (xy 342.136741 -319.063415)
			(xy 342.153494 -319.084198) (xy 342.161063 -319.092952) (xy 342.181816 -319.10314) (xy 342.193372 -319.103756)
			(xy 342.273636 -319.103756) (xy 342.285201 -319.103164) (xy 342.305974 -319.092986) (xy 342.313514 -319.084198)
			(xy 342.330267 -319.063415) (xy 342.368621 -319.026285) (xy 342.411775 -318.994863) (xy 342.458889 -318.969764)
			(xy 342.509041 -318.951478) (xy 342.561252 -318.940361) (xy 342.614504 -318.936631) (xy 342.667756 -318.940361)
			(xy 342.719967 -318.951478) (xy 342.770119 -318.969764) (xy 342.817233 -318.994863) (xy 342.860387 -319.026285)
			(xy 342.898741 -319.063415) (xy 342.915494 -319.084198) (xy 342.923063 -319.092952) (xy 342.943816 -319.10314)
			(xy 342.955372 -319.103756) (xy 343.035636 -319.103756) (xy 343.047201 -319.103164) (xy 343.067974 -319.092986)
			(xy 343.075514 -319.084198) (xy 343.092267 -319.063415) (xy 343.130621 -319.026285) (xy 343.173775 -318.994863)
			(xy 343.220889 -318.969764) (xy 343.271041 -318.951478) (xy 343.323252 -318.940361) (xy 343.376504 -318.936631)
			(xy 343.429756 -318.940361) (xy 343.481967 -318.951478) (xy 343.532119 -318.969764) (xy 343.579233 -318.994863)
			(xy 343.622387 -319.026285) (xy 343.660741 -319.063415) (xy 343.677494 -319.084198) (xy 343.685063 -319.092952)
			(xy 343.705816 -319.10314) (xy 343.717372 -319.103756) (xy 343.797636 -319.103756) (xy 343.809201 -319.103164)
			(xy 343.829974 -319.092986) (xy 343.837514 -319.084198) (xy 343.854267 -319.063415) (xy 343.892621 -319.026285)
			(xy 343.935775 -318.994863) (xy 343.982889 -318.969764) (xy 344.033041 -318.951478) (xy 344.085252 -318.940361)
			(xy 344.138504 -318.936631) (xy 344.191756 -318.940361) (xy 344.243967 -318.951478) (xy 344.294119 -318.969764)
			(xy 344.341233 -318.994863) (xy 344.384387 -319.026285) (xy 344.422741 -319.063415) (xy 344.439494 -319.084198)
			(xy 344.447063 -319.092952) (xy 344.467816 -319.10314) (xy 344.479372 -319.103756) (xy 344.559636 -319.103756)
			(xy 344.571201 -319.103164) (xy 344.591974 -319.092986) (xy 344.599514 -319.084198) (xy 344.616267 -319.063415)
			(xy 344.654621 -319.026285) (xy 344.697775 -318.994863) (xy 344.744889 -318.969764) (xy 344.795041 -318.951478)
			(xy 344.847252 -318.940361) (xy 344.900504 -318.936631) (xy 344.953756 -318.940361) (xy 345.005967 -318.951478)
			(xy 345.056119 -318.969764) (xy 345.103233 -318.994863) (xy 345.146387 -319.026285) (xy 345.184741 -319.063415)
			(xy 345.201494 -319.084198) (xy 345.209063 -319.092952) (xy 345.229816 -319.10314) (xy 345.241372 -319.103756)
			(xy 345.321636 -319.103756) (xy 345.333201 -319.103164) (xy 345.353974 -319.092986) (xy 345.361514 -319.084198)
			(xy 345.378267 -319.063415) (xy 345.416621 -319.026285) (xy 345.459775 -318.994863) (xy 345.506889 -318.969764)
			(xy 345.557041 -318.951478) (xy 345.609252 -318.940361) (xy 345.662504 -318.936631) (xy 345.715756 -318.940361)
			(xy 345.767967 -318.951478) (xy 345.818119 -318.969764) (xy 345.865233 -318.994863) (xy 345.908387 -319.026285)
			(xy 345.946741 -319.063415) (xy 345.963494 -319.084198) (xy 345.971063 -319.092952) (xy 345.991816 -319.10314)
			(xy 346.003372 -319.103756) (xy 346.083636 -319.103756) (xy 346.095201 -319.103164) (xy 346.115974 -319.092986)
			(xy 346.123514 -319.084198) (xy 346.140267 -319.063415) (xy 346.178621 -319.026285) (xy 346.221775 -318.994863)
			(xy 346.268889 -318.969764) (xy 346.319041 -318.951478) (xy 346.371252 -318.940361) (xy 346.424504 -318.936631)
			(xy 346.477756 -318.940361) (xy 346.529967 -318.951478) (xy 346.580119 -318.969764) (xy 346.627233 -318.994863)
			(xy 346.670387 -319.026285) (xy 346.708741 -319.063415) (xy 346.725494 -319.084198) (xy 346.733063 -319.092952)
			(xy 346.753816 -319.10314) (xy 346.765372 -319.103756) (xy 346.845636 -319.103756) (xy 346.857201 -319.103164)
			(xy 346.877974 -319.092986) (xy 346.885514 -319.084198) (xy 346.903697 -319.061707) (xy 346.945718 -319.021973)
			(xy 346.993255 -318.989035) (xy 347.045218 -318.963647) (xy 347.100417 -318.946393) (xy 347.157588 -318.937666)
			(xy 347.186504 -318.937132) (xy 347.213759 -318.937552) (xy 347.267713 -318.94531) (xy 347.320014 -318.960669)
			(xy 347.369597 -318.983315) (xy 347.415452 -319.012787) (xy 347.456646 -319.048485) (xy 347.49234 -319.089683)
			(xy 347.521806 -319.135541) (xy 347.544447 -319.185127) (xy 347.559799 -319.23743) (xy 347.567551 -319.291385)
			(xy 347.568012 -319.31864) (xy 347.567484 -319.347557) (xy 347.558761 -319.404729) (xy 347.541508 -319.459929)
			(xy 347.516118 -319.511892) (xy 347.483174 -319.559426) (xy 347.443432 -319.601441) (xy 347.420946 -319.61963)
			(xy 347.412166 -319.627174) (xy 347.401994 -319.647947) (xy 347.401388 -319.659508) (xy 347.401388 -319.739772)
			(xy 347.401979 -319.751337) (xy 347.41216 -319.772108) (xy 347.420946 -319.77965) (xy 347.443415 -319.797858)
			(xy 347.483149 -319.839875) (xy 347.516088 -319.887407) (xy 347.541479 -319.939365) (xy 347.558739 -319.994559)
			(xy 347.567474 -320.051725) (xy 347.568012 -320.08064) (xy 351.617026 -320.08064) (xy 351.617563 -320.051724)
			(xy 351.626287 -319.994553) (xy 351.64354 -319.939354) (xy 351.668928 -319.887392) (xy 351.701869 -319.839858)
			(xy 351.741608 -319.79784) (xy 351.764092 -319.77965) (xy 351.772826 -319.772061) (xy 351.783025 -319.751323)
			(xy 351.78365 -319.739772) (xy 351.78365 -319.659508) (xy 351.783092 -319.647938) (xy 351.772891 -319.627166)
			(xy 351.764092 -319.61963) (xy 351.741621 -319.601424) (xy 351.701886 -319.559407) (xy 351.668945 -319.511875)
			(xy 351.643555 -319.459917) (xy 351.626296 -319.404722) (xy 351.617563 -319.347555) (xy 351.617026 -319.31864)
			(xy 351.617493 -319.291387) (xy 351.625245 -319.237434) (xy 351.640598 -319.185134) (xy 351.663238 -319.135552)
			(xy 351.692705 -319.089697) (xy 351.728399 -319.048503) (xy 351.769592 -319.012809) (xy 351.815447 -318.983341)
			(xy 351.865028 -318.9607) (xy 351.917328 -318.945346) (xy 351.971281 -318.937593) (xy 351.998534 -318.937132)
			(xy 352.02745 -318.937685) (xy 352.08462 -318.946405) (xy 352.139819 -318.963656) (xy 352.191781 -318.989041)
			(xy 352.239315 -319.021979) (xy 352.281333 -319.061715) (xy 352.299524 -319.084198) (xy 352.30708 -319.092966)
			(xy 352.327843 -319.103146) (xy 352.339402 -319.103756) (xy 352.419666 -319.103756) (xy 352.431234 -319.103181)
			(xy 352.452006 -319.092991) (xy 352.459544 -319.084198) (xy 352.476297 -319.063415) (xy 352.514651 -319.026285)
			(xy 352.557805 -318.994863) (xy 352.604919 -318.969764) (xy 352.655071 -318.951478) (xy 352.707282 -318.940361)
			(xy 352.760534 -318.936631) (xy 352.813786 -318.940361) (xy 352.865997 -318.951478) (xy 352.916149 -318.969764)
			(xy 352.963263 -318.994863) (xy 353.006417 -319.026285) (xy 353.044771 -319.063415) (xy 353.061524 -319.084198)
			(xy 353.06908 -319.092966) (xy 353.089843 -319.103146) (xy 353.101402 -319.103756) (xy 353.181666 -319.103756)
			(xy 353.193234 -319.103181) (xy 353.214006 -319.092991) (xy 353.221544 -319.084198) (xy 353.238297 -319.063415)
			(xy 353.276651 -319.026285) (xy 353.319805 -318.994863) (xy 353.366919 -318.969764) (xy 353.417071 -318.951478)
			(xy 353.469282 -318.940361) (xy 353.522534 -318.936631) (xy 353.575786 -318.940361) (xy 353.627997 -318.951478)
			(xy 353.678149 -318.969764) (xy 353.725263 -318.994863) (xy 353.768417 -319.026285) (xy 353.806771 -319.063415)
			(xy 353.823524 -319.084198) (xy 353.83108 -319.092966) (xy 353.851843 -319.103146) (xy 353.863402 -319.103756)
			(xy 353.943666 -319.103756) (xy 353.955234 -319.103181) (xy 353.976006 -319.092991) (xy 353.983544 -319.084198)
			(xy 354.000297 -319.063415) (xy 354.038651 -319.026285) (xy 354.081805 -318.994863) (xy 354.128919 -318.969764)
			(xy 354.179071 -318.951478) (xy 354.231282 -318.940361) (xy 354.284534 -318.936631) (xy 354.337786 -318.940361)
			(xy 354.389997 -318.951478) (xy 354.440149 -318.969764) (xy 354.487263 -318.994863) (xy 354.530417 -319.026285)
			(xy 354.568771 -319.063415) (xy 354.585524 -319.084198) (xy 354.59308 -319.092966) (xy 354.613843 -319.103146)
			(xy 354.625402 -319.103756) (xy 354.705666 -319.103756) (xy 354.717234 -319.103181) (xy 354.738006 -319.092991)
			(xy 354.745544 -319.084198) (xy 354.762297 -319.063415) (xy 354.800651 -319.026285) (xy 354.843805 -318.994863)
			(xy 354.890919 -318.969764) (xy 354.941071 -318.951478) (xy 354.993282 -318.940361) (xy 355.046534 -318.936631)
			(xy 355.099786 -318.940361) (xy 355.151997 -318.951478) (xy 355.202149 -318.969764) (xy 355.249263 -318.994863)
			(xy 355.292417 -319.026285) (xy 355.330771 -319.063415) (xy 355.347524 -319.084198) (xy 355.35508 -319.092966)
			(xy 355.375843 -319.103146) (xy 355.387402 -319.103756) (xy 355.467666 -319.103756) (xy 355.479234 -319.103181)
			(xy 355.500006 -319.092991) (xy 355.507544 -319.084198) (xy 355.524297 -319.063415) (xy 355.562651 -319.026285)
			(xy 355.605805 -318.994863) (xy 355.652919 -318.969764) (xy 355.703071 -318.951478) (xy 355.755282 -318.940361)
			(xy 355.808534 -318.936631) (xy 355.861786 -318.940361) (xy 355.913997 -318.951478) (xy 355.964149 -318.969764)
			(xy 356.011263 -318.994863) (xy 356.054417 -319.026285) (xy 356.092771 -319.063415) (xy 356.109524 -319.084198)
			(xy 356.11708 -319.092966) (xy 356.137843 -319.103146) (xy 356.149402 -319.103756) (xy 356.229666 -319.103756)
			(xy 356.241234 -319.103181) (xy 356.262006 -319.092991) (xy 356.269544 -319.084198) (xy 356.286297 -319.063415)
			(xy 356.324651 -319.026285) (xy 356.367805 -318.994863) (xy 356.414919 -318.969764) (xy 356.465071 -318.951478)
			(xy 356.517282 -318.940361) (xy 356.570534 -318.936631) (xy 356.623786 -318.940361) (xy 356.675997 -318.951478)
			(xy 356.726149 -318.969764) (xy 356.773263 -318.994863) (xy 356.816417 -319.026285) (xy 356.854771 -319.063415)
			(xy 356.871524 -319.084198) (xy 356.87908 -319.092966) (xy 356.899843 -319.103146) (xy 356.911402 -319.103756)
			(xy 356.991666 -319.103756) (xy 357.003234 -319.103181) (xy 357.024006 -319.092991) (xy 357.031544 -319.084198)
			(xy 357.048297 -319.063415) (xy 357.086651 -319.026285) (xy 357.129805 -318.994863) (xy 357.176919 -318.969764)
			(xy 357.227071 -318.951478) (xy 357.279282 -318.940361) (xy 357.332534 -318.936631) (xy 357.385786 -318.940361)
			(xy 357.437997 -318.951478) (xy 357.488149 -318.969764) (xy 357.535263 -318.994863) (xy 357.578417 -319.026285)
			(xy 357.616771 -319.063415) (xy 357.633524 -319.084198) (xy 357.64108 -319.092966) (xy 357.661843 -319.103146)
			(xy 357.673402 -319.103756) (xy 357.753666 -319.103756) (xy 357.765234 -319.103181) (xy 357.786006 -319.092991)
			(xy 357.793544 -319.084198) (xy 357.810297 -319.063415) (xy 357.848651 -319.026285) (xy 357.891805 -318.994863)
			(xy 357.938919 -318.969764) (xy 357.989071 -318.951478) (xy 358.041282 -318.940361) (xy 358.094534 -318.936631)
			(xy 358.147786 -318.940361) (xy 358.199997 -318.951478) (xy 358.250149 -318.969764) (xy 358.297263 -318.994863)
			(xy 358.340417 -319.026285) (xy 358.378771 -319.063415) (xy 358.395524 -319.084198) (xy 358.40308 -319.092966)
			(xy 358.423843 -319.103146) (xy 358.435402 -319.103756) (xy 358.515666 -319.103756) (xy 358.527234 -319.103181)
			(xy 358.548006 -319.092991) (xy 358.555544 -319.084198) (xy 358.572297 -319.063415) (xy 358.610651 -319.026285)
			(xy 358.653805 -318.994863) (xy 358.700919 -318.969764) (xy 358.751071 -318.951478) (xy 358.803282 -318.940361)
			(xy 358.856534 -318.936631) (xy 358.909786 -318.940361) (xy 358.961997 -318.951478) (xy 359.012149 -318.969764)
			(xy 359.059263 -318.994863) (xy 359.102417 -319.026285) (xy 359.140771 -319.063415) (xy 359.157524 -319.084198)
			(xy 359.16508 -319.092966) (xy 359.185843 -319.103146) (xy 359.197402 -319.103756) (xy 359.277666 -319.103756)
			(xy 359.289234 -319.103181) (xy 359.310006 -319.092991) (xy 359.317544 -319.084198) (xy 359.334297 -319.063415)
			(xy 359.372651 -319.026285) (xy 359.415805 -318.994863) (xy 359.462919 -318.969764) (xy 359.513071 -318.951478)
			(xy 359.565282 -318.940361) (xy 359.618534 -318.936631) (xy 359.671786 -318.940361) (xy 359.723997 -318.951478)
			(xy 359.774149 -318.969764) (xy 359.821263 -318.994863) (xy 359.864417 -319.026285) (xy 359.902771 -319.063415)
			(xy 359.919524 -319.084198) (xy 359.92708 -319.092966) (xy 359.947843 -319.103146) (xy 359.959402 -319.103756)
			(xy 360.039666 -319.103756) (xy 360.051234 -319.103181) (xy 360.072006 -319.092991) (xy 360.079544 -319.084198)
			(xy 360.096297 -319.063415) (xy 360.134651 -319.026285) (xy 360.177805 -318.994863) (xy 360.224919 -318.969764)
			(xy 360.275071 -318.951478) (xy 360.327282 -318.940361) (xy 360.380534 -318.936631) (xy 360.433786 -318.940361)
			(xy 360.485997 -318.951478) (xy 360.536149 -318.969764) (xy 360.583263 -318.994863) (xy 360.626417 -319.026285)
			(xy 360.664771 -319.063415) (xy 360.681524 -319.084198) (xy 360.68908 -319.092966) (xy 360.709843 -319.103146)
			(xy 360.721402 -319.103756) (xy 360.801666 -319.103756) (xy 360.813234 -319.103181) (xy 360.834006 -319.092991)
			(xy 360.841544 -319.084198) (xy 360.85971 -319.061693) (xy 360.901735 -319.021959) (xy 360.949275 -318.989023)
			(xy 361.001241 -318.963638) (xy 361.056443 -318.946387) (xy 361.113617 -318.937664) (xy 361.142534 -318.937132)
			(xy 361.16979 -318.937523) (xy 361.223745 -318.945286) (xy 361.276047 -318.960648) (xy 361.32563 -318.983298)
			(xy 361.371485 -319.012773) (xy 361.412678 -319.048474) (xy 361.448371 -319.089675) (xy 361.477838 -319.135535)
			(xy 361.500478 -319.185123) (xy 361.51583 -319.237427) (xy 361.523582 -319.291384) (xy 361.524042 -319.31864)
			(xy 361.523502 -319.347556) (xy 361.514781 -319.404728) (xy 361.497528 -319.459927) (xy 361.472141 -319.511889)
			(xy 361.4392 -319.559423) (xy 361.399461 -319.60144) (xy 361.376976 -319.61963) (xy 361.368201 -319.627179)
			(xy 361.358026 -319.647948) (xy 361.357418 -319.659508) (xy 361.357418 -319.739772) (xy 361.357998 -319.751339)
			(xy 361.368185 -319.77211) (xy 361.376976 -319.77965) (xy 361.399431 -319.797875) (xy 361.439169 -319.839887)
			(xy 361.472112 -319.887415) (xy 361.497505 -319.939369) (xy 361.514768 -319.994561) (xy 361.523503 -320.051726)
			(xy 361.524042 -320.08064) (xy 361.52356 -320.107891) (xy 361.515798 -320.161837) (xy 361.50044 -320.214129)
			(xy 361.477797 -320.263705) (xy 361.448329 -320.309553) (xy 361.412638 -320.350742) (xy 361.371448 -320.386433)
			(xy 361.325599 -320.4159) (xy 361.276024 -320.438542) (xy 361.223731 -320.4539) (xy 361.169785 -320.46166)
			(xy 361.142534 -320.462148) (xy 361.113617 -320.461625) (xy 361.056445 -320.4529) (xy 361.001246 -320.435644)
			(xy 360.949283 -320.410253) (xy 360.901749 -320.37731) (xy 360.859733 -320.337568) (xy 360.841544 -320.315082)
			(xy 360.833962 -320.306341) (xy 360.813218 -320.296147) (xy 360.801666 -320.295524) (xy 360.721402 -320.295524)
			(xy 360.709833 -320.296087) (xy 360.689062 -320.306286) (xy 360.681524 -320.315082) (xy 360.664771 -320.335865)
			(xy 360.626417 -320.372995) (xy 360.583263 -320.404417) (xy 360.536149 -320.429516) (xy 360.485997 -320.447802)
			(xy 360.433786 -320.458919) (xy 360.380534 -320.462649) (xy 360.327282 -320.458919) (xy 360.275071 -320.447802)
			(xy 360.224919 -320.429516) (xy 360.177805 -320.404417) (xy 360.134651 -320.372995) (xy 360.096297 -320.335865)
			(xy 360.079544 -320.315082) (xy 360.071962 -320.306341) (xy 360.051218 -320.296147) (xy 360.039666 -320.295524)
			(xy 359.959402 -320.295524) (xy 359.947833 -320.296087) (xy 359.927062 -320.306286) (xy 359.919524 -320.315082)
			(xy 359.902771 -320.335865) (xy 359.864417 -320.372995) (xy 359.821263 -320.404417) (xy 359.774149 -320.429516)
			(xy 359.723997 -320.447802) (xy 359.671786 -320.458919) (xy 359.618534 -320.462649) (xy 359.565282 -320.458919)
			(xy 359.513071 -320.447802) (xy 359.462919 -320.429516) (xy 359.415805 -320.404417) (xy 359.372651 -320.372995)
			(xy 359.334297 -320.335865) (xy 359.317544 -320.315082) (xy 359.309962 -320.306341) (xy 359.289218 -320.296147)
			(xy 359.277666 -320.295524) (xy 359.197402 -320.295524) (xy 359.185833 -320.296087) (xy 359.165062 -320.306286)
			(xy 359.157524 -320.315082) (xy 359.140771 -320.335865) (xy 359.102417 -320.372995) (xy 359.059263 -320.404417)
			(xy 359.012149 -320.429516) (xy 358.961997 -320.447802) (xy 358.909786 -320.458919) (xy 358.856534 -320.462649)
			(xy 358.803282 -320.458919) (xy 358.751071 -320.447802) (xy 358.700919 -320.429516) (xy 358.653805 -320.404417)
			(xy 358.610651 -320.372995) (xy 358.572297 -320.335865) (xy 358.555544 -320.315082) (xy 358.547962 -320.306341)
			(xy 358.527218 -320.296147) (xy 358.515666 -320.295524) (xy 358.435402 -320.295524) (xy 358.423833 -320.296087)
			(xy 358.403062 -320.306286) (xy 358.395524 -320.315082) (xy 358.378771 -320.335865) (xy 358.340417 -320.372995)
			(xy 358.297263 -320.404417) (xy 358.250149 -320.429516) (xy 358.199997 -320.447802) (xy 358.147786 -320.458919)
			(xy 358.094534 -320.462649) (xy 358.041282 -320.458919) (xy 357.989071 -320.447802) (xy 357.938919 -320.429516)
			(xy 357.891805 -320.404417) (xy 357.848651 -320.372995) (xy 357.810297 -320.335865) (xy 357.793544 -320.315082)
			(xy 357.785962 -320.306341) (xy 357.765218 -320.296147) (xy 357.753666 -320.295524) (xy 357.673402 -320.295524)
			(xy 357.661833 -320.296087) (xy 357.641062 -320.306286) (xy 357.633524 -320.315082) (xy 357.616771 -320.335865)
			(xy 357.578417 -320.372995) (xy 357.535263 -320.404417) (xy 357.488149 -320.429516) (xy 357.437997 -320.447802)
			(xy 357.385786 -320.458919) (xy 357.332534 -320.462649) (xy 357.279282 -320.458919) (xy 357.227071 -320.447802)
			(xy 357.176919 -320.429516) (xy 357.129805 -320.404417) (xy 357.086651 -320.372995) (xy 357.048297 -320.335865)
			(xy 357.031544 -320.315082) (xy 357.023962 -320.306341) (xy 357.003218 -320.296147) (xy 356.991666 -320.295524)
			(xy 356.911402 -320.295524) (xy 356.899833 -320.296087) (xy 356.879062 -320.306286) (xy 356.871524 -320.315082)
			(xy 356.854771 -320.335865) (xy 356.816417 -320.372995) (xy 356.773263 -320.404417) (xy 356.726149 -320.429516)
			(xy 356.675997 -320.447802) (xy 356.623786 -320.458919) (xy 356.570534 -320.462649) (xy 356.517282 -320.458919)
			(xy 356.465071 -320.447802) (xy 356.414919 -320.429516) (xy 356.367805 -320.404417) (xy 356.324651 -320.372995)
			(xy 356.286297 -320.335865) (xy 356.269544 -320.315082) (xy 356.261962 -320.306341) (xy 356.241218 -320.296147)
			(xy 356.229666 -320.295524) (xy 356.149402 -320.295524) (xy 356.137833 -320.296087) (xy 356.117062 -320.306286)
			(xy 356.109524 -320.315082) (xy 356.092771 -320.335865) (xy 356.054417 -320.372995) (xy 356.011263 -320.404417)
			(xy 355.964149 -320.429516) (xy 355.913997 -320.447802) (xy 355.861786 -320.458919) (xy 355.808534 -320.462649)
			(xy 355.755282 -320.458919) (xy 355.703071 -320.447802) (xy 355.652919 -320.429516) (xy 355.605805 -320.404417)
			(xy 355.562651 -320.372995) (xy 355.524297 -320.335865) (xy 355.507544 -320.315082) (xy 355.499962 -320.306341)
			(xy 355.479218 -320.296147) (xy 355.467666 -320.295524) (xy 355.387402 -320.295524) (xy 355.375833 -320.296087)
			(xy 355.355062 -320.306286) (xy 355.347524 -320.315082) (xy 355.330771 -320.335865) (xy 355.292417 -320.372995)
			(xy 355.249263 -320.404417) (xy 355.202149 -320.429516) (xy 355.151997 -320.447802) (xy 355.099786 -320.458919)
			(xy 355.046534 -320.462649) (xy 354.993282 -320.458919) (xy 354.941071 -320.447802) (xy 354.890919 -320.429516)
			(xy 354.843805 -320.404417) (xy 354.800651 -320.372995) (xy 354.762297 -320.335865) (xy 354.745544 -320.315082)
			(xy 354.737962 -320.306341) (xy 354.717218 -320.296147) (xy 354.705666 -320.295524) (xy 354.625402 -320.295524)
			(xy 354.613833 -320.296087) (xy 354.593062 -320.306286) (xy 354.585524 -320.315082) (xy 354.568771 -320.335865)
			(xy 354.530417 -320.372995) (xy 354.487263 -320.404417) (xy 354.440149 -320.429516) (xy 354.389997 -320.447802)
			(xy 354.337786 -320.458919) (xy 354.284534 -320.462649) (xy 354.231282 -320.458919) (xy 354.179071 -320.447802)
			(xy 354.128919 -320.429516) (xy 354.081805 -320.404417) (xy 354.038651 -320.372995) (xy 354.000297 -320.335865)
			(xy 353.983544 -320.315082) (xy 353.975962 -320.306341) (xy 353.955218 -320.296147) (xy 353.943666 -320.295524)
			(xy 353.863402 -320.295524) (xy 353.851833 -320.296087) (xy 353.831062 -320.306286) (xy 353.823524 -320.315082)
			(xy 353.806771 -320.335865) (xy 353.768417 -320.372995) (xy 353.725263 -320.404417) (xy 353.678149 -320.429516)
			(xy 353.627997 -320.447802) (xy 353.575786 -320.458919) (xy 353.522534 -320.462649) (xy 353.469282 -320.458919)
			(xy 353.417071 -320.447802) (xy 353.366919 -320.429516) (xy 353.319805 -320.404417) (xy 353.276651 -320.372995)
			(xy 353.238297 -320.335865) (xy 353.221544 -320.315082) (xy 353.213962 -320.306341) (xy 353.193218 -320.296147)
			(xy 353.181666 -320.295524) (xy 353.101402 -320.295524) (xy 353.089833 -320.296087) (xy 353.069062 -320.306286)
			(xy 353.061524 -320.315082) (xy 353.044771 -320.335865) (xy 353.006417 -320.372995) (xy 352.963263 -320.404417)
			(xy 352.916149 -320.429516) (xy 352.865997 -320.447802) (xy 352.813786 -320.458919) (xy 352.760534 -320.462649)
			(xy 352.707282 -320.458919) (xy 352.655071 -320.447802) (xy 352.604919 -320.429516) (xy 352.557805 -320.404417)
			(xy 352.514651 -320.372995) (xy 352.476297 -320.335865) (xy 352.459544 -320.315082) (xy 352.451962 -320.306341)
			(xy 352.431218 -320.296147) (xy 352.419666 -320.295524) (xy 352.339402 -320.295524) (xy 352.327833 -320.296087)
			(xy 352.307062 -320.306286) (xy 352.299524 -320.315082) (xy 352.281315 -320.33755) (xy 352.239299 -320.377287)
			(xy 352.191768 -320.410229) (xy 352.139811 -320.43562) (xy 352.084616 -320.452879) (xy 352.027449 -320.461611)
			(xy 351.998534 -320.462148) (xy 351.971285 -320.46159) (xy 351.917342 -320.453839) (xy 351.865051 -320.438491)
			(xy 351.815477 -320.415856) (xy 351.769629 -320.386397) (xy 351.728439 -320.350713) (xy 351.692747 -320.309531)
			(xy 351.663279 -320.263688) (xy 351.640635 -320.214118) (xy 351.625276 -320.16183) (xy 351.617515 -320.107888)
			(xy 351.617026 -320.08064) (xy 347.568012 -320.08064) (xy 347.567559 -320.107892) (xy 347.559798 -320.161841)
			(xy 347.544438 -320.214136) (xy 347.521792 -320.263713) (xy 347.492322 -320.309563) (xy 347.456627 -320.350753)
			(xy 347.415434 -320.386444) (xy 347.369581 -320.415909) (xy 347.320002 -320.43855) (xy 347.267706 -320.453905)
			(xy 347.213756 -320.461662) (xy 347.186504 -320.462148) (xy 347.157586 -320.461646) (xy 347.100413 -320.452917)
			(xy 347.045213 -320.435657) (xy 346.993251 -320.410262) (xy 346.945718 -320.377315) (xy 346.903703 -320.33757)
			(xy 346.885514 -320.315082) (xy 346.877945 -320.306328) (xy 346.857192 -320.296141) (xy 346.845636 -320.295524)
			(xy 346.765372 -320.295524) (xy 346.753808 -320.296127) (xy 346.733036 -320.306298) (xy 346.725494 -320.315082)
			(xy 346.708741 -320.335865) (xy 346.670387 -320.372995) (xy 346.627233 -320.404417) (xy 346.580119 -320.429516)
			(xy 346.529967 -320.447802) (xy 346.477756 -320.458919) (xy 346.424504 -320.462649) (xy 346.371252 -320.458919)
			(xy 346.319041 -320.447802) (xy 346.268889 -320.429516) (xy 346.221775 -320.404417) (xy 346.178621 -320.372995)
			(xy 346.140267 -320.335865) (xy 346.123514 -320.315082) (xy 346.115945 -320.306328) (xy 346.095192 -320.296141)
			(xy 346.083636 -320.295524) (xy 346.003372 -320.295524) (xy 345.991808 -320.296127) (xy 345.971036 -320.306298)
			(xy 345.963494 -320.315082) (xy 345.946741 -320.335865) (xy 345.908387 -320.372995) (xy 345.865233 -320.404417)
			(xy 345.818119 -320.429516) (xy 345.767967 -320.447802) (xy 345.715756 -320.458919) (xy 345.662504 -320.462649)
			(xy 345.609252 -320.458919) (xy 345.557041 -320.447802) (xy 345.506889 -320.429516) (xy 345.459775 -320.404417)
			(xy 345.416621 -320.372995) (xy 345.378267 -320.335865) (xy 345.361514 -320.315082) (xy 345.353945 -320.306328)
			(xy 345.333192 -320.296141) (xy 345.321636 -320.295524) (xy 345.241372 -320.295524) (xy 345.229808 -320.296127)
			(xy 345.209036 -320.306298) (xy 345.201494 -320.315082) (xy 345.184741 -320.335865) (xy 345.146387 -320.372995)
			(xy 345.103233 -320.404417) (xy 345.056119 -320.429516) (xy 345.005967 -320.447802) (xy 344.953756 -320.458919)
			(xy 344.900504 -320.462649) (xy 344.847252 -320.458919) (xy 344.795041 -320.447802) (xy 344.744889 -320.429516)
			(xy 344.697775 -320.404417) (xy 344.654621 -320.372995) (xy 344.616267 -320.335865) (xy 344.599514 -320.315082)
			(xy 344.591945 -320.306328) (xy 344.571192 -320.296141) (xy 344.559636 -320.295524) (xy 344.479372 -320.295524)
			(xy 344.467808 -320.296127) (xy 344.447036 -320.306298) (xy 344.439494 -320.315082) (xy 344.422741 -320.335865)
			(xy 344.384387 -320.372995) (xy 344.341233 -320.404417) (xy 344.294119 -320.429516) (xy 344.243967 -320.447802)
			(xy 344.191756 -320.458919) (xy 344.138504 -320.462649) (xy 344.085252 -320.458919) (xy 344.033041 -320.447802)
			(xy 343.982889 -320.429516) (xy 343.935775 -320.404417) (xy 343.892621 -320.372995) (xy 343.854267 -320.335865)
			(xy 343.837514 -320.315082) (xy 343.829945 -320.306328) (xy 343.809192 -320.296141) (xy 343.797636 -320.295524)
			(xy 343.717372 -320.295524) (xy 343.705808 -320.296127) (xy 343.685036 -320.306298) (xy 343.677494 -320.315082)
			(xy 343.660741 -320.335865) (xy 343.622387 -320.372995) (xy 343.579233 -320.404417) (xy 343.532119 -320.429516)
			(xy 343.481967 -320.447802) (xy 343.429756 -320.458919) (xy 343.376504 -320.462649) (xy 343.323252 -320.458919)
			(xy 343.271041 -320.447802) (xy 343.220889 -320.429516) (xy 343.173775 -320.404417) (xy 343.130621 -320.372995)
			(xy 343.092267 -320.335865) (xy 343.075514 -320.315082) (xy 343.067945 -320.306328) (xy 343.047192 -320.296141)
			(xy 343.035636 -320.295524) (xy 342.955372 -320.295524) (xy 342.943808 -320.296127) (xy 342.923036 -320.306298)
			(xy 342.915494 -320.315082) (xy 342.898741 -320.335865) (xy 342.860387 -320.372995) (xy 342.817233 -320.404417)
			(xy 342.770119 -320.429516) (xy 342.719967 -320.447802) (xy 342.667756 -320.458919) (xy 342.614504 -320.462649)
			(xy 342.561252 -320.458919) (xy 342.509041 -320.447802) (xy 342.458889 -320.429516) (xy 342.411775 -320.404417)
			(xy 342.368621 -320.372995) (xy 342.330267 -320.335865) (xy 342.313514 -320.315082) (xy 342.305945 -320.306328)
			(xy 342.285192 -320.296141) (xy 342.273636 -320.295524) (xy 342.193372 -320.295524) (xy 342.181808 -320.296127)
			(xy 342.161036 -320.306298) (xy 342.153494 -320.315082) (xy 342.136741 -320.335865) (xy 342.098387 -320.372995)
			(xy 342.055233 -320.404417) (xy 342.008119 -320.429516) (xy 341.957967 -320.447802) (xy 341.905756 -320.458919)
			(xy 341.852504 -320.462649) (xy 341.799252 -320.458919) (xy 341.747041 -320.447802) (xy 341.696889 -320.429516)
			(xy 341.649775 -320.404417) (xy 341.606621 -320.372995) (xy 341.568267 -320.335865) (xy 341.551514 -320.315082)
			(xy 341.543945 -320.306328) (xy 341.523192 -320.296141) (xy 341.511636 -320.295524) (xy 341.431372 -320.295524)
			(xy 341.419808 -320.296127) (xy 341.399036 -320.306298) (xy 341.391494 -320.315082) (xy 341.374741 -320.335865)
			(xy 341.336387 -320.372995) (xy 341.293233 -320.404417) (xy 341.246119 -320.429516) (xy 341.195967 -320.447802)
			(xy 341.143756 -320.458919) (xy 341.090504 -320.462649) (xy 341.037252 -320.458919) (xy 340.985041 -320.447802)
			(xy 340.934889 -320.429516) (xy 340.887775 -320.404417) (xy 340.844621 -320.372995) (xy 340.806267 -320.335865)
			(xy 340.789514 -320.315082) (xy 340.781945 -320.306328) (xy 340.761192 -320.296141) (xy 340.749636 -320.295524)
			(xy 340.669372 -320.295524) (xy 340.657808 -320.296127) (xy 340.637036 -320.306298) (xy 340.629494 -320.315082)
			(xy 340.612741 -320.335865) (xy 340.574387 -320.372995) (xy 340.531233 -320.404417) (xy 340.484119 -320.429516)
			(xy 340.433967 -320.447802) (xy 340.381756 -320.458919) (xy 340.328504 -320.462649) (xy 340.275252 -320.458919)
			(xy 340.223041 -320.447802) (xy 340.172889 -320.429516) (xy 340.125775 -320.404417) (xy 340.082621 -320.372995)
			(xy 340.044267 -320.335865) (xy 340.027514 -320.315082) (xy 340.019945 -320.306328) (xy 339.999192 -320.296141)
			(xy 339.987636 -320.295524) (xy 339.907372 -320.295524) (xy 339.895808 -320.296127) (xy 339.875036 -320.306298)
			(xy 339.867494 -320.315082) (xy 339.850741 -320.335865) (xy 339.812387 -320.372995) (xy 339.769233 -320.404417)
			(xy 339.722119 -320.429516) (xy 339.671967 -320.447802) (xy 339.619756 -320.458919) (xy 339.566504 -320.462649)
			(xy 339.513252 -320.458919) (xy 339.461041 -320.447802) (xy 339.410889 -320.429516) (xy 339.363775 -320.404417)
			(xy 339.320621 -320.372995) (xy 339.282267 -320.335865) (xy 339.265514 -320.315082) (xy 339.257945 -320.306328)
			(xy 339.237192 -320.296141) (xy 339.225636 -320.295524) (xy 339.145372 -320.295524) (xy 339.133808 -320.296127)
			(xy 339.113036 -320.306298) (xy 339.105494 -320.315082) (xy 339.087302 -320.337565) (xy 339.045283 -320.377301)
			(xy 338.997748 -320.41024) (xy 338.945787 -320.435629) (xy 338.89059 -320.452885) (xy 338.83342 -320.461614)
			(xy 338.804504 -320.462148) (xy 338.777255 -320.461619) (xy 338.723311 -320.453864) (xy 338.671019 -320.438511)
			(xy 338.621445 -320.415873) (xy 338.575596 -320.386411) (xy 338.534407 -320.350724) (xy 338.498715 -320.309539)
			(xy 338.469248 -320.263694) (xy 338.446604 -320.214122) (xy 338.431246 -320.161832) (xy 338.423485 -320.107889)
			(xy 338.422996 -320.08064) (xy 330.386182 -320.08064) (xy 330.386182 -325.37781) (xy 330.386606 -325.38788)
			(xy 330.394321 -325.406483) (xy 330.401168 -325.413878) (xy 330.996838 -326.009548) (xy 331.878208 -326.009548)
			(xy 331.878208 -325.955052) (xy 331.885963 -325.90111) (xy 331.901316 -325.848822) (xy 331.923954 -325.79925)
			(xy 331.953416 -325.753404) (xy 331.989102 -325.712218) (xy 332.030286 -325.676529) (xy 332.07613 -325.647065)
			(xy 332.125701 -325.624424) (xy 332.177989 -325.609068) (xy 332.23193 -325.60131) (xy 332.259178 -325.600822)
			(xy 332.29036 -325.601455) (xy 332.35189 -325.611625) (xy 332.410952 -325.63165) (xy 332.438756 -325.64578)
			(xy 332.448662 -325.65086) (xy 332.469744 -325.652384) (xy 332.561946 -325.618348) (xy 332.577186 -325.603616)
			(xy 332.58125 -325.593202) (xy 332.592142 -325.566797) (xy 332.620668 -325.517315) (xy 332.656255 -325.47264)
			(xy 332.698105 -325.43377) (xy 332.745282 -325.401575) (xy 332.796734 -325.376775) (xy 332.851307 -325.359924)
			(xy 332.907784 -325.351398) (xy 332.936342 -325.350886) (xy 332.963591 -325.351387) (xy 333.017533 -325.359148)
			(xy 333.069822 -325.374506) (xy 333.119393 -325.39715) (xy 333.165238 -325.426617) (xy 333.206422 -325.462308)
			(xy 333.242109 -325.503496) (xy 333.271571 -325.549344) (xy 333.294208 -325.598917) (xy 333.309561 -325.651208)
			(xy 333.317316 -325.705151) (xy 333.317316 -325.759649) (xy 333.309561 -325.813592) (xy 333.294208 -325.865883)
			(xy 333.271571 -325.915456) (xy 333.242109 -325.961304) (xy 333.206422 -326.002492) (xy 333.165238 -326.038183)
			(xy 333.119393 -326.06765) (xy 333.069822 -326.090294) (xy 333.017533 -326.105652) (xy 332.963591 -326.113413)
			(xy 332.936342 -326.113902) (xy 332.905161 -326.113259) (xy 332.843631 -326.103093) (xy 332.784569 -326.083072)
			(xy 332.756764 -326.068944) (xy 332.746858 -326.063864) (xy 332.725776 -326.06234) (xy 332.633574 -326.096376)
			(xy 332.618334 -326.111108) (xy 332.61427 -326.121522) (xy 332.603375 -326.147925) (xy 332.574847 -326.197406)
			(xy 332.539261 -326.24208) (xy 332.497411 -326.280949) (xy 332.450234 -326.313144) (xy 332.398784 -326.337945)
			(xy 332.344211 -326.354797) (xy 332.287736 -326.363325) (xy 332.259178 -326.363838) (xy 332.23193 -326.36329)
			(xy 332.177989 -326.355532) (xy 332.125701 -326.340176) (xy 332.07613 -326.317535) (xy 332.030286 -326.288071)
			(xy 331.989102 -326.252382) (xy 331.953416 -326.211196) (xy 331.923954 -326.16535) (xy 331.901316 -326.115778)
			(xy 331.885963 -326.06349) (xy 331.878208 -326.009548) (xy 330.996838 -326.009548) (xy 332.998064 -328.010774)
			(xy 334.46288 -328.010774) (xy 334.466951 -327.955152) (xy 334.479077 -327.900715) (xy 334.499 -327.848624)
			(xy 334.526296 -327.799989) (xy 334.560382 -327.755846) (xy 334.600531 -327.717137) (xy 334.645889 -327.684686)
			(xy 334.695489 -327.659185) (xy 334.748273 -327.641178) (xy 334.803116 -327.631048) (xy 334.85885 -327.629011)
			(xy 334.914287 -327.635111) (xy 334.968244 -327.649217) (xy 335.019573 -327.671029) (xy 335.067179 -327.700083)
			(xy 335.110047 -327.735758) (xy 335.147264 -327.777295) (xy 335.178037 -327.823808) (xy 335.201709 -327.874305)
			(xy 335.217777 -327.927712) (xy 335.225897 -327.982888) (xy 335.226406 -328.010774) (xy 335.225897 -328.03866)
			(xy 335.217777 -328.093836) (xy 335.201709 -328.147243) (xy 335.178037 -328.19774) (xy 335.147264 -328.244253)
			(xy 335.110047 -328.28579) (xy 335.067179 -328.321465) (xy 335.019573 -328.350519) (xy 334.968244 -328.372331)
			(xy 334.914287 -328.386437) (xy 334.85885 -328.392537) (xy 334.803116 -328.3905) (xy 334.748273 -328.38037)
			(xy 334.695489 -328.362363) (xy 334.645889 -328.336862) (xy 334.600531 -328.304411) (xy 334.560382 -328.265702)
			(xy 334.526296 -328.221559) (xy 334.499 -328.172924) (xy 334.479077 -328.120833) (xy 334.466951 -328.066396)
			(xy 334.46288 -328.010774) (xy 332.998064 -328.010774) (xy 334.014064 -329.026774) (xy 334.46288 -329.026774)
			(xy 334.466951 -328.971152) (xy 334.479077 -328.916715) (xy 334.499 -328.864624) (xy 334.526296 -328.815989)
			(xy 334.560382 -328.771846) (xy 334.600531 -328.733137) (xy 334.645889 -328.700686) (xy 334.695489 -328.675185)
			(xy 334.748273 -328.657178) (xy 334.803116 -328.647048) (xy 334.85885 -328.645011) (xy 334.914287 -328.651111)
			(xy 334.968244 -328.665217) (xy 335.019573 -328.687029) (xy 335.067179 -328.716083) (xy 335.110047 -328.751758)
			(xy 335.147264 -328.793295) (xy 335.178037 -328.839808) (xy 335.201709 -328.890305) (xy 335.217777 -328.943712)
			(xy 335.225897 -328.998888) (xy 335.226406 -329.026774) (xy 335.225897 -329.05466) (xy 335.217777 -329.109836)
			(xy 335.201709 -329.163243) (xy 335.178037 -329.21374) (xy 335.147264 -329.260253) (xy 335.110047 -329.30179)
			(xy 335.067179 -329.337465) (xy 335.019573 -329.366519) (xy 334.968244 -329.388331) (xy 334.914287 -329.402437)
			(xy 334.85885 -329.408537) (xy 334.803116 -329.4065) (xy 334.748273 -329.39637) (xy 334.695489 -329.378363)
			(xy 334.645889 -329.352862) (xy 334.600531 -329.320411) (xy 334.560382 -329.281702) (xy 334.526296 -329.237559)
			(xy 334.499 -329.188924) (xy 334.479077 -329.136833) (xy 334.466951 -329.082396) (xy 334.46288 -329.026774)
			(xy 334.014064 -329.026774) (xy 335.984596 -330.997306) (xy 351.42119 -330.997306) (xy 351.425261 -330.941684)
			(xy 351.437387 -330.887247) (xy 351.45731 -330.835156) (xy 351.484606 -330.786521) (xy 351.518692 -330.742378)
			(xy 351.558841 -330.703669) (xy 351.604199 -330.671218) (xy 351.653799 -330.645717) (xy 351.706583 -330.62771)
			(xy 351.761426 -330.61758) (xy 351.81716 -330.615543) (xy 351.872597 -330.621643) (xy 351.926554 -330.635749)
			(xy 351.977883 -330.657561) (xy 352.025489 -330.686615) (xy 352.068357 -330.72229) (xy 352.105574 -330.763827)
			(xy 352.136347 -330.81034) (xy 352.160019 -330.860837) (xy 352.176087 -330.914244) (xy 352.184207 -330.96942)
			(xy 352.184716 -330.997306) (xy 352.43719 -330.997306) (xy 352.441261 -330.941684) (xy 352.453387 -330.887247)
			(xy 352.47331 -330.835156) (xy 352.500606 -330.786521) (xy 352.534692 -330.742378) (xy 352.574841 -330.703669)
			(xy 352.620199 -330.671218) (xy 352.669799 -330.645717) (xy 352.722583 -330.62771) (xy 352.777426 -330.61758)
			(xy 352.83316 -330.615543) (xy 352.888597 -330.621643) (xy 352.942554 -330.635749) (xy 352.950595 -330.639166)
			(xy 359.716576 -330.639166) (xy 359.720647 -330.583544) (xy 359.732773 -330.529107) (xy 359.752696 -330.477016)
			(xy 359.779992 -330.428381) (xy 359.814078 -330.384238) (xy 359.854227 -330.345529) (xy 359.899585 -330.313078)
			(xy 359.949185 -330.287577) (xy 360.001969 -330.26957) (xy 360.056812 -330.25944) (xy 360.112546 -330.257403)
			(xy 360.167983 -330.263503) (xy 360.22194 -330.277609) (xy 360.273269 -330.299421) (xy 360.320875 -330.328475)
			(xy 360.363743 -330.36415) (xy 360.40096 -330.405687) (xy 360.431733 -330.4522) (xy 360.455405 -330.502697)
			(xy 360.471473 -330.556104) (xy 360.479593 -330.61128) (xy 360.480023 -330.634848) (xy 360.612434 -330.634848)
			(xy 360.616505 -330.579226) (xy 360.628631 -330.524789) (xy 360.648554 -330.472698) (xy 360.67585 -330.424063)
			(xy 360.709936 -330.37992) (xy 360.750085 -330.341211) (xy 360.795443 -330.30876) (xy 360.845043 -330.283259)
			(xy 360.897827 -330.265252) (xy 360.95267 -330.255122) (xy 361.008404 -330.253085) (xy 361.063841 -330.259185)
			(xy 361.117798 -330.273291) (xy 361.169127 -330.295103) (xy 361.216733 -330.324157) (xy 361.259601 -330.359832)
			(xy 361.296818 -330.401369) (xy 361.327591 -330.447882) (xy 361.351263 -330.498379) (xy 361.367331 -330.551786)
			(xy 361.375451 -330.606962) (xy 361.375953 -330.634457) (xy 361.500817 -330.634457) (xy 361.500817 -330.579943)
			(xy 361.508575 -330.525984) (xy 361.523934 -330.473679) (xy 361.546581 -330.424092) (xy 361.576055 -330.378233)
			(xy 361.611755 -330.337035) (xy 361.652955 -330.301338) (xy 361.698817 -330.271868) (xy 361.748405 -330.249225)
			(xy 361.800712 -330.23387) (xy 361.854671 -330.226115) (xy 361.881928 -330.225654) (xy 361.907882 -330.226066)
			(xy 361.959312 -330.233101) (xy 362.00931 -330.24705) (xy 362.056954 -330.267655) (xy 362.10136 -330.294536)
			(xy 362.141708 -330.327193) (xy 362.17725 -330.365025) (xy 362.20733 -330.407329) (xy 362.219748 -330.430124)
			(xy 362.226098 -330.442062) (xy 362.248704 -330.45654) (xy 362.363512 -330.462128) (xy 362.387388 -330.449682)
			(xy 362.394754 -330.438506) (xy 362.409906 -330.416079) (xy 362.445615 -330.375404) (xy 362.48671 -330.340181)
			(xy 362.532369 -330.311115) (xy 362.581676 -330.288789) (xy 362.633641 -330.273651) (xy 362.687223 -330.266005)
			(xy 362.714286 -330.265532) (xy 362.743578 -330.266126) (xy 362.801473 -330.275085) (xy 362.857321 -330.292781)
			(xy 362.909811 -330.318797) (xy 362.957713 -330.352524) (xy 362.999902 -330.39317) (xy 363.01807 -330.416154)
			(xy 363.025436 -330.42606) (xy 363.047026 -330.436474) (xy 363.153706 -330.434442) (xy 363.175042 -330.423266)
			(xy 363.182154 -330.413106) (xy 363.197551 -330.391988) (xy 363.233128 -330.353707) (xy 363.273599 -330.320643)
			(xy 363.318205 -330.293413) (xy 363.366111 -330.272529) (xy 363.41642 -330.258381) (xy 363.46819 -330.251235)
			(xy 363.49432 -330.2508) (xy 363.521571 -330.251271) (xy 363.575518 -330.25903) (xy 363.627811 -330.274387)
			(xy 363.677387 -330.29703) (xy 363.723236 -330.326498) (xy 363.764424 -330.36219) (xy 363.800114 -330.40338)
			(xy 363.82958 -330.449231) (xy 363.85222 -330.498808) (xy 363.867574 -330.551102) (xy 363.87533 -330.605049)
			(xy 363.87533 -330.659551) (xy 363.867574 -330.713498) (xy 363.85222 -330.765792) (xy 363.829579 -330.815369)
			(xy 363.800114 -330.86122) (xy 363.764424 -330.90241) (xy 363.723236 -330.938102) (xy 363.677387 -330.96757)
			(xy 363.627811 -330.990213) (xy 363.575518 -331.00557) (xy 363.521571 -331.013329) (xy 363.49432 -331.013816)
			(xy 363.465025 -331.01331) (xy 363.407125 -331.004335) (xy 363.351274 -330.986624) (xy 363.298784 -330.960591)
			(xy 363.250885 -330.926847) (xy 363.2087 -330.886185) (xy 363.190536 -330.863194) (xy 363.18317 -330.853288)
			(xy 363.16158 -330.842874) (xy 363.0549 -330.844906) (xy 363.033564 -330.856082) (xy 363.026452 -330.866242)
			(xy 363.011066 -330.887368) (xy 362.975485 -330.925646) (xy 362.935012 -330.958709) (xy 362.890404 -330.985936)
			(xy 362.842497 -331.006819) (xy 362.792187 -331.020966) (xy 362.740416 -331.028113) (xy 362.714286 -331.028548)
			(xy 362.688332 -331.028123) (xy 362.636903 -331.02109) (xy 362.586905 -331.007143) (xy 362.539262 -330.98654)
			(xy 362.494855 -330.959661) (xy 362.454507 -330.927005) (xy 362.418965 -330.889175) (xy 362.388885 -330.846872)
			(xy 362.376466 -330.824078) (xy 362.370116 -330.81214) (xy 362.34751 -330.797662) (xy 362.232702 -330.792074)
			(xy 362.208826 -330.80452) (xy 362.20146 -330.815696) (xy 362.186267 -330.838095) (xy 362.150569 -330.878775)
			(xy 362.109482 -330.914003) (xy 362.06383 -330.943074) (xy 362.014529 -330.965405) (xy 361.962568 -330.980547)
			(xy 361.908989 -330.988196) (xy 361.881928 -330.98867) (xy 361.854671 -330.988285) (xy 361.800712 -330.98053)
			(xy 361.748405 -330.965175) (xy 361.698817 -330.942532) (xy 361.652955 -330.913062) (xy 361.611755 -330.877365)
			(xy 361.576055 -330.836167) (xy 361.546581 -330.790308) (xy 361.523934 -330.740721) (xy 361.508576 -330.688416)
			(xy 361.500817 -330.634457) (xy 361.375953 -330.634457) (xy 361.37596 -330.634848) (xy 361.375451 -330.662734)
			(xy 361.367331 -330.71791) (xy 361.351263 -330.771317) (xy 361.327591 -330.821814) (xy 361.296818 -330.868327)
			(xy 361.259601 -330.909864) (xy 361.216733 -330.945539) (xy 361.169127 -330.974593) (xy 361.117798 -330.996405)
			(xy 361.063841 -331.010511) (xy 361.008404 -331.016611) (xy 360.95267 -331.014574) (xy 360.897827 -331.004444)
			(xy 360.845043 -330.986437) (xy 360.795443 -330.960936) (xy 360.750085 -330.928485) (xy 360.709936 -330.889776)
			(xy 360.67585 -330.845633) (xy 360.648554 -330.796998) (xy 360.628631 -330.744907) (xy 360.616505 -330.69047)
			(xy 360.612434 -330.634848) (xy 360.480023 -330.634848) (xy 360.480102 -330.639166) (xy 360.479593 -330.667052)
			(xy 360.471473 -330.722228) (xy 360.455405 -330.775635) (xy 360.431733 -330.826132) (xy 360.40096 -330.872645)
			(xy 360.363743 -330.914182) (xy 360.320875 -330.949857) (xy 360.273269 -330.978911) (xy 360.22194 -331.000723)
			(xy 360.167983 -331.014829) (xy 360.112546 -331.020929) (xy 360.056812 -331.018892) (xy 360.001969 -331.008762)
			(xy 359.949185 -330.990755) (xy 359.899585 -330.965254) (xy 359.854227 -330.932803) (xy 359.814078 -330.894094)
			(xy 359.779992 -330.849951) (xy 359.752696 -330.801316) (xy 359.732773 -330.749225) (xy 359.720647 -330.694788)
			(xy 359.716576 -330.639166) (xy 352.950595 -330.639166) (xy 352.993883 -330.657561) (xy 353.041489 -330.686615)
			(xy 353.084357 -330.72229) (xy 353.121574 -330.763827) (xy 353.152347 -330.81034) (xy 353.176019 -330.860837)
			(xy 353.192087 -330.914244) (xy 353.200207 -330.96942) (xy 353.200716 -330.997306) (xy 353.200207 -331.025192)
			(xy 353.192087 -331.080368) (xy 353.176019 -331.133775) (xy 353.152347 -331.184272) (xy 353.121574 -331.230785)
			(xy 353.084357 -331.272322) (xy 353.041489 -331.307997) (xy 352.993883 -331.337051) (xy 352.942554 -331.358863)
			(xy 352.888597 -331.372969) (xy 352.83316 -331.379069) (xy 352.777426 -331.377032) (xy 352.722583 -331.366902)
			(xy 352.669799 -331.348895) (xy 352.620199 -331.323394) (xy 352.574841 -331.290943) (xy 352.534692 -331.252234)
			(xy 352.500606 -331.208091) (xy 352.47331 -331.159456) (xy 352.453387 -331.107365) (xy 352.441261 -331.052928)
			(xy 352.43719 -330.997306) (xy 352.184716 -330.997306) (xy 352.184207 -331.025192) (xy 352.176087 -331.080368)
			(xy 352.160019 -331.133775) (xy 352.136347 -331.184272) (xy 352.105574 -331.230785) (xy 352.068357 -331.272322)
			(xy 352.025489 -331.307997) (xy 351.977883 -331.337051) (xy 351.926554 -331.358863) (xy 351.872597 -331.372969)
			(xy 351.81716 -331.379069) (xy 351.761426 -331.377032) (xy 351.706583 -331.366902) (xy 351.653799 -331.348895)
			(xy 351.604199 -331.323394) (xy 351.558841 -331.290943) (xy 351.518692 -331.252234) (xy 351.484606 -331.208091)
			(xy 351.45731 -331.159456) (xy 351.437387 -331.107365) (xy 351.425261 -331.052928) (xy 351.42119 -330.997306)
			(xy 335.984596 -330.997306) (xy 336.563208 -331.575918) (xy 357.9655 -331.575918) (xy 357.969571 -331.520296)
			(xy 357.981697 -331.465859) (xy 358.00162 -331.413768) (xy 358.028916 -331.365133) (xy 358.063002 -331.32099)
			(xy 358.103151 -331.282281) (xy 358.148509 -331.24983) (xy 358.198109 -331.224329) (xy 358.250893 -331.206322)
			(xy 358.305736 -331.196192) (xy 358.36147 -331.194155) (xy 358.416907 -331.200255) (xy 358.470864 -331.214361)
			(xy 358.522193 -331.236173) (xy 358.569799 -331.265227) (xy 358.612667 -331.300902) (xy 358.649884 -331.342439)
			(xy 358.680657 -331.388952) (xy 358.704329 -331.439449) (xy 358.720397 -331.492856) (xy 358.728517 -331.548032)
			(xy 358.729026 -331.575918) (xy 358.728517 -331.603804) (xy 358.720397 -331.65898) (xy 358.704329 -331.712387)
			(xy 358.680657 -331.762884) (xy 358.649884 -331.809397) (xy 358.612667 -331.850934) (xy 358.569799 -331.886609)
			(xy 358.522193 -331.915663) (xy 358.470864 -331.937475) (xy 358.416907 -331.951581) (xy 358.36147 -331.957681)
			(xy 358.305736 -331.955644) (xy 358.250893 -331.945514) (xy 358.198109 -331.927507) (xy 358.148509 -331.902006)
			(xy 358.103151 -331.869555) (xy 358.063002 -331.830846) (xy 358.028916 -331.786703) (xy 358.00162 -331.738068)
			(xy 357.981697 -331.685977) (xy 357.969571 -331.63154) (xy 357.9655 -331.575918) (xy 336.563208 -331.575918)
			(xy 337.934561 -332.947271) (xy 365.368753 -332.947271) (xy 365.368753 -332.887329) (xy 365.376578 -332.827899)
			(xy 365.392093 -332.77) (xy 365.415033 -332.71462) (xy 365.445006 -332.66271) (xy 365.481498 -332.615155)
			(xy 365.523886 -332.572772) (xy 365.571443 -332.536283) (xy 365.623356 -332.506315) (xy 365.678737 -332.48338)
			(xy 365.736639 -332.46787) (xy 365.796069 -332.460051) (xy 365.82604 -332.459584) (xy 366.68964 -332.459584)
			(xy 366.719605 -332.460093) (xy 366.779023 -332.46792) (xy 366.836911 -332.483435) (xy 366.892278 -332.506374)
			(xy 366.944178 -332.536342) (xy 366.991723 -332.572828) (xy 367.034098 -332.615207) (xy 367.07058 -332.662755)
			(xy 367.100544 -332.714658) (xy 367.123478 -332.770027) (xy 367.138988 -332.827916) (xy 367.14681 -332.887335)
			(xy 367.14681 -332.947265) (xy 367.138988 -333.006684) (xy 367.123478 -333.064573) (xy 367.100544 -333.119942)
			(xy 367.07058 -333.171845) (xy 367.034098 -333.219393) (xy 366.991723 -333.261772) (xy 366.944178 -333.298258)
			(xy 366.892278 -333.328226) (xy 366.836911 -333.351165) (xy 366.779023 -333.36668) (xy 366.719605 -333.374507)
			(xy 366.68964 -333.375) (xy 365.82604 -333.375) (xy 365.796069 -333.374549) (xy 365.736639 -333.36673)
			(xy 365.678737 -333.35122) (xy 365.623356 -333.328285) (xy 365.571443 -333.298317) (xy 365.523886 -333.261828)
			(xy 365.481498 -333.219445) (xy 365.445006 -333.17189) (xy 365.415033 -333.11998) (xy 365.392093 -333.0646)
			(xy 365.376578 -333.006701) (xy 365.368753 -332.947271) (xy 337.934561 -332.947271) (xy 340.815676 -335.828386)
			(xy 340.823078 -335.835222) (xy 340.841676 -335.842931) (xy 340.851744 -335.843372) (xy 346.911168 -335.843372)
			(xy 346.92122 -335.843875) (xy 346.939784 -335.851594) (xy 346.947236 -335.858358) (xy 350.724724 -339.635846)
			(xy 350.732121 -339.642694) (xy 350.75072 -339.650429) (xy 350.760792 -339.650832) (xy 357.038148 -339.650832)
			(xy 357.038148 -339.651086) (xy 366.018572 -339.651086)
		)
		(stroke
			(width 0)
			(type solid)
		)
		(fill yes)
		(layer "In7.Cu")
		(net "GND")
	)
	(gr_poly
		(pts
			(xy 47.619666 -299.85589) (xy 47.620174 -299.85589) (xy 47.627334 -299.854186) (xy 47.640361 -299.847354)
			(xy 47.645828 -299.842428) (xy 47.760382 -299.727874) (xy 47.765367 -299.722446) (xy 47.772221 -299.709408)
			(xy 47.773844 -299.70222) (xy 47.773844 -299.701712) (xy 47.77486 -299.692314) (xy 47.77486 -299.577252)
			(xy 47.774488 -299.568147) (xy 47.768108 -299.551092) (xy 47.762414 -299.543978) (xy 47.756826 -299.53712)
			(xy 47.740316 -299.528484) (xy 47.73041 -299.527214) (xy 47.706833 -299.523262) (xy 47.66121 -299.508993)
			(xy 47.618364 -299.487795) (xy 47.579342 -299.460184) (xy 47.545095 -299.426835) (xy 47.516458 -299.388559)
			(xy 47.49413 -299.346291) (xy 47.478656 -299.301063) (xy 47.470412 -299.253976) (xy 47.469601 -299.206181)
			(xy 47.476242 -299.158841) (xy 47.490172 -299.113114) (xy 47.511053 -299.070113) (xy 47.538374 -299.030887)
			(xy 47.554642 -299.013372) (xy 47.572515 -298.995483) (xy 47.613074 -298.965289) (xy 47.658052 -298.942185)
			(xy 47.706221 -298.926804) (xy 47.731172 -298.922694) (xy 47.732696 -298.92244) (xy 47.737268 -298.921932)
			(xy 47.74529 -298.919879) (xy 47.759533 -298.911452) (xy 47.765208 -298.905422) (xy 47.77486 -298.894246)
			(xy 47.797707 -298.894668) (xy 47.842953 -298.901048) (xy 47.86503 -298.906946) (xy 47.876714 -298.910248)
			(xy 47.88789 -298.908216) (xy 47.89805 -298.905168) (xy 47.899828 -298.90339) (xy 47.915068 -298.88815)
			(xy 47.920402 -298.883324) (xy 47.971456 -298.845224) (xy 47.979444 -298.838427) (xy 47.988699 -298.819632)
			(xy 47.989236 -298.809156) (xy 47.989236 -297.740578) (xy 47.988642 -297.730077) (xy 47.979248 -297.711284)
			(xy 47.971202 -297.70451) (xy 47.94885 -297.687492) (xy 47.948342 -297.686984) (xy 47.93234 -297.675046)
			(xy 47.923083 -297.667944) (xy 47.905538 -297.652562) (xy 47.897288 -297.644312) (xy 47.88789 -297.641518)
			(xy 47.876714 -297.639486) (xy 47.86503 -297.642788) (xy 47.842953 -297.64868) (xy 47.797706 -297.65505)
			(xy 47.77486 -297.655488) (xy 47.748875 -297.654975) (xy 47.697547 -297.64684) (xy 47.648123 -297.630775)
			(xy 47.601821 -297.607177) (xy 47.55978 -297.576626) (xy 47.523035 -297.539875) (xy 47.492492 -297.497828)
			(xy 47.468902 -297.451521) (xy 47.452846 -297.402095) (xy 47.44472 -297.350765) (xy 47.444152 -297.32478)
			(xy 47.444701 -297.298269) (xy 47.453206 -297.245932) (xy 47.469947 -297.19562) (xy 47.481744 -297.171872)
			(xy 47.481744 -297.171618) (xy 47.481998 -297.171364) (xy 47.484726 -297.165582) (xy 47.487553 -297.153119)
			(xy 47.487586 -297.146726) (xy 47.487078 -297.133264) (xy 47.472092 -297.108626) (xy 47.433738 -297.04538)
			(xy 47.427205 -297.036551) (xy 47.408504 -297.025081) (xy 47.39767 -297.023282) (xy 47.394622 -297.023028)
			(xy 47.206916 -297.023028) (xy 47.202344 -297.023282) (xy 47.20209 -297.023282) (xy 47.191147 -297.025182)
			(xy 47.172322 -297.036919) (xy 47.165768 -297.045888) (xy 47.1551 -297.063414) (xy 47.118524 -297.123612)
			(xy 47.115736 -297.128993) (xy 47.112517 -297.140675) (xy 47.112174 -297.146726) (xy 47.11192 -297.159426)
			(xy 47.11954 -297.174412) (xy 47.123096 -297.181778) (xy 47.133345 -297.204209) (xy 47.147823 -297.251352)
			(xy 47.155137 -297.300122) (xy 47.155608 -297.32478) (xy 47.155098 -297.350767) (xy 47.146968 -297.402102)
			(xy 47.130907 -297.451532) (xy 47.107311 -297.497842) (xy 47.076761 -297.53989) (xy 47.04001 -297.576641)
			(xy 46.997962 -297.607191) (xy 46.951652 -297.630787) (xy 46.902222 -297.646848) (xy 46.850887 -297.654978)
			(xy 46.798913 -297.654978) (xy 46.747578 -297.646848) (xy 46.698148 -297.630787) (xy 46.651838 -297.607191)
			(xy 46.60979 -297.576641) (xy 46.573039 -297.53989) (xy 46.542489 -297.497842) (xy 46.518893 -297.451532)
			(xy 46.502832 -297.402102) (xy 46.494702 -297.350767) (xy 46.494192 -297.32478) (xy 46.494741 -297.298269)
			(xy 46.503247 -297.245932) (xy 46.51999 -297.195622) (xy 46.531784 -297.171872) (xy 46.531784 -297.171618)
			(xy 46.532038 -297.171364) (xy 46.534764 -297.165582) (xy 46.537589 -297.153119) (xy 46.537626 -297.146726)
			(xy 46.537118 -297.133264) (xy 46.522132 -297.108626) (xy 46.483778 -297.04538) (xy 46.477241 -297.03656)
			(xy 46.458536 -297.025112) (xy 46.44771 -297.023282) (xy 46.444662 -297.023028) (xy 46.256956 -297.023028)
			(xy 46.252384 -297.023282) (xy 46.25213 -297.023282) (xy 46.241182 -297.025175) (xy 46.222344 -297.036904)
			(xy 46.215808 -297.045888) (xy 46.20514 -297.063414) (xy 46.168564 -297.123612) (xy 46.165774 -297.128993)
			(xy 46.162553 -297.140675) (xy 46.162214 -297.146726) (xy 46.16196 -297.159426) (xy 46.16958 -297.174412)
			(xy 46.173136 -297.181778) (xy 46.183384 -297.20421) (xy 46.19786 -297.251352) (xy 46.205173 -297.300122)
			(xy 46.205648 -297.32478) (xy 46.205138 -297.350767) (xy 46.197008 -297.402102) (xy 46.180947 -297.451532)
			(xy 46.157351 -297.497842) (xy 46.126801 -297.53989) (xy 46.09005 -297.576641) (xy 46.048002 -297.607191)
			(xy 46.001692 -297.630787) (xy 45.952262 -297.646848) (xy 45.900927 -297.654978) (xy 45.848953 -297.654978)
			(xy 45.797618 -297.646848) (xy 45.748188 -297.630787) (xy 45.701878 -297.607191) (xy 45.65983 -297.576641)
			(xy 45.623079 -297.53989) (xy 45.592529 -297.497842) (xy 45.568933 -297.451532) (xy 45.552872 -297.402102)
			(xy 45.544742 -297.350767) (xy 45.544232 -297.32478) (xy 45.544782 -297.298269) (xy 45.553289 -297.245933)
			(xy 45.570033 -297.195623) (xy 45.581824 -297.171872) (xy 45.581824 -297.171618) (xy 45.582078 -297.171364)
			(xy 45.584807 -297.165583) (xy 45.587635 -297.153119) (xy 45.587666 -297.146726) (xy 45.587158 -297.133264)
			(xy 45.572172 -297.108626) (xy 45.533818 -297.04538) (xy 45.527284 -297.036554) (xy 45.508581 -297.025092)
			(xy 45.49775 -297.023282) (xy 45.494702 -297.023028) (xy 45.306996 -297.023028) (xy 45.302424 -297.023282)
			(xy 45.30217 -297.023282) (xy 45.29123 -297.025186) (xy 45.272411 -297.036926) (xy 45.265848 -297.045888)
			(xy 45.25518 -297.063414) (xy 45.218604 -297.123612) (xy 45.215817 -297.128994) (xy 45.212599 -297.140675)
			(xy 45.212254 -297.146726) (xy 45.212 -297.159426) (xy 45.21962 -297.174412) (xy 45.223176 -297.181778)
			(xy 45.233426 -297.204209) (xy 45.247904 -297.251352) (xy 45.255219 -297.300122) (xy 45.255688 -297.32478)
			(xy 45.255178 -297.350767) (xy 45.247048 -297.402102) (xy 45.230987 -297.451532) (xy 45.207391 -297.497842)
			(xy 45.176841 -297.53989) (xy 45.14009 -297.576641) (xy 45.098042 -297.607191) (xy 45.051732 -297.630787)
			(xy 45.002302 -297.646848) (xy 44.950967 -297.654978) (xy 44.898993 -297.654978) (xy 44.847658 -297.646848)
			(xy 44.798228 -297.630787) (xy 44.751918 -297.607191) (xy 44.70987 -297.576641) (xy 44.673119 -297.53989)
			(xy 44.642569 -297.497842) (xy 44.618973 -297.451532) (xy 44.602912 -297.402102) (xy 44.594782 -297.350767)
			(xy 44.594272 -297.32478) (xy 44.594821 -297.298269) (xy 44.603326 -297.245932) (xy 44.620068 -297.195621)
			(xy 44.631864 -297.171872) (xy 44.631864 -297.171618) (xy 44.632118 -297.171364) (xy 44.634845 -297.165582)
			(xy 44.637671 -297.153119) (xy 44.637706 -297.146726) (xy 44.637198 -297.133264) (xy 44.622212 -297.108626)
			(xy 44.583858 -297.04538) (xy 44.577327 -297.036548) (xy 44.558626 -297.025072) (xy 44.54779 -297.023282)
			(xy 44.544742 -297.023028) (xy 44.356782 -297.023028) (xy 44.35221 -297.023282) (xy 44.351956 -297.023282)
			(xy 44.341005 -297.02517) (xy 44.322159 -297.036894) (xy 44.315634 -297.045888) (xy 44.304966 -297.063414)
			(xy 44.26839 -297.123612) (xy 44.265599 -297.128993) (xy 44.262376 -297.140674) (xy 44.26204 -297.146726)
			(xy 44.261786 -297.159426) (xy 44.269406 -297.174412) (xy 44.272962 -297.181778) (xy 44.283212 -297.204209)
			(xy 44.297691 -297.251352) (xy 44.305006 -297.300122) (xy 44.305474 -297.32478) (xy 44.304964 -297.350767)
			(xy 44.296834 -297.402102) (xy 44.280773 -297.451532) (xy 44.257177 -297.497842) (xy 44.226627 -297.53989)
			(xy 44.189876 -297.576641) (xy 44.147828 -297.607191) (xy 44.101518 -297.630787) (xy 44.052088 -297.646848)
			(xy 44.000753 -297.654978) (xy 43.948779 -297.654978) (xy 43.897444 -297.646848) (xy 43.848014 -297.630787)
			(xy 43.801704 -297.607191) (xy 43.759656 -297.576641) (xy 43.722905 -297.53989) (xy 43.692355 -297.497842)
			(xy 43.668759 -297.451532) (xy 43.652698 -297.402102) (xy 43.644568 -297.350767) (xy 43.644058 -297.32478)
			(xy 43.644607 -297.298269) (xy 43.653112 -297.245932) (xy 43.669853 -297.195621) (xy 43.68165 -297.171872)
			(xy 43.68165 -297.171618) (xy 43.681904 -297.171364) (xy 43.684632 -297.165582) (xy 43.687458 -297.153119)
			(xy 43.687492 -297.146726) (xy 43.686984 -297.133264) (xy 43.671998 -297.108626) (xy 43.633644 -297.04538)
			(xy 43.627112 -297.03655) (xy 43.60841 -297.025078) (xy 43.597576 -297.023282) (xy 43.594528 -297.023028)
			(xy 42.456862 -297.023028) (xy 42.45229 -297.023282) (xy 42.452036 -297.023282) (xy 42.441088 -297.025174)
			(xy 42.422248 -297.036901) (xy 42.415714 -297.045888) (xy 42.405046 -297.063414) (xy 42.36847 -297.123612)
			(xy 42.36568 -297.128993) (xy 42.362458 -297.140675) (xy 42.36212 -297.146726) (xy 42.361866 -297.159426)
			(xy 42.369486 -297.174412) (xy 42.373042 -297.181778) (xy 42.38329 -297.20421) (xy 42.397766 -297.251352)
			(xy 42.405079 -297.300122) (xy 42.405554 -297.32478) (xy 42.405044 -297.350767) (xy 42.396914 -297.402102)
			(xy 42.380853 -297.451532) (xy 42.357257 -297.497842) (xy 42.326707 -297.53989) (xy 42.289956 -297.576641)
			(xy 42.247908 -297.607191) (xy 42.201598 -297.630787) (xy 42.152168 -297.646848) (xy 42.100833 -297.654978)
			(xy 42.048859 -297.654978) (xy 41.997524 -297.646848) (xy 41.948094 -297.630787) (xy 41.901784 -297.607191)
			(xy 41.859736 -297.576641) (xy 41.822985 -297.53989) (xy 41.792435 -297.497842) (xy 41.768839 -297.451532)
			(xy 41.752778 -297.402102) (xy 41.744648 -297.350767) (xy 41.744138 -297.32478) (xy 41.74464 -297.29858)
			(xy 41.752907 -297.246836) (xy 41.769232 -297.197043) (xy 41.793206 -297.150448) (xy 41.824229 -297.108218)
			(xy 41.861524 -297.071409) (xy 41.882568 -297.055794) (xy 41.882822 -297.05554) (xy 41.890546 -297.049391)
			(xy 41.900998 -297.032665) (xy 41.903142 -297.023028) (xy 41.903396 -297.022012) (xy 41.906952 -296.980102)
			(xy 41.906952 -296.979594) (xy 41.91 -296.94124) (xy 41.910319 -296.930155) (xy 41.902673 -296.909364)
			(xy 41.895268 -296.901108) (xy 38.698678 -293.704518) (xy 38.690469 -293.697041) (xy 38.669645 -293.689414)
			(xy 38.658546 -293.689786) (xy 38.620192 -293.692834) (xy 38.619684 -293.692834) (xy 38.577774 -293.69639)
			(xy 38.576758 -293.696644) (xy 38.567113 -293.69877) (xy 38.55038 -293.709224) (xy 38.544246 -293.716964)
			(xy 38.543992 -293.717218) (xy 38.528362 -293.738253) (xy 38.491568 -293.775565) (xy 38.449344 -293.8066)
			(xy 38.40275 -293.830581) (xy 38.352955 -293.846904) (xy 38.301207 -293.855162) (xy 38.275006 -293.855648)
			(xy 38.249017 -293.855139) (xy 38.19768 -293.847009) (xy 38.148246 -293.830949) (xy 38.101933 -293.807355)
			(xy 38.05988 -293.776806) (xy 38.023124 -293.740055) (xy 37.99257 -293.698007) (xy 37.968968 -293.651697)
			(xy 37.952901 -293.602265) (xy 37.944765 -293.550929) (xy 37.944298 -293.52494) (xy 37.944803 -293.498742)
			(xy 37.953077 -293.447003) (xy 37.969408 -293.397217) (xy 37.993388 -293.35063) (xy 38.024417 -293.308409)
			(xy 38.061716 -293.27161) (xy 38.082728 -293.255954) (xy 38.082982 -293.2557) (xy 38.090706 -293.249552)
			(xy 38.101153 -293.232824) (xy 38.103302 -293.223188) (xy 38.103556 -293.222172) (xy 38.107112 -293.180262)
			(xy 38.107112 -293.179754) (xy 38.11016 -293.1414) (xy 38.11049 -293.130311) (xy 38.102857 -293.109506)
			(xy 38.095428 -293.101268) (xy 37.748464 -292.754304) (xy 37.740259 -292.746813) (xy 37.719433 -292.739153)
			(xy 37.708332 -292.739572) (xy 37.631116 -292.745922) (xy 37.626798 -292.74643) (xy 37.62233 -292.747278)
			(xy 37.613766 -292.750338) (xy 37.60978 -292.752526) (xy 37.608002 -292.753542) (xy 37.60493 -292.75554)
			(xy 37.599319 -292.760254) (xy 37.596826 -292.76294) (xy 37.594032 -292.767004) (xy 37.578393 -292.788069)
			(xy 37.541571 -292.825436) (xy 37.49931 -292.85652) (xy 37.452672 -292.880543) (xy 37.402826 -292.8969)
			(xy 37.351023 -292.905182) (xy 37.324792 -292.905688) (xy 37.298804 -292.905204) (xy 37.247467 -292.897072)
			(xy 37.198035 -292.881009) (xy 37.151724 -292.85741) (xy 37.109676 -292.826858) (xy 37.072924 -292.790103)
			(xy 37.042375 -292.748052) (xy 37.018781 -292.701739) (xy 37.002722 -292.652305) (xy 36.994594 -292.600968)
			(xy 36.994084 -292.57498) (xy 36.99459 -292.54907) (xy 37.002678 -292.497885) (xy 37.018652 -292.448588)
			(xy 37.042123 -292.402388) (xy 37.072513 -292.360414) (xy 37.10908 -292.323697) (xy 37.12972 -292.308026)
			(xy 37.135562 -292.302946) (xy 37.144452 -292.294056) (xy 37.147246 -292.289738) (xy 37.15004 -292.284912)
			(xy 37.153342 -292.274498) (xy 37.1602 -292.19144) (xy 37.160519 -292.180355) (xy 37.152873 -292.159564)
			(xy 37.145468 -292.151308) (xy 36.798504 -291.804344) (xy 36.790298 -291.796859) (xy 36.769472 -291.789218)
			(xy 36.758372 -291.789612) (xy 36.680902 -291.795962) (xy 36.675427 -291.796608) (xy 36.664921 -291.79994)
			(xy 36.660074 -291.802566) (xy 36.650422 -291.8079) (xy 36.643818 -291.817298) (xy 36.628156 -291.838287)
			(xy 36.59132 -291.87551) (xy 36.549084 -291.906468) (xy 36.502499 -291.93039) (xy 36.45273 -291.94668)
			(xy 36.401016 -291.95493) (xy 36.374832 -291.955474) (xy 36.348842 -291.954993) (xy 36.297502 -291.946866)
			(xy 36.248065 -291.930806) (xy 36.20175 -291.907209) (xy 36.159697 -291.876657) (xy 36.122942 -291.839902)
			(xy 36.09239 -291.797848) (xy 36.068793 -291.751533) (xy 36.052734 -291.702096) (xy 36.044607 -291.650756)
			(xy 36.044124 -291.624766) (xy 36.044617 -291.598577) (xy 36.052859 -291.546853) (xy 36.069146 -291.497073)
			(xy 36.093073 -291.45048) (xy 36.124042 -291.408239) (xy 36.161278 -291.371405) (xy 36.1823 -291.35578)
			(xy 36.191698 -291.349176) (xy 36.197032 -291.339524) (xy 36.199673 -291.334683) (xy 36.203012 -291.324175)
			(xy 36.203636 -291.318696) (xy 36.209986 -291.241226) (xy 36.210301 -291.230143) (xy 36.20265 -291.209357)
			(xy 36.195254 -291.201094) (xy 34.358834 -289.364674) (xy 34.351988 -289.357276) (xy 34.344257 -289.338677)
			(xy 34.343848 -289.328606) (xy 34.343848 -287.510982) (xy 34.342642 -287.498967) (xy 34.330707 -287.478016)
			(xy 34.320988 -287.47085) (xy 34.318448 -287.46958) (xy 34.241232 -287.424622) (xy 34.235647 -287.421887)
			(xy 34.223573 -287.418926) (xy 34.217356 -287.41878) (xy 34.19221 -287.425384) (xy 34.186622 -287.428432)
			(xy 34.158337 -287.44321) (xy 34.098061 -287.464157) (xy 34.03514 -287.474782) (xy 34.003234 -287.475422)
			(xy 34.00298 -287.475422) (xy 33.975729 -287.474935) (xy 33.921781 -287.467176) (xy 33.869487 -287.451818)
			(xy 33.81991 -287.429175) (xy 33.774061 -287.399707) (xy 33.732871 -287.364014) (xy 33.697181 -287.322823)
			(xy 33.667715 -287.276972) (xy 33.645075 -287.227394) (xy 33.62972 -287.175099) (xy 33.621964 -287.121151)
			(xy 33.621964 -287.066649) (xy 33.62972 -287.012701) (xy 33.645075 -286.960406) (xy 33.667715 -286.910828)
			(xy 33.697181 -286.864977) (xy 33.732871 -286.823786) (xy 33.774061 -286.788093) (xy 33.81991 -286.758625)
			(xy 33.869487 -286.735982) (xy 33.921781 -286.720624) (xy 33.975729 -286.712865) (xy 34.00298 -286.712406)
			(xy 34.003234 -286.712406) (xy 34.035137 -286.713072) (xy 34.098052 -286.723709) (xy 34.158331 -286.744635)
			(xy 34.186622 -286.759396) (xy 34.19221 -286.762444) (xy 34.217356 -286.769048) (xy 34.223572 -286.768897)
			(xy 34.235644 -286.765934) (xy 34.241232 -286.763206) (xy 34.313622 -286.721042) (xy 34.318702 -286.717994)
			(xy 34.32048 -286.716978) (xy 34.320734 -286.716978) (xy 34.321496 -286.71647) (xy 34.331061 -286.709226)
			(xy 34.34271 -286.688285) (xy 34.343848 -286.676338) (xy 34.343848 -284.310582) (xy 34.342642 -284.298567)
			(xy 34.330707 -284.277616) (xy 34.320988 -284.27045) (xy 34.318448 -284.26918) (xy 34.241232 -284.224222)
			(xy 34.235647 -284.221487) (xy 34.223573 -284.218526) (xy 34.217356 -284.21838) (xy 34.19221 -284.224984)
			(xy 34.186622 -284.228032) (xy 34.158337 -284.24281) (xy 34.098061 -284.263757) (xy 34.03514 -284.274382)
			(xy 34.003234 -284.275022) (xy 34.00298 -284.275022) (xy 33.975729 -284.274535) (xy 33.921781 -284.266776)
			(xy 33.869487 -284.251418) (xy 33.81991 -284.228775) (xy 33.774061 -284.199307) (xy 33.732871 -284.163614)
			(xy 33.697181 -284.122423) (xy 33.667715 -284.076572) (xy 33.645075 -284.026994) (xy 33.62972 -283.974699)
			(xy 33.621964 -283.920751) (xy 33.621964 -283.866249) (xy 33.62972 -283.812301) (xy 33.645075 -283.760006)
			(xy 33.667715 -283.710428) (xy 33.697181 -283.664577) (xy 33.732871 -283.623386) (xy 33.774061 -283.587693)
			(xy 33.81991 -283.558225) (xy 33.869487 -283.535582) (xy 33.921781 -283.520224) (xy 33.975729 -283.512465)
			(xy 34.00298 -283.512006) (xy 34.003234 -283.512006) (xy 34.035137 -283.512672) (xy 34.098052 -283.523309)
			(xy 34.158331 -283.544235) (xy 34.186622 -283.558996) (xy 34.19221 -283.562044) (xy 34.217356 -283.568648)
			(xy 34.223572 -283.568497) (xy 34.235644 -283.565534) (xy 34.241232 -283.562806) (xy 34.313622 -283.520642)
			(xy 34.318702 -283.517594) (xy 34.32048 -283.516578) (xy 34.320734 -283.516578) (xy 34.321496 -283.51607)
			(xy 34.331061 -283.508826) (xy 34.34271 -283.487885) (xy 34.343848 -283.475938) (xy 34.343848 -281.110182)
			(xy 34.342642 -281.098167) (xy 34.330707 -281.077216) (xy 34.320988 -281.07005) (xy 34.318448 -281.06878)
			(xy 34.241232 -281.023822) (xy 34.235647 -281.021087) (xy 34.223573 -281.018126) (xy 34.217356 -281.01798)
			(xy 34.19221 -281.024584) (xy 34.186622 -281.027632) (xy 34.158337 -281.04241) (xy 34.098061 -281.063357)
			(xy 34.03514 -281.073982) (xy 34.003234 -281.074622) (xy 34.00298 -281.074622) (xy 33.975729 -281.074135)
			(xy 33.921781 -281.066376) (xy 33.869487 -281.051018) (xy 33.81991 -281.028375) (xy 33.774061 -280.998907)
			(xy 33.732871 -280.963214) (xy 33.697181 -280.922023) (xy 33.667715 -280.876172) (xy 33.645075 -280.826594)
			(xy 33.62972 -280.774299) (xy 33.621964 -280.720351) (xy 33.621964 -280.665849) (xy 33.62972 -280.611901)
			(xy 33.645075 -280.559606) (xy 33.667715 -280.510028) (xy 33.697181 -280.464177) (xy 33.732871 -280.422986)
			(xy 33.774061 -280.387293) (xy 33.81991 -280.357825) (xy 33.869487 -280.335182) (xy 33.921781 -280.319824)
			(xy 33.975729 -280.312065) (xy 34.00298 -280.311606) (xy 34.003234 -280.311606) (xy 34.035137 -280.312272)
			(xy 34.098052 -280.322909) (xy 34.158331 -280.343835) (xy 34.186622 -280.358596) (xy 34.19221 -280.361644)
			(xy 34.217356 -280.368248) (xy 34.223572 -280.368097) (xy 34.235644 -280.365134) (xy 34.241232 -280.362406)
			(xy 34.313622 -280.320242) (xy 34.318702 -280.317194) (xy 34.32048 -280.316178) (xy 34.320734 -280.316178)
			(xy 34.321496 -280.31567) (xy 34.331061 -280.308426) (xy 34.34271 -280.287485) (xy 34.343848 -280.275538)
			(xy 34.343848 -280.044398) (xy 34.343506 -280.035797) (xy 34.33778 -280.019577) (xy 34.332672 -280.012648)
			(xy 34.332164 -280.01214) (xy 34.329116 -280.008584) (xy 34.075878 -279.755346) (xy 34.072146 -279.751827)
			(xy 34.06357 -279.746203) (xy 34.05886 -279.74417) (xy 34.050224 -279.740614) (xy 32.202374 -279.740614)
			(xy 32.200596 -279.740868) (xy 32.190849 -279.742355) (xy 32.173466 -279.751625) (xy 32.166814 -279.758902)
			(xy 32.149288 -279.779984) (xy 32.116776 -279.819354) (xy 32.113331 -279.823719) (xy 32.108207 -279.833584)
			(xy 32.106616 -279.838912) (xy 32.103822 -279.84958) (xy 32.105854 -279.86101) (xy 32.108916 -279.878375)
			(xy 32.112222 -279.913483) (xy 32.112458 -279.931114) (xy 32.111972 -279.958365) (xy 32.104216 -280.012313)
			(xy 32.088861 -280.064608) (xy 32.066219 -280.114185) (xy 32.036753 -280.160035) (xy 32.001062 -280.201226)
			(xy 31.959871 -280.236917) (xy 31.914021 -280.266383) (xy 31.864444 -280.289025) (xy 31.812149 -280.30438)
			(xy 31.758201 -280.312136) (xy 31.703699 -280.312136) (xy 31.649751 -280.30438) (xy 31.597456 -280.289025)
			(xy 31.547879 -280.266383) (xy 31.502029 -280.236917) (xy 31.460838 -280.201226) (xy 31.425147 -280.160035)
			(xy 31.395681 -280.114185) (xy 31.373039 -280.064608) (xy 31.357684 -280.012313) (xy 31.349928 -279.958365)
			(xy 31.349442 -279.931114) (xy 31.349442 -279.930352) (xy 31.350091 -279.899107) (xy 31.360304 -279.837456)
			(xy 31.369762 -279.80767) (xy 31.372556 -279.799796) (xy 31.372556 -279.791414) (xy 31.372138 -279.781394)
			(xy 31.364469 -279.76288) (xy 31.350295 -279.748714) (xy 31.331776 -279.741056) (xy 31.321756 -279.740614)
			(xy 31.285688 -279.740614) (xy 31.275669 -279.741036) (xy 31.257159 -279.748708) (xy 31.242994 -279.762881)
			(xy 31.235331 -279.781395) (xy 31.234888 -279.791414) (xy 31.234888 -283.893514) (xy 31.338012 -283.893514)
			(xy 31.338555 -283.864132) (xy 31.347584 -283.806065) (xy 31.365415 -283.75007) (xy 31.391626 -283.697475)
			(xy 31.425597 -283.649524) (xy 31.466521 -283.607352) (xy 31.48965 -283.589222) (xy 31.498575 -283.581743)
			(xy 31.509034 -283.560968) (xy 31.509716 -283.549344) (xy 31.510986 -283.457396) (xy 31.50108 -283.436314)
			(xy 31.491936 -283.428948) (xy 31.470088 -283.410742) (xy 31.431546 -283.368924) (xy 31.399638 -283.321849)
			(xy 31.375071 -283.270559) (xy 31.358388 -283.216191) (xy 31.34996 -283.159949) (xy 31.349442 -283.131514)
			(xy 31.349928 -283.104263) (xy 31.357684 -283.050315) (xy 31.373039 -282.99802) (xy 31.395681 -282.948443)
			(xy 31.425147 -282.902593) (xy 31.460838 -282.861402) (xy 31.502029 -282.825711) (xy 31.547879 -282.796245)
			(xy 31.597456 -282.773603) (xy 31.649751 -282.758248) (xy 31.703699 -282.750492) (xy 31.758201 -282.750492)
			(xy 31.812149 -282.758248) (xy 31.864444 -282.773603) (xy 31.914021 -282.796245) (xy 31.959871 -282.825711)
			(xy 32.001062 -282.861402) (xy 32.036753 -282.902593) (xy 32.066219 -282.948443) (xy 32.088861 -282.99802)
			(xy 32.104216 -283.050315) (xy 32.111972 -283.104263) (xy 32.112458 -283.131514) (xy 32.111907 -283.160896)
			(xy 32.102876 -283.218961) (xy 32.085044 -283.274954) (xy 32.058835 -283.327549) (xy 32.024867 -283.3755)
			(xy 31.983946 -283.417674) (xy 31.96082 -283.435806) (xy 31.951877 -283.443267) (xy 31.94143 -283.464056)
			(xy 31.940754 -283.475684) (xy 31.939484 -283.567632) (xy 31.94939 -283.588714) (xy 31.958534 -283.59608)
			(xy 31.980362 -283.614309) (xy 32.018902 -283.656124) (xy 32.05081 -283.703195) (xy 32.07538 -283.75448)
			(xy 32.092068 -283.808843) (xy 32.100505 -283.865081) (xy 32.101028 -283.893514) (xy 32.734502 -283.893514)
			(xy 32.738573 -283.837892) (xy 32.750699 -283.783455) (xy 32.770622 -283.731364) (xy 32.797918 -283.682729)
			(xy 32.832004 -283.638586) (xy 32.872153 -283.599877) (xy 32.917511 -283.567426) (xy 32.967111 -283.541925)
			(xy 33.019895 -283.523918) (xy 33.074738 -283.513788) (xy 33.130472 -283.511751) (xy 33.185909 -283.517851)
			(xy 33.239866 -283.531957) (xy 33.291195 -283.553769) (xy 33.338801 -283.582823) (xy 33.381669 -283.618498)
			(xy 33.418886 -283.660035) (xy 33.449659 -283.706548) (xy 33.473331 -283.757045) (xy 33.489399 -283.810452)
			(xy 33.497519 -283.865628) (xy 33.498028 -283.893514) (xy 33.497519 -283.9214) (xy 33.489399 -283.976576)
			(xy 33.473331 -284.029983) (xy 33.449659 -284.08048) (xy 33.418886 -284.126993) (xy 33.381669 -284.16853)
			(xy 33.338801 -284.204205) (xy 33.291195 -284.233259) (xy 33.239866 -284.255071) (xy 33.185909 -284.269177)
			(xy 33.130472 -284.275277) (xy 33.074738 -284.27324) (xy 33.019895 -284.26311) (xy 32.967111 -284.245103)
			(xy 32.917511 -284.219602) (xy 32.872153 -284.187151) (xy 32.832004 -284.148442) (xy 32.797918 -284.104299)
			(xy 32.770622 -284.055664) (xy 32.750699 -284.003573) (xy 32.738573 -283.949136) (xy 32.734502 -283.893514)
			(xy 32.101028 -283.893514) (xy 32.100542 -283.920765) (xy 32.092786 -283.974713) (xy 32.077431 -284.027008)
			(xy 32.054789 -284.076585) (xy 32.025323 -284.122435) (xy 31.989632 -284.163626) (xy 31.948441 -284.199317)
			(xy 31.902591 -284.228783) (xy 31.853014 -284.251425) (xy 31.800719 -284.26678) (xy 31.746771 -284.274536)
			(xy 31.692269 -284.274536) (xy 31.638321 -284.26678) (xy 31.586026 -284.251425) (xy 31.536449 -284.228783)
			(xy 31.490599 -284.199317) (xy 31.449408 -284.163626) (xy 31.413717 -284.122435) (xy 31.384251 -284.076585)
			(xy 31.361609 -284.027008) (xy 31.346254 -283.974713) (xy 31.338498 -283.920765) (xy 31.338012 -283.893514)
			(xy 31.234888 -283.893514) (xy 31.234888 -287.093914) (xy 31.338012 -287.093914) (xy 31.338555 -287.064532)
			(xy 31.347584 -287.006465) (xy 31.365415 -286.95047) (xy 31.391626 -286.897875) (xy 31.425597 -286.849924)
			(xy 31.466521 -286.807752) (xy 31.48965 -286.789622) (xy 31.498575 -286.782143) (xy 31.509034 -286.761368)
			(xy 31.509716 -286.749744) (xy 31.510986 -286.657796) (xy 31.50108 -286.636714) (xy 31.491936 -286.629348)
			(xy 31.470088 -286.611142) (xy 31.431546 -286.569324) (xy 31.399638 -286.522249) (xy 31.375071 -286.470959)
			(xy 31.358388 -286.416591) (xy 31.34996 -286.360349) (xy 31.349442 -286.331914) (xy 31.349928 -286.304663)
			(xy 31.357684 -286.250715) (xy 31.373039 -286.19842) (xy 31.395681 -286.148843) (xy 31.425147 -286.102993)
			(xy 31.460838 -286.061802) (xy 31.502029 -286.026111) (xy 31.547879 -285.996645) (xy 31.597456 -285.974003)
			(xy 31.649751 -285.958648) (xy 31.703699 -285.950892) (xy 31.758201 -285.950892) (xy 31.812149 -285.958648)
			(xy 31.864444 -285.974003) (xy 31.914021 -285.996645) (xy 31.959871 -286.026111) (xy 32.001062 -286.061802)
			(xy 32.036753 -286.102993) (xy 32.066219 -286.148843) (xy 32.088861 -286.19842) (xy 32.104216 -286.250715)
			(xy 32.111972 -286.304663) (xy 32.112458 -286.331914) (xy 32.111907 -286.361296) (xy 32.102876 -286.419361)
			(xy 32.085044 -286.475354) (xy 32.058835 -286.527949) (xy 32.024867 -286.5759) (xy 31.983946 -286.618074)
			(xy 31.96082 -286.636206) (xy 31.951877 -286.643667) (xy 31.94143 -286.664456) (xy 31.940754 -286.676084)
			(xy 31.939484 -286.768032) (xy 31.94939 -286.789114) (xy 31.958534 -286.79648) (xy 31.980362 -286.814709)
			(xy 32.018902 -286.856524) (xy 32.05081 -286.903595) (xy 32.07538 -286.95488) (xy 32.092068 -287.009243)
			(xy 32.100505 -287.065481) (xy 32.101028 -287.093914) (xy 32.734502 -287.093914) (xy 32.738573 -287.038292)
			(xy 32.750699 -286.983855) (xy 32.770622 -286.931764) (xy 32.797918 -286.883129) (xy 32.832004 -286.838986)
			(xy 32.872153 -286.800277) (xy 32.917511 -286.767826) (xy 32.967111 -286.742325) (xy 33.019895 -286.724318)
			(xy 33.074738 -286.714188) (xy 33.130472 -286.712151) (xy 33.185909 -286.718251) (xy 33.239866 -286.732357)
			(xy 33.291195 -286.754169) (xy 33.338801 -286.783223) (xy 33.381669 -286.818898) (xy 33.418886 -286.860435)
			(xy 33.449659 -286.906948) (xy 33.473331 -286.957445) (xy 33.489399 -287.010852) (xy 33.497519 -287.066028)
			(xy 33.498028 -287.093914) (xy 33.497519 -287.1218) (xy 33.489399 -287.176976) (xy 33.473331 -287.230383)
			(xy 33.449659 -287.28088) (xy 33.418886 -287.327393) (xy 33.381669 -287.36893) (xy 33.338801 -287.404605)
			(xy 33.291195 -287.433659) (xy 33.239866 -287.455471) (xy 33.185909 -287.469577) (xy 33.130472 -287.475677)
			(xy 33.074738 -287.47364) (xy 33.019895 -287.46351) (xy 32.967111 -287.445503) (xy 32.917511 -287.420002)
			(xy 32.872153 -287.387551) (xy 32.832004 -287.348842) (xy 32.797918 -287.304699) (xy 32.770622 -287.256064)
			(xy 32.750699 -287.203973) (xy 32.738573 -287.149536) (xy 32.734502 -287.093914) (xy 32.101028 -287.093914)
			(xy 32.100542 -287.121165) (xy 32.092786 -287.175113) (xy 32.077431 -287.227408) (xy 32.054789 -287.276985)
			(xy 32.025323 -287.322835) (xy 31.989632 -287.364026) (xy 31.948441 -287.399717) (xy 31.902591 -287.429183)
			(xy 31.853014 -287.451825) (xy 31.800719 -287.46718) (xy 31.746771 -287.474936) (xy 31.692269 -287.474936)
			(xy 31.638321 -287.46718) (xy 31.586026 -287.451825) (xy 31.536449 -287.429183) (xy 31.490599 -287.399717)
			(xy 31.449408 -287.364026) (xy 31.413717 -287.322835) (xy 31.384251 -287.276985) (xy 31.361609 -287.227408)
			(xy 31.346254 -287.175113) (xy 31.338498 -287.121165) (xy 31.338012 -287.093914) (xy 31.234888 -287.093914)
			(xy 31.234888 -289.927538) (xy 31.235314 -289.936825) (xy 31.241945 -289.954177) (xy 31.254295 -289.968053)
			(xy 31.26232 -289.97275) (xy 31.342838 -290.014152) (xy 31.351219 -290.01798) (xy 31.369517 -290.020025)
			(xy 31.387366 -290.015508) (xy 31.395162 -290.010596) (xy 31.395416 -290.010342) (xy 31.408048 -290.001539)
			(xy 31.434497 -289.985773) (xy 31.448248 -289.978846) (xy 31.448502 -289.978846) (xy 31.459235 -289.97267)
			(xy 31.473701 -289.952623) (xy 31.476188 -289.940492) (xy 31.48838 -289.857434) (xy 31.489429 -289.845071)
			(xy 31.481195 -289.821709) (xy 31.472632 -289.81273) (xy 31.472378 -289.81273) (xy 31.453356 -289.79461)
			(xy 31.419968 -289.754048) (xy 31.392466 -289.709287) (xy 31.37137 -289.661173) (xy 31.357079 -289.610619)
			(xy 31.349864 -289.558582) (xy 31.349442 -289.532314) (xy 31.349928 -289.505063) (xy 31.357684 -289.451115)
			(xy 31.373039 -289.39882) (xy 31.395681 -289.349243) (xy 31.425147 -289.303393) (xy 31.460838 -289.262202)
			(xy 31.502029 -289.226511) (xy 31.547879 -289.197045) (xy 31.597456 -289.174403) (xy 31.649751 -289.159048)
			(xy 31.703699 -289.151292) (xy 31.758201 -289.151292) (xy 31.812149 -289.159048) (xy 31.864444 -289.174403)
			(xy 31.914021 -289.197045) (xy 31.959871 -289.226511) (xy 32.001062 -289.262202) (xy 32.036753 -289.303393)
			(xy 32.066219 -289.349243) (xy 32.088861 -289.39882) (xy 32.104216 -289.451115) (xy 32.111972 -289.505063)
			(xy 32.112458 -289.532314) (xy 32.112003 -289.558896) (xy 32.104631 -289.611545) (xy 32.090017 -289.66266)
			(xy 32.068446 -289.711249) (xy 32.040334 -289.756372) (xy 32.006228 -289.797152) (xy 31.966788 -289.8328)
			(xy 31.922779 -289.862625) (xy 31.899098 -289.874706) (xy 31.898844 -289.874706) (xy 31.888023 -289.880777)
			(xy 31.873525 -289.900879) (xy 31.871158 -289.91306) (xy 31.858966 -289.996118) (xy 31.857771 -290.008497)
			(xy 31.866017 -290.031933) (xy 31.874714 -290.040822) (xy 31.874968 -290.040822) (xy 31.89399 -290.058942)
			(xy 31.927376 -290.099503) (xy 31.954876 -290.144265) (xy 31.975969 -290.192379) (xy 31.990255 -290.242933)
			(xy 31.997373 -290.294314) (xy 33.620962 -290.294314) (xy 33.625033 -290.238692) (xy 33.637159 -290.184255)
			(xy 33.657082 -290.132164) (xy 33.684378 -290.083529) (xy 33.718464 -290.039386) (xy 33.758613 -290.000677)
			(xy 33.803971 -289.968226) (xy 33.853571 -289.942725) (xy 33.906355 -289.924718) (xy 33.961198 -289.914588)
			(xy 34.016932 -289.912551) (xy 34.072369 -289.918651) (xy 34.126326 -289.932757) (xy 34.177655 -289.954569)
			(xy 34.225261 -289.983623) (xy 34.268129 -290.019298) (xy 34.305346 -290.060835) (xy 34.336119 -290.107348)
			(xy 34.359791 -290.157845) (xy 34.375859 -290.211252) (xy 34.383979 -290.266428) (xy 34.384488 -290.294314)
			(xy 34.383979 -290.3222) (xy 34.375859 -290.377376) (xy 34.359791 -290.430783) (xy 34.336119 -290.48128)
			(xy 34.305346 -290.527793) (xy 34.268129 -290.56933) (xy 34.225261 -290.605005) (xy 34.177655 -290.634059)
			(xy 34.126326 -290.655871) (xy 34.072369 -290.669977) (xy 34.016932 -290.676077) (xy 33.961198 -290.67404)
			(xy 33.906355 -290.66391) (xy 33.853571 -290.645903) (xy 33.803971 -290.620402) (xy 33.758613 -290.587951)
			(xy 33.718464 -290.549242) (xy 33.684378 -290.505099) (xy 33.657082 -290.456464) (xy 33.637159 -290.404373)
			(xy 33.625033 -290.349936) (xy 33.620962 -290.294314) (xy 31.997373 -290.294314) (xy 31.997464 -290.294971)
			(xy 31.997904 -290.321238) (xy 31.997416 -290.348487) (xy 31.989655 -290.402431) (xy 31.974296 -290.454721)
			(xy 31.951653 -290.504293) (xy 31.922185 -290.550138) (xy 31.886494 -290.591324) (xy 31.845305 -290.627011)
			(xy 31.799456 -290.656473) (xy 31.749881 -290.679111) (xy 31.69759 -290.694464) (xy 31.643645 -290.702219)
			(xy 31.616396 -290.702746) (xy 31.586944 -290.702187) (xy 31.528747 -290.693097) (xy 31.472644 -290.675151)
			(xy 31.419975 -290.648777) (xy 31.39567 -290.632134) (xy 31.395162 -290.632134) (xy 31.395162 -290.63188)
			(xy 31.387392 -290.626908) (xy 31.36953 -290.622361) (xy 31.351219 -290.624467) (xy 31.342838 -290.628324)
			(xy 31.26232 -290.669726) (xy 31.254244 -290.674357) (xy 31.241862 -290.688239) (xy 31.235277 -290.705635)
			(xy 31.234888 -290.714938) (xy 31.234888 -290.820856) (xy 32.748218 -290.820856) (xy 32.752289 -290.765234)
			(xy 32.764415 -290.710797) (xy 32.784338 -290.658706) (xy 32.811634 -290.610071) (xy 32.84572 -290.565928)
			(xy 32.885869 -290.527219) (xy 32.931227 -290.494768) (xy 32.980827 -290.469267) (xy 33.033611 -290.45126)
			(xy 33.088454 -290.44113) (xy 33.144188 -290.439093) (xy 33.199625 -290.445193) (xy 33.253582 -290.459299)
			(xy 33.304911 -290.481111) (xy 33.352517 -290.510165) (xy 33.395385 -290.54584) (xy 33.432602 -290.587377)
			(xy 33.463375 -290.63389) (xy 33.487047 -290.684387) (xy 33.503115 -290.737794) (xy 33.511235 -290.79297)
			(xy 33.511744 -290.820856) (xy 33.511235 -290.848742) (xy 33.503115 -290.903918) (xy 33.487047 -290.957325)
			(xy 33.463375 -291.007822) (xy 33.432602 -291.054335) (xy 33.395385 -291.095872) (xy 33.352517 -291.131547)
			(xy 33.304911 -291.160601) (xy 33.253582 -291.182413) (xy 33.199625 -291.196519) (xy 33.144188 -291.202619)
			(xy 33.088454 -291.200582) (xy 33.033611 -291.190452) (xy 32.980827 -291.172445) (xy 32.931227 -291.146944)
			(xy 32.885869 -291.114493) (xy 32.84572 -291.075784) (xy 32.811634 -291.031641) (xy 32.784338 -290.983006)
			(xy 32.764415 -290.930915) (xy 32.752289 -290.876478) (xy 32.748218 -290.820856) (xy 31.234888 -290.820856)
			(xy 31.234888 -292.278054) (xy 31.235904 -292.287452) (xy 31.235904 -292.28796) (xy 31.237606 -292.295121)
			(xy 31.244435 -292.308151) (xy 31.249366 -292.313614) (xy 31.379668 -292.443916) (xy 31.38043 -292.444678)
			(xy 31.3817 -292.445694) (xy 31.388781 -292.451501) (xy 31.405831 -292.45815) (xy 31.414974 -292.458648)
			(xy 31.436564 -292.458648) (xy 31.441112 -292.458524) (xy 31.450055 -292.456864) (xy 31.454344 -292.455346)
			(xy 31.478728 -292.446202) (xy 31.485332 -292.440614) (xy 31.506056 -292.423833) (xy 31.551276 -292.395571)
			(xy 31.599983 -292.373866) (xy 31.651234 -292.359138) (xy 31.704034 -292.351674) (xy 31.730696 -292.351206)
			(xy 31.73095 -292.351206) (xy 31.758205 -292.351666) (xy 31.81216 -292.359417) (xy 31.864463 -292.374769)
			(xy 31.914049 -292.397409) (xy 31.959907 -292.426876) (xy 32.001105 -292.46257) (xy 32.036803 -292.503764)
			(xy 32.066274 -292.549619) (xy 32.077856 -292.57498) (xy 36.069028 -292.57498) (xy 36.072988 -292.525926)
			(xy 36.084765 -292.478142) (xy 36.104056 -292.432866) (xy 36.130359 -292.39127) (xy 36.162994 -292.354433)
			(xy 36.201115 -292.323308) (xy 36.243736 -292.298701) (xy 36.289752 -292.281249) (xy 36.337971 -292.271405)
			(xy 36.387146 -292.269424) (xy 36.436001 -292.275356) (xy 36.483272 -292.289048) (xy 36.527734 -292.310146)
			(xy 36.568237 -292.338102) (xy 36.60373 -292.372194) (xy 36.633295 -292.411538) (xy 36.656166 -292.455115)
			(xy 36.67175 -292.501796) (xy 36.679645 -292.550373) (xy 36.68014 -292.57498) (xy 36.679645 -292.599587)
			(xy 36.67175 -292.648164) (xy 36.656166 -292.694845) (xy 36.633295 -292.738422) (xy 36.60373 -292.777766)
			(xy 36.568237 -292.811858) (xy 36.527734 -292.839814) (xy 36.483272 -292.860912) (xy 36.436001 -292.874604)
			(xy 36.387146 -292.880536) (xy 36.337971 -292.878555) (xy 36.289752 -292.868711) (xy 36.243736 -292.851259)
			(xy 36.201115 -292.826652) (xy 36.162994 -292.795527) (xy 36.130359 -292.75869) (xy 36.104056 -292.717094)
			(xy 36.084765 -292.671818) (xy 36.072988 -292.624034) (xy 36.069028 -292.57498) (xy 32.077856 -292.57498)
			(xy 32.088918 -292.599203) (xy 32.104275 -292.651504) (xy 32.112031 -292.705459) (xy 32.112458 -292.732714)
			(xy 32.111926 -292.761237) (xy 32.103435 -292.817649) (xy 32.086644 -292.872169) (xy 32.061928 -292.923583)
			(xy 32.029835 -292.970747) (xy 32.010858 -292.992048) (xy 32.004508 -292.998906) (xy 31.990538 -293.03345)
			(xy 31.990538 -293.034212) (xy 31.990538 -293.044118) (xy 31.994348 -293.053008) (xy 31.996353 -293.057574)
			(xy 32.001847 -293.065893) (xy 32.00527 -293.069518) (xy 32.430466 -293.494714) (xy 32.734502 -293.494714)
			(xy 32.738573 -293.439092) (xy 32.750699 -293.384655) (xy 32.770622 -293.332564) (xy 32.797918 -293.283929)
			(xy 32.832004 -293.239786) (xy 32.872153 -293.201077) (xy 32.917511 -293.168626) (xy 32.967111 -293.143125)
			(xy 33.019895 -293.125118) (xy 33.074738 -293.114988) (xy 33.130472 -293.112951) (xy 33.185909 -293.119051)
			(xy 33.239866 -293.133157) (xy 33.291195 -293.154969) (xy 33.338801 -293.184023) (xy 33.381669 -293.219698)
			(xy 33.418886 -293.261235) (xy 33.449659 -293.307748) (xy 33.473331 -293.358245) (xy 33.489399 -293.411652)
			(xy 33.497519 -293.466828) (xy 33.498028 -293.494714) (xy 33.620962 -293.494714) (xy 33.625033 -293.439092)
			(xy 33.637159 -293.384655) (xy 33.657082 -293.332564) (xy 33.684378 -293.283929) (xy 33.718464 -293.239786)
			(xy 33.758613 -293.201077) (xy 33.803971 -293.168626) (xy 33.853571 -293.143125) (xy 33.906355 -293.125118)
			(xy 33.961198 -293.114988) (xy 34.016932 -293.112951) (xy 34.072369 -293.119051) (xy 34.126326 -293.133157)
			(xy 34.177655 -293.154969) (xy 34.225261 -293.184023) (xy 34.268129 -293.219698) (xy 34.305346 -293.261235)
			(xy 34.336119 -293.307748) (xy 34.359791 -293.358245) (xy 34.375859 -293.411652) (xy 34.383979 -293.466828)
			(xy 34.384488 -293.494714) (xy 34.383979 -293.5226) (xy 34.375859 -293.577776) (xy 34.359791 -293.631183)
			(xy 34.336119 -293.68168) (xy 34.305346 -293.728193) (xy 34.268129 -293.76973) (xy 34.225261 -293.805405)
			(xy 34.177655 -293.834459) (xy 34.126326 -293.856271) (xy 34.072369 -293.870377) (xy 34.016932 -293.876477)
			(xy 33.961198 -293.87444) (xy 33.906355 -293.86431) (xy 33.853571 -293.846303) (xy 33.803971 -293.820802)
			(xy 33.758613 -293.788351) (xy 33.718464 -293.749642) (xy 33.684378 -293.705499) (xy 33.657082 -293.656864)
			(xy 33.637159 -293.604773) (xy 33.625033 -293.550336) (xy 33.620962 -293.494714) (xy 33.498028 -293.494714)
			(xy 33.497519 -293.5226) (xy 33.489399 -293.577776) (xy 33.473331 -293.631183) (xy 33.449659 -293.68168)
			(xy 33.418886 -293.728193) (xy 33.381669 -293.76973) (xy 33.338801 -293.805405) (xy 33.291195 -293.834459)
			(xy 33.239866 -293.856271) (xy 33.185909 -293.870377) (xy 33.130472 -293.876477) (xy 33.074738 -293.87444)
			(xy 33.019895 -293.86431) (xy 32.967111 -293.846303) (xy 32.917511 -293.820802) (xy 32.872153 -293.788351)
			(xy 32.832004 -293.749642) (xy 32.797918 -293.705499) (xy 32.770622 -293.656864) (xy 32.750699 -293.604773)
			(xy 32.738573 -293.550336) (xy 32.734502 -293.494714) (xy 32.430466 -293.494714) (xy 33.410652 -294.4749)
			(xy 36.069028 -294.4749) (xy 36.072988 -294.425846) (xy 36.084765 -294.378062) (xy 36.104056 -294.332786)
			(xy 36.130359 -294.29119) (xy 36.162994 -294.254353) (xy 36.201115 -294.223228) (xy 36.243736 -294.198621)
			(xy 36.289752 -294.181169) (xy 36.337971 -294.171325) (xy 36.387146 -294.169344) (xy 36.436001 -294.175276)
			(xy 36.483272 -294.188968) (xy 36.527734 -294.210066) (xy 36.568237 -294.238022) (xy 36.60373 -294.272114)
			(xy 36.633295 -294.311458) (xy 36.656166 -294.355035) (xy 36.67175 -294.401716) (xy 36.679645 -294.450293)
			(xy 36.68014 -294.4749) (xy 37.018988 -294.4749) (xy 37.022948 -294.425846) (xy 37.034725 -294.378062)
			(xy 37.054016 -294.332786) (xy 37.080319 -294.29119) (xy 37.112954 -294.254353) (xy 37.151075 -294.223228)
			(xy 37.193696 -294.198621) (xy 37.239712 -294.181169) (xy 37.287931 -294.171325) (xy 37.337106 -294.169344)
			(xy 37.385961 -294.175276) (xy 37.433232 -294.188968) (xy 37.477694 -294.210066) (xy 37.518197 -294.238022)
			(xy 37.55369 -294.272114) (xy 37.583255 -294.311458) (xy 37.606126 -294.355035) (xy 37.62171 -294.401716)
			(xy 37.629605 -294.450293) (xy 37.6301 -294.4749) (xy 37.969202 -294.4749) (xy 37.973162 -294.425846)
			(xy 37.984939 -294.378062) (xy 38.00423 -294.332786) (xy 38.030533 -294.29119) (xy 38.063168 -294.254353)
			(xy 38.101289 -294.223228) (xy 38.14391 -294.198621) (xy 38.189926 -294.181169) (xy 38.238145 -294.171325)
			(xy 38.28732 -294.169344) (xy 38.336175 -294.175276) (xy 38.383446 -294.188968) (xy 38.427908 -294.210066)
			(xy 38.468411 -294.238022) (xy 38.503904 -294.272114) (xy 38.533469 -294.311458) (xy 38.55634 -294.355035)
			(xy 38.571924 -294.401716) (xy 38.579819 -294.450293) (xy 38.580314 -294.4749) (xy 38.579819 -294.499507)
			(xy 38.571924 -294.548084) (xy 38.55634 -294.594765) (xy 38.533469 -294.638342) (xy 38.503904 -294.677686)
			(xy 38.468411 -294.711778) (xy 38.427908 -294.739734) (xy 38.383446 -294.760832) (xy 38.336175 -294.774524)
			(xy 38.28732 -294.780456) (xy 38.238145 -294.778475) (xy 38.189926 -294.768631) (xy 38.14391 -294.751179)
			(xy 38.101289 -294.726572) (xy 38.063168 -294.695447) (xy 38.030533 -294.65861) (xy 38.00423 -294.617014)
			(xy 37.984939 -294.571738) (xy 37.973162 -294.523954) (xy 37.969202 -294.4749) (xy 37.6301 -294.4749)
			(xy 37.629605 -294.499507) (xy 37.62171 -294.548084) (xy 37.606126 -294.594765) (xy 37.583255 -294.638342)
			(xy 37.55369 -294.677686) (xy 37.518197 -294.711778) (xy 37.477694 -294.739734) (xy 37.433232 -294.760832)
			(xy 37.385961 -294.774524) (xy 37.337106 -294.780456) (xy 37.287931 -294.778475) (xy 37.239712 -294.768631)
			(xy 37.193696 -294.751179) (xy 37.151075 -294.726572) (xy 37.112954 -294.695447) (xy 37.080319 -294.65861)
			(xy 37.054016 -294.617014) (xy 37.034725 -294.571738) (xy 37.022948 -294.523954) (xy 37.018988 -294.4749)
			(xy 36.68014 -294.4749) (xy 36.679645 -294.499507) (xy 36.67175 -294.548084) (xy 36.656166 -294.594765)
			(xy 36.633295 -294.638342) (xy 36.60373 -294.677686) (xy 36.568237 -294.711778) (xy 36.527734 -294.739734)
			(xy 36.483272 -294.760832) (xy 36.436001 -294.774524) (xy 36.387146 -294.780456) (xy 36.337971 -294.778475)
			(xy 36.289752 -294.768631) (xy 36.243736 -294.751179) (xy 36.201115 -294.726572) (xy 36.162994 -294.695447)
			(xy 36.130359 -294.65861) (xy 36.104056 -294.617014) (xy 36.084765 -294.571738) (xy 36.072988 -294.523954)
			(xy 36.069028 -294.4749) (xy 33.410652 -294.4749) (xy 35.310572 -296.37482) (xy 37.019242 -296.37482)
			(xy 37.023202 -296.325766) (xy 37.034979 -296.277982) (xy 37.05427 -296.232706) (xy 37.080573 -296.19111)
			(xy 37.113208 -296.154273) (xy 37.151329 -296.123148) (xy 37.19395 -296.098541) (xy 37.239966 -296.081089)
			(xy 37.288185 -296.071245) (xy 37.33736 -296.069264) (xy 37.386215 -296.075196) (xy 37.433486 -296.088888)
			(xy 37.477948 -296.109986) (xy 37.518451 -296.137942) (xy 37.553944 -296.172034) (xy 37.583509 -296.211378)
			(xy 37.60638 -296.254955) (xy 37.621964 -296.301636) (xy 37.629859 -296.350213) (xy 37.630354 -296.37482)
			(xy 37.968948 -296.37482) (xy 37.972908 -296.325766) (xy 37.984685 -296.277982) (xy 38.003976 -296.232706)
			(xy 38.030279 -296.19111) (xy 38.062914 -296.154273) (xy 38.101035 -296.123148) (xy 38.143656 -296.098541)
			(xy 38.189672 -296.081089) (xy 38.237891 -296.071245) (xy 38.287066 -296.069264) (xy 38.335921 -296.075196)
			(xy 38.383192 -296.088888) (xy 38.427654 -296.109986) (xy 38.468157 -296.137942) (xy 38.50365 -296.172034)
			(xy 38.533215 -296.211378) (xy 38.556086 -296.254955) (xy 38.57167 -296.301636) (xy 38.579565 -296.350213)
			(xy 38.58006 -296.37482) (xy 38.919162 -296.37482) (xy 38.923122 -296.325766) (xy 38.934899 -296.277982)
			(xy 38.95419 -296.232706) (xy 38.980493 -296.19111) (xy 39.013128 -296.154273) (xy 39.051249 -296.123148)
			(xy 39.09387 -296.098541) (xy 39.139886 -296.081089) (xy 39.188105 -296.071245) (xy 39.23728 -296.069264)
			(xy 39.286135 -296.075196) (xy 39.333406 -296.088888) (xy 39.377868 -296.109986) (xy 39.418371 -296.137942)
			(xy 39.453864 -296.172034) (xy 39.483429 -296.211378) (xy 39.5063 -296.254955) (xy 39.521884 -296.301636)
			(xy 39.529779 -296.350213) (xy 39.530274 -296.37482) (xy 39.869122 -296.37482) (xy 39.873082 -296.325766)
			(xy 39.884859 -296.277982) (xy 39.90415 -296.232706) (xy 39.930453 -296.19111) (xy 39.963088 -296.154273)
			(xy 40.001209 -296.123148) (xy 40.04383 -296.098541) (xy 40.089846 -296.081089) (xy 40.138065 -296.071245)
			(xy 40.18724 -296.069264) (xy 40.236095 -296.075196) (xy 40.283366 -296.088888) (xy 40.327828 -296.109986)
			(xy 40.368331 -296.137942) (xy 40.403824 -296.172034) (xy 40.433389 -296.211378) (xy 40.45626 -296.254955)
			(xy 40.471844 -296.301636) (xy 40.479739 -296.350213) (xy 40.480234 -296.37482) (xy 40.479739 -296.399427)
			(xy 40.471844 -296.448004) (xy 40.45626 -296.494685) (xy 40.433389 -296.538262) (xy 40.403824 -296.577606)
			(xy 40.368331 -296.611698) (xy 40.327828 -296.639654) (xy 40.283366 -296.660752) (xy 40.236095 -296.674444)
			(xy 40.18724 -296.680376) (xy 40.138065 -296.678395) (xy 40.089846 -296.668551) (xy 40.04383 -296.651099)
			(xy 40.001209 -296.626492) (xy 39.963088 -296.595367) (xy 39.930453 -296.55853) (xy 39.90415 -296.516934)
			(xy 39.884859 -296.471658) (xy 39.873082 -296.423874) (xy 39.869122 -296.37482) (xy 39.530274 -296.37482)
			(xy 39.529779 -296.399427) (xy 39.521884 -296.448004) (xy 39.5063 -296.494685) (xy 39.483429 -296.538262)
			(xy 39.453864 -296.577606) (xy 39.418371 -296.611698) (xy 39.377868 -296.639654) (xy 39.333406 -296.660752)
			(xy 39.286135 -296.674444) (xy 39.23728 -296.680376) (xy 39.188105 -296.678395) (xy 39.139886 -296.668551)
			(xy 39.09387 -296.651099) (xy 39.051249 -296.626492) (xy 39.013128 -296.595367) (xy 38.980493 -296.55853)
			(xy 38.95419 -296.516934) (xy 38.934899 -296.471658) (xy 38.923122 -296.423874) (xy 38.919162 -296.37482)
			(xy 38.58006 -296.37482) (xy 38.579565 -296.399427) (xy 38.57167 -296.448004) (xy 38.556086 -296.494685)
			(xy 38.533215 -296.538262) (xy 38.50365 -296.577606) (xy 38.468157 -296.611698) (xy 38.427654 -296.639654)
			(xy 38.383192 -296.660752) (xy 38.335921 -296.674444) (xy 38.287066 -296.680376) (xy 38.237891 -296.678395)
			(xy 38.189672 -296.668551) (xy 38.143656 -296.651099) (xy 38.101035 -296.626492) (xy 38.062914 -296.595367)
			(xy 38.030279 -296.55853) (xy 38.003976 -296.516934) (xy 37.984685 -296.471658) (xy 37.972908 -296.423874)
			(xy 37.968948 -296.37482) (xy 37.630354 -296.37482) (xy 37.629859 -296.399427) (xy 37.621964 -296.448004)
			(xy 37.60638 -296.494685) (xy 37.583509 -296.538262) (xy 37.553944 -296.577606) (xy 37.518451 -296.611698)
			(xy 37.477948 -296.639654) (xy 37.433486 -296.660752) (xy 37.386215 -296.674444) (xy 37.33736 -296.680376)
			(xy 37.288185 -296.678395) (xy 37.239966 -296.668551) (xy 37.19395 -296.651099) (xy 37.151329 -296.626492)
			(xy 37.113208 -296.595367) (xy 37.080573 -296.55853) (xy 37.05427 -296.516934) (xy 37.034979 -296.471658)
			(xy 37.023202 -296.423874) (xy 37.019242 -296.37482) (xy 35.310572 -296.37482) (xy 36.012882 -297.07713)
			(xy 36.019994 -297.082972) (xy 36.025757 -297.086549) (xy 36.038634 -297.090791) (xy 36.045394 -297.091354)
			(xy 36.117784 -297.093132) (xy 36.122525 -297.093075) (xy 36.131859 -297.091417) (xy 36.136326 -297.08983)
			(xy 36.144708 -297.086528) (xy 36.152074 -297.079924) (xy 36.170425 -297.063863) (xy 36.210963 -297.036752)
			(xy 36.25504 -297.015886) (xy 36.301703 -297.001714) (xy 36.349941 -296.994546) (xy 36.374324 -296.994072)
			(xy 37.324538 -296.994072) (xy 37.350525 -296.994584) (xy 37.401858 -297.00272) (xy 37.451286 -297.018786)
			(xy 37.497593 -297.042385) (xy 37.539639 -297.072937) (xy 37.576388 -297.10969) (xy 37.606935 -297.151739)
			(xy 37.630529 -297.198049) (xy 37.646589 -297.247479) (xy 37.654719 -297.298813) (xy 37.654719 -297.32478)
			(xy 37.968948 -297.32478) (xy 37.972908 -297.275726) (xy 37.984685 -297.227942) (xy 38.003976 -297.182666)
			(xy 38.030279 -297.14107) (xy 38.062914 -297.104233) (xy 38.101035 -297.073108) (xy 38.143656 -297.048501)
			(xy 38.189672 -297.031049) (xy 38.237891 -297.021205) (xy 38.287066 -297.019224) (xy 38.335921 -297.025156)
			(xy 38.383192 -297.038848) (xy 38.427654 -297.059946) (xy 38.468157 -297.087902) (xy 38.50365 -297.121994)
			(xy 38.533215 -297.161338) (xy 38.556086 -297.204915) (xy 38.57167 -297.251596) (xy 38.579565 -297.300173)
			(xy 38.58006 -297.32478) (xy 38.919162 -297.32478) (xy 38.923122 -297.275726) (xy 38.934899 -297.227942)
			(xy 38.95419 -297.182666) (xy 38.980493 -297.14107) (xy 39.013128 -297.104233) (xy 39.051249 -297.073108)
			(xy 39.09387 -297.048501) (xy 39.139886 -297.031049) (xy 39.188105 -297.021205) (xy 39.23728 -297.019224)
			(xy 39.286135 -297.025156) (xy 39.333406 -297.038848) (xy 39.377868 -297.059946) (xy 39.418371 -297.087902)
			(xy 39.453864 -297.121994) (xy 39.483429 -297.161338) (xy 39.5063 -297.204915) (xy 39.521884 -297.251596)
			(xy 39.529779 -297.300173) (xy 39.530274 -297.32478) (xy 39.529779 -297.349387) (xy 39.521884 -297.397964)
			(xy 39.5063 -297.444645) (xy 39.483429 -297.488222) (xy 39.453864 -297.527566) (xy 39.418371 -297.561658)
			(xy 39.377868 -297.589614) (xy 39.333406 -297.610712) (xy 39.286135 -297.624404) (xy 39.23728 -297.630336)
			(xy 39.188105 -297.628355) (xy 39.139886 -297.618511) (xy 39.09387 -297.601059) (xy 39.051249 -297.576452)
			(xy 39.013128 -297.545327) (xy 38.980493 -297.50849) (xy 38.95419 -297.466894) (xy 38.934899 -297.421618)
			(xy 38.923122 -297.373834) (xy 38.919162 -297.32478) (xy 38.58006 -297.32478) (xy 38.579565 -297.349387)
			(xy 38.57167 -297.397964) (xy 38.556086 -297.444645) (xy 38.533215 -297.488222) (xy 38.50365 -297.527566)
			(xy 38.468157 -297.561658) (xy 38.427654 -297.589614) (xy 38.383192 -297.610712) (xy 38.335921 -297.624404)
			(xy 38.287066 -297.630336) (xy 38.237891 -297.628355) (xy 38.189672 -297.618511) (xy 38.143656 -297.601059)
			(xy 38.101035 -297.576452) (xy 38.062914 -297.545327) (xy 38.030279 -297.50849) (xy 38.003976 -297.466894)
			(xy 37.984685 -297.421618) (xy 37.972908 -297.373834) (xy 37.968948 -297.32478) (xy 37.654719 -297.32478)
			(xy 37.654719 -297.350787) (xy 37.646589 -297.402121) (xy 37.630529 -297.451551) (xy 37.606935 -297.497861)
			(xy 37.576388 -297.53991) (xy 37.539639 -297.576663) (xy 37.497593 -297.607215) (xy 37.451286 -297.630814)
			(xy 37.401858 -297.64688) (xy 37.350525 -297.655016) (xy 37.324538 -297.655488) (xy 36.713922 -297.655488)
			(xy 36.703973 -297.65603) (xy 36.685604 -297.663699) (xy 36.671503 -297.677749) (xy 36.667186 -297.68673)
			(xy 36.663643 -297.696175) (xy 36.663543 -297.71633) (xy 36.671258 -297.734951) (xy 36.678108 -297.742356)
			(xy 36.962842 -298.02709) (xy 36.969954 -298.032932) (xy 36.975717 -298.03651) (xy 36.988594 -298.040757)
			(xy 36.995354 -298.041314) (xy 37.063934 -298.043092) (xy 37.066982 -298.043092) (xy 37.071915 -298.043103)
			(xy 37.081639 -298.041447) (xy 37.086286 -298.03979) (xy 37.094922 -298.036488) (xy 37.102288 -298.029884)
			(xy 37.120638 -298.013821) (xy 37.161175 -297.986708) (xy 37.205252 -297.965839) (xy 37.251916 -297.951667)
			(xy 37.300154 -297.944499) (xy 37.324538 -297.944032) (xy 37.350524 -297.944518) (xy 37.401856 -297.952654)
			(xy 37.451283 -297.96872) (xy 37.497588 -297.992321) (xy 37.539631 -298.022874) (xy 37.576376 -298.059629)
			(xy 37.60692 -298.101679) (xy 37.63051 -298.147989) (xy 37.646564 -298.19742) (xy 37.654688 -298.248754)
			(xy 37.655246 -298.27474) (xy 37.968948 -298.27474) (xy 37.972908 -298.225686) (xy 37.984685 -298.177902)
			(xy 38.003976 -298.132626) (xy 38.030279 -298.09103) (xy 38.062914 -298.054193) (xy 38.101035 -298.023068)
			(xy 38.143656 -297.998461) (xy 38.189672 -297.981009) (xy 38.237891 -297.971165) (xy 38.287066 -297.969184)
			(xy 38.335921 -297.975116) (xy 38.383192 -297.988808) (xy 38.427654 -298.009906) (xy 38.468157 -298.037862)
			(xy 38.50365 -298.071954) (xy 38.533215 -298.111298) (xy 38.556086 -298.154875) (xy 38.57167 -298.201556)
			(xy 38.579565 -298.250133) (xy 38.58006 -298.27474) (xy 38.579565 -298.299347) (xy 38.57167 -298.347924)
			(xy 38.556086 -298.394605) (xy 38.533215 -298.438182) (xy 38.50365 -298.477526) (xy 38.468157 -298.511618)
			(xy 38.427654 -298.539574) (xy 38.383192 -298.560672) (xy 38.335921 -298.574364) (xy 38.287066 -298.580296)
			(xy 38.237891 -298.578315) (xy 38.189672 -298.568471) (xy 38.143656 -298.551019) (xy 38.101035 -298.526412)
			(xy 38.062914 -298.495287) (xy 38.030279 -298.45845) (xy 38.003976 -298.416854) (xy 37.984685 -298.371578)
			(xy 37.972908 -298.323794) (xy 37.968948 -298.27474) (xy 37.655246 -298.27474) (xy 37.654814 -298.299127)
			(xy 37.647656 -298.347373) (xy 37.633485 -298.394043) (xy 37.61261 -298.438125) (xy 37.585484 -298.47866)
			(xy 37.569394 -298.49699) (xy 37.56279 -298.504356) (xy 37.559488 -298.512992) (xy 37.557959 -298.517278)
			(xy 37.556294 -298.526223) (xy 37.556186 -298.530772) (xy 37.556694 -298.548298) (xy 37.558218 -298.605448)
			(xy 37.558902 -298.611648) (xy 37.562887 -298.623465) (xy 37.566092 -298.628816) (xy 37.56914 -298.63288)
			(xy 37.572696 -298.636944) (xy 37.932614 -298.996862) (xy 37.938991 -299.002089) (xy 37.954147 -299.008558)
			(xy 37.962332 -299.009562) (xy 38.03523 -299.01134) (xy 38.0401 -299.011332) (xy 38.049695 -299.009679)
			(xy 38.05428 -299.008038) (xy 38.062916 -299.004736) (xy 38.070282 -298.998132) (xy 38.0872 -298.98343)
			(xy 38.124535 -298.958631) (xy 38.165092 -298.939552) (xy 38.208001 -298.926603) (xy 38.252342 -298.920063)
			(xy 38.274752 -298.919646) (xy 38.298749 -298.920089) (xy 38.346153 -298.927589) (xy 38.3918 -298.942413)
			(xy 38.434566 -298.964195) (xy 38.473398 -298.992399) (xy 38.50734 -299.02633) (xy 38.535556 -299.065154)
			(xy 38.557351 -299.107913) (xy 38.572189 -299.153556) (xy 38.579704 -299.200957) (xy 38.58006 -299.224954)
			(xy 38.579484 -299.251502) (xy 38.570295 -299.303797) (xy 38.552203 -299.353715) (xy 38.525752 -299.399754)
			(xy 38.491741 -299.440526) (xy 38.471856 -299.458126) (xy 38.470078 -299.45965) (xy 38.468554 -299.461174)
			(xy 38.461865 -299.468585) (xy 38.45426 -299.48702) (xy 38.454257 -299.506963) (xy 38.461856 -299.525401)
			(xy 38.468554 -299.532802) (xy 38.504368 -299.568616) (xy 38.511777 -299.575304) (xy 38.530212 -299.582895)
			(xy 38.540182 -299.583348) (xy 38.909498 -299.583348) (xy 38.91859 -299.582922) (xy 38.935598 -299.576474)
			(xy 38.949286 -299.564496) (xy 38.953948 -299.556678) (xy 38.975284 -299.512736) (xy 38.975284 -299.512228)
			(xy 38.98265 -299.496988) (xy 38.98646 -299.486066) (xy 38.988339 -299.474297) (xy 38.982383 -299.451249)
			(xy 38.97503 -299.44187) (xy 38.959865 -299.423771) (xy 38.934323 -299.384058) (xy 38.914698 -299.341112)
			(xy 38.90139 -299.295808) (xy 38.894671 -299.249071) (xy 38.894258 -299.225462) (xy 38.894258 -299.224954)
			(xy 38.894771 -299.198963) (xy 38.902906 -299.14762) (xy 38.918968 -299.09818) (xy 38.942562 -299.05186)
			(xy 38.973109 -299.009799) (xy 39.009856 -298.973031) (xy 39.0519 -298.942461) (xy 39.098207 -298.91884)
			(xy 39.147637 -298.90275) (xy 39.198975 -298.894586) (xy 39.224966 -298.893992) (xy 39.26967 -298.893992)
			(xy 39.280392 -298.893568) (xy 39.299989 -298.884877) (xy 39.307516 -298.877228) (xy 39.365174 -298.813474)
			(xy 39.371778 -298.793154) (xy 39.370762 -298.782486) (xy 39.368984 -298.749974) (xy 39.368984 -298.749466)
			(xy 39.369154 -298.735876) (xy 39.371446 -298.708791) (xy 39.373556 -298.695364) (xy 39.375588 -298.68368)
			(xy 39.368476 -298.66082) (xy 39.303706 -298.593002) (xy 39.295177 -298.585008) (xy 39.273213 -298.577079)
			(xy 39.261542 -298.577762) (xy 39.261288 -298.577762) (xy 39.252244 -298.578809) (xy 39.23407 -298.579951)
			(xy 39.224966 -298.580048) (xy 39.200142 -298.579559) (xy 39.151148 -298.571522) (xy 39.104101 -298.555663)
			(xy 39.060238 -298.532403) (xy 39.020717 -298.502352) (xy 38.986578 -298.466304) (xy 38.958721 -298.425207)
			(xy 38.937879 -298.380145) (xy 38.924602 -298.332305) (xy 38.91924 -298.282947) (xy 38.921934 -298.233372)
			(xy 38.932613 -298.184885) (xy 38.950995 -298.138765) (xy 38.976596 -298.096227) (xy 39.008743 -298.05839)
			(xy 39.046587 -298.026253) (xy 39.089132 -298.000662) (xy 39.135256 -297.982291) (xy 39.183745 -297.971624)
			(xy 39.233321 -297.968942) (xy 39.282678 -297.974316) (xy 39.330515 -297.987605) (xy 39.375572 -298.008457)
			(xy 39.416662 -298.036324) (xy 39.452702 -298.070472) (xy 39.482743 -298.110001) (xy 39.505993 -298.153869)
			(xy 39.521839 -298.20092) (xy 39.529865 -298.249916) (xy 39.530274 -298.27474) (xy 39.530171 -298.283781)
			(xy 39.52903 -298.301827) (xy 39.527988 -298.310808) (xy 39.527988 -298.311316) (xy 39.526718 -298.323)
			(xy 39.534846 -298.345352) (xy 39.611046 -298.41825) (xy 39.633906 -298.425362) (xy 39.64559 -298.42333)
			(xy 39.659083 -298.421261) (xy 39.686296 -298.419095) (xy 39.699946 -298.419012) (xy 39.770304 -298.419012)
			(xy 39.780998 -298.418453) (xy 39.80056 -298.4098) (xy 39.80815 -298.402248) (xy 39.865808 -298.337732)
			(xy 39.872412 -298.317412) (xy 39.871396 -298.306744) (xy 39.869618 -298.27474) (xy 39.87014 -298.249485)
			(xy 39.878453 -298.199663) (xy 39.894854 -298.151889) (xy 39.918895 -298.107466) (xy 39.949919 -298.067606)
			(xy 39.987081 -298.033396) (xy 40.029367 -298.00577) (xy 40.075623 -297.98548) (xy 40.124588 -297.97308)
			(xy 40.174926 -297.968909) (xy 40.225264 -297.97308) (xy 40.274229 -297.98548) (xy 40.320485 -298.00577)
			(xy 40.362771 -298.033396) (xy 40.399933 -298.067606) (xy 40.430957 -298.107466) (xy 40.454998 -298.151889)
			(xy 40.471399 -298.199663) (xy 40.479712 -298.249485) (xy 40.480234 -298.27474) (xy 40.478456 -298.30649)
			(xy 40.478456 -298.306998) (xy 40.47744 -298.317412) (xy 40.484044 -298.337732) (xy 40.541702 -298.402248)
			(xy 40.549218 -298.409909) (xy 40.568824 -298.418594) (xy 40.579548 -298.419012) (xy 40.649906 -298.419012)
			(xy 40.663556 -298.41911) (xy 40.690769 -298.421269) (xy 40.704262 -298.42333) (xy 40.715946 -298.425362)
			(xy 40.738806 -298.41825) (xy 40.806624 -298.35348) (xy 40.81461 -298.344948) (xy 40.822523 -298.322986)
			(xy 40.821864 -298.311316) (xy 40.821864 -298.311062) (xy 40.820814 -298.302018) (xy 40.819668 -298.283844)
			(xy 40.819578 -298.27474) (xy 40.820061 -298.249917) (xy 40.828086 -298.200924) (xy 40.843933 -298.153875)
			(xy 40.867182 -298.11001) (xy 40.897223 -298.070484) (xy 40.933262 -298.036339) (xy 40.97435 -298.008475)
			(xy 41.019406 -297.987625) (xy 41.067241 -297.974339) (xy 41.116596 -297.968968) (xy 41.166169 -297.971652)
			(xy 41.214655 -297.982321) (xy 41.260776 -298.000695) (xy 41.303316 -298.026287) (xy 41.341156 -298.058426)
			(xy 41.373297 -298.096263) (xy 41.398894 -298.138801) (xy 41.417271 -298.18492) (xy 41.427944 -298.233405)
			(xy 41.430186 -298.27474) (xy 41.769042 -298.27474) (xy 41.773002 -298.225686) (xy 41.784779 -298.177902)
			(xy 41.80407 -298.132626) (xy 41.830373 -298.09103) (xy 41.863008 -298.054193) (xy 41.901129 -298.023068)
			(xy 41.94375 -297.998461) (xy 41.989766 -297.981009) (xy 42.037985 -297.971165) (xy 42.08716 -297.969184)
			(xy 42.136015 -297.975116) (xy 42.183286 -297.988808) (xy 42.227748 -298.009906) (xy 42.268251 -298.037862)
			(xy 42.303744 -298.071954) (xy 42.333309 -298.111298) (xy 42.35618 -298.154875) (xy 42.371764 -298.201556)
			(xy 42.379659 -298.250133) (xy 42.380154 -298.27474) (xy 43.668962 -298.27474) (xy 43.672922 -298.225686)
			(xy 43.684699 -298.177902) (xy 43.70399 -298.132626) (xy 43.730293 -298.09103) (xy 43.762928 -298.054193)
			(xy 43.801049 -298.023068) (xy 43.84367 -297.998461) (xy 43.889686 -297.981009) (xy 43.937905 -297.971165)
			(xy 43.98708 -297.969184) (xy 44.035935 -297.975116) (xy 44.083206 -297.988808) (xy 44.127668 -298.009906)
			(xy 44.168171 -298.037862) (xy 44.203664 -298.071954) (xy 44.233229 -298.111298) (xy 44.2561 -298.154875)
			(xy 44.271684 -298.201556) (xy 44.279579 -298.250133) (xy 44.280074 -298.27474) (xy 44.619176 -298.27474)
			(xy 44.623136 -298.225686) (xy 44.634913 -298.177902) (xy 44.654204 -298.132626) (xy 44.680507 -298.09103)
			(xy 44.713142 -298.054193) (xy 44.751263 -298.023068) (xy 44.793884 -297.998461) (xy 44.8399 -297.981009)
			(xy 44.888119 -297.971165) (xy 44.937294 -297.969184) (xy 44.986149 -297.975116) (xy 45.03342 -297.988808)
			(xy 45.077882 -298.009906) (xy 45.118385 -298.037862) (xy 45.153878 -298.071954) (xy 45.183443 -298.111298)
			(xy 45.206314 -298.154875) (xy 45.221898 -298.201556) (xy 45.229793 -298.250133) (xy 45.230288 -298.27474)
			(xy 45.569136 -298.27474) (xy 45.573096 -298.225686) (xy 45.584873 -298.177902) (xy 45.604164 -298.132626)
			(xy 45.630467 -298.09103) (xy 45.663102 -298.054193) (xy 45.701223 -298.023068) (xy 45.743844 -297.998461)
			(xy 45.78986 -297.981009) (xy 45.838079 -297.971165) (xy 45.887254 -297.969184) (xy 45.936109 -297.975116)
			(xy 45.98338 -297.988808) (xy 46.027842 -298.009906) (xy 46.068345 -298.037862) (xy 46.103838 -298.071954)
			(xy 46.133403 -298.111298) (xy 46.156274 -298.154875) (xy 46.171858 -298.201556) (xy 46.179753 -298.250133)
			(xy 46.180248 -298.27474) (xy 46.179753 -298.299347) (xy 46.171858 -298.347924) (xy 46.156274 -298.394605)
			(xy 46.133403 -298.438182) (xy 46.103838 -298.477526) (xy 46.068345 -298.511618) (xy 46.027842 -298.539574)
			(xy 45.98338 -298.560672) (xy 45.936109 -298.574364) (xy 45.887254 -298.580296) (xy 45.838079 -298.578315)
			(xy 45.78986 -298.568471) (xy 45.743844 -298.551019) (xy 45.701223 -298.526412) (xy 45.663102 -298.495287)
			(xy 45.630467 -298.45845) (xy 45.604164 -298.416854) (xy 45.584873 -298.371578) (xy 45.573096 -298.323794)
			(xy 45.569136 -298.27474) (xy 45.230288 -298.27474) (xy 45.229793 -298.299347) (xy 45.221898 -298.347924)
			(xy 45.206314 -298.394605) (xy 45.183443 -298.438182) (xy 45.153878 -298.477526) (xy 45.118385 -298.511618)
			(xy 45.077882 -298.539574) (xy 45.03342 -298.560672) (xy 44.986149 -298.574364) (xy 44.937294 -298.580296)
			(xy 44.888119 -298.578315) (xy 44.8399 -298.568471) (xy 44.793884 -298.551019) (xy 44.751263 -298.526412)
			(xy 44.713142 -298.495287) (xy 44.680507 -298.45845) (xy 44.654204 -298.416854) (xy 44.634913 -298.371578)
			(xy 44.623136 -298.323794) (xy 44.619176 -298.27474) (xy 44.280074 -298.27474) (xy 44.279579 -298.299347)
			(xy 44.271684 -298.347924) (xy 44.2561 -298.394605) (xy 44.233229 -298.438182) (xy 44.203664 -298.477526)
			(xy 44.168171 -298.511618) (xy 44.127668 -298.539574) (xy 44.083206 -298.560672) (xy 44.035935 -298.574364)
			(xy 43.98708 -298.580296) (xy 43.937905 -298.578315) (xy 43.889686 -298.568471) (xy 43.84367 -298.551019)
			(xy 43.801049 -298.526412) (xy 43.762928 -298.495287) (xy 43.730293 -298.45845) (xy 43.70399 -298.416854)
			(xy 43.684699 -298.371578) (xy 43.672922 -298.323794) (xy 43.668962 -298.27474) (xy 42.380154 -298.27474)
			(xy 42.379659 -298.299347) (xy 42.371764 -298.347924) (xy 42.35618 -298.394605) (xy 42.333309 -298.438182)
			(xy 42.303744 -298.477526) (xy 42.268251 -298.511618) (xy 42.227748 -298.539574) (xy 42.183286 -298.560672)
			(xy 42.136015 -298.574364) (xy 42.08716 -298.580296) (xy 42.037985 -298.578315) (xy 41.989766 -298.568471)
			(xy 41.94375 -298.551019) (xy 41.901129 -298.526412) (xy 41.863008 -298.495287) (xy 41.830373 -298.45845)
			(xy 41.80407 -298.416854) (xy 41.784779 -298.371578) (xy 41.773002 -298.323794) (xy 41.769042 -298.27474)
			(xy 41.430186 -298.27474) (xy 41.430633 -298.282978) (xy 41.425266 -298.332333) (xy 41.411984 -298.38017)
			(xy 41.391138 -298.425227) (xy 41.363277 -298.466318) (xy 41.329135 -298.50236) (xy 41.289612 -298.532404)
			(xy 41.245749 -298.555657) (xy 41.198701 -298.571507) (xy 41.149709 -298.579537) (xy 41.124886 -298.580048)
			(xy 41.115845 -298.579943) (xy 41.0978 -298.578797) (xy 41.088818 -298.577762) (xy 41.08831 -298.577762)
			(xy 41.076626 -298.576492) (xy 41.054274 -298.58462) (xy 40.981376 -298.66082) (xy 40.974264 -298.68368)
			(xy 40.976296 -298.695364) (xy 40.978425 -298.708852) (xy 40.980713 -298.736066) (xy 40.980868 -298.74972)
			(xy 40.980713 -298.763438) (xy 40.978422 -298.790777) (xy 40.976296 -298.80433) (xy 40.974264 -298.816014)
			(xy 40.981376 -298.838874) (xy 41.054528 -298.915328) (xy 41.076372 -298.923456) (xy 41.082468 -298.922694)
			(xy 41.093017 -298.921293) (xy 41.114245 -298.919769) (xy 41.124886 -298.919646) (xy 41.148879 -298.920116)
			(xy 41.196275 -298.92762) (xy 41.241914 -298.942445) (xy 41.284672 -298.964227) (xy 41.323496 -298.99243)
			(xy 41.357431 -299.026358) (xy 41.385641 -299.065177) (xy 41.407432 -299.10793) (xy 41.422266 -299.153566)
			(xy 41.42978 -299.200961) (xy 41.43019 -299.2247) (xy 41.769042 -299.2247) (xy 41.773002 -299.175646)
			(xy 41.784779 -299.127862) (xy 41.80407 -299.082586) (xy 41.830373 -299.04099) (xy 41.863008 -299.004153)
			(xy 41.901129 -298.973028) (xy 41.94375 -298.948421) (xy 41.989766 -298.930969) (xy 42.037985 -298.921125)
			(xy 42.08716 -298.919144) (xy 42.136015 -298.925076) (xy 42.183286 -298.938768) (xy 42.227748 -298.959866)
			(xy 42.268251 -298.987822) (xy 42.303744 -299.021914) (xy 42.333309 -299.061258) (xy 42.35618 -299.104835)
			(xy 42.371764 -299.151516) (xy 42.379659 -299.200093) (xy 42.380154 -299.2247) (xy 42.380149 -299.224954)
			(xy 43.668962 -299.224954) (xy 43.672922 -299.1759) (xy 43.684699 -299.128116) (xy 43.70399 -299.08284)
			(xy 43.730293 -299.041244) (xy 43.762928 -299.004407) (xy 43.801049 -298.973282) (xy 43.84367 -298.948675)
			(xy 43.889686 -298.931223) (xy 43.937905 -298.921379) (xy 43.98708 -298.919398) (xy 44.035935 -298.92533)
			(xy 44.083206 -298.939022) (xy 44.127668 -298.96012) (xy 44.168171 -298.988076) (xy 44.203664 -299.022168)
			(xy 44.233229 -299.061512) (xy 44.2561 -299.105089) (xy 44.271684 -299.15177) (xy 44.279579 -299.200347)
			(xy 44.280074 -299.224954) (xy 44.619176 -299.224954) (xy 44.623136 -299.1759) (xy 44.634913 -299.128116)
			(xy 44.654204 -299.08284) (xy 44.680507 -299.041244) (xy 44.713142 -299.004407) (xy 44.751263 -298.973282)
			(xy 44.793884 -298.948675) (xy 44.8399 -298.931223) (xy 44.888119 -298.921379) (xy 44.937294 -298.919398)
			(xy 44.986149 -298.92533) (xy 45.03342 -298.939022) (xy 45.077882 -298.96012) (xy 45.118385 -298.988076)
			(xy 45.153878 -299.022168) (xy 45.183443 -299.061512) (xy 45.206314 -299.105089) (xy 45.221898 -299.15177)
			(xy 45.229793 -299.200347) (xy 45.230288 -299.224954) (xy 45.569136 -299.224954) (xy 45.573096 -299.1759)
			(xy 45.584873 -299.128116) (xy 45.604164 -299.08284) (xy 45.630467 -299.041244) (xy 45.663102 -299.004407)
			(xy 45.701223 -298.973282) (xy 45.743844 -298.948675) (xy 45.78986 -298.931223) (xy 45.838079 -298.921379)
			(xy 45.887254 -298.919398) (xy 45.936109 -298.92533) (xy 45.98338 -298.939022) (xy 46.027842 -298.96012)
			(xy 46.068345 -298.988076) (xy 46.103838 -299.022168) (xy 46.133403 -299.061512) (xy 46.156274 -299.105089)
			(xy 46.171858 -299.15177) (xy 46.179753 -299.200347) (xy 46.180248 -299.224954) (xy 46.519096 -299.224954)
			(xy 46.523056 -299.1759) (xy 46.534833 -299.128116) (xy 46.554124 -299.08284) (xy 46.580427 -299.041244)
			(xy 46.613062 -299.004407) (xy 46.651183 -298.973282) (xy 46.693804 -298.948675) (xy 46.73982 -298.931223)
			(xy 46.788039 -298.921379) (xy 46.837214 -298.919398) (xy 46.886069 -298.92533) (xy 46.93334 -298.939022)
			(xy 46.977802 -298.96012) (xy 47.018305 -298.988076) (xy 47.053798 -299.022168) (xy 47.083363 -299.061512)
			(xy 47.106234 -299.105089) (xy 47.121818 -299.15177) (xy 47.129713 -299.200347) (xy 47.130208 -299.224954)
			(xy 47.129713 -299.249561) (xy 47.121818 -299.298138) (xy 47.106234 -299.344819) (xy 47.083363 -299.388396)
			(xy 47.053798 -299.42774) (xy 47.018305 -299.461832) (xy 46.977802 -299.489788) (xy 46.93334 -299.510886)
			(xy 46.886069 -299.524578) (xy 46.837214 -299.53051) (xy 46.788039 -299.528529) (xy 46.73982 -299.518685)
			(xy 46.693804 -299.501233) (xy 46.651183 -299.476626) (xy 46.613062 -299.445501) (xy 46.580427 -299.408664)
			(xy 46.554124 -299.367068) (xy 46.534833 -299.321792) (xy 46.523056 -299.274008) (xy 46.519096 -299.224954)
			(xy 46.180248 -299.224954) (xy 46.179753 -299.249561) (xy 46.171858 -299.298138) (xy 46.156274 -299.344819)
			(xy 46.133403 -299.388396) (xy 46.103838 -299.42774) (xy 46.068345 -299.461832) (xy 46.027842 -299.489788)
			(xy 45.98338 -299.510886) (xy 45.936109 -299.524578) (xy 45.887254 -299.53051) (xy 45.838079 -299.528529)
			(xy 45.78986 -299.518685) (xy 45.743844 -299.501233) (xy 45.701223 -299.476626) (xy 45.663102 -299.445501)
			(xy 45.630467 -299.408664) (xy 45.604164 -299.367068) (xy 45.584873 -299.321792) (xy 45.573096 -299.274008)
			(xy 45.569136 -299.224954) (xy 45.230288 -299.224954) (xy 45.229793 -299.249561) (xy 45.221898 -299.298138)
			(xy 45.206314 -299.344819) (xy 45.183443 -299.388396) (xy 45.153878 -299.42774) (xy 45.118385 -299.461832)
			(xy 45.077882 -299.489788) (xy 45.03342 -299.510886) (xy 44.986149 -299.524578) (xy 44.937294 -299.53051)
			(xy 44.888119 -299.528529) (xy 44.8399 -299.518685) (xy 44.793884 -299.501233) (xy 44.751263 -299.476626)
			(xy 44.713142 -299.445501) (xy 44.680507 -299.408664) (xy 44.654204 -299.367068) (xy 44.634913 -299.321792)
			(xy 44.623136 -299.274008) (xy 44.619176 -299.224954) (xy 44.280074 -299.224954) (xy 44.279579 -299.249561)
			(xy 44.271684 -299.298138) (xy 44.2561 -299.344819) (xy 44.233229 -299.388396) (xy 44.203664 -299.42774)
			(xy 44.168171 -299.461832) (xy 44.127668 -299.489788) (xy 44.083206 -299.510886) (xy 44.035935 -299.524578)
			(xy 43.98708 -299.53051) (xy 43.937905 -299.528529) (xy 43.889686 -299.518685) (xy 43.84367 -299.501233)
			(xy 43.801049 -299.476626) (xy 43.762928 -299.445501) (xy 43.730293 -299.408664) (xy 43.70399 -299.367068)
			(xy 43.684699 -299.321792) (xy 43.672922 -299.274008) (xy 43.668962 -299.224954) (xy 42.380149 -299.224954)
			(xy 42.379659 -299.249307) (xy 42.371764 -299.297884) (xy 42.35618 -299.344565) (xy 42.333309 -299.388142)
			(xy 42.303744 -299.427486) (xy 42.268251 -299.461578) (xy 42.227748 -299.489534) (xy 42.183286 -299.510632)
			(xy 42.136015 -299.524324) (xy 42.08716 -299.530256) (xy 42.037985 -299.528275) (xy 41.989766 -299.518431)
			(xy 41.94375 -299.500979) (xy 41.901129 -299.476372) (xy 41.863008 -299.445247) (xy 41.830373 -299.40841)
			(xy 41.80407 -299.366814) (xy 41.784779 -299.321538) (xy 41.773002 -299.273754) (xy 41.769042 -299.2247)
			(xy 41.43019 -299.2247) (xy 41.430194 -299.224954) (xy 41.430194 -299.225462) (xy 41.429651 -299.250713)
			(xy 41.421296 -299.300521) (xy 41.404858 -299.348275) (xy 41.380785 -299.392672) (xy 41.365678 -299.412914)
			(xy 41.361614 -299.417994) (xy 41.350438 -299.444156) (xy 41.349676 -299.450506) (xy 41.351962 -299.464984)
			(xy 41.356788 -299.47489) (xy 41.394634 -299.554392) (xy 41.399115 -299.562832) (xy 41.413069 -299.575867)
			(xy 41.430809 -299.582933) (xy 41.440354 -299.583348) (xy 41.448228 -299.583348) (xy 41.492947 -299.583868)
			(xy 41.581998 -299.592176) (xy 41.669897 -299.608689) (xy 41.755892 -299.633265) (xy 41.839243 -299.665695)
			(xy 41.919235 -299.705699) (xy 41.995182 -299.752935) (xy 42.066431 -299.806996) (xy 42.099738 -299.83684)
			(xy 42.106342 -299.84319) (xy 42.131488 -299.85335) (xy 42.14114 -299.856144) (xy 42.150284 -299.856906)
			(xy 47.610268 -299.856906)
		)
		(stroke
			(width 0)
			(type solid)
		)
		(fill yes)
		(layer "In7.Cu")
		(net "SYSPLL_VDDA18_PEX0")
	)
	(gr_poly
		(pts
			(xy 256.686812 -301.515272) (xy 256.69484 -301.515027) (xy 256.710116 -301.510098) (xy 256.716784 -301.50562)
			(xy 256.748228 -301.483321) (xy 256.814013 -301.443126) (xy 256.88273 -301.408179) (xy 256.918206 -301.393098)
			(xy 257.64871 -301.090584) (xy 257.653536 -301.088552) (xy 257.65379 -301.088552) (xy 257.991356 -300.948598)
			(xy 257.997198 -300.945804) (xy 258.000552 -300.943805) (xy 258.006671 -300.938955) (xy 258.00939 -300.936152)
			(xy 258.019804 -300.924976) (xy 258.023614 -300.920912) (xy 258.034028 -300.903894) (xy 258.035552 -300.899068)
			(xy 258.046006 -300.872313) (xy 258.073793 -300.822041) (xy 258.108806 -300.776504) (xy 258.150251 -300.736734)
			(xy 258.197193 -300.70363) (xy 258.248569 -300.67794) (xy 258.303216 -300.660246) (xy 258.359899 -300.650949)
			(xy 258.388612 -300.650148) (xy 258.3942 -300.650148) (xy 258.422923 -300.650725) (xy 258.479703 -300.659462)
			(xy 258.534525 -300.676632) (xy 258.56057 -300.688756) (xy 258.565904 -300.691296) (xy 258.57962 -300.694598)
			(xy 258.584515 -300.695576) (xy 258.594493 -300.695831) (xy 258.599432 -300.695106) (xy 258.605528 -300.69409)
			(xy 260.181598 -300.04131) (xy 260.190611 -300.037042) (xy 260.204686 -300.022944) (xy 260.212298 -300.004535)
			(xy 260.21284 -299.994574) (xy 260.21284 -299.551344) (xy 260.21241 -299.542441) (xy 260.206241 -299.525734)
			(xy 260.194734 -299.51214) (xy 260.187186 -299.507402) (xy 260.098794 -299.456602) (xy 260.072124 -299.456856)
			(xy 260.060186 -299.463714) (xy 260.038325 -299.475883) (xy 259.992113 -299.495061) (xy 259.943794 -299.508043)
			(xy 259.894194 -299.514609) (xy 259.869178 -299.515022) (xy 259.868924 -299.515022) (xy 259.841669 -299.514561)
			(xy 259.787713 -299.506806) (xy 259.735411 -299.491452) (xy 259.685826 -299.46881) (xy 259.639968 -299.439341)
			(xy 259.598771 -299.403646) (xy 259.563073 -299.362451) (xy 259.533602 -299.316595) (xy 259.510957 -299.267012)
			(xy 259.495599 -299.21471) (xy 259.487841 -299.160755) (xy 259.487841 -299.106245) (xy 259.495599 -299.05229)
			(xy 259.510957 -298.999988) (xy 259.533602 -298.950405) (xy 259.563073 -298.904549) (xy 259.598771 -298.863354)
			(xy 259.639968 -298.827659) (xy 259.685826 -298.79819) (xy 259.735411 -298.775548) (xy 259.787713 -298.760194)
			(xy 259.841669 -298.752439) (xy 259.868924 -298.752006) (xy 259.869178 -298.752006) (xy 259.894198 -298.752394)
			(xy 259.943808 -298.75893) (xy 259.992135 -298.771906) (xy 260.038348 -298.791099) (xy 260.060186 -298.803314)
			(xy 260.072124 -298.810172) (xy 260.098794 -298.810426) (xy 260.186424 -298.760388) (xy 260.19125 -298.755308)
			(xy 260.197854 -298.748704) (xy 260.204706 -298.741308) (xy 260.212449 -298.722709) (xy 260.21284 -298.712636)
			(xy 260.21284 -296.350944) (xy 260.21241 -296.342041) (xy 260.206241 -296.325334) (xy 260.194734 -296.31174)
			(xy 260.187186 -296.307002) (xy 260.098794 -296.256202) (xy 260.072124 -296.256456) (xy 260.060186 -296.263314)
			(xy 260.038325 -296.275483) (xy 259.992113 -296.294661) (xy 259.943794 -296.307643) (xy 259.894194 -296.314209)
			(xy 259.869178 -296.314622) (xy 259.868924 -296.314622) (xy 259.841669 -296.314161) (xy 259.787713 -296.306406)
			(xy 259.735411 -296.291052) (xy 259.685826 -296.26841) (xy 259.639968 -296.238941) (xy 259.598771 -296.203246)
			(xy 259.563073 -296.162051) (xy 259.533602 -296.116195) (xy 259.510957 -296.066612) (xy 259.495599 -296.01431)
			(xy 259.487841 -295.960355) (xy 259.487841 -295.905845) (xy 259.495599 -295.85189) (xy 259.510957 -295.799588)
			(xy 259.533602 -295.750005) (xy 259.563073 -295.704149) (xy 259.598771 -295.662954) (xy 259.639968 -295.627259)
			(xy 259.685826 -295.59779) (xy 259.735411 -295.575148) (xy 259.787713 -295.559794) (xy 259.841669 -295.552039)
			(xy 259.868924 -295.551606) (xy 259.869178 -295.551606) (xy 259.894198 -295.551994) (xy 259.943808 -295.55853)
			(xy 259.992135 -295.571506) (xy 260.038348 -295.590699) (xy 260.060186 -295.602914) (xy 260.072124 -295.609772)
			(xy 260.098794 -295.610026) (xy 260.186424 -295.559988) (xy 260.19125 -295.554908) (xy 260.197854 -295.548304)
			(xy 260.204706 -295.540908) (xy 260.212449 -295.522309) (xy 260.21284 -295.512236) (xy 260.21284 -293.150544)
			(xy 260.21241 -293.141641) (xy 260.206241 -293.124934) (xy 260.194734 -293.11134) (xy 260.187186 -293.106602)
			(xy 260.098794 -293.055802) (xy 260.072124 -293.056056) (xy 260.060186 -293.062914) (xy 260.038325 -293.075083)
			(xy 259.992113 -293.094261) (xy 259.943794 -293.107243) (xy 259.894194 -293.113809) (xy 259.869178 -293.114222)
			(xy 259.868924 -293.114222) (xy 259.841669 -293.113761) (xy 259.787713 -293.106006) (xy 259.735411 -293.090652)
			(xy 259.685826 -293.06801) (xy 259.639968 -293.038541) (xy 259.598771 -293.002846) (xy 259.563073 -292.961651)
			(xy 259.533602 -292.915795) (xy 259.510957 -292.866212) (xy 259.495599 -292.81391) (xy 259.487841 -292.759955)
			(xy 259.487841 -292.705445) (xy 259.495599 -292.65149) (xy 259.510957 -292.599188) (xy 259.533602 -292.549605)
			(xy 259.563073 -292.503749) (xy 259.598771 -292.462554) (xy 259.639968 -292.426859) (xy 259.685826 -292.39739)
			(xy 259.735411 -292.374748) (xy 259.787713 -292.359394) (xy 259.841669 -292.351639) (xy 259.868924 -292.351206)
			(xy 259.869178 -292.351206) (xy 259.894198 -292.351594) (xy 259.943808 -292.35813) (xy 259.992135 -292.371106)
			(xy 260.038348 -292.390299) (xy 260.060186 -292.402514) (xy 260.072124 -292.409372) (xy 260.098794 -292.409626)
			(xy 260.186424 -292.359588) (xy 260.19125 -292.354508) (xy 260.197854 -292.347904) (xy 260.204706 -292.340508)
			(xy 260.212449 -292.321909) (xy 260.21284 -292.311836) (xy 260.21284 -289.950144) (xy 260.21241 -289.941241)
			(xy 260.206241 -289.924534) (xy 260.194734 -289.91094) (xy 260.187186 -289.906202) (xy 260.098794 -289.855402)
			(xy 260.072124 -289.855656) (xy 260.060186 -289.862514) (xy 260.038325 -289.874683) (xy 259.992113 -289.893861)
			(xy 259.943794 -289.906843) (xy 259.894194 -289.913409) (xy 259.869178 -289.913822) (xy 259.868924 -289.913822)
			(xy 259.841669 -289.913361) (xy 259.787713 -289.905606) (xy 259.735411 -289.890252) (xy 259.685826 -289.86761)
			(xy 259.639968 -289.838141) (xy 259.598771 -289.802446) (xy 259.563073 -289.761251) (xy 259.533602 -289.715395)
			(xy 259.510957 -289.665812) (xy 259.495599 -289.61351) (xy 259.487841 -289.559555) (xy 259.487841 -289.505045)
			(xy 259.495599 -289.45109) (xy 259.510957 -289.398788) (xy 259.533602 -289.349205) (xy 259.563073 -289.303349)
			(xy 259.598771 -289.262154) (xy 259.639968 -289.226459) (xy 259.685826 -289.19699) (xy 259.735411 -289.174348)
			(xy 259.787713 -289.158994) (xy 259.841669 -289.151239) (xy 259.868924 -289.150806) (xy 259.869178 -289.150806)
			(xy 259.894198 -289.151194) (xy 259.943808 -289.15773) (xy 259.992135 -289.170706) (xy 260.038348 -289.189899)
			(xy 260.060186 -289.202114) (xy 260.072124 -289.208972) (xy 260.098794 -289.209226) (xy 260.186424 -289.159188)
			(xy 260.19125 -289.154108) (xy 260.197854 -289.147504) (xy 260.204706 -289.140108) (xy 260.212449 -289.121509)
			(xy 260.21284 -289.111436) (xy 260.21284 -286.749744) (xy 260.21241 -286.740841) (xy 260.206241 -286.724134)
			(xy 260.194734 -286.71054) (xy 260.187186 -286.705802) (xy 260.098794 -286.655002) (xy 260.072124 -286.655256)
			(xy 260.060186 -286.662114) (xy 260.038325 -286.674283) (xy 259.992113 -286.693461) (xy 259.943794 -286.706443)
			(xy 259.894194 -286.713009) (xy 259.869178 -286.713422) (xy 259.868924 -286.713422) (xy 259.841669 -286.712961)
			(xy 259.787713 -286.705206) (xy 259.735411 -286.689852) (xy 259.685826 -286.66721) (xy 259.639968 -286.637741)
			(xy 259.598771 -286.602046) (xy 259.563073 -286.560851) (xy 259.533602 -286.514995) (xy 259.510957 -286.465412)
			(xy 259.495599 -286.41311) (xy 259.487841 -286.359155) (xy 259.487841 -286.304645) (xy 259.495599 -286.25069)
			(xy 259.510957 -286.198388) (xy 259.533602 -286.148805) (xy 259.563073 -286.102949) (xy 259.598771 -286.061754)
			(xy 259.639968 -286.026059) (xy 259.685826 -285.99659) (xy 259.735411 -285.973948) (xy 259.787713 -285.958594)
			(xy 259.841669 -285.950839) (xy 259.868924 -285.950406) (xy 259.869178 -285.950406) (xy 259.894198 -285.950794)
			(xy 259.943808 -285.95733) (xy 259.992135 -285.970306) (xy 260.038348 -285.989499) (xy 260.060186 -286.001714)
			(xy 260.072124 -286.008572) (xy 260.098794 -286.008826) (xy 260.186424 -285.958788) (xy 260.19125 -285.953708)
			(xy 260.197854 -285.947104) (xy 260.204706 -285.939708) (xy 260.212449 -285.921109) (xy 260.21284 -285.911036)
			(xy 260.21284 -283.549344) (xy 260.21241 -283.540441) (xy 260.206241 -283.523734) (xy 260.194734 -283.51014)
			(xy 260.187186 -283.505402) (xy 260.098794 -283.454602) (xy 260.072124 -283.454856) (xy 260.060186 -283.461714)
			(xy 260.038325 -283.473883) (xy 259.992113 -283.493061) (xy 259.943794 -283.506043) (xy 259.894194 -283.512609)
			(xy 259.869178 -283.513022) (xy 259.868924 -283.513022) (xy 259.841669 -283.512561) (xy 259.787713 -283.504806)
			(xy 259.735411 -283.489452) (xy 259.685826 -283.46681) (xy 259.639968 -283.437341) (xy 259.598771 -283.401646)
			(xy 259.563073 -283.360451) (xy 259.533602 -283.314595) (xy 259.510957 -283.265012) (xy 259.495599 -283.21271)
			(xy 259.487841 -283.158755) (xy 259.487841 -283.104245) (xy 259.495599 -283.05029) (xy 259.510957 -282.997988)
			(xy 259.533602 -282.948405) (xy 259.563073 -282.902549) (xy 259.598771 -282.861354) (xy 259.639968 -282.825659)
			(xy 259.685826 -282.79619) (xy 259.735411 -282.773548) (xy 259.787713 -282.758194) (xy 259.841669 -282.750439)
			(xy 259.868924 -282.750006) (xy 259.869178 -282.750006) (xy 259.894198 -282.750394) (xy 259.943808 -282.75693)
			(xy 259.992135 -282.769906) (xy 260.038348 -282.789099) (xy 260.060186 -282.801314) (xy 260.072124 -282.808172)
			(xy 260.098794 -282.808426) (xy 260.186424 -282.758388) (xy 260.19125 -282.753308) (xy 260.197854 -282.746704)
			(xy 260.204706 -282.739308) (xy 260.212449 -282.720709) (xy 260.21284 -282.710636) (xy 260.21284 -280.348944)
			(xy 260.21241 -280.340041) (xy 260.206241 -280.323334) (xy 260.194734 -280.30974) (xy 260.187186 -280.305002)
			(xy 260.098794 -280.254202) (xy 260.072124 -280.254456) (xy 260.060186 -280.261314) (xy 260.038325 -280.273483)
			(xy 259.992113 -280.292661) (xy 259.943794 -280.305643) (xy 259.894194 -280.312209) (xy 259.869178 -280.312622)
			(xy 259.868924 -280.312622) (xy 259.841669 -280.312161) (xy 259.787713 -280.304406) (xy 259.735411 -280.289052)
			(xy 259.685826 -280.26641) (xy 259.639968 -280.236941) (xy 259.598771 -280.201246) (xy 259.563073 -280.160051)
			(xy 259.533602 -280.114195) (xy 259.510957 -280.064612) (xy 259.495599 -280.01231) (xy 259.487841 -279.958355)
			(xy 259.487841 -279.903845) (xy 259.495599 -279.84989) (xy 259.510957 -279.797588) (xy 259.533602 -279.748005)
			(xy 259.563073 -279.702149) (xy 259.598771 -279.660954) (xy 259.639968 -279.625259) (xy 259.685826 -279.59579)
			(xy 259.735411 -279.573148) (xy 259.787713 -279.557794) (xy 259.841669 -279.550039) (xy 259.868924 -279.549606)
			(xy 259.869178 -279.549606) (xy 259.894198 -279.549994) (xy 259.943808 -279.55653) (xy 259.992135 -279.569506)
			(xy 260.038348 -279.588699) (xy 260.060186 -279.600914) (xy 260.072124 -279.607772) (xy 260.098794 -279.608026)
			(xy 260.186424 -279.557988) (xy 260.19125 -279.552908) (xy 260.197854 -279.546304) (xy 260.204706 -279.538908)
			(xy 260.212449 -279.520309) (xy 260.21284 -279.510236) (xy 260.21284 -278.875236) (xy 260.20522 -278.85644)
			(xy 260.197854 -278.849328) (xy 256.695194 -275.346668) (xy 256.688353 -275.339267) (xy 256.680632 -275.320669)
			(xy 256.680208 -275.3106) (xy 256.680208 -268.781276) (xy 256.680636 -268.771208) (xy 256.688357 -268.752611)
			(xy 256.695194 -268.745208) (xy 263.532112 -261.90829) (xy 263.538966 -261.900895) (xy 263.546711 -261.882296)
			(xy 263.547098 -261.872222) (xy 263.547098 -259.94868) (xy 263.522206 -259.904992) (xy 263.498084 -259.890172)
			(xy 263.454102 -259.854531) (xy 263.415868 -259.812782) (xy 263.384222 -259.765842) (xy 263.359858 -259.714742)
			(xy 263.343312 -259.660603) (xy 263.334947 -259.604614) (xy 263.334946 -259.548003) (xy 263.343309 -259.492013)
			(xy 263.359852 -259.437873) (xy 263.384214 -259.386772) (xy 263.415858 -259.339831) (xy 263.45409 -259.29808)
			(xy 263.498071 -259.262437) (xy 263.522206 -259.24764) (xy 263.547098 -259.203952) (xy 263.547098 -256.74828)
			(xy 263.522206 -256.704592) (xy 263.498084 -256.689772) (xy 263.454102 -256.654131) (xy 263.415868 -256.612382)
			(xy 263.384222 -256.565442) (xy 263.359858 -256.514342) (xy 263.343312 -256.460203) (xy 263.334947 -256.404214)
			(xy 263.334946 -256.347603) (xy 263.343309 -256.291613) (xy 263.359852 -256.237473) (xy 263.384214 -256.186372)
			(xy 263.415858 -256.139431) (xy 263.45409 -256.09768) (xy 263.498071 -256.062037) (xy 263.522206 -256.04724)
			(xy 263.547098 -256.003552) (xy 263.547098 -253.843028) (xy 263.529572 -253.817374) (xy 263.51484 -253.811532)
			(xy 263.49 -253.801285) (xy 263.443235 -253.774821) (xy 263.400646 -253.742057) (xy 263.363076 -253.703642)
			(xy 263.331267 -253.660335) (xy 263.305849 -253.612994) (xy 263.287324 -253.562554) (xy 263.27606 -253.510015)
			(xy 263.272279 -253.456415) (xy 263.276056 -253.402814) (xy 263.287316 -253.350274) (xy 263.305836 -253.299833)
			(xy 263.331251 -253.25249) (xy 263.363057 -253.209181) (xy 263.400624 -253.170762) (xy 263.443211 -253.137995)
			(xy 263.489974 -253.111528) (xy 263.51484 -253.101348) (xy 263.529572 -253.095506) (xy 263.547098 -253.069852)
			(xy 263.547098 -251.54509) (xy 263.529572 -251.519436) (xy 263.51484 -251.513594) (xy 263.490003 -251.503346)
			(xy 263.443244 -251.476883) (xy 263.40066 -251.444121) (xy 263.363094 -251.405708) (xy 263.33129 -251.362404)
			(xy 263.305876 -251.315066) (xy 263.287355 -251.264631) (xy 263.276094 -251.212096) (xy 263.272315 -251.158501)
			(xy 263.276093 -251.104905) (xy 263.287354 -251.05237) (xy 263.305875 -251.001935) (xy 263.331289 -250.954597)
			(xy 263.363093 -250.911293) (xy 263.400659 -250.87288) (xy 263.443242 -250.840118) (xy 263.490002 -250.813654)
			(xy 263.51484 -250.80341) (xy 263.529572 -250.797568) (xy 263.547098 -250.771914) (xy 263.547098 -236.498638)
			(xy 263.546663 -236.488573) (xy 263.538933 -236.469985) (xy 263.532112 -236.46257) (xy 263.155176 -236.085634)
			(xy 263.147778 -236.078788) (xy 263.129179 -236.071056) (xy 263.119108 -236.070648) (xy 258.16179 -236.070648)
			(xy 258.151722 -236.071074) (xy 258.133124 -236.078797) (xy 258.125722 -236.085634) (xy 257.826256 -236.3851)
			(xy 257.819403 -236.392496) (xy 257.81166 -236.411094) (xy 257.81127 -236.421168) (xy 257.81127 -236.758988)
			(xy 258.093208 -236.758988) (xy 258.097279 -236.703366) (xy 258.109405 -236.648929) (xy 258.129328 -236.596838)
			(xy 258.156624 -236.548203) (xy 258.19071 -236.50406) (xy 258.230859 -236.465351) (xy 258.276217 -236.4329)
			(xy 258.325817 -236.407399) (xy 258.378601 -236.389392) (xy 258.433444 -236.379262) (xy 258.489178 -236.377225)
			(xy 258.544615 -236.383325) (xy 258.598572 -236.397431) (xy 258.649901 -236.419243) (xy 258.697507 -236.448297)
			(xy 258.740375 -236.483972) (xy 258.777592 -236.525509) (xy 258.808365 -236.572022) (xy 258.832037 -236.622519)
			(xy 258.848105 -236.675926) (xy 258.856225 -236.731102) (xy 258.856734 -236.758988) (xy 258.856225 -236.786874)
			(xy 258.848105 -236.84205) (xy 258.832037 -236.895457) (xy 258.808365 -236.945954) (xy 258.777592 -236.992467)
			(xy 258.740375 -237.034004) (xy 258.697507 -237.069679) (xy 258.649901 -237.098733) (xy 258.598572 -237.120545)
			(xy 258.544615 -237.134651) (xy 258.489178 -237.140751) (xy 258.433444 -237.138714) (xy 258.378601 -237.128584)
			(xy 258.325817 -237.110577) (xy 258.276217 -237.085076) (xy 258.230859 -237.052625) (xy 258.19071 -237.013916)
			(xy 258.156624 -236.969773) (xy 258.129328 -236.921138) (xy 258.109405 -236.869047) (xy 258.097279 -236.81461)
			(xy 258.093208 -236.758988) (xy 257.81127 -236.758988) (xy 257.81127 -237.936532) (xy 257.831336 -237.963202)
			(xy 257.847592 -237.968282) (xy 257.873494 -237.976486) (xy 257.922847 -237.999207) (xy 257.968476 -238.028703)
			(xy 258.009455 -238.064377) (xy 258.044957 -238.105506) (xy 258.074262 -238.151258) (xy 258.096776 -238.200706)
			(xy 258.105994 -238.232188) (xy 258.575808 -238.232188) (xy 258.579879 -238.176566) (xy 258.592005 -238.122129)
			(xy 258.611928 -238.070038) (xy 258.639224 -238.021403) (xy 258.67331 -237.97726) (xy 258.713459 -237.938551)
			(xy 258.758817 -237.9061) (xy 258.808417 -237.880599) (xy 258.861201 -237.862592) (xy 258.916044 -237.852462)
			(xy 258.971778 -237.850425) (xy 259.027215 -237.856525) (xy 259.081172 -237.870631) (xy 259.132501 -237.892443)
			(xy 259.180107 -237.921497) (xy 259.222975 -237.957172) (xy 259.260192 -237.998709) (xy 259.290965 -238.045222)
			(xy 259.314637 -238.095719) (xy 259.330705 -238.149126) (xy 259.338825 -238.204302) (xy 259.339334 -238.232188)
			(xy 259.541008 -238.232188) (xy 259.545079 -238.176566) (xy 259.557205 -238.122129) (xy 259.577128 -238.070038)
			(xy 259.604424 -238.021403) (xy 259.63851 -237.97726) (xy 259.678659 -237.938551) (xy 259.724017 -237.9061)
			(xy 259.773617 -237.880599) (xy 259.826401 -237.862592) (xy 259.881244 -237.852462) (xy 259.936978 -237.850425)
			(xy 259.992415 -237.856525) (xy 260.046372 -237.870631) (xy 260.097701 -237.892443) (xy 260.145307 -237.921497)
			(xy 260.188175 -237.957172) (xy 260.225392 -237.998709) (xy 260.256165 -238.045222) (xy 260.279837 -238.095719)
			(xy 260.295905 -238.149126) (xy 260.304025 -238.204302) (xy 260.304534 -238.232188) (xy 260.304025 -238.260074)
			(xy 260.295905 -238.31525) (xy 260.279837 -238.368657) (xy 260.256165 -238.419154) (xy 260.225392 -238.465667)
			(xy 260.188175 -238.507204) (xy 260.145307 -238.542879) (xy 260.097701 -238.571933) (xy 260.046372 -238.593745)
			(xy 259.992415 -238.607851) (xy 259.936978 -238.613951) (xy 259.881244 -238.611914) (xy 259.826401 -238.601784)
			(xy 259.773617 -238.583777) (xy 259.724017 -238.558276) (xy 259.678659 -238.525825) (xy 259.63851 -238.487116)
			(xy 259.604424 -238.442973) (xy 259.577128 -238.394338) (xy 259.557205 -238.342247) (xy 259.545079 -238.28781)
			(xy 259.541008 -238.232188) (xy 259.339334 -238.232188) (xy 259.338825 -238.260074) (xy 259.330705 -238.31525)
			(xy 259.314637 -238.368657) (xy 259.290965 -238.419154) (xy 259.260192 -238.465667) (xy 259.222975 -238.507204)
			(xy 259.180107 -238.542879) (xy 259.132501 -238.571933) (xy 259.081172 -238.593745) (xy 259.027215 -238.607851)
			(xy 258.971778 -238.613951) (xy 258.916044 -238.611914) (xy 258.861201 -238.601784) (xy 258.808417 -238.583777)
			(xy 258.758817 -238.558276) (xy 258.713459 -238.525825) (xy 258.67331 -238.487116) (xy 258.639224 -238.442973)
			(xy 258.611928 -238.394338) (xy 258.592005 -238.342247) (xy 258.579879 -238.28781) (xy 258.575808 -238.232188)
			(xy 258.105994 -238.232188) (xy 258.112043 -238.252849) (xy 258.119755 -238.306631) (xy 258.119756 -238.360963)
			(xy 258.112045 -238.414745) (xy 258.096778 -238.466888) (xy 258.074265 -238.516336) (xy 258.044961 -238.562088)
			(xy 258.00946 -238.603218) (xy 257.968481 -238.638893) (xy 257.922853 -238.66839) (xy 257.873501 -238.691112)
			(xy 257.847592 -238.699294) (xy 257.831336 -238.704374) (xy 257.81127 -238.731044) (xy 257.81127 -241.280188)
			(xy 261.547608 -241.280188) (xy 261.551679 -241.224566) (xy 261.563805 -241.170129) (xy 261.583728 -241.118038)
			(xy 261.611024 -241.069403) (xy 261.64511 -241.02526) (xy 261.685259 -240.986551) (xy 261.730617 -240.9541)
			(xy 261.780217 -240.928599) (xy 261.833001 -240.910592) (xy 261.887844 -240.900462) (xy 261.943578 -240.898425)
			(xy 261.999015 -240.904525) (xy 262.052972 -240.918631) (xy 262.104301 -240.940443) (xy 262.151907 -240.969497)
			(xy 262.194775 -241.005172) (xy 262.231992 -241.046709) (xy 262.262765 -241.093222) (xy 262.286437 -241.143719)
			(xy 262.302505 -241.197126) (xy 262.310625 -241.252302) (xy 262.311134 -241.280188) (xy 262.310625 -241.308074)
			(xy 262.302505 -241.36325) (xy 262.286437 -241.416657) (xy 262.262765 -241.467154) (xy 262.231992 -241.513667)
			(xy 262.194775 -241.555204) (xy 262.151907 -241.590879) (xy 262.104301 -241.619933) (xy 262.052972 -241.641745)
			(xy 261.999015 -241.655851) (xy 261.943578 -241.661951) (xy 261.887844 -241.659914) (xy 261.833001 -241.649784)
			(xy 261.780217 -241.631777) (xy 261.730617 -241.606276) (xy 261.685259 -241.573825) (xy 261.64511 -241.535116)
			(xy 261.611024 -241.490973) (xy 261.583728 -241.442338) (xy 261.563805 -241.390247) (xy 261.551679 -241.33581)
			(xy 261.547608 -241.280188) (xy 257.81127 -241.280188) (xy 257.81127 -241.686588) (xy 258.423408 -241.686588)
			(xy 258.427479 -241.630966) (xy 258.439605 -241.576529) (xy 258.459528 -241.524438) (xy 258.486824 -241.475803)
			(xy 258.52091 -241.43166) (xy 258.561059 -241.392951) (xy 258.606417 -241.3605) (xy 258.656017 -241.334999)
			(xy 258.708801 -241.316992) (xy 258.763644 -241.306862) (xy 258.819378 -241.304825) (xy 258.874815 -241.310925)
			(xy 258.928772 -241.325031) (xy 258.980101 -241.346843) (xy 259.027707 -241.375897) (xy 259.070575 -241.411572)
			(xy 259.107792 -241.453109) (xy 259.138565 -241.499622) (xy 259.162237 -241.550119) (xy 259.178305 -241.603526)
			(xy 259.186425 -241.658702) (xy 259.186934 -241.686588) (xy 259.591808 -241.686588) (xy 259.595879 -241.630966)
			(xy 259.608005 -241.576529) (xy 259.627928 -241.524438) (xy 259.655224 -241.475803) (xy 259.68931 -241.43166)
			(xy 259.729459 -241.392951) (xy 259.774817 -241.3605) (xy 259.824417 -241.334999) (xy 259.877201 -241.316992)
			(xy 259.932044 -241.306862) (xy 259.987778 -241.304825) (xy 260.043215 -241.310925) (xy 260.097172 -241.325031)
			(xy 260.148501 -241.346843) (xy 260.196107 -241.375897) (xy 260.238975 -241.411572) (xy 260.276192 -241.453109)
			(xy 260.306965 -241.499622) (xy 260.330637 -241.550119) (xy 260.346705 -241.603526) (xy 260.354825 -241.658702)
			(xy 260.355334 -241.686588) (xy 260.354825 -241.714474) (xy 260.346705 -241.76965) (xy 260.330637 -241.823057)
			(xy 260.306965 -241.873554) (xy 260.276192 -241.920067) (xy 260.238975 -241.961604) (xy 260.196107 -241.997279)
			(xy 260.148501 -242.026333) (xy 260.097172 -242.048145) (xy 260.043215 -242.062251) (xy 259.987778 -242.068351)
			(xy 259.932044 -242.066314) (xy 259.877201 -242.056184) (xy 259.824417 -242.038177) (xy 259.774817 -242.012676)
			(xy 259.729459 -241.980225) (xy 259.68931 -241.941516) (xy 259.655224 -241.897373) (xy 259.627928 -241.848738)
			(xy 259.608005 -241.796647) (xy 259.595879 -241.74221) (xy 259.591808 -241.686588) (xy 259.186934 -241.686588)
			(xy 259.186425 -241.714474) (xy 259.178305 -241.76965) (xy 259.162237 -241.823057) (xy 259.138565 -241.873554)
			(xy 259.107792 -241.920067) (xy 259.070575 -241.961604) (xy 259.027707 -241.997279) (xy 258.980101 -242.026333)
			(xy 258.928772 -242.048145) (xy 258.874815 -242.062251) (xy 258.819378 -242.068351) (xy 258.763644 -242.066314)
			(xy 258.708801 -242.056184) (xy 258.656017 -242.038177) (xy 258.606417 -242.012676) (xy 258.561059 -241.980225)
			(xy 258.52091 -241.941516) (xy 258.486824 -241.897373) (xy 258.459528 -241.848738) (xy 258.439605 -241.796647)
			(xy 258.427479 -241.74221) (xy 258.423408 -241.686588) (xy 257.81127 -241.686588) (xy 257.81127 -242.314476)
			(xy 262.093962 -242.314476) (xy 262.098033 -242.258854) (xy 262.110159 -242.204417) (xy 262.130082 -242.152326)
			(xy 262.157378 -242.103691) (xy 262.191464 -242.059548) (xy 262.231613 -242.020839) (xy 262.276971 -241.988388)
			(xy 262.326571 -241.962887) (xy 262.379355 -241.94488) (xy 262.434198 -241.93475) (xy 262.489932 -241.932713)
			(xy 262.545369 -241.938813) (xy 262.599326 -241.952919) (xy 262.650655 -241.974731) (xy 262.698261 -242.003785)
			(xy 262.741129 -242.03946) (xy 262.778346 -242.080997) (xy 262.809119 -242.12751) (xy 262.832791 -242.178007)
			(xy 262.848859 -242.231414) (xy 262.856979 -242.28659) (xy 262.857488 -242.314476) (xy 262.856979 -242.342362)
			(xy 262.848859 -242.397538) (xy 262.832791 -242.450945) (xy 262.809119 -242.501442) (xy 262.778346 -242.547955)
			(xy 262.741129 -242.589492) (xy 262.698261 -242.625167) (xy 262.650655 -242.654221) (xy 262.599326 -242.676033)
			(xy 262.545369 -242.690139) (xy 262.489932 -242.696239) (xy 262.434198 -242.694202) (xy 262.379355 -242.684072)
			(xy 262.326571 -242.666065) (xy 262.276971 -242.640564) (xy 262.231613 -242.608113) (xy 262.191464 -242.569404)
			(xy 262.157378 -242.525261) (xy 262.130082 -242.476626) (xy 262.110159 -242.424535) (xy 262.098033 -242.370098)
			(xy 262.093962 -242.314476) (xy 257.81127 -242.314476) (xy 257.81127 -243.540788) (xy 260.658608 -243.540788)
			(xy 260.662679 -243.485166) (xy 260.674805 -243.430729) (xy 260.694728 -243.378638) (xy 260.722024 -243.330003)
			(xy 260.75611 -243.28586) (xy 260.796259 -243.247151) (xy 260.841617 -243.2147) (xy 260.891217 -243.189199)
			(xy 260.944001 -243.171192) (xy 260.998844 -243.161062) (xy 261.054578 -243.159025) (xy 261.110015 -243.165125)
			(xy 261.163972 -243.179231) (xy 261.215301 -243.201043) (xy 261.262907 -243.230097) (xy 261.305775 -243.265772)
			(xy 261.342992 -243.307309) (xy 261.373765 -243.353822) (xy 261.397437 -243.404319) (xy 261.413505 -243.457726)
			(xy 261.421625 -243.512902) (xy 261.422134 -243.540788) (xy 261.421625 -243.568674) (xy 261.413505 -243.62385)
			(xy 261.397437 -243.677257) (xy 261.373765 -243.727754) (xy 261.342992 -243.774267) (xy 261.305775 -243.815804)
			(xy 261.262907 -243.851479) (xy 261.215301 -243.880533) (xy 261.163972 -243.902345) (xy 261.110015 -243.916451)
			(xy 261.054578 -243.922551) (xy 260.998844 -243.920514) (xy 260.944001 -243.910384) (xy 260.891217 -243.892377)
			(xy 260.841617 -243.866876) (xy 260.796259 -243.834425) (xy 260.75611 -243.795716) (xy 260.722024 -243.751573)
			(xy 260.694728 -243.702938) (xy 260.674805 -243.650847) (xy 260.662679 -243.59641) (xy 260.658608 -243.540788)
			(xy 257.81127 -243.540788) (xy 257.81127 -248.72442) (xy 257.83114 -248.742629) (xy 257.866073 -248.78367)
			(xy 257.894891 -248.829213) (xy 257.917024 -248.878354) (xy 257.932031 -248.930118) (xy 257.939615 -248.983477)
			(xy 257.940048 -249.010424) (xy 258.192268 -249.010424) (xy 258.196339 -248.954802) (xy 258.208465 -248.900365)
			(xy 258.228388 -248.848274) (xy 258.255684 -248.799639) (xy 258.28977 -248.755496) (xy 258.329919 -248.716787)
			(xy 258.375277 -248.684336) (xy 258.424877 -248.658835) (xy 258.477661 -248.640828) (xy 258.532504 -248.630698)
			(xy 258.588238 -248.628661) (xy 258.643675 -248.634761) (xy 258.697632 -248.648867) (xy 258.748961 -248.670679)
			(xy 258.796567 -248.699733) (xy 258.839435 -248.735408) (xy 258.876652 -248.776945) (xy 258.907425 -248.823458)
			(xy 258.931097 -248.873955) (xy 258.947165 -248.927362) (xy 258.955285 -248.982538) (xy 258.955794 -249.010424)
			(xy 258.95533 -249.035824) (xy 259.186678 -249.035824) (xy 259.190749 -248.980202) (xy 259.202875 -248.925765)
			(xy 259.222798 -248.873674) (xy 259.250094 -248.825039) (xy 259.28418 -248.780896) (xy 259.324329 -248.742187)
			(xy 259.369687 -248.709736) (xy 259.419287 -248.684235) (xy 259.472071 -248.666228) (xy 259.526914 -248.656098)
			(xy 259.582648 -248.654061) (xy 259.638085 -248.660161) (xy 259.692042 -248.674267) (xy 259.743371 -248.696079)
			(xy 259.790977 -248.725133) (xy 259.833845 -248.760808) (xy 259.871062 -248.802345) (xy 259.901835 -248.848858)
			(xy 259.925507 -248.899355) (xy 259.941575 -248.952762) (xy 259.949695 -249.007938) (xy 259.950204 -249.035824)
			(xy 259.949695 -249.06371) (xy 259.941575 -249.118886) (xy 259.925507 -249.172293) (xy 259.901835 -249.22279)
			(xy 259.871062 -249.269303) (xy 259.833845 -249.31084) (xy 259.790977 -249.346515) (xy 259.743371 -249.375569)
			(xy 259.692042 -249.397381) (xy 259.638085 -249.411487) (xy 259.582648 -249.417587) (xy 259.526914 -249.41555)
			(xy 259.472071 -249.40542) (xy 259.419287 -249.387413) (xy 259.369687 -249.361912) (xy 259.324329 -249.329461)
			(xy 259.28418 -249.290752) (xy 259.250094 -249.246609) (xy 259.222798 -249.197974) (xy 259.202875 -249.145883)
			(xy 259.190749 -249.091446) (xy 259.186678 -249.035824) (xy 258.95533 -249.035824) (xy 258.955285 -249.03831)
			(xy 258.947165 -249.093486) (xy 258.931097 -249.146893) (xy 258.907425 -249.19739) (xy 258.876652 -249.243903)
			(xy 258.839435 -249.28544) (xy 258.796567 -249.321115) (xy 258.748961 -249.350169) (xy 258.697632 -249.371981)
			(xy 258.643675 -249.386087) (xy 258.588238 -249.392187) (xy 258.532504 -249.39015) (xy 258.477661 -249.38002)
			(xy 258.424877 -249.362013) (xy 258.375277 -249.336512) (xy 258.329919 -249.304061) (xy 258.28977 -249.265352)
			(xy 258.255684 -249.221209) (xy 258.228388 -249.172574) (xy 258.208465 -249.120483) (xy 258.196339 -249.066046)
			(xy 258.192268 -249.010424) (xy 257.940048 -249.010424) (xy 257.939032 -249.037856) (xy 257.940215 -249.064971)
			(xy 257.935827 -249.119068) (xy 257.923819 -249.171997) (xy 257.904434 -249.222691) (xy 257.878062 -249.270127)
			(xy 257.845236 -249.313349) (xy 257.826256 -249.33275) (xy 257.819411 -249.340149) (xy 257.811686 -249.358747)
			(xy 257.81127 -249.368818) (xy 257.81127 -250.850908) (xy 257.811694 -250.860978) (xy 257.819407 -250.879583)
			(xy 257.826256 -250.886976) (xy 257.845478 -250.90662) (xy 257.878652 -250.950439) (xy 257.905194 -250.998564)
			(xy 257.924555 -251.050001) (xy 257.936335 -251.103684) (xy 257.940288 -251.158501) (xy 257.940288 -251.158502)
			(xy 258.192268 -251.158502) (xy 258.196339 -251.10288) (xy 258.208465 -251.048443) (xy 258.228388 -250.996352)
			(xy 258.255684 -250.947717) (xy 258.28977 -250.903574) (xy 258.329919 -250.864865) (xy 258.375277 -250.832414)
			(xy 258.424877 -250.806913) (xy 258.477661 -250.788906) (xy 258.532504 -250.778776) (xy 258.588238 -250.776739)
			(xy 258.643675 -250.782839) (xy 258.697632 -250.796945) (xy 258.748961 -250.818757) (xy 258.796567 -250.847811)
			(xy 258.839435 -250.883486) (xy 258.876652 -250.925023) (xy 258.907425 -250.971536) (xy 258.931097 -251.022033)
			(xy 258.947165 -251.07544) (xy 258.955285 -251.130616) (xy 258.955794 -251.158502) (xy 259.208268 -251.158502)
			(xy 259.212339 -251.10288) (xy 259.224465 -251.048443) (xy 259.244388 -250.996352) (xy 259.271684 -250.947717)
			(xy 259.30577 -250.903574) (xy 259.345919 -250.864865) (xy 259.391277 -250.832414) (xy 259.440877 -250.806913)
			(xy 259.493661 -250.788906) (xy 259.548504 -250.778776) (xy 259.604238 -250.776739) (xy 259.659675 -250.782839)
			(xy 259.713632 -250.796945) (xy 259.764961 -250.818757) (xy 259.812567 -250.847811) (xy 259.855435 -250.883486)
			(xy 259.892652 -250.925023) (xy 259.923425 -250.971536) (xy 259.947097 -251.022033) (xy 259.963165 -251.07544)
			(xy 259.971285 -251.130616) (xy 259.971794 -251.158502) (xy 260.224268 -251.158502) (xy 260.228339 -251.10288)
			(xy 260.240465 -251.048443) (xy 260.260388 -250.996352) (xy 260.287684 -250.947717) (xy 260.32177 -250.903574)
			(xy 260.361919 -250.864865) (xy 260.407277 -250.832414) (xy 260.456877 -250.806913) (xy 260.509661 -250.788906)
			(xy 260.564504 -250.778776) (xy 260.620238 -250.776739) (xy 260.675675 -250.782839) (xy 260.729632 -250.796945)
			(xy 260.780961 -250.818757) (xy 260.828567 -250.847811) (xy 260.871435 -250.883486) (xy 260.908652 -250.925023)
			(xy 260.939425 -250.971536) (xy 260.963097 -251.022033) (xy 260.979165 -251.07544) (xy 260.987285 -251.130616)
			(xy 260.987794 -251.158502) (xy 261.240268 -251.158502) (xy 261.244339 -251.10288) (xy 261.256465 -251.048443)
			(xy 261.276388 -250.996352) (xy 261.303684 -250.947717) (xy 261.33777 -250.903574) (xy 261.377919 -250.864865)
			(xy 261.423277 -250.832414) (xy 261.472877 -250.806913) (xy 261.525661 -250.788906) (xy 261.580504 -250.778776)
			(xy 261.636238 -250.776739) (xy 261.691675 -250.782839) (xy 261.745632 -250.796945) (xy 261.796961 -250.818757)
			(xy 261.844567 -250.847811) (xy 261.887435 -250.883486) (xy 261.924652 -250.925023) (xy 261.955425 -250.971536)
			(xy 261.979097 -251.022033) (xy 261.995165 -251.07544) (xy 262.003285 -251.130616) (xy 262.003794 -251.158502)
			(xy 262.256268 -251.158502) (xy 262.260339 -251.10288) (xy 262.272465 -251.048443) (xy 262.292388 -250.996352)
			(xy 262.319684 -250.947717) (xy 262.35377 -250.903574) (xy 262.393919 -250.864865) (xy 262.439277 -250.832414)
			(xy 262.488877 -250.806913) (xy 262.541661 -250.788906) (xy 262.596504 -250.778776) (xy 262.652238 -250.776739)
			(xy 262.707675 -250.782839) (xy 262.761632 -250.796945) (xy 262.812961 -250.818757) (xy 262.860567 -250.847811)
			(xy 262.903435 -250.883486) (xy 262.940652 -250.925023) (xy 262.971425 -250.971536) (xy 262.995097 -251.022033)
			(xy 263.011165 -251.07544) (xy 263.019285 -251.130616) (xy 263.019794 -251.158502) (xy 263.019285 -251.186388)
			(xy 263.011165 -251.241564) (xy 262.995097 -251.294971) (xy 262.971425 -251.345468) (xy 262.940652 -251.391981)
			(xy 262.903435 -251.433518) (xy 262.860567 -251.469193) (xy 262.812961 -251.498247) (xy 262.761632 -251.520059)
			(xy 262.707675 -251.534165) (xy 262.652238 -251.540265) (xy 262.596504 -251.538228) (xy 262.541661 -251.528098)
			(xy 262.488877 -251.510091) (xy 262.439277 -251.48459) (xy 262.393919 -251.452139) (xy 262.35377 -251.41343)
			(xy 262.319684 -251.369287) (xy 262.292388 -251.320652) (xy 262.272465 -251.268561) (xy 262.260339 -251.214124)
			(xy 262.256268 -251.158502) (xy 262.003794 -251.158502) (xy 262.003285 -251.186388) (xy 261.995165 -251.241564)
			(xy 261.979097 -251.294971) (xy 261.955425 -251.345468) (xy 261.924652 -251.391981) (xy 261.887435 -251.433518)
			(xy 261.844567 -251.469193) (xy 261.796961 -251.498247) (xy 261.745632 -251.520059) (xy 261.691675 -251.534165)
			(xy 261.636238 -251.540265) (xy 261.580504 -251.538228) (xy 261.525661 -251.528098) (xy 261.472877 -251.510091)
			(xy 261.423277 -251.48459) (xy 261.377919 -251.452139) (xy 261.33777 -251.41343) (xy 261.303684 -251.369287)
			(xy 261.276388 -251.320652) (xy 261.256465 -251.268561) (xy 261.244339 -251.214124) (xy 261.240268 -251.158502)
			(xy 260.987794 -251.158502) (xy 260.987285 -251.186388) (xy 260.979165 -251.241564) (xy 260.963097 -251.294971)
			(xy 260.939425 -251.345468) (xy 260.908652 -251.391981) (xy 260.871435 -251.433518) (xy 260.828567 -251.469193)
			(xy 260.780961 -251.498247) (xy 260.729632 -251.520059) (xy 260.675675 -251.534165) (xy 260.620238 -251.540265)
			(xy 260.564504 -251.538228) (xy 260.509661 -251.528098) (xy 260.456877 -251.510091) (xy 260.407277 -251.48459)
			(xy 260.361919 -251.452139) (xy 260.32177 -251.41343) (xy 260.287684 -251.369287) (xy 260.260388 -251.320652)
			(xy 260.240465 -251.268561) (xy 260.228339 -251.214124) (xy 260.224268 -251.158502) (xy 259.971794 -251.158502)
			(xy 259.971285 -251.186388) (xy 259.963165 -251.241564) (xy 259.947097 -251.294971) (xy 259.923425 -251.345468)
			(xy 259.892652 -251.391981) (xy 259.855435 -251.433518) (xy 259.812567 -251.469193) (xy 259.764961 -251.498247)
			(xy 259.713632 -251.520059) (xy 259.659675 -251.534165) (xy 259.604238 -251.540265) (xy 259.548504 -251.538228)
			(xy 259.493661 -251.528098) (xy 259.440877 -251.510091) (xy 259.391277 -251.48459) (xy 259.345919 -251.452139)
			(xy 259.30577 -251.41343) (xy 259.271684 -251.369287) (xy 259.244388 -251.320652) (xy 259.224465 -251.268561)
			(xy 259.212339 -251.214124) (xy 259.208268 -251.158502) (xy 258.955794 -251.158502) (xy 258.955285 -251.186388)
			(xy 258.947165 -251.241564) (xy 258.931097 -251.294971) (xy 258.907425 -251.345468) (xy 258.876652 -251.391981)
			(xy 258.839435 -251.433518) (xy 258.796567 -251.469193) (xy 258.748961 -251.498247) (xy 258.697632 -251.520059)
			(xy 258.643675 -251.534165) (xy 258.588238 -251.540265) (xy 258.532504 -251.538228) (xy 258.477661 -251.528098)
			(xy 258.424877 -251.510091) (xy 258.375277 -251.48459) (xy 258.329919 -251.452139) (xy 258.28977 -251.41343)
			(xy 258.255684 -251.369287) (xy 258.228388 -251.320652) (xy 258.208465 -251.268561) (xy 258.196339 -251.214124)
			(xy 258.192268 -251.158502) (xy 257.940288 -251.158502) (xy 257.936334 -251.213319) (xy 257.924555 -251.267002)
			(xy 257.905193 -251.318438) (xy 257.878651 -251.366564) (xy 257.845477 -251.410382) (xy 257.826256 -251.430028)
			(xy 257.819408 -251.437425) (xy 257.811675 -251.456024) (xy 257.81127 -251.466096) (xy 257.81127 -253.148846)
			(xy 257.811701 -253.158913) (xy 257.819423 -253.177508) (xy 257.826256 -253.184914) (xy 257.845476 -253.204558)
			(xy 257.878644 -253.248376) (xy 257.905181 -253.2965) (xy 257.924537 -253.347934) (xy 257.936312 -253.401614)
			(xy 257.940261 -253.456428) (xy 257.94026 -253.45644) (xy 258.192268 -253.45644) (xy 258.196339 -253.400818)
			(xy 258.208465 -253.346381) (xy 258.228388 -253.29429) (xy 258.255684 -253.245655) (xy 258.28977 -253.201512)
			(xy 258.329919 -253.162803) (xy 258.375277 -253.130352) (xy 258.424877 -253.104851) (xy 258.477661 -253.086844)
			(xy 258.532504 -253.076714) (xy 258.588238 -253.074677) (xy 258.643675 -253.080777) (xy 258.697632 -253.094883)
			(xy 258.748961 -253.116695) (xy 258.796567 -253.145749) (xy 258.839435 -253.181424) (xy 258.876652 -253.222961)
			(xy 258.907425 -253.269474) (xy 258.931097 -253.319971) (xy 258.947165 -253.373378) (xy 258.955285 -253.428554)
			(xy 258.955794 -253.45644) (xy 259.208268 -253.45644) (xy 259.212339 -253.400818) (xy 259.224465 -253.346381)
			(xy 259.244388 -253.29429) (xy 259.271684 -253.245655) (xy 259.30577 -253.201512) (xy 259.345919 -253.162803)
			(xy 259.391277 -253.130352) (xy 259.440877 -253.104851) (xy 259.493661 -253.086844) (xy 259.548504 -253.076714)
			(xy 259.604238 -253.074677) (xy 259.659675 -253.080777) (xy 259.713632 -253.094883) (xy 259.764961 -253.116695)
			(xy 259.812567 -253.145749) (xy 259.855435 -253.181424) (xy 259.892652 -253.222961) (xy 259.923425 -253.269474)
			(xy 259.947097 -253.319971) (xy 259.963165 -253.373378) (xy 259.971285 -253.428554) (xy 259.971794 -253.45644)
			(xy 260.224268 -253.45644) (xy 260.228339 -253.400818) (xy 260.240465 -253.346381) (xy 260.260388 -253.29429)
			(xy 260.287684 -253.245655) (xy 260.32177 -253.201512) (xy 260.361919 -253.162803) (xy 260.407277 -253.130352)
			(xy 260.456877 -253.104851) (xy 260.509661 -253.086844) (xy 260.564504 -253.076714) (xy 260.620238 -253.074677)
			(xy 260.675675 -253.080777) (xy 260.729632 -253.094883) (xy 260.780961 -253.116695) (xy 260.828567 -253.145749)
			(xy 260.871435 -253.181424) (xy 260.908652 -253.222961) (xy 260.939425 -253.269474) (xy 260.963097 -253.319971)
			(xy 260.979165 -253.373378) (xy 260.987285 -253.428554) (xy 260.987794 -253.45644) (xy 261.240268 -253.45644)
			(xy 261.244339 -253.400818) (xy 261.256465 -253.346381) (xy 261.276388 -253.29429) (xy 261.303684 -253.245655)
			(xy 261.33777 -253.201512) (xy 261.377919 -253.162803) (xy 261.423277 -253.130352) (xy 261.472877 -253.104851)
			(xy 261.525661 -253.086844) (xy 261.580504 -253.076714) (xy 261.636238 -253.074677) (xy 261.691675 -253.080777)
			(xy 261.745632 -253.094883) (xy 261.796961 -253.116695) (xy 261.844567 -253.145749) (xy 261.887435 -253.181424)
			(xy 261.924652 -253.222961) (xy 261.955425 -253.269474) (xy 261.979097 -253.319971) (xy 261.995165 -253.373378)
			(xy 262.003285 -253.428554) (xy 262.003794 -253.45644) (xy 262.256268 -253.45644) (xy 262.260339 -253.400818)
			(xy 262.272465 -253.346381) (xy 262.292388 -253.29429) (xy 262.319684 -253.245655) (xy 262.35377 -253.201512)
			(xy 262.393919 -253.162803) (xy 262.439277 -253.130352) (xy 262.488877 -253.104851) (xy 262.541661 -253.086844)
			(xy 262.596504 -253.076714) (xy 262.652238 -253.074677) (xy 262.707675 -253.080777) (xy 262.761632 -253.094883)
			(xy 262.812961 -253.116695) (xy 262.860567 -253.145749) (xy 262.903435 -253.181424) (xy 262.940652 -253.222961)
			(xy 262.971425 -253.269474) (xy 262.995097 -253.319971) (xy 263.011165 -253.373378) (xy 263.019285 -253.428554)
			(xy 263.019794 -253.45644) (xy 263.019285 -253.484326) (xy 263.011165 -253.539502) (xy 262.995097 -253.592909)
			(xy 262.971425 -253.643406) (xy 262.940652 -253.689919) (xy 262.903435 -253.731456) (xy 262.860567 -253.767131)
			(xy 262.812961 -253.796185) (xy 262.761632 -253.817997) (xy 262.707675 -253.832103) (xy 262.652238 -253.838203)
			(xy 262.596504 -253.836166) (xy 262.541661 -253.826036) (xy 262.488877 -253.808029) (xy 262.439277 -253.782528)
			(xy 262.393919 -253.750077) (xy 262.35377 -253.711368) (xy 262.319684 -253.667225) (xy 262.292388 -253.61859)
			(xy 262.272465 -253.566499) (xy 262.260339 -253.512062) (xy 262.256268 -253.45644) (xy 262.003794 -253.45644)
			(xy 262.003285 -253.484326) (xy 261.995165 -253.539502) (xy 261.979097 -253.592909) (xy 261.955425 -253.643406)
			(xy 261.924652 -253.689919) (xy 261.887435 -253.731456) (xy 261.844567 -253.767131) (xy 261.796961 -253.796185)
			(xy 261.745632 -253.817997) (xy 261.691675 -253.832103) (xy 261.636238 -253.838203) (xy 261.580504 -253.836166)
			(xy 261.525661 -253.826036) (xy 261.472877 -253.808029) (xy 261.423277 -253.782528) (xy 261.377919 -253.750077)
			(xy 261.33777 -253.711368) (xy 261.303684 -253.667225) (xy 261.276388 -253.61859) (xy 261.256465 -253.566499)
			(xy 261.244339 -253.512062) (xy 261.240268 -253.45644) (xy 260.987794 -253.45644) (xy 260.987285 -253.484326)
			(xy 260.979165 -253.539502) (xy 260.963097 -253.592909) (xy 260.939425 -253.643406) (xy 260.908652 -253.689919)
			(xy 260.871435 -253.731456) (xy 260.828567 -253.767131) (xy 260.780961 -253.796185) (xy 260.729632 -253.817997)
			(xy 260.675675 -253.832103) (xy 260.620238 -253.838203) (xy 260.564504 -253.836166) (xy 260.509661 -253.826036)
			(xy 260.456877 -253.808029) (xy 260.407277 -253.782528) (xy 260.361919 -253.750077) (xy 260.32177 -253.711368)
			(xy 260.287684 -253.667225) (xy 260.260388 -253.61859) (xy 260.240465 -253.566499) (xy 260.228339 -253.512062)
			(xy 260.224268 -253.45644) (xy 259.971794 -253.45644) (xy 259.971285 -253.484326) (xy 259.963165 -253.539502)
			(xy 259.947097 -253.592909) (xy 259.923425 -253.643406) (xy 259.892652 -253.689919) (xy 259.855435 -253.731456)
			(xy 259.812567 -253.767131) (xy 259.764961 -253.796185) (xy 259.713632 -253.817997) (xy 259.659675 -253.832103)
			(xy 259.604238 -253.838203) (xy 259.548504 -253.836166) (xy 259.493661 -253.826036) (xy 259.440877 -253.808029)
			(xy 259.391277 -253.782528) (xy 259.345919 -253.750077) (xy 259.30577 -253.711368) (xy 259.271684 -253.667225)
			(xy 259.244388 -253.61859) (xy 259.224465 -253.566499) (xy 259.212339 -253.512062) (xy 259.208268 -253.45644)
			(xy 258.955794 -253.45644) (xy 258.955285 -253.484326) (xy 258.947165 -253.539502) (xy 258.931097 -253.592909)
			(xy 258.907425 -253.643406) (xy 258.876652 -253.689919) (xy 258.839435 -253.731456) (xy 258.796567 -253.767131)
			(xy 258.748961 -253.796185) (xy 258.697632 -253.817997) (xy 258.643675 -253.832103) (xy 258.588238 -253.838203)
			(xy 258.532504 -253.836166) (xy 258.477661 -253.826036) (xy 258.424877 -253.808029) (xy 258.375277 -253.782528)
			(xy 258.329919 -253.750077) (xy 258.28977 -253.711368) (xy 258.255684 -253.667225) (xy 258.228388 -253.61859)
			(xy 258.208465 -253.566499) (xy 258.196339 -253.512062) (xy 258.192268 -253.45644) (xy 257.94026 -253.45644)
			(xy 257.936304 -253.511241) (xy 257.924521 -253.564919) (xy 257.905157 -253.616351) (xy 257.878613 -253.664471)
			(xy 257.845439 -253.708285) (xy 257.826256 -253.727966) (xy 257.819414 -253.735365) (xy 257.811695 -253.753964)
			(xy 257.81127 -253.764034) (xy 257.81127 -255.362964) (xy 257.810835 -255.373028) (xy 257.8031 -255.391613)
			(xy 257.796284 -255.399032) (xy 257.096768 -256.098548) (xy 260.081774 -256.098548) (xy 260.085845 -256.042926)
			(xy 260.097971 -255.988489) (xy 260.117894 -255.936398) (xy 260.14519 -255.887763) (xy 260.179276 -255.84362)
			(xy 260.219425 -255.804911) (xy 260.264783 -255.77246) (xy 260.314383 -255.746959) (xy 260.367167 -255.728952)
			(xy 260.42201 -255.718822) (xy 260.477744 -255.716785) (xy 260.533181 -255.722885) (xy 260.587138 -255.736991)
			(xy 260.638467 -255.758803) (xy 260.686073 -255.787857) (xy 260.728941 -255.823532) (xy 260.766158 -255.865069)
			(xy 260.796931 -255.911582) (xy 260.820603 -255.962079) (xy 260.836671 -256.015486) (xy 260.844791 -256.070662)
			(xy 260.8453 -256.098548) (xy 260.844791 -256.126434) (xy 260.836671 -256.18161) (xy 260.820603 -256.235017)
			(xy 260.796931 -256.285514) (xy 260.766158 -256.332027) (xy 260.728941 -256.373564) (xy 260.726115 -256.375916)
			(xy 260.969504 -256.375916) (xy 260.973575 -256.320294) (xy 260.985701 -256.265857) (xy 261.005624 -256.213766)
			(xy 261.03292 -256.165131) (xy 261.067006 -256.120988) (xy 261.107155 -256.082279) (xy 261.152513 -256.049828)
			(xy 261.202113 -256.024327) (xy 261.254897 -256.00632) (xy 261.30974 -255.99619) (xy 261.365474 -255.994153)
			(xy 261.420911 -256.000253) (xy 261.474868 -256.014359) (xy 261.526197 -256.036171) (xy 261.573803 -256.065225)
			(xy 261.616671 -256.1009) (xy 261.653888 -256.142437) (xy 261.684661 -256.18895) (xy 261.708333 -256.239447)
			(xy 261.724401 -256.292854) (xy 261.732521 -256.34803) (xy 261.73303 -256.375916) (xy 262.44499 -256.375916)
			(xy 262.449061 -256.320294) (xy 262.461187 -256.265857) (xy 262.48111 -256.213766) (xy 262.508406 -256.165131)
			(xy 262.542492 -256.120988) (xy 262.582641 -256.082279) (xy 262.627999 -256.049828) (xy 262.677599 -256.024327)
			(xy 262.730383 -256.00632) (xy 262.785226 -255.99619) (xy 262.84096 -255.994153) (xy 262.896397 -256.000253)
			(xy 262.950354 -256.014359) (xy 263.001683 -256.036171) (xy 263.049289 -256.065225) (xy 263.092157 -256.1009)
			(xy 263.129374 -256.142437) (xy 263.160147 -256.18895) (xy 263.183819 -256.239447) (xy 263.199887 -256.292854)
			(xy 263.208007 -256.34803) (xy 263.208516 -256.375916) (xy 263.208007 -256.403802) (xy 263.199887 -256.458978)
			(xy 263.183819 -256.512385) (xy 263.160147 -256.562882) (xy 263.129374 -256.609395) (xy 263.092157 -256.650932)
			(xy 263.049289 -256.686607) (xy 263.001683 -256.715661) (xy 262.950354 -256.737473) (xy 262.896397 -256.751579)
			(xy 262.84096 -256.757679) (xy 262.785226 -256.755642) (xy 262.730383 -256.745512) (xy 262.677599 -256.727505)
			(xy 262.627999 -256.702004) (xy 262.582641 -256.669553) (xy 262.542492 -256.630844) (xy 262.508406 -256.586701)
			(xy 262.48111 -256.538066) (xy 262.461187 -256.485975) (xy 262.449061 -256.431538) (xy 262.44499 -256.375916)
			(xy 261.73303 -256.375916) (xy 261.732521 -256.403802) (xy 261.724401 -256.458978) (xy 261.708333 -256.512385)
			(xy 261.684661 -256.562882) (xy 261.653888 -256.609395) (xy 261.616671 -256.650932) (xy 261.573803 -256.686607)
			(xy 261.526197 -256.715661) (xy 261.474868 -256.737473) (xy 261.420911 -256.751579) (xy 261.365474 -256.757679)
			(xy 261.30974 -256.755642) (xy 261.254897 -256.745512) (xy 261.202113 -256.727505) (xy 261.152513 -256.702004)
			(xy 261.107155 -256.669553) (xy 261.067006 -256.630844) (xy 261.03292 -256.586701) (xy 261.005624 -256.538066)
			(xy 260.985701 -256.485975) (xy 260.973575 -256.431538) (xy 260.969504 -256.375916) (xy 260.726115 -256.375916)
			(xy 260.686073 -256.409239) (xy 260.638467 -256.438293) (xy 260.587138 -256.460105) (xy 260.533181 -256.474211)
			(xy 260.477744 -256.480311) (xy 260.42201 -256.478274) (xy 260.367167 -256.468144) (xy 260.314383 -256.450137)
			(xy 260.264783 -256.424636) (xy 260.219425 -256.392185) (xy 260.179276 -256.353476) (xy 260.14519 -256.309333)
			(xy 260.117894 -256.260698) (xy 260.097971 -256.208607) (xy 260.085845 -256.15417) (xy 260.081774 -256.098548)
			(xy 257.096768 -256.098548) (xy 256.207768 -256.987548) (xy 260.081774 -256.987548) (xy 260.085845 -256.931926)
			(xy 260.097971 -256.877489) (xy 260.117894 -256.825398) (xy 260.14519 -256.776763) (xy 260.179276 -256.73262)
			(xy 260.219425 -256.693911) (xy 260.264783 -256.66146) (xy 260.314383 -256.635959) (xy 260.367167 -256.617952)
			(xy 260.42201 -256.607822) (xy 260.477744 -256.605785) (xy 260.533181 -256.611885) (xy 260.587138 -256.625991)
			(xy 260.638467 -256.647803) (xy 260.686073 -256.676857) (xy 260.728941 -256.712532) (xy 260.766158 -256.754069)
			(xy 260.796931 -256.800582) (xy 260.820603 -256.851079) (xy 260.836671 -256.904486) (xy 260.844791 -256.959662)
			(xy 260.8453 -256.987548) (xy 260.844791 -257.015434) (xy 260.836671 -257.07061) (xy 260.820603 -257.124017)
			(xy 260.796931 -257.174514) (xy 260.766158 -257.221027) (xy 260.728941 -257.262564) (xy 260.686073 -257.298239)
			(xy 260.638467 -257.327293) (xy 260.587138 -257.349105) (xy 260.533181 -257.363211) (xy 260.477744 -257.369311)
			(xy 260.42201 -257.367274) (xy 260.367167 -257.357144) (xy 260.314383 -257.339137) (xy 260.264783 -257.313636)
			(xy 260.219425 -257.281185) (xy 260.179276 -257.242476) (xy 260.14519 -257.198333) (xy 260.117894 -257.149698)
			(xy 260.097971 -257.097607) (xy 260.085845 -257.04317) (xy 260.081774 -256.987548) (xy 256.207768 -256.987548)
			(xy 255.589024 -257.606292) (xy 255.581622 -257.613127) (xy 255.563023 -257.620835) (xy 255.552956 -257.621278)
			(xy 254.96012 -258.214114) (xy 256.61061 -258.214114) (xy 256.614681 -258.158492) (xy 256.626807 -258.104055)
			(xy 256.64673 -258.051964) (xy 256.674026 -258.003329) (xy 256.708112 -257.959186) (xy 256.748261 -257.920477)
			(xy 256.793619 -257.888026) (xy 256.843219 -257.862525) (xy 256.896003 -257.844518) (xy 256.950846 -257.834388)
			(xy 257.00658 -257.832351) (xy 257.062017 -257.838451) (xy 257.115974 -257.852557) (xy 257.167303 -257.874369)
			(xy 257.214909 -257.903423) (xy 257.257777 -257.939098) (xy 257.294994 -257.980635) (xy 257.325767 -258.027148)
			(xy 257.349439 -258.077645) (xy 257.365507 -258.131052) (xy 257.373627 -258.186228) (xy 257.374136 -258.214114)
			(xy 257.373627 -258.242) (xy 257.365507 -258.297176) (xy 257.349439 -258.350583) (xy 257.325767 -258.40108)
			(xy 257.294994 -258.447593) (xy 257.257777 -258.48913) (xy 257.214909 -258.524805) (xy 257.167303 -258.553859)
			(xy 257.115974 -258.575671) (xy 257.062017 -258.589777) (xy 257.00658 -258.595877) (xy 256.950846 -258.59384)
			(xy 256.896003 -258.58371) (xy 256.843219 -258.565703) (xy 256.793619 -258.540202) (xy 256.748261 -258.507751)
			(xy 256.708112 -258.469042) (xy 256.674026 -258.424899) (xy 256.64673 -258.376264) (xy 256.626807 -258.324173)
			(xy 256.614681 -258.269736) (xy 256.61061 -258.214114) (xy 254.96012 -258.214114) (xy 254.524256 -258.649978)
			(xy 255.126234 -258.649978) (xy 255.130305 -258.594356) (xy 255.142431 -258.539919) (xy 255.162354 -258.487828)
			(xy 255.18965 -258.439193) (xy 255.223736 -258.39505) (xy 255.263885 -258.356341) (xy 255.309243 -258.32389)
			(xy 255.358843 -258.298389) (xy 255.411627 -258.280382) (xy 255.46647 -258.270252) (xy 255.522204 -258.268215)
			(xy 255.577641 -258.274315) (xy 255.631598 -258.288421) (xy 255.682927 -258.310233) (xy 255.730533 -258.339287)
			(xy 255.773401 -258.374962) (xy 255.810618 -258.416499) (xy 255.841391 -258.463012) (xy 255.865063 -258.513509)
			(xy 255.881131 -258.566916) (xy 255.889251 -258.622092) (xy 255.88976 -258.649978) (xy 255.889251 -258.677864)
			(xy 255.881131 -258.73304) (xy 255.865063 -258.786447) (xy 255.841391 -258.836944) (xy 255.810618 -258.883457)
			(xy 255.773401 -258.924994) (xy 255.730533 -258.960669) (xy 255.682927 -258.989723) (xy 255.631598 -259.011535)
			(xy 255.577641 -259.025641) (xy 255.522204 -259.031741) (xy 255.46647 -259.029704) (xy 255.411627 -259.019574)
			(xy 255.358843 -259.001567) (xy 255.309243 -258.976066) (xy 255.263885 -258.943615) (xy 255.223736 -258.904906)
			(xy 255.18965 -258.860763) (xy 255.162354 -258.812128) (xy 255.142431 -258.760037) (xy 255.130305 -258.7056)
			(xy 255.126234 -258.649978) (xy 254.524256 -258.649978) (xy 253.597918 -259.576316) (xy 262.44499 -259.576316)
			(xy 262.449061 -259.520694) (xy 262.461187 -259.466257) (xy 262.48111 -259.414166) (xy 262.508406 -259.365531)
			(xy 262.542492 -259.321388) (xy 262.582641 -259.282679) (xy 262.627999 -259.250228) (xy 262.677599 -259.224727)
			(xy 262.730383 -259.20672) (xy 262.785226 -259.19659) (xy 262.84096 -259.194553) (xy 262.896397 -259.200653)
			(xy 262.950354 -259.214759) (xy 263.001683 -259.236571) (xy 263.049289 -259.265625) (xy 263.092157 -259.3013)
			(xy 263.129374 -259.342837) (xy 263.160147 -259.38935) (xy 263.183819 -259.439847) (xy 263.199887 -259.493254)
			(xy 263.208007 -259.54843) (xy 263.208516 -259.576316) (xy 263.208007 -259.604202) (xy 263.199887 -259.659378)
			(xy 263.183819 -259.712785) (xy 263.160147 -259.763282) (xy 263.129374 -259.809795) (xy 263.092157 -259.851332)
			(xy 263.049289 -259.887007) (xy 263.001683 -259.916061) (xy 262.950354 -259.937873) (xy 262.896397 -259.951979)
			(xy 262.84096 -259.958079) (xy 262.785226 -259.956042) (xy 262.730383 -259.945912) (xy 262.677599 -259.927905)
			(xy 262.627999 -259.902404) (xy 262.582641 -259.869953) (xy 262.542492 -259.831244) (xy 262.508406 -259.787101)
			(xy 262.48111 -259.738466) (xy 262.461187 -259.686375) (xy 262.449061 -259.631938) (xy 262.44499 -259.576316)
			(xy 253.597918 -259.576316) (xy 253.292102 -259.882132) (xy 253.28526 -259.889532) (xy 253.277537 -259.90813)
			(xy 253.277116 -259.9182) (xy 253.277116 -260.027674) (xy 254.29159 -260.027674) (xy 254.295661 -259.972052)
			(xy 254.307787 -259.917615) (xy 254.32771 -259.865524) (xy 254.355006 -259.816889) (xy 254.389092 -259.772746)
			(xy 254.429241 -259.734037) (xy 254.474599 -259.701586) (xy 254.524199 -259.676085) (xy 254.576983 -259.658078)
			(xy 254.631826 -259.647948) (xy 254.68756 -259.645911) (xy 254.742997 -259.652011) (xy 254.796954 -259.666117)
			(xy 254.848283 -259.687929) (xy 254.895889 -259.716983) (xy 254.938757 -259.752658) (xy 254.975974 -259.794195)
			(xy 255.006747 -259.840708) (xy 255.030419 -259.891205) (xy 255.046487 -259.944612) (xy 255.054607 -259.999788)
			(xy 255.055116 -260.027674) (xy 255.054607 -260.05556) (xy 255.052394 -260.0706) (xy 255.842768 -260.0706)
			(xy 255.846839 -260.014978) (xy 255.858965 -259.960541) (xy 255.878888 -259.90845) (xy 255.906184 -259.859815)
			(xy 255.94027 -259.815672) (xy 255.980419 -259.776963) (xy 256.025777 -259.744512) (xy 256.075377 -259.719011)
			(xy 256.128161 -259.701004) (xy 256.183004 -259.690874) (xy 256.238738 -259.688837) (xy 256.294175 -259.694937)
			(xy 256.348132 -259.709043) (xy 256.399461 -259.730855) (xy 256.447067 -259.759909) (xy 256.489935 -259.795584)
			(xy 256.527152 -259.837121) (xy 256.557925 -259.883634) (xy 256.581597 -259.934131) (xy 256.597665 -259.987538)
			(xy 256.605785 -260.042714) (xy 256.606294 -260.0706) (xy 256.605816 -260.096762) (xy 259.858762 -260.096762)
			(xy 259.862833 -260.04114) (xy 259.874959 -259.986703) (xy 259.894882 -259.934612) (xy 259.922178 -259.885977)
			(xy 259.956264 -259.841834) (xy 259.996413 -259.803125) (xy 260.041771 -259.770674) (xy 260.091371 -259.745173)
			(xy 260.144155 -259.727166) (xy 260.198998 -259.717036) (xy 260.254732 -259.714999) (xy 260.310169 -259.721099)
			(xy 260.364126 -259.735205) (xy 260.415455 -259.757017) (xy 260.463061 -259.786071) (xy 260.505929 -259.821746)
			(xy 260.543146 -259.863283) (xy 260.573919 -259.909796) (xy 260.597591 -259.960293) (xy 260.613659 -260.0137)
			(xy 260.621779 -260.068876) (xy 260.622288 -260.096762) (xy 260.621779 -260.124648) (xy 260.613659 -260.179824)
			(xy 260.597591 -260.233231) (xy 260.573919 -260.283728) (xy 260.543146 -260.330241) (xy 260.505929 -260.371778)
			(xy 260.463061 -260.407453) (xy 260.415455 -260.436507) (xy 260.364126 -260.458319) (xy 260.310169 -260.472425)
			(xy 260.254732 -260.478525) (xy 260.198998 -260.476488) (xy 260.144155 -260.466358) (xy 260.091371 -260.448351)
			(xy 260.041771 -260.42285) (xy 259.996413 -260.390399) (xy 259.956264 -260.35169) (xy 259.922178 -260.307547)
			(xy 259.894882 -260.258912) (xy 259.874959 -260.206821) (xy 259.862833 -260.152384) (xy 259.858762 -260.096762)
			(xy 256.605816 -260.096762) (xy 256.605785 -260.098486) (xy 256.597665 -260.153662) (xy 256.581597 -260.207069)
			(xy 256.557925 -260.257566) (xy 256.527152 -260.304079) (xy 256.489935 -260.345616) (xy 256.447067 -260.381291)
			(xy 256.399461 -260.410345) (xy 256.348132 -260.432157) (xy 256.294175 -260.446263) (xy 256.238738 -260.452363)
			(xy 256.183004 -260.450326) (xy 256.128161 -260.440196) (xy 256.075377 -260.422189) (xy 256.025777 -260.396688)
			(xy 255.980419 -260.364237) (xy 255.94027 -260.325528) (xy 255.906184 -260.281385) (xy 255.878888 -260.23275)
			(xy 255.858965 -260.180659) (xy 255.846839 -260.126222) (xy 255.842768 -260.0706) (xy 255.052394 -260.0706)
			(xy 255.046487 -260.110736) (xy 255.030419 -260.164143) (xy 255.006747 -260.21464) (xy 254.975974 -260.261153)
			(xy 254.938757 -260.30269) (xy 254.895889 -260.338365) (xy 254.848283 -260.367419) (xy 254.796954 -260.389231)
			(xy 254.742997 -260.403337) (xy 254.68756 -260.409437) (xy 254.631826 -260.4074) (xy 254.576983 -260.39727)
			(xy 254.524199 -260.379263) (xy 254.474599 -260.353762) (xy 254.429241 -260.321311) (xy 254.389092 -260.282602)
			(xy 254.355006 -260.238459) (xy 254.32771 -260.189824) (xy 254.307787 -260.137733) (xy 254.295661 -260.083296)
			(xy 254.29159 -260.027674) (xy 253.277116 -260.027674) (xy 253.277116 -261.817955) (xy 257.719243 -261.817955)
			(xy 257.719243 -261.763445) (xy 257.727001 -261.709491) (xy 257.742358 -261.657189) (xy 257.765003 -261.607606)
			(xy 257.794474 -261.56175) (xy 257.830171 -261.520556) (xy 257.871368 -261.484861) (xy 257.917225 -261.455393)
			(xy 257.96681 -261.432751) (xy 258.019112 -261.417396) (xy 258.073067 -261.409641) (xy 258.100322 -261.40918)
			(xy 258.129238 -261.409724) (xy 258.18641 -261.418444) (xy 258.241609 -261.435694) (xy 258.293572 -261.461081)
			(xy 258.341106 -261.494022) (xy 258.383122 -261.533761) (xy 258.401312 -261.556246) (xy 258.408865 -261.565016)
			(xy 258.429631 -261.575193) (xy 258.44119 -261.575804) (xy 258.521454 -261.575804) (xy 258.533018 -261.575206)
			(xy 258.55379 -261.565031) (xy 258.561332 -261.556246) (xy 258.578085 -261.535463) (xy 258.616439 -261.498333)
			(xy 258.659593 -261.466911) (xy 258.706707 -261.441812) (xy 258.756859 -261.423526) (xy 258.80907 -261.412409)
			(xy 258.862322 -261.408679) (xy 258.915574 -261.412409) (xy 258.967785 -261.423526) (xy 259.017937 -261.441812)
			(xy 259.065051 -261.466911) (xy 259.108205 -261.498333) (xy 259.146559 -261.535463) (xy 259.163312 -261.556246)
			(xy 259.170865 -261.565016) (xy 259.191631 -261.575193) (xy 259.20319 -261.575804) (xy 259.283454 -261.575804)
			(xy 259.295018 -261.575206) (xy 259.31579 -261.565031) (xy 259.323332 -261.556246) (xy 259.341491 -261.533736)
			(xy 259.383519 -261.494005) (xy 259.431061 -261.461071) (xy 259.483029 -261.435687) (xy 259.538231 -261.418436)
			(xy 259.595404 -261.409712) (xy 259.624322 -261.40918) (xy 259.651571 -261.409692) (xy 259.705515 -261.417451)
			(xy 259.757805 -261.432807) (xy 259.807378 -261.455449) (xy 259.853224 -261.484915) (xy 259.894411 -261.520605)
			(xy 259.930099 -261.561793) (xy 259.959562 -261.607641) (xy 259.982201 -261.657215) (xy 259.997554 -261.709507)
			(xy 260.00531 -261.763451) (xy 260.00531 -261.817949) (xy 259.997554 -261.871893) (xy 259.982201 -261.924185)
			(xy 259.959562 -261.973759) (xy 259.930099 -262.019607) (xy 259.894411 -262.060795) (xy 259.853224 -262.096485)
			(xy 259.807378 -262.125951) (xy 259.757805 -262.148593) (xy 259.705515 -262.163949) (xy 259.651571 -262.171708)
			(xy 259.624322 -262.172196) (xy 259.595406 -262.171663) (xy 259.538235 -262.162937) (xy 259.483036 -262.145682)
			(xy 259.431075 -262.120294) (xy 259.38354 -262.087353) (xy 259.341523 -262.047614) (xy 259.323332 -262.02513)
			(xy 259.315764 -262.016375) (xy 259.295009 -262.006191) (xy 259.283454 -262.005572) (xy 259.20319 -262.005572)
			(xy 259.191617 -262.006112) (xy 259.170845 -262.016325) (xy 259.163312 -262.02513) (xy 259.146559 -262.045913)
			(xy 259.108205 -262.083043) (xy 259.065051 -262.114465) (xy 259.017937 -262.139564) (xy 258.967785 -262.15785)
			(xy 258.915574 -262.168967) (xy 258.862322 -262.172697) (xy 258.80907 -262.168967) (xy 258.756859 -262.15785)
			(xy 258.706707 -262.139564) (xy 258.659593 -262.114465) (xy 258.616439 -262.083043) (xy 258.578085 -262.045913)
			(xy 258.561332 -262.02513) (xy 258.553764 -262.016375) (xy 258.533009 -262.006191) (xy 258.521454 -262.005572)
			(xy 258.44119 -262.005572) (xy 258.429617 -262.006112) (xy 258.408845 -262.016325) (xy 258.401312 -262.02513)
			(xy 258.383122 -262.047614) (xy 258.341101 -262.087348) (xy 258.293566 -262.120286) (xy 258.241604 -262.145674)
			(xy 258.186407 -262.16293) (xy 258.129238 -262.17166) (xy 258.100322 -262.172196) (xy 258.073067 -262.171759)
			(xy 258.019112 -262.164004) (xy 257.96681 -262.148649) (xy 257.917225 -262.126007) (xy 257.871368 -262.096539)
			(xy 257.830171 -262.060844) (xy 257.794474 -262.01965) (xy 257.765003 -261.973794) (xy 257.742358 -261.924211)
			(xy 257.727001 -261.871909) (xy 257.719243 -261.817955) (xy 253.277116 -261.817955) (xy 253.277116 -262.912352)
			(xy 257.3688 -262.912352) (xy 257.372871 -262.85673) (xy 257.384997 -262.802293) (xy 257.40492 -262.750202)
			(xy 257.432216 -262.701567) (xy 257.466302 -262.657424) (xy 257.506451 -262.618715) (xy 257.551809 -262.586264)
			(xy 257.601409 -262.560763) (xy 257.654193 -262.542756) (xy 257.709036 -262.532626) (xy 257.76477 -262.530589)
			(xy 257.820207 -262.536689) (xy 257.874164 -262.550795) (xy 257.925493 -262.572607) (xy 257.973099 -262.601661)
			(xy 258.015967 -262.637336) (xy 258.053184 -262.678873) (xy 258.083957 -262.725386) (xy 258.107629 -262.775883)
			(xy 258.123697 -262.82929) (xy 258.131817 -262.884466) (xy 258.132326 -262.912352) (xy 258.132205 -262.918956)
			(xy 259.357114 -262.918956) (xy 259.358638 -262.885682) (xy 259.361365 -262.857344) (xy 259.374247 -262.801891)
			(xy 259.395228 -262.748969) (xy 259.423843 -262.699754) (xy 259.459455 -262.655338) (xy 259.501273 -262.61671)
			(xy 259.548369 -262.584726) (xy 259.599695 -262.560098) (xy 259.654113 -262.543373) (xy 259.710411 -262.534922)
			(xy 259.738876 -262.5344) (xy 259.767335 -262.534919) (xy 259.823619 -262.543399) (xy 259.878019 -262.560145)
			(xy 259.929329 -262.584785) (xy 259.976409 -262.616773) (xy 260.018217 -262.655399) (xy 260.053823 -262.699806)
			(xy 260.082439 -262.749008) (xy 260.103429 -262.801916) (xy 260.116328 -262.857354) (xy 260.119114 -262.885682)
			(xy 260.120638 -262.918956) (xy 260.120152 -262.946225) (xy 260.11239 -263.000209) (xy 260.097025 -263.052539)
			(xy 260.074368 -263.102149) (xy 260.044882 -263.14803) (xy 260.009167 -263.189247) (xy 259.96795 -263.224962)
			(xy 259.922069 -263.254448) (xy 259.872459 -263.277105) (xy 259.820129 -263.29247) (xy 259.766145 -263.300232)
			(xy 259.711607 -263.300232) (xy 259.657623 -263.29247) (xy 259.605293 -263.277105) (xy 259.555683 -263.254448)
			(xy 259.509802 -263.224962) (xy 259.468585 -263.189247) (xy 259.43287 -263.14803) (xy 259.403384 -263.102149)
			(xy 259.380727 -263.052539) (xy 259.365362 -263.000209) (xy 259.3576 -262.946225) (xy 259.357114 -262.918956)
			(xy 258.132205 -262.918956) (xy 258.131817 -262.940238) (xy 258.123697 -262.995414) (xy 258.107629 -263.048821)
			(xy 258.083957 -263.099318) (xy 258.053184 -263.145831) (xy 258.015967 -263.187368) (xy 257.973099 -263.223043)
			(xy 257.925493 -263.252097) (xy 257.874164 -263.273909) (xy 257.820207 -263.288015) (xy 257.76477 -263.294115)
			(xy 257.709036 -263.292078) (xy 257.654193 -263.281948) (xy 257.601409 -263.263941) (xy 257.551809 -263.23844)
			(xy 257.506451 -263.205989) (xy 257.466302 -263.16728) (xy 257.432216 -263.123137) (xy 257.40492 -263.074502)
			(xy 257.384997 -263.022411) (xy 257.372871 -262.967974) (xy 257.3688 -262.912352) (xy 253.277116 -262.912352)
			(xy 253.277116 -279.931114) (xy 258.01142 -279.931114) (xy 258.015491 -279.875492) (xy 258.027617 -279.821055)
			(xy 258.04754 -279.768964) (xy 258.074836 -279.720329) (xy 258.108922 -279.676186) (xy 258.149071 -279.637477)
			(xy 258.194429 -279.605026) (xy 258.244029 -279.579525) (xy 258.296813 -279.561518) (xy 258.351656 -279.551388)
			(xy 258.40739 -279.549351) (xy 258.462827 -279.555451) (xy 258.516784 -279.569557) (xy 258.568113 -279.591369)
			(xy 258.615719 -279.620423) (xy 258.658587 -279.656098) (xy 258.695804 -279.697635) (xy 258.726577 -279.744148)
			(xy 258.750249 -279.794645) (xy 258.766317 -279.848052) (xy 258.774437 -279.903228) (xy 258.774946 -279.931114)
			(xy 258.774437 -279.959) (xy 258.766317 -280.014176) (xy 258.750249 -280.067583) (xy 258.726577 -280.11808)
			(xy 258.695804 -280.164593) (xy 258.658587 -280.20613) (xy 258.615719 -280.241805) (xy 258.568113 -280.270859)
			(xy 258.516784 -280.292671) (xy 258.462827 -280.306777) (xy 258.40739 -280.312877) (xy 258.351656 -280.31084)
			(xy 258.296813 -280.30071) (xy 258.244029 -280.282703) (xy 258.194429 -280.257202) (xy 258.149071 -280.224751)
			(xy 258.108922 -280.186042) (xy 258.074836 -280.141899) (xy 258.04754 -280.093264) (xy 258.027617 -280.041173)
			(xy 258.015491 -279.986736) (xy 258.01142 -279.931114) (xy 253.277116 -279.931114) (xy 253.277116 -283.131514)
			(xy 258.01142 -283.131514) (xy 258.015491 -283.075892) (xy 258.027617 -283.021455) (xy 258.04754 -282.969364)
			(xy 258.074836 -282.920729) (xy 258.108922 -282.876586) (xy 258.149071 -282.837877) (xy 258.194429 -282.805426)
			(xy 258.244029 -282.779925) (xy 258.296813 -282.761918) (xy 258.351656 -282.751788) (xy 258.40739 -282.749751)
			(xy 258.462827 -282.755851) (xy 258.516784 -282.769957) (xy 258.568113 -282.791769) (xy 258.615719 -282.820823)
			(xy 258.658587 -282.856498) (xy 258.695804 -282.898035) (xy 258.726577 -282.944548) (xy 258.750249 -282.995045)
			(xy 258.766317 -283.048452) (xy 258.774437 -283.103628) (xy 258.774946 -283.131514) (xy 258.774437 -283.1594)
			(xy 258.766317 -283.214576) (xy 258.750249 -283.267983) (xy 258.726577 -283.31848) (xy 258.695804 -283.364993)
			(xy 258.658587 -283.40653) (xy 258.615719 -283.442205) (xy 258.568113 -283.471259) (xy 258.516784 -283.493071)
			(xy 258.462827 -283.507177) (xy 258.40739 -283.513277) (xy 258.351656 -283.51124) (xy 258.296813 -283.50111)
			(xy 258.244029 -283.483103) (xy 258.194429 -283.457602) (xy 258.149071 -283.425151) (xy 258.108922 -283.386442)
			(xy 258.074836 -283.342299) (xy 258.04754 -283.293664) (xy 258.027617 -283.241573) (xy 258.015491 -283.187136)
			(xy 258.01142 -283.131514) (xy 253.277116 -283.131514) (xy 253.277116 -286.331914) (xy 258.01142 -286.331914)
			(xy 258.015491 -286.276292) (xy 258.027617 -286.221855) (xy 258.04754 -286.169764) (xy 258.074836 -286.121129)
			(xy 258.108922 -286.076986) (xy 258.149071 -286.038277) (xy 258.194429 -286.005826) (xy 258.244029 -285.980325)
			(xy 258.296813 -285.962318) (xy 258.351656 -285.952188) (xy 258.40739 -285.950151) (xy 258.462827 -285.956251)
			(xy 258.516784 -285.970357) (xy 258.568113 -285.992169) (xy 258.615719 -286.021223) (xy 258.658587 -286.056898)
			(xy 258.695804 -286.098435) (xy 258.726577 -286.144948) (xy 258.750249 -286.195445) (xy 258.766317 -286.248852)
			(xy 258.774437 -286.304028) (xy 258.774946 -286.331914) (xy 258.774437 -286.3598) (xy 258.766317 -286.414976)
			(xy 258.750249 -286.468383) (xy 258.726577 -286.51888) (xy 258.695804 -286.565393) (xy 258.658587 -286.60693)
			(xy 258.615719 -286.642605) (xy 258.568113 -286.671659) (xy 258.516784 -286.693471) (xy 258.462827 -286.707577)
			(xy 258.40739 -286.713677) (xy 258.351656 -286.71164) (xy 258.296813 -286.70151) (xy 258.244029 -286.683503)
			(xy 258.194429 -286.658002) (xy 258.149071 -286.625551) (xy 258.108922 -286.586842) (xy 258.074836 -286.542699)
			(xy 258.04754 -286.494064) (xy 258.027617 -286.441973) (xy 258.015491 -286.387536) (xy 258.01142 -286.331914)
			(xy 253.277116 -286.331914) (xy 253.277116 -289.532314) (xy 258.01142 -289.532314) (xy 258.015491 -289.476692)
			(xy 258.027617 -289.422255) (xy 258.04754 -289.370164) (xy 258.074836 -289.321529) (xy 258.108922 -289.277386)
			(xy 258.149071 -289.238677) (xy 258.194429 -289.206226) (xy 258.244029 -289.180725) (xy 258.296813 -289.162718)
			(xy 258.351656 -289.152588) (xy 258.40739 -289.150551) (xy 258.462827 -289.156651) (xy 258.516784 -289.170757)
			(xy 258.568113 -289.192569) (xy 258.615719 -289.221623) (xy 258.658587 -289.257298) (xy 258.695804 -289.298835)
			(xy 258.726577 -289.345348) (xy 258.750249 -289.395845) (xy 258.766317 -289.449252) (xy 258.774437 -289.504428)
			(xy 258.774946 -289.532314) (xy 258.774437 -289.5602) (xy 258.766317 -289.615376) (xy 258.750249 -289.668783)
			(xy 258.726577 -289.71928) (xy 258.695804 -289.765793) (xy 258.658587 -289.80733) (xy 258.615719 -289.843005)
			(xy 258.568113 -289.872059) (xy 258.516784 -289.893871) (xy 258.462827 -289.907977) (xy 258.40739 -289.914077)
			(xy 258.351656 -289.91204) (xy 258.296813 -289.90191) (xy 258.244029 -289.883903) (xy 258.194429 -289.858402)
			(xy 258.149071 -289.825951) (xy 258.108922 -289.787242) (xy 258.074836 -289.743099) (xy 258.04754 -289.694464)
			(xy 258.027617 -289.642373) (xy 258.015491 -289.587936) (xy 258.01142 -289.532314) (xy 253.277116 -289.532314)
			(xy 253.277116 -292.732714) (xy 258.01142 -292.732714) (xy 258.015491 -292.677092) (xy 258.027617 -292.622655)
			(xy 258.04754 -292.570564) (xy 258.074836 -292.521929) (xy 258.108922 -292.477786) (xy 258.149071 -292.439077)
			(xy 258.194429 -292.406626) (xy 258.244029 -292.381125) (xy 258.296813 -292.363118) (xy 258.351656 -292.352988)
			(xy 258.40739 -292.350951) (xy 258.462827 -292.357051) (xy 258.516784 -292.371157) (xy 258.568113 -292.392969)
			(xy 258.615719 -292.422023) (xy 258.658587 -292.457698) (xy 258.695804 -292.499235) (xy 258.726577 -292.545748)
			(xy 258.750249 -292.596245) (xy 258.766317 -292.649652) (xy 258.774437 -292.704828) (xy 258.774946 -292.732714)
			(xy 258.774437 -292.7606) (xy 258.766317 -292.815776) (xy 258.750249 -292.869183) (xy 258.726577 -292.91968)
			(xy 258.695804 -292.966193) (xy 258.658587 -293.00773) (xy 258.615719 -293.043405) (xy 258.568113 -293.072459)
			(xy 258.516784 -293.094271) (xy 258.462827 -293.108377) (xy 258.40739 -293.114477) (xy 258.351656 -293.11244)
			(xy 258.296813 -293.10231) (xy 258.244029 -293.084303) (xy 258.194429 -293.058802) (xy 258.149071 -293.026351)
			(xy 258.108922 -292.987642) (xy 258.074836 -292.943499) (xy 258.04754 -292.894864) (xy 258.027617 -292.842773)
			(xy 258.015491 -292.788336) (xy 258.01142 -292.732714) (xy 253.277116 -292.732714) (xy 253.277116 -293.921688)
			(xy 253.284736 -293.940484) (xy 253.292102 -293.947596) (xy 253.548388 -294.203882) (xy 253.556516 -294.210486)
			(xy 253.56947 -294.218868) (xy 253.574296 -294.2209) (xy 253.650416 -294.251019) (xy 253.799956 -294.317669)
			(xy 253.946089 -294.39149) (xy 254.017526 -294.431466) (xy 254.090419 -294.473423) (xy 254.232408 -294.563604)
			(xy 254.369736 -294.660736) (xy 254.502063 -294.764579) (xy 254.565912 -294.819324) (xy 254.627374 -294.873261)
			(xy 254.745609 -294.986251) (xy 254.858239 -295.104829) (xy 254.965 -295.228718) (xy 255.065641 -295.357627)
			(xy 255.159927 -295.491255) (xy 255.247638 -295.629288) (xy 255.328567 -295.771403) (xy 255.402525 -295.917267)
			(xy 255.409618 -295.933114) (xy 258.01142 -295.933114) (xy 258.015491 -295.877492) (xy 258.027617 -295.823055)
			(xy 258.04754 -295.770964) (xy 258.074836 -295.722329) (xy 258.108922 -295.678186) (xy 258.149071 -295.639477)
			(xy 258.194429 -295.607026) (xy 258.244029 -295.581525) (xy 258.296813 -295.563518) (xy 258.351656 -295.553388)
			(xy 258.40739 -295.551351) (xy 258.462827 -295.557451) (xy 258.516784 -295.571557) (xy 258.568113 -295.593369)
			(xy 258.615719 -295.622423) (xy 258.658587 -295.658098) (xy 258.695804 -295.699635) (xy 258.726577 -295.746148)
			(xy 258.750249 -295.796645) (xy 258.766317 -295.850052) (xy 258.774437 -295.905228) (xy 258.774946 -295.933114)
			(xy 258.774437 -295.961) (xy 258.766317 -296.016176) (xy 258.750249 -296.069583) (xy 258.726577 -296.12008)
			(xy 258.695804 -296.166593) (xy 258.658587 -296.20813) (xy 258.615719 -296.243805) (xy 258.568113 -296.272859)
			(xy 258.516784 -296.294671) (xy 258.462827 -296.308777) (xy 258.40739 -296.314877) (xy 258.351656 -296.31284)
			(xy 258.296813 -296.30271) (xy 258.244029 -296.284703) (xy 258.194429 -296.259202) (xy 258.149071 -296.226751)
			(xy 258.108922 -296.188042) (xy 258.074836 -296.143899) (xy 258.04754 -296.095264) (xy 258.027617 -296.043173)
			(xy 258.015491 -295.988736) (xy 258.01142 -295.933114) (xy 255.409618 -295.933114) (xy 255.469339 -296.066539)
			(xy 255.528852 -296.218869) (xy 255.580926 -296.3739) (xy 255.625437 -296.531269) (xy 255.662282 -296.690608)
			(xy 255.691374 -296.851542) (xy 255.712646 -297.013696) (xy 255.726047 -297.176688) (xy 255.731546 -297.340139)
			(xy 255.72913 -297.503664) (xy 255.718805 -297.66688) (xy 255.700595 -297.829406) (xy 255.674543 -297.99086)
			(xy 255.640709 -298.150865) (xy 255.599173 -298.309046) (xy 255.550032 -298.465031) (xy 255.493402 -298.618456)
			(xy 255.429415 -298.768962) (xy 255.35822 -298.916195) (xy 255.279985 -299.059811) (xy 255.23508 -299.133514)
			(xy 258.01142 -299.133514) (xy 258.015491 -299.077892) (xy 258.027617 -299.023455) (xy 258.04754 -298.971364)
			(xy 258.074836 -298.922729) (xy 258.108922 -298.878586) (xy 258.149071 -298.839877) (xy 258.194429 -298.807426)
			(xy 258.244029 -298.781925) (xy 258.296813 -298.763918) (xy 258.351656 -298.753788) (xy 258.40739 -298.751751)
			(xy 258.462827 -298.757851) (xy 258.516784 -298.771957) (xy 258.568113 -298.793769) (xy 258.615719 -298.822823)
			(xy 258.658587 -298.858498) (xy 258.695804 -298.900035) (xy 258.726577 -298.946548) (xy 258.750249 -298.997045)
			(xy 258.766317 -299.050452) (xy 258.774437 -299.105628) (xy 258.774946 -299.133514) (xy 258.774437 -299.1614)
			(xy 258.766317 -299.216576) (xy 258.750249 -299.269983) (xy 258.726577 -299.32048) (xy 258.695804 -299.366993)
			(xy 258.658587 -299.40853) (xy 258.615719 -299.444205) (xy 258.568113 -299.473259) (xy 258.516784 -299.495071)
			(xy 258.462827 -299.509177) (xy 258.40739 -299.515277) (xy 258.351656 -299.51324) (xy 258.296813 -299.50311)
			(xy 258.244029 -299.485103) (xy 258.194429 -299.459602) (xy 258.149071 -299.427151) (xy 258.108922 -299.388442)
			(xy 258.074836 -299.344299) (xy 258.04754 -299.295664) (xy 258.027617 -299.243573) (xy 258.015491 -299.189136)
			(xy 258.01142 -299.133514) (xy 255.23508 -299.133514) (xy 255.194893 -299.199473) (xy 255.103144 -299.334855)
			(xy 255.004951 -299.465639) (xy 254.900546 -299.591519) (xy 254.790172 -299.7122) (xy 254.674088 -299.827399)
			(xy 254.552567 -299.936846) (xy 254.425892 -300.040286) (xy 254.294361 -300.137476) (xy 254.158281 -300.228187)
			(xy 254.017972 -300.312209) (xy 253.873762 -300.389343) (xy 253.725988 -300.459409) (xy 253.574998 -300.522243)
			(xy 253.421144 -300.577699) (xy 253.264788 -300.625645) (xy 253.185676 -300.646338) (xy 253.1749 -300.649669)
			(xy 253.157503 -300.66398) (xy 253.147887 -300.684351) (xy 253.147322 -300.695614) (xy 253.147322 -300.823884)
			(xy 253.154942 -300.84268) (xy 253.162308 -300.849792) (xy 253.812802 -301.500286) (xy 253.8202 -301.507133)
			(xy 253.838798 -301.514869) (xy 253.84887 -301.515272)
		)
		(stroke
			(width 0)
			(type solid)
		)
		(fill yes)
		(layer "In7.Cu")
		(net "P1V8_PLL0_PEX2")
	)
	(gr_poly
		(pts
			(xy 274.409916 -299.856906) (xy 274.419922 -299.856415) (xy 274.438409 -299.848753) (xy 274.452559 -299.834601)
			(xy 274.460217 -299.816112) (xy 274.460716 -299.806106) (xy 274.460716 -299.798486) (xy 274.45843 -299.790866)
			(xy 274.451934 -299.768695) (xy 274.444912 -299.723033) (xy 274.44446 -299.699934) (xy 274.444639 -299.685688)
			(xy 274.447313 -299.657321) (xy 274.449794 -299.643292) (xy 274.45208 -299.630846) (xy 274.444714 -299.607224)
			(xy 274.376388 -299.538644) (xy 274.367146 -299.530505) (xy 274.343661 -299.523219) (xy 274.33143 -299.524674)
			(xy 274.331176 -299.524674) (xy 274.317211 -299.527159) (xy 274.288971 -299.52983) (xy 274.274788 -299.530008)
			(xy 274.249967 -299.529521) (xy 274.20098 -299.521488) (xy 274.153938 -299.505636) (xy 274.11008 -299.482382)
			(xy 274.070562 -299.452339) (xy 274.036425 -299.416299) (xy 274.008568 -299.37521) (xy 273.987726 -299.330156)
			(xy 273.974447 -299.282324) (xy 273.969081 -299.232974) (xy 273.97177 -299.183405) (xy 273.982442 -299.134925)
			(xy 274.000818 -299.08881) (xy 274.026411 -299.046275) (xy 274.058549 -299.008441) (xy 274.096384 -298.976304)
			(xy 274.13892 -298.950712) (xy 274.185036 -298.932339) (xy 274.233517 -298.921668) (xy 274.283086 -298.918981)
			(xy 274.332436 -298.924349) (xy 274.380268 -298.93763) (xy 274.425321 -298.958474) (xy 274.466408 -298.986333)
			(xy 274.502447 -299.020471) (xy 274.532488 -299.05999) (xy 274.555741 -299.103849) (xy 274.571591 -299.150892)
			(xy 274.579622 -299.199879) (xy 274.580096 -299.2247) (xy 274.580093 -299.224954) (xy 275.868904 -299.224954)
			(xy 275.872864 -299.1759) (xy 275.884641 -299.128116) (xy 275.903932 -299.08284) (xy 275.930235 -299.041244)
			(xy 275.96287 -299.004407) (xy 276.000991 -298.973282) (xy 276.043612 -298.948675) (xy 276.089628 -298.931223)
			(xy 276.137847 -298.921379) (xy 276.187022 -298.919398) (xy 276.235877 -298.92533) (xy 276.283148 -298.939022)
			(xy 276.32761 -298.96012) (xy 276.368113 -298.988076) (xy 276.403606 -299.022168) (xy 276.433171 -299.061512)
			(xy 276.456042 -299.105089) (xy 276.471626 -299.15177) (xy 276.479521 -299.200347) (xy 276.480016 -299.224954)
			(xy 276.819118 -299.224954) (xy 276.823078 -299.1759) (xy 276.834855 -299.128116) (xy 276.854146 -299.08284)
			(xy 276.880449 -299.041244) (xy 276.913084 -299.004407) (xy 276.951205 -298.973282) (xy 276.993826 -298.948675)
			(xy 277.039842 -298.931223) (xy 277.088061 -298.921379) (xy 277.137236 -298.919398) (xy 277.186091 -298.92533)
			(xy 277.233362 -298.939022) (xy 277.277824 -298.96012) (xy 277.318327 -298.988076) (xy 277.35382 -299.022168)
			(xy 277.383385 -299.061512) (xy 277.406256 -299.105089) (xy 277.42184 -299.15177) (xy 277.429735 -299.200347)
			(xy 277.43023 -299.224954) (xy 277.769078 -299.224954) (xy 277.773038 -299.1759) (xy 277.784815 -299.128116)
			(xy 277.804106 -299.08284) (xy 277.830409 -299.041244) (xy 277.863044 -299.004407) (xy 277.901165 -298.973282)
			(xy 277.943786 -298.948675) (xy 277.989802 -298.931223) (xy 278.038021 -298.921379) (xy 278.087196 -298.919398)
			(xy 278.136051 -298.92533) (xy 278.183322 -298.939022) (xy 278.227784 -298.96012) (xy 278.268287 -298.988076)
			(xy 278.30378 -299.022168) (xy 278.333345 -299.061512) (xy 278.356216 -299.105089) (xy 278.3718 -299.15177)
			(xy 278.379695 -299.200347) (xy 278.38019 -299.224954) (xy 278.719038 -299.224954) (xy 278.722998 -299.1759)
			(xy 278.734775 -299.128116) (xy 278.754066 -299.08284) (xy 278.780369 -299.041244) (xy 278.813004 -299.004407)
			(xy 278.851125 -298.973282) (xy 278.893746 -298.948675) (xy 278.939762 -298.931223) (xy 278.987981 -298.921379)
			(xy 279.037156 -298.919398) (xy 279.086011 -298.92533) (xy 279.133282 -298.939022) (xy 279.177744 -298.96012)
			(xy 279.218247 -298.988076) (xy 279.25374 -299.022168) (xy 279.283305 -299.061512) (xy 279.306176 -299.105089)
			(xy 279.32176 -299.15177) (xy 279.329655 -299.200347) (xy 279.33015 -299.224954) (xy 279.329655 -299.249561)
			(xy 279.32176 -299.298138) (xy 279.306176 -299.344819) (xy 279.283305 -299.388396) (xy 279.25374 -299.42774)
			(xy 279.218247 -299.461832) (xy 279.177744 -299.489788) (xy 279.133282 -299.510886) (xy 279.086011 -299.524578)
			(xy 279.037156 -299.53051) (xy 278.987981 -299.528529) (xy 278.939762 -299.518685) (xy 278.893746 -299.501233)
			(xy 278.851125 -299.476626) (xy 278.813004 -299.445501) (xy 278.780369 -299.408664) (xy 278.754066 -299.367068)
			(xy 278.734775 -299.321792) (xy 278.722998 -299.274008) (xy 278.719038 -299.224954) (xy 278.38019 -299.224954)
			(xy 278.379695 -299.249561) (xy 278.3718 -299.298138) (xy 278.356216 -299.344819) (xy 278.333345 -299.388396)
			(xy 278.30378 -299.42774) (xy 278.268287 -299.461832) (xy 278.227784 -299.489788) (xy 278.183322 -299.510886)
			(xy 278.136051 -299.524578) (xy 278.087196 -299.53051) (xy 278.038021 -299.528529) (xy 277.989802 -299.518685)
			(xy 277.943786 -299.501233) (xy 277.901165 -299.476626) (xy 277.863044 -299.445501) (xy 277.830409 -299.408664)
			(xy 277.804106 -299.367068) (xy 277.784815 -299.321792) (xy 277.773038 -299.274008) (xy 277.769078 -299.224954)
			(xy 277.43023 -299.224954) (xy 277.429735 -299.249561) (xy 277.42184 -299.298138) (xy 277.406256 -299.344819)
			(xy 277.383385 -299.388396) (xy 277.35382 -299.42774) (xy 277.318327 -299.461832) (xy 277.277824 -299.489788)
			(xy 277.233362 -299.510886) (xy 277.186091 -299.524578) (xy 277.137236 -299.53051) (xy 277.088061 -299.528529)
			(xy 277.039842 -299.518685) (xy 276.993826 -299.501233) (xy 276.951205 -299.476626) (xy 276.913084 -299.445501)
			(xy 276.880449 -299.408664) (xy 276.854146 -299.367068) (xy 276.834855 -299.321792) (xy 276.823078 -299.274008)
			(xy 276.819118 -299.224954) (xy 276.480016 -299.224954) (xy 276.479521 -299.249561) (xy 276.471626 -299.298138)
			(xy 276.456042 -299.344819) (xy 276.433171 -299.388396) (xy 276.403606 -299.42774) (xy 276.368113 -299.461832)
			(xy 276.32761 -299.489788) (xy 276.283148 -299.510886) (xy 276.235877 -299.524578) (xy 276.187022 -299.53051)
			(xy 276.137847 -299.528529) (xy 276.089628 -299.518685) (xy 276.043612 -299.501233) (xy 276.000991 -299.476626)
			(xy 275.96287 -299.445501) (xy 275.930235 -299.408664) (xy 275.903932 -299.367068) (xy 275.884641 -299.321792)
			(xy 275.872864 -299.274008) (xy 275.868904 -299.224954) (xy 274.580093 -299.224954) (xy 274.579921 -299.238946)
			(xy 274.577253 -299.267314) (xy 274.574762 -299.281342) (xy 274.572476 -299.293788) (xy 274.579842 -299.31741)
			(xy 274.648168 -299.38599) (xy 274.657405 -299.394147) (xy 274.680897 -299.401462) (xy 274.693126 -299.39996)
			(xy 274.69338 -299.39996) (xy 274.707345 -299.397473) (xy 274.735585 -299.394798) (xy 274.749768 -299.394626)
			(xy 274.773762 -299.39507) (xy 274.821159 -299.402573) (xy 274.866799 -299.417399) (xy 274.909557 -299.439183)
			(xy 274.94838 -299.467389) (xy 274.982313 -299.501321) (xy 275.010518 -299.540145) (xy 275.032302 -299.582903)
			(xy 275.047128 -299.628543) (xy 275.05463 -299.67594) (xy 275.055076 -299.699934) (xy 275.055006 -299.710381)
			(xy 275.053608 -299.731227) (xy 275.052282 -299.74159) (xy 275.050758 -299.752258) (xy 275.057108 -299.773594)
			(xy 275.114512 -299.839634) (xy 275.122097 -299.847477) (xy 275.141967 -299.856437) (xy 275.152866 -299.856906)
			(xy 279.81021 -299.856906) (xy 279.819608 -299.85589) (xy 279.820116 -299.85589) (xy 279.827273 -299.854181)
			(xy 279.840292 -299.847342) (xy 279.84577 -299.842428) (xy 279.960324 -299.727874) (xy 279.965305 -299.722444)
			(xy 279.972154 -299.709405) (xy 279.973786 -299.70222) (xy 279.973786 -299.701712) (xy 279.974802 -299.692314)
			(xy 279.974802 -299.577252) (xy 279.974431 -299.568146) (xy 279.968056 -299.551088) (xy 279.962356 -299.543978)
			(xy 279.956768 -299.53712) (xy 279.940258 -299.528484) (xy 279.930352 -299.527214) (xy 279.906779 -299.523258)
			(xy 279.861163 -299.508984) (xy 279.818326 -299.487782) (xy 279.779311 -299.46017) (xy 279.745071 -299.426821)
			(xy 279.716441 -299.388547) (xy 279.694117 -299.346284) (xy 279.678646 -299.30106) (xy 279.670404 -299.253979)
			(xy 279.669592 -299.206189) (xy 279.67623 -299.158855) (xy 279.690156 -299.113132) (xy 279.711031 -299.070134)
			(xy 279.738344 -299.03091) (xy 279.754584 -299.013372) (xy 279.772455 -298.99548) (xy 279.813012 -298.965277)
			(xy 279.857989 -298.942166) (xy 279.906158 -298.926775) (xy 279.931114 -298.922694) (xy 279.932638 -298.92244)
			(xy 279.93721 -298.921932) (xy 279.945236 -298.919886) (xy 279.959492 -298.91147) (xy 279.96515 -298.905422)
			(xy 279.974802 -298.894246) (xy 279.997649 -298.894664) (xy 280.042898 -298.901037) (xy 280.064972 -298.906946)
			(xy 280.076656 -298.910248) (xy 280.087832 -298.908216) (xy 280.0985 -298.904914) (xy 280.099262 -298.904152)
			(xy 280.103072 -298.900342) (xy 280.110712 -298.89294) (xy 280.126855 -298.879084) (xy 280.13533 -298.872656)
			(xy 280.135838 -298.872148) (xy 280.171144 -298.845224) (xy 280.179281 -298.838503) (xy 280.188794 -298.819693)
			(xy 280.189432 -298.809156) (xy 280.189432 -297.740578) (xy 280.18889 -297.731098) (xy 280.181138 -297.713788)
			(xy 280.174446 -297.70705) (xy 280.131266 -297.674284) (xy 280.122412 -297.667337) (xy 280.105632 -297.652334)
			(xy 280.097738 -297.644312) (xy 280.087832 -297.641518) (xy 280.076656 -297.639486) (xy 280.064972 -297.642788)
			(xy 280.042895 -297.648682) (xy 279.997648 -297.655058) (xy 279.974802 -297.655488) (xy 279.948813 -297.655005)
			(xy 279.897476 -297.646874) (xy 279.848042 -297.630812) (xy 279.80173 -297.607214) (xy 279.75968 -297.576661)
			(xy 279.722927 -297.539906) (xy 279.692377 -297.497855) (xy 279.668782 -297.451541) (xy 279.652722 -297.402107)
			(xy 279.644594 -297.350769) (xy 279.644094 -297.32478) (xy 279.644643 -297.298269) (xy 279.653149 -297.245932)
			(xy 279.669892 -297.195622) (xy 279.681686 -297.171872) (xy 279.681686 -297.171618) (xy 279.68194 -297.171364)
			(xy 279.684666 -297.165582) (xy 279.687491 -297.153119) (xy 279.687528 -297.146726) (xy 279.68702 -297.133264)
			(xy 279.672034 -297.108626) (xy 279.63368 -297.04538) (xy 279.627143 -297.036559) (xy 279.608438 -297.025111)
			(xy 279.597612 -297.023282) (xy 279.594564 -297.023028) (xy 279.406858 -297.023028) (xy 279.402286 -297.023282)
			(xy 279.402032 -297.023282) (xy 279.391084 -297.025174) (xy 279.372245 -297.036903) (xy 279.36571 -297.045888)
			(xy 279.355042 -297.063414) (xy 279.318466 -297.123612) (xy 279.315676 -297.128993) (xy 279.312455 -297.140675)
			(xy 279.312116 -297.146726) (xy 279.311862 -297.159426) (xy 279.319482 -297.174412) (xy 279.323038 -297.181778)
			(xy 279.333286 -297.20421) (xy 279.347762 -297.251352) (xy 279.355075 -297.300122) (xy 279.35555 -297.32478)
			(xy 279.35504 -297.350767) (xy 279.34691 -297.402102) (xy 279.330849 -297.451532) (xy 279.307253 -297.497842)
			(xy 279.276703 -297.53989) (xy 279.239952 -297.576641) (xy 279.197904 -297.607191) (xy 279.151594 -297.630787)
			(xy 279.102164 -297.646848) (xy 279.050829 -297.654978) (xy 278.998855 -297.654978) (xy 278.94752 -297.646848)
			(xy 278.89809 -297.630787) (xy 278.85178 -297.607191) (xy 278.809732 -297.576641) (xy 278.772981 -297.53989)
			(xy 278.742431 -297.497842) (xy 278.718835 -297.451532) (xy 278.702774 -297.402102) (xy 278.694644 -297.350767)
			(xy 278.694134 -297.32478) (xy 278.694684 -297.298269) (xy 278.703191 -297.245933) (xy 278.719935 -297.195624)
			(xy 278.731726 -297.171872) (xy 278.731726 -297.171618) (xy 278.73198 -297.171364) (xy 278.734709 -297.165583)
			(xy 278.737537 -297.153119) (xy 278.737568 -297.146726) (xy 278.73706 -297.133264) (xy 278.722074 -297.108626)
			(xy 278.68372 -297.04538) (xy 278.677186 -297.036554) (xy 278.658483 -297.025091) (xy 278.647652 -297.023282)
			(xy 278.644604 -297.023028) (xy 278.456898 -297.023028) (xy 278.452326 -297.023282) (xy 278.452072 -297.023282)
			(xy 278.441131 -297.025185) (xy 278.422312 -297.036926) (xy 278.41575 -297.045888) (xy 278.405082 -297.063414)
			(xy 278.368506 -297.123612) (xy 278.365718 -297.128994) (xy 278.362501 -297.140675) (xy 278.362156 -297.146726)
			(xy 278.361902 -297.159426) (xy 278.369522 -297.174412) (xy 278.373078 -297.181778) (xy 278.383328 -297.204209)
			(xy 278.397806 -297.251352) (xy 278.405121 -297.300122) (xy 278.40559 -297.32478) (xy 278.40508 -297.350767)
			(xy 278.39695 -297.402102) (xy 278.380889 -297.451532) (xy 278.357293 -297.497842) (xy 278.326743 -297.53989)
			(xy 278.289992 -297.576641) (xy 278.247944 -297.607191) (xy 278.201634 -297.630787) (xy 278.152204 -297.646848)
			(xy 278.100869 -297.654978) (xy 278.048895 -297.654978) (xy 277.99756 -297.646848) (xy 277.94813 -297.630787)
			(xy 277.90182 -297.607191) (xy 277.859772 -297.576641) (xy 277.823021 -297.53989) (xy 277.792471 -297.497842)
			(xy 277.768875 -297.451532) (xy 277.752814 -297.402102) (xy 277.744684 -297.350767) (xy 277.744174 -297.32478)
			(xy 277.744723 -297.298269) (xy 277.753229 -297.245932) (xy 277.76997 -297.195621) (xy 277.781766 -297.171872)
			(xy 277.781766 -297.171618) (xy 277.78202 -297.171364) (xy 277.784747 -297.165582) (xy 277.787573 -297.153119)
			(xy 277.787608 -297.146726) (xy 277.7871 -297.133264) (xy 277.772114 -297.108626) (xy 277.73376 -297.04538)
			(xy 277.727229 -297.036548) (xy 277.708528 -297.025071) (xy 277.697692 -297.023282) (xy 277.694644 -297.023028)
			(xy 277.506938 -297.023028) (xy 277.502366 -297.023282) (xy 277.502112 -297.023282) (xy 277.491167 -297.025178)
			(xy 277.472334 -297.036911) (xy 277.46579 -297.045888) (xy 277.455122 -297.063414) (xy 277.418546 -297.123612)
			(xy 277.415757 -297.128993) (xy 277.412537 -297.140675) (xy 277.412196 -297.146726) (xy 277.411942 -297.159426)
			(xy 277.419562 -297.174412) (xy 277.423118 -297.181778) (xy 277.433366 -297.20421) (xy 277.447843 -297.251352)
			(xy 277.455157 -297.300122) (xy 277.45563 -297.32478) (xy 277.45512 -297.350767) (xy 277.44699 -297.402102)
			(xy 277.430929 -297.451532) (xy 277.407333 -297.497842) (xy 277.376783 -297.53989) (xy 277.340032 -297.576641)
			(xy 277.297984 -297.607191) (xy 277.251674 -297.630787) (xy 277.202244 -297.646848) (xy 277.150909 -297.654978)
			(xy 277.098935 -297.654978) (xy 277.0476 -297.646848) (xy 276.99817 -297.630787) (xy 276.95186 -297.607191)
			(xy 276.909812 -297.576641) (xy 276.873061 -297.53989) (xy 276.842511 -297.497842) (xy 276.818915 -297.451532)
			(xy 276.802854 -297.402102) (xy 276.794724 -297.350767) (xy 276.794214 -297.32478) (xy 276.794764 -297.298269)
			(xy 276.80327 -297.245933) (xy 276.820014 -297.195623) (xy 276.831806 -297.171872) (xy 276.831806 -297.171618)
			(xy 276.83206 -297.171364) (xy 276.834785 -297.165582) (xy 276.837609 -297.153118) (xy 276.837648 -297.146726)
			(xy 276.83714 -297.133264) (xy 276.822154 -297.108626) (xy 276.7838 -297.04538) (xy 276.777265 -297.036556)
			(xy 276.758561 -297.025101) (xy 276.747732 -297.023282) (xy 276.744684 -297.023028) (xy 276.556724 -297.023028)
			(xy 276.552152 -297.023282) (xy 276.551898 -297.023282) (xy 276.540954 -297.025181) (xy 276.522126 -297.036916)
			(xy 276.515576 -297.045888) (xy 276.504908 -297.063414) (xy 276.468332 -297.123612) (xy 276.465543 -297.128993)
			(xy 276.462324 -297.140675) (xy 276.461982 -297.146726) (xy 276.461728 -297.159426) (xy 276.469348 -297.174412)
			(xy 276.472904 -297.181778) (xy 276.483153 -297.20421) (xy 276.49763 -297.251352) (xy 276.504944 -297.300122)
			(xy 276.505416 -297.32478) (xy 276.504906 -297.350767) (xy 276.496776 -297.402102) (xy 276.480715 -297.451532)
			(xy 276.457119 -297.497842) (xy 276.426569 -297.53989) (xy 276.389818 -297.576641) (xy 276.34777 -297.607191)
			(xy 276.30146 -297.630787) (xy 276.25203 -297.646848) (xy 276.200695 -297.654978) (xy 276.148721 -297.654978)
			(xy 276.097386 -297.646848) (xy 276.047956 -297.630787) (xy 276.001646 -297.607191) (xy 275.959598 -297.576641)
			(xy 275.922847 -297.53989) (xy 275.892297 -297.497842) (xy 275.868701 -297.451532) (xy 275.85264 -297.402102)
			(xy 275.84451 -297.350767) (xy 275.844 -297.32478) (xy 275.84455 -297.298269) (xy 275.853056 -297.245933)
			(xy 275.869799 -297.195622) (xy 275.881592 -297.171872) (xy 275.881592 -297.171618) (xy 275.881846 -297.171364)
			(xy 275.884572 -297.165582) (xy 275.887396 -297.153119) (xy 275.887434 -297.146726) (xy 275.886926 -297.133264)
			(xy 275.87194 -297.108626) (xy 275.833586 -297.04538) (xy 275.82705 -297.036558) (xy 275.808345 -297.025108)
			(xy 275.797518 -297.023282) (xy 275.79447 -297.023028) (xy 274.656804 -297.023028) (xy 274.652232 -297.023282)
			(xy 274.651978 -297.023282) (xy 274.641037 -297.025184) (xy 274.622215 -297.036923) (xy 274.615656 -297.045888)
			(xy 274.604988 -297.063414) (xy 274.568412 -297.123612) (xy 274.565624 -297.128994) (xy 274.562406 -297.140675)
			(xy 274.562062 -297.146726) (xy 274.561808 -297.159426) (xy 274.569428 -297.174412) (xy 274.572984 -297.181778)
			(xy 274.583233 -297.204209) (xy 274.597712 -297.251352) (xy 274.605026 -297.300122) (xy 274.605496 -297.32478)
			(xy 274.604986 -297.350767) (xy 274.596856 -297.402102) (xy 274.580795 -297.451532) (xy 274.557199 -297.497842)
			(xy 274.526649 -297.53989) (xy 274.489898 -297.576641) (xy 274.44785 -297.607191) (xy 274.40154 -297.630787)
			(xy 274.35211 -297.646848) (xy 274.300775 -297.654978) (xy 274.248801 -297.654978) (xy 274.197466 -297.646848)
			(xy 274.148036 -297.630787) (xy 274.101726 -297.607191) (xy 274.059678 -297.576641) (xy 274.022927 -297.53989)
			(xy 273.992377 -297.497842) (xy 273.968781 -297.451532) (xy 273.95272 -297.402102) (xy 273.94459 -297.350767)
			(xy 273.94408 -297.32478) (xy 273.944582 -297.29858) (xy 273.95285 -297.246837) (xy 273.969177 -297.197046)
			(xy 273.993153 -297.150454) (xy 274.024178 -297.108226) (xy 274.061475 -297.071421) (xy 274.08251 -297.055794)
			(xy 274.082764 -297.05554) (xy 274.090483 -297.049388) (xy 274.100926 -297.032661) (xy 274.103084 -297.023028)
			(xy 274.103338 -297.022012) (xy 274.106894 -296.980102) (xy 274.106894 -296.979594) (xy 274.109942 -296.94124)
			(xy 274.110262 -296.930155) (xy 274.10262 -296.90936) (xy 274.09521 -296.901108) (xy 270.89862 -293.704518)
			(xy 270.890413 -293.697033) (xy 270.869588 -293.689389) (xy 270.858488 -293.689786) (xy 270.820134 -293.692834)
			(xy 270.819626 -293.692834) (xy 270.777716 -293.69639) (xy 270.7767 -293.696644) (xy 270.767061 -293.698779)
			(xy 270.750344 -293.709244) (xy 270.744188 -293.716964) (xy 270.743934 -293.717218) (xy 270.728303 -293.73825)
			(xy 270.691507 -293.775555) (xy 270.649282 -293.806583) (xy 270.602688 -293.830556) (xy 270.552894 -293.846871)
			(xy 270.501148 -293.85512) (xy 270.474948 -293.855648) (xy 270.448955 -293.855168) (xy 270.397608 -293.847043)
			(xy 270.348165 -293.830986) (xy 270.301842 -293.807391) (xy 270.259781 -293.776841) (xy 270.223017 -293.740086)
			(xy 270.192455 -293.698033) (xy 270.168848 -293.651717) (xy 270.152777 -293.602277) (xy 270.144638 -293.550933)
			(xy 270.14424 -293.52494) (xy 270.144745 -293.498741) (xy 270.153018 -293.447001) (xy 270.169347 -293.397213)
			(xy 270.193325 -293.350623) (xy 270.22435 -293.308398) (xy 270.261646 -293.271594) (xy 270.28267 -293.255954)
			(xy 270.282924 -293.2557) (xy 270.290642 -293.249548) (xy 270.301081 -293.23282) (xy 270.303244 -293.223188)
			(xy 270.303498 -293.222172) (xy 270.307054 -293.180262) (xy 270.307054 -293.179754) (xy 270.310102 -293.1414)
			(xy 270.310433 -293.130311) (xy 270.302805 -293.109502) (xy 270.29537 -293.101268) (xy 269.948406 -292.754304)
			(xy 269.940198 -292.746824) (xy 269.919374 -292.739187) (xy 269.908274 -292.739572) (xy 269.831058 -292.745922)
			(xy 269.82674 -292.74643) (xy 269.822274 -292.747283) (xy 269.813715 -292.750351) (xy 269.809722 -292.752526)
			(xy 269.807944 -292.753542) (xy 269.804871 -292.755539) (xy 269.799256 -292.760249) (xy 269.796768 -292.76294)
			(xy 269.793974 -292.767004) (xy 269.778336 -292.788071) (xy 269.741515 -292.825443) (xy 269.699255 -292.856533)
			(xy 269.652617 -292.880561) (xy 269.602771 -292.896924) (xy 269.550966 -292.905212) (xy 269.524734 -292.905688)
			(xy 269.498744 -292.905207) (xy 269.447402 -292.89708) (xy 269.397964 -292.881021) (xy 269.351648 -292.857424)
			(xy 269.309593 -292.826873) (xy 269.272837 -292.790117) (xy 269.242283 -292.748064) (xy 269.218685 -292.701749)
			(xy 269.202623 -292.652312) (xy 269.194494 -292.60097) (xy 269.194026 -292.57498) (xy 269.194532 -292.54907)
			(xy 269.202621 -292.497886) (xy 269.218597 -292.448591) (xy 269.242069 -292.402393) (xy 269.272462 -292.360422)
			(xy 269.309031 -292.323708) (xy 269.329662 -292.308026) (xy 269.335504 -292.302946) (xy 269.344394 -292.294056)
			(xy 269.347188 -292.289738) (xy 269.349982 -292.284912) (xy 269.353284 -292.274498) (xy 269.360142 -292.19144)
			(xy 269.360462 -292.180355) (xy 269.35282 -292.15956) (xy 269.34541 -292.151308) (xy 268.998446 -291.804344)
			(xy 268.990242 -291.796852) (xy 268.969415 -291.789193) (xy 268.958314 -291.789612) (xy 268.880844 -291.795962)
			(xy 268.875368 -291.796604) (xy 268.864857 -291.799928) (xy 268.860016 -291.802566) (xy 268.850364 -291.8079)
			(xy 268.84376 -291.817298) (xy 268.828099 -291.838289) (xy 268.791265 -291.875517) (xy 268.749029 -291.90648)
			(xy 268.702445 -291.930408) (xy 268.652674 -291.946704) (xy 268.600959 -291.95496) (xy 268.574774 -291.955474)
			(xy 268.548787 -291.954989) (xy 268.497454 -291.946854) (xy 268.448025 -291.930789) (xy 268.401718 -291.90719)
			(xy 268.359672 -291.876636) (xy 268.322925 -291.839882) (xy 268.292379 -291.797831) (xy 268.268788 -291.75152)
			(xy 268.252732 -291.702088) (xy 268.244606 -291.650753) (xy 268.244066 -291.624766) (xy 268.244559 -291.598578)
			(xy 268.252801 -291.546854) (xy 268.26909 -291.497076) (xy 268.293019 -291.450485) (xy 268.32399 -291.408247)
			(xy 268.36123 -291.371417) (xy 268.382242 -291.35578) (xy 268.39164 -291.349176) (xy 268.396974 -291.339524)
			(xy 268.399618 -291.334684) (xy 268.402961 -291.324176) (xy 268.403578 -291.318696) (xy 268.409928 -291.241226)
			(xy 268.410244 -291.230142) (xy 268.402597 -291.209353) (xy 268.395196 -291.201094) (xy 266.558776 -289.364674)
			(xy 266.551925 -289.357278) (xy 266.544188 -289.338679) (xy 266.54379 -289.328606) (xy 266.54379 -287.510982)
			(xy 266.542581 -287.49897) (xy 266.530638 -287.478029) (xy 266.52093 -287.47085) (xy 266.51839 -287.46958)
			(xy 266.441174 -287.424622) (xy 266.435588 -287.421893) (xy 266.423513 -287.418947) (xy 266.417298 -287.41878)
			(xy 266.392152 -287.425384) (xy 266.386564 -287.428432) (xy 266.358278 -287.443205) (xy 266.298002 -287.464144)
			(xy 266.235081 -287.474759) (xy 266.203176 -287.475422) (xy 266.202922 -287.475422) (xy 266.175667 -287.474961)
			(xy 266.121712 -287.467206) (xy 266.069409 -287.451851) (xy 266.019824 -287.429209) (xy 265.973967 -287.399741)
			(xy 265.93277 -287.364046) (xy 265.897073 -287.322851) (xy 265.867601 -287.276995) (xy 265.844957 -287.227411)
			(xy 265.829599 -287.17511) (xy 265.821841 -287.121155) (xy 265.821841 -287.066645) (xy 265.829599 -287.01269)
			(xy 265.844957 -286.960389) (xy 265.867601 -286.910805) (xy 265.897073 -286.864949) (xy 265.93277 -286.823754)
			(xy 265.973967 -286.788059) (xy 266.019824 -286.758591) (xy 266.069409 -286.735949) (xy 266.121712 -286.720594)
			(xy 266.175667 -286.712839) (xy 266.202922 -286.712406) (xy 266.203176 -286.712406) (xy 266.235078 -286.713075)
			(xy 266.29799 -286.723719) (xy 266.358266 -286.74465) (xy 266.386564 -286.759396) (xy 266.392152 -286.762444)
			(xy 266.417298 -286.769048) (xy 266.423516 -286.768904) (xy 266.435594 -286.765953) (xy 266.441174 -286.763206)
			(xy 266.513564 -286.721042) (xy 266.518644 -286.717994) (xy 266.520422 -286.716978) (xy 266.520676 -286.716978)
			(xy 266.521438 -286.71647) (xy 266.531012 -286.709231) (xy 266.542674 -286.688289) (xy 266.54379 -286.676338)
			(xy 266.54379 -284.310582) (xy 266.542581 -284.29857) (xy 266.530638 -284.277629) (xy 266.52093 -284.27045)
			(xy 266.51839 -284.26918) (xy 266.441174 -284.224222) (xy 266.435588 -284.221493) (xy 266.423513 -284.218547)
			(xy 266.417298 -284.21838) (xy 266.392152 -284.224984) (xy 266.386564 -284.228032) (xy 266.358278 -284.242805)
			(xy 266.298002 -284.263744) (xy 266.235081 -284.274359) (xy 266.203176 -284.275022) (xy 266.202922 -284.275022)
			(xy 266.175667 -284.274561) (xy 266.121712 -284.266806) (xy 266.069409 -284.251451) (xy 266.019824 -284.228809)
			(xy 265.973967 -284.199341) (xy 265.93277 -284.163646) (xy 265.897073 -284.122451) (xy 265.867601 -284.076595)
			(xy 265.844957 -284.027011) (xy 265.829599 -283.97471) (xy 265.821841 -283.920755) (xy 265.821841 -283.866245)
			(xy 265.829599 -283.81229) (xy 265.844957 -283.759989) (xy 265.867601 -283.710405) (xy 265.897073 -283.664549)
			(xy 265.93277 -283.623354) (xy 265.973967 -283.587659) (xy 266.019824 -283.558191) (xy 266.069409 -283.535549)
			(xy 266.121712 -283.520194) (xy 266.175667 -283.512439) (xy 266.202922 -283.512006) (xy 266.203176 -283.512006)
			(xy 266.235078 -283.512675) (xy 266.29799 -283.523319) (xy 266.358266 -283.54425) (xy 266.386564 -283.558996)
			(xy 266.392152 -283.562044) (xy 266.417298 -283.568648) (xy 266.423516 -283.568504) (xy 266.435594 -283.565553)
			(xy 266.441174 -283.562806) (xy 266.513564 -283.520642) (xy 266.518644 -283.517594) (xy 266.520422 -283.516578)
			(xy 266.520676 -283.516578) (xy 266.521438 -283.51607) (xy 266.531012 -283.508831) (xy 266.542674 -283.487889)
			(xy 266.54379 -283.475938) (xy 266.54379 -281.110182) (xy 266.542581 -281.09817) (xy 266.530638 -281.077229)
			(xy 266.52093 -281.07005) (xy 266.51839 -281.06878) (xy 266.441174 -281.023822) (xy 266.435588 -281.021093)
			(xy 266.423513 -281.018147) (xy 266.417298 -281.01798) (xy 266.392152 -281.024584) (xy 266.386564 -281.027632)
			(xy 266.358278 -281.042405) (xy 266.298002 -281.063344) (xy 266.235081 -281.073959) (xy 266.203176 -281.074622)
			(xy 266.202922 -281.074622) (xy 266.175667 -281.074161) (xy 266.121712 -281.066406) (xy 266.069409 -281.051051)
			(xy 266.019824 -281.028409) (xy 265.973967 -280.998941) (xy 265.93277 -280.963246) (xy 265.897073 -280.922051)
			(xy 265.867601 -280.876195) (xy 265.844957 -280.826611) (xy 265.829599 -280.77431) (xy 265.821841 -280.720355)
			(xy 265.821841 -280.665845) (xy 265.829599 -280.61189) (xy 265.844957 -280.559589) (xy 265.867601 -280.510005)
			(xy 265.897073 -280.464149) (xy 265.93277 -280.422954) (xy 265.973967 -280.387259) (xy 266.019824 -280.357791)
			(xy 266.069409 -280.335149) (xy 266.121712 -280.319794) (xy 266.175667 -280.312039) (xy 266.202922 -280.311606)
			(xy 266.203176 -280.311606) (xy 266.235078 -280.312275) (xy 266.29799 -280.322919) (xy 266.358266 -280.34385)
			(xy 266.386564 -280.358596) (xy 266.392152 -280.361644) (xy 266.417298 -280.368248) (xy 266.423516 -280.368104)
			(xy 266.435594 -280.365153) (xy 266.441174 -280.362406) (xy 266.513564 -280.320242) (xy 266.518644 -280.317194)
			(xy 266.520422 -280.316178) (xy 266.520676 -280.316178) (xy 266.521438 -280.31567) (xy 266.531012 -280.308431)
			(xy 266.542674 -280.287489) (xy 266.54379 -280.275538) (xy 266.54379 -280.044398) (xy 266.543449 -280.035797)
			(xy 266.537727 -280.019574) (xy 266.532614 -280.012648) (xy 266.532106 -280.01214) (xy 266.529058 -280.008584)
			(xy 266.27582 -279.755346) (xy 266.27209 -279.751824) (xy 266.263516 -279.746193) (xy 266.258802 -279.74417)
			(xy 266.250166 -279.740614) (xy 264.402316 -279.740614) (xy 264.400538 -279.740868) (xy 264.390787 -279.742348)
			(xy 264.373393 -279.751608) (xy 264.366756 -279.758902) (xy 264.34923 -279.779984) (xy 264.316718 -279.819354)
			(xy 264.313271 -279.823718) (xy 264.308143 -279.833582) (xy 264.306558 -279.838912) (xy 264.303764 -279.84958)
			(xy 264.305796 -279.86101) (xy 264.308858 -279.878375) (xy 264.312163 -279.913483) (xy 264.3124 -279.931114)
			(xy 264.311914 -279.958365) (xy 264.304158 -280.012313) (xy 264.288803 -280.064608) (xy 264.266161 -280.114185)
			(xy 264.236695 -280.160035) (xy 264.201004 -280.201226) (xy 264.159813 -280.236917) (xy 264.113963 -280.266383)
			(xy 264.064386 -280.289025) (xy 264.012091 -280.30438) (xy 263.958143 -280.312136) (xy 263.903641 -280.312136)
			(xy 263.849693 -280.30438) (xy 263.797398 -280.289025) (xy 263.747821 -280.266383) (xy 263.701971 -280.236917)
			(xy 263.66078 -280.201226) (xy 263.625089 -280.160035) (xy 263.595623 -280.114185) (xy 263.572981 -280.064608)
			(xy 263.557626 -280.012313) (xy 263.54987 -279.958365) (xy 263.549384 -279.931114) (xy 263.549384 -279.930352)
			(xy 263.550033 -279.899107) (xy 263.560244 -279.837456) (xy 263.569704 -279.80767) (xy 263.572498 -279.799796)
			(xy 263.572498 -279.791414) (xy 263.572081 -279.781391) (xy 263.564413 -279.76287) (xy 263.550241 -279.748693)
			(xy 263.531721 -279.741021) (xy 263.521698 -279.740614) (xy 263.48563 -279.740614) (xy 263.475606 -279.741028)
			(xy 263.457081 -279.748694) (xy 263.442903 -279.762867) (xy 263.435232 -279.78139) (xy 263.43483 -279.791414)
			(xy 263.43483 -283.893514) (xy 263.537954 -283.893514) (xy 263.53852 -283.864133) (xy 263.547548 -283.806068)
			(xy 263.565376 -283.750075) (xy 263.591583 -283.69748) (xy 263.625547 -283.649528) (xy 263.666466 -283.607354)
			(xy 263.689592 -283.589222) (xy 263.698524 -283.58175) (xy 263.708977 -283.560969) (xy 263.709658 -283.549344)
			(xy 263.710928 -283.457396) (xy 263.701022 -283.436314) (xy 263.691878 -283.428948) (xy 263.670018 -283.410756)
			(xy 263.63148 -283.368933) (xy 263.599575 -283.321855) (xy 263.57501 -283.270563) (xy 263.558329 -283.216193)
			(xy 263.549902 -283.15995) (xy 263.549384 -283.131514) (xy 263.54987 -283.104263) (xy 263.557626 -283.050315)
			(xy 263.572981 -282.99802) (xy 263.595623 -282.948443) (xy 263.625089 -282.902593) (xy 263.66078 -282.861402)
			(xy 263.701971 -282.825711) (xy 263.747821 -282.796245) (xy 263.797398 -282.773603) (xy 263.849693 -282.758248)
			(xy 263.903641 -282.750492) (xy 263.958143 -282.750492) (xy 264.012091 -282.758248) (xy 264.064386 -282.773603)
			(xy 264.113963 -282.796245) (xy 264.159813 -282.825711) (xy 264.201004 -282.861402) (xy 264.236695 -282.902593)
			(xy 264.266161 -282.948443) (xy 264.288803 -282.99802) (xy 264.304158 -283.050315) (xy 264.311914 -283.104263)
			(xy 264.3124 -283.131514) (xy 264.311872 -283.160897) (xy 264.302839 -283.218964) (xy 264.285005 -283.274959)
			(xy 264.258791 -283.327554) (xy 264.224818 -283.375505) (xy 264.183891 -283.417676) (xy 264.160762 -283.435806)
			(xy 264.151826 -283.443275) (xy 264.141373 -283.464057) (xy 264.140696 -283.475684) (xy 264.139426 -283.567632)
			(xy 264.149332 -283.588714) (xy 264.158476 -283.59608) (xy 264.180292 -283.614323) (xy 264.218835 -283.656133)
			(xy 264.250747 -283.703201) (xy 264.275319 -283.754484) (xy 264.292009 -283.808845) (xy 264.300447 -283.865081)
			(xy 264.30097 -283.893514) (xy 264.934444 -283.893514) (xy 264.938515 -283.837892) (xy 264.950641 -283.783455)
			(xy 264.970564 -283.731364) (xy 264.99786 -283.682729) (xy 265.031946 -283.638586) (xy 265.072095 -283.599877)
			(xy 265.117453 -283.567426) (xy 265.167053 -283.541925) (xy 265.219837 -283.523918) (xy 265.27468 -283.513788)
			(xy 265.330414 -283.511751) (xy 265.385851 -283.517851) (xy 265.439808 -283.531957) (xy 265.491137 -283.553769)
			(xy 265.538743 -283.582823) (xy 265.581611 -283.618498) (xy 265.618828 -283.660035) (xy 265.649601 -283.706548)
			(xy 265.673273 -283.757045) (xy 265.689341 -283.810452) (xy 265.697461 -283.865628) (xy 265.69797 -283.893514)
			(xy 265.697461 -283.9214) (xy 265.689341 -283.976576) (xy 265.673273 -284.029983) (xy 265.649601 -284.08048)
			(xy 265.618828 -284.126993) (xy 265.581611 -284.16853) (xy 265.538743 -284.204205) (xy 265.491137 -284.233259)
			(xy 265.439808 -284.255071) (xy 265.385851 -284.269177) (xy 265.330414 -284.275277) (xy 265.27468 -284.27324)
			(xy 265.219837 -284.26311) (xy 265.167053 -284.245103) (xy 265.117453 -284.219602) (xy 265.072095 -284.187151)
			(xy 265.031946 -284.148442) (xy 264.99786 -284.104299) (xy 264.970564 -284.055664) (xy 264.950641 -284.003573)
			(xy 264.938515 -283.949136) (xy 264.934444 -283.893514) (xy 264.30097 -283.893514) (xy 264.300484 -283.920765)
			(xy 264.292728 -283.974713) (xy 264.277373 -284.027008) (xy 264.254731 -284.076585) (xy 264.225265 -284.122435)
			(xy 264.189574 -284.163626) (xy 264.148383 -284.199317) (xy 264.102533 -284.228783) (xy 264.052956 -284.251425)
			(xy 264.000661 -284.26678) (xy 263.946713 -284.274536) (xy 263.892211 -284.274536) (xy 263.838263 -284.26678)
			(xy 263.785968 -284.251425) (xy 263.736391 -284.228783) (xy 263.690541 -284.199317) (xy 263.64935 -284.163626)
			(xy 263.613659 -284.122435) (xy 263.584193 -284.076585) (xy 263.561551 -284.027008) (xy 263.546196 -283.974713)
			(xy 263.53844 -283.920765) (xy 263.537954 -283.893514) (xy 263.43483 -283.893514) (xy 263.43483 -287.093914)
			(xy 263.537954 -287.093914) (xy 263.53852 -287.064533) (xy 263.547548 -287.006468) (xy 263.565376 -286.950475)
			(xy 263.591583 -286.89788) (xy 263.625547 -286.849928) (xy 263.666466 -286.807754) (xy 263.689592 -286.789622)
			(xy 263.698524 -286.78215) (xy 263.708977 -286.761369) (xy 263.709658 -286.749744) (xy 263.710928 -286.657796)
			(xy 263.701022 -286.636714) (xy 263.691878 -286.629348) (xy 263.670018 -286.611156) (xy 263.63148 -286.569333)
			(xy 263.599575 -286.522255) (xy 263.57501 -286.470963) (xy 263.558329 -286.416593) (xy 263.549902 -286.36035)
			(xy 263.549384 -286.331914) (xy 263.54987 -286.304663) (xy 263.557626 -286.250715) (xy 263.572981 -286.19842)
			(xy 263.595623 -286.148843) (xy 263.625089 -286.102993) (xy 263.66078 -286.061802) (xy 263.701971 -286.026111)
			(xy 263.747821 -285.996645) (xy 263.797398 -285.974003) (xy 263.849693 -285.958648) (xy 263.903641 -285.950892)
			(xy 263.958143 -285.950892) (xy 264.012091 -285.958648) (xy 264.064386 -285.974003) (xy 264.113963 -285.996645)
			(xy 264.159813 -286.026111) (xy 264.201004 -286.061802) (xy 264.236695 -286.102993) (xy 264.266161 -286.148843)
			(xy 264.288803 -286.19842) (xy 264.304158 -286.250715) (xy 264.311914 -286.304663) (xy 264.3124 -286.331914)
			(xy 264.311872 -286.361297) (xy 264.302839 -286.419364) (xy 264.285005 -286.475359) (xy 264.258791 -286.527954)
			(xy 264.224818 -286.575905) (xy 264.183891 -286.618076) (xy 264.160762 -286.636206) (xy 264.151826 -286.643675)
			(xy 264.141373 -286.664457) (xy 264.140696 -286.676084) (xy 264.139426 -286.768032) (xy 264.149332 -286.789114)
			(xy 264.158476 -286.79648) (xy 264.180292 -286.814723) (xy 264.218835 -286.856533) (xy 264.250747 -286.903601)
			(xy 264.275319 -286.954884) (xy 264.292009 -287.009245) (xy 264.300447 -287.065481) (xy 264.30097 -287.093914)
			(xy 264.934444 -287.093914) (xy 264.938515 -287.038292) (xy 264.950641 -286.983855) (xy 264.970564 -286.931764)
			(xy 264.99786 -286.883129) (xy 265.031946 -286.838986) (xy 265.072095 -286.800277) (xy 265.117453 -286.767826)
			(xy 265.167053 -286.742325) (xy 265.219837 -286.724318) (xy 265.27468 -286.714188) (xy 265.330414 -286.712151)
			(xy 265.385851 -286.718251) (xy 265.439808 -286.732357) (xy 265.491137 -286.754169) (xy 265.538743 -286.783223)
			(xy 265.581611 -286.818898) (xy 265.618828 -286.860435) (xy 265.649601 -286.906948) (xy 265.673273 -286.957445)
			(xy 265.689341 -287.010852) (xy 265.697461 -287.066028) (xy 265.69797 -287.093914) (xy 265.697461 -287.1218)
			(xy 265.689341 -287.176976) (xy 265.673273 -287.230383) (xy 265.649601 -287.28088) (xy 265.618828 -287.327393)
			(xy 265.581611 -287.36893) (xy 265.538743 -287.404605) (xy 265.491137 -287.433659) (xy 265.439808 -287.455471)
			(xy 265.385851 -287.469577) (xy 265.330414 -287.475677) (xy 265.27468 -287.47364) (xy 265.219837 -287.46351)
			(xy 265.167053 -287.445503) (xy 265.117453 -287.420002) (xy 265.072095 -287.387551) (xy 265.031946 -287.348842)
			(xy 264.99786 -287.304699) (xy 264.970564 -287.256064) (xy 264.950641 -287.203973) (xy 264.938515 -287.149536)
			(xy 264.934444 -287.093914) (xy 264.30097 -287.093914) (xy 264.300484 -287.121165) (xy 264.292728 -287.175113)
			(xy 264.277373 -287.227408) (xy 264.254731 -287.276985) (xy 264.225265 -287.322835) (xy 264.189574 -287.364026)
			(xy 264.148383 -287.399717) (xy 264.102533 -287.429183) (xy 264.052956 -287.451825) (xy 264.000661 -287.46718)
			(xy 263.946713 -287.474936) (xy 263.892211 -287.474936) (xy 263.838263 -287.46718) (xy 263.785968 -287.451825)
			(xy 263.736391 -287.429183) (xy 263.690541 -287.399717) (xy 263.64935 -287.364026) (xy 263.613659 -287.322835)
			(xy 263.584193 -287.276985) (xy 263.561551 -287.227408) (xy 263.546196 -287.175113) (xy 263.53844 -287.121165)
			(xy 263.537954 -287.093914) (xy 263.43483 -287.093914) (xy 263.43483 -290.294314) (xy 263.537954 -290.294314)
			(xy 263.53852 -290.264933) (xy 263.547548 -290.206868) (xy 263.565376 -290.150875) (xy 263.591583 -290.09828)
			(xy 263.625547 -290.050328) (xy 263.666466 -290.008154) (xy 263.689592 -289.990022) (xy 263.698524 -289.98255)
			(xy 263.708977 -289.961769) (xy 263.709658 -289.950144) (xy 263.710928 -289.858196) (xy 263.701022 -289.837114)
			(xy 263.691878 -289.829748) (xy 263.670018 -289.811556) (xy 263.63148 -289.769733) (xy 263.599575 -289.722655)
			(xy 263.57501 -289.671363) (xy 263.558329 -289.616993) (xy 263.549902 -289.56075) (xy 263.549384 -289.532314)
			(xy 263.54987 -289.505063) (xy 263.557626 -289.451115) (xy 263.572981 -289.39882) (xy 263.595623 -289.349243)
			(xy 263.625089 -289.303393) (xy 263.66078 -289.262202) (xy 263.701971 -289.226511) (xy 263.747821 -289.197045)
			(xy 263.797398 -289.174403) (xy 263.849693 -289.159048) (xy 263.903641 -289.151292) (xy 263.958143 -289.151292)
			(xy 264.012091 -289.159048) (xy 264.064386 -289.174403) (xy 264.113963 -289.197045) (xy 264.159813 -289.226511)
			(xy 264.201004 -289.262202) (xy 264.236695 -289.303393) (xy 264.266161 -289.349243) (xy 264.288803 -289.39882)
			(xy 264.304158 -289.451115) (xy 264.311914 -289.505063) (xy 264.3124 -289.532314) (xy 264.311872 -289.561697)
			(xy 264.302839 -289.619764) (xy 264.285005 -289.675759) (xy 264.258791 -289.728354) (xy 264.224818 -289.776305)
			(xy 264.183891 -289.818476) (xy 264.160762 -289.836606) (xy 264.151826 -289.844075) (xy 264.141373 -289.864857)
			(xy 264.140696 -289.876484) (xy 264.139426 -289.968432) (xy 264.149332 -289.989514) (xy 264.158476 -289.99688)
			(xy 264.180292 -290.015123) (xy 264.218835 -290.056933) (xy 264.250747 -290.104001) (xy 264.275319 -290.155284)
			(xy 264.292009 -290.209645) (xy 264.300447 -290.265881) (xy 264.30097 -290.294314) (xy 264.934444 -290.294314)
			(xy 264.938515 -290.238692) (xy 264.950641 -290.184255) (xy 264.970564 -290.132164) (xy 264.99786 -290.083529)
			(xy 265.031946 -290.039386) (xy 265.072095 -290.000677) (xy 265.117453 -289.968226) (xy 265.167053 -289.942725)
			(xy 265.219837 -289.924718) (xy 265.27468 -289.914588) (xy 265.330414 -289.912551) (xy 265.385851 -289.918651)
			(xy 265.439808 -289.932757) (xy 265.491137 -289.954569) (xy 265.538743 -289.983623) (xy 265.581611 -290.019298)
			(xy 265.618828 -290.060835) (xy 265.649601 -290.107348) (xy 265.673273 -290.157845) (xy 265.689341 -290.211252)
			(xy 265.697461 -290.266428) (xy 265.69797 -290.294314) (xy 265.820904 -290.294314) (xy 265.824975 -290.238692)
			(xy 265.837101 -290.184255) (xy 265.857024 -290.132164) (xy 265.88432 -290.083529) (xy 265.918406 -290.039386)
			(xy 265.958555 -290.000677) (xy 266.003913 -289.968226) (xy 266.053513 -289.942725) (xy 266.106297 -289.924718)
			(xy 266.16114 -289.914588) (xy 266.216874 -289.912551) (xy 266.272311 -289.918651) (xy 266.326268 -289.932757)
			(xy 266.377597 -289.954569) (xy 266.425203 -289.983623) (xy 266.468071 -290.019298) (xy 266.505288 -290.060835)
			(xy 266.536061 -290.107348) (xy 266.559733 -290.157845) (xy 266.575801 -290.211252) (xy 266.583921 -290.266428)
			(xy 266.58443 -290.294314) (xy 266.583921 -290.3222) (xy 266.575801 -290.377376) (xy 266.559733 -290.430783)
			(xy 266.536061 -290.48128) (xy 266.505288 -290.527793) (xy 266.468071 -290.56933) (xy 266.425203 -290.605005)
			(xy 266.377597 -290.634059) (xy 266.326268 -290.655871) (xy 266.272311 -290.669977) (xy 266.216874 -290.676077)
			(xy 266.16114 -290.67404) (xy 266.106297 -290.66391) (xy 266.053513 -290.645903) (xy 266.003913 -290.620402)
			(xy 265.958555 -290.587951) (xy 265.918406 -290.549242) (xy 265.88432 -290.505099) (xy 265.857024 -290.456464)
			(xy 265.837101 -290.404373) (xy 265.824975 -290.349936) (xy 265.820904 -290.294314) (xy 265.69797 -290.294314)
			(xy 265.697461 -290.3222) (xy 265.689341 -290.377376) (xy 265.673273 -290.430783) (xy 265.649601 -290.48128)
			(xy 265.618828 -290.527793) (xy 265.581611 -290.56933) (xy 265.538743 -290.605005) (xy 265.491137 -290.634059)
			(xy 265.439808 -290.655871) (xy 265.385851 -290.669977) (xy 265.330414 -290.676077) (xy 265.27468 -290.67404)
			(xy 265.219837 -290.66391) (xy 265.167053 -290.645903) (xy 265.117453 -290.620402) (xy 265.072095 -290.587951)
			(xy 265.031946 -290.549242) (xy 264.99786 -290.505099) (xy 264.970564 -290.456464) (xy 264.950641 -290.404373)
			(xy 264.938515 -290.349936) (xy 264.934444 -290.294314) (xy 264.30097 -290.294314) (xy 264.300484 -290.321565)
			(xy 264.292728 -290.375513) (xy 264.277373 -290.427808) (xy 264.254731 -290.477385) (xy 264.225265 -290.523235)
			(xy 264.189574 -290.564426) (xy 264.148383 -290.600117) (xy 264.102533 -290.629583) (xy 264.052956 -290.652225)
			(xy 264.000661 -290.66758) (xy 263.946713 -290.675336) (xy 263.892211 -290.675336) (xy 263.838263 -290.66758)
			(xy 263.785968 -290.652225) (xy 263.736391 -290.629583) (xy 263.690541 -290.600117) (xy 263.64935 -290.564426)
			(xy 263.613659 -290.523235) (xy 263.584193 -290.477385) (xy 263.561551 -290.427808) (xy 263.546196 -290.375513)
			(xy 263.53844 -290.321565) (xy 263.537954 -290.294314) (xy 263.43483 -290.294314) (xy 263.43483 -292.278054)
			(xy 263.435846 -292.287452) (xy 263.435846 -292.28796) (xy 263.437546 -292.295122) (xy 263.444369 -292.308157)
			(xy 263.449308 -292.313614) (xy 263.57961 -292.443916) (xy 263.580372 -292.444678) (xy 263.581642 -292.445694)
			(xy 263.588725 -292.451496) (xy 263.605775 -292.45813) (xy 263.614916 -292.458648) (xy 263.636506 -292.458648)
			(xy 263.641053 -292.458521) (xy 263.649994 -292.456853) (xy 263.654286 -292.455346) (xy 263.67867 -292.446202)
			(xy 263.685274 -292.440614) (xy 263.705999 -292.423835) (xy 263.75122 -292.395579) (xy 263.799928 -292.373879)
			(xy 263.851178 -292.359157) (xy 263.903977 -292.351698) (xy 263.930638 -292.351206) (xy 263.930892 -292.351206)
			(xy 263.958145 -292.351669) (xy 264.012096 -292.359425) (xy 264.064394 -292.37478) (xy 264.113974 -292.397423)
			(xy 264.159827 -292.426891) (xy 264.20102 -292.462585) (xy 264.236713 -292.503778) (xy 264.26618 -292.549631)
			(xy 264.277756 -292.57498) (xy 268.26897 -292.57498) (xy 268.27293 -292.525926) (xy 268.284707 -292.478142)
			(xy 268.303998 -292.432866) (xy 268.330301 -292.39127) (xy 268.362936 -292.354433) (xy 268.401057 -292.323308)
			(xy 268.443678 -292.298701) (xy 268.489694 -292.281249) (xy 268.537913 -292.271405) (xy 268.587088 -292.269424)
			(xy 268.635943 -292.275356) (xy 268.683214 -292.289048) (xy 268.727676 -292.310146) (xy 268.768179 -292.338102)
			(xy 268.803672 -292.372194) (xy 268.833237 -292.411538) (xy 268.856108 -292.455115) (xy 268.871692 -292.501796)
			(xy 268.879587 -292.550373) (xy 268.880082 -292.57498) (xy 268.879587 -292.599587) (xy 268.871692 -292.648164)
			(xy 268.856108 -292.694845) (xy 268.833237 -292.738422) (xy 268.803672 -292.777766) (xy 268.768179 -292.811858)
			(xy 268.727676 -292.839814) (xy 268.683214 -292.860912) (xy 268.635943 -292.874604) (xy 268.587088 -292.880536)
			(xy 268.537913 -292.878555) (xy 268.489694 -292.868711) (xy 268.443678 -292.851259) (xy 268.401057 -292.826652)
			(xy 268.362936 -292.795527) (xy 268.330301 -292.75869) (xy 268.303998 -292.717094) (xy 268.284707 -292.671818)
			(xy 268.27293 -292.624034) (xy 268.26897 -292.57498) (xy 264.277756 -292.57498) (xy 264.288822 -292.599212)
			(xy 264.304176 -292.65151) (xy 264.311932 -292.705461) (xy 264.3124 -292.732714) (xy 264.311869 -292.761238)
			(xy 264.303379 -292.81765) (xy 264.286589 -292.872171) (xy 264.261874 -292.923587) (xy 264.229784 -292.970753)
			(xy 264.2108 -292.992048) (xy 264.20445 -292.998906) (xy 264.19048 -293.03345) (xy 264.19048 -293.034212)
			(xy 264.19048 -293.044118) (xy 264.19429 -293.053008) (xy 264.196296 -293.057572) (xy 264.201794 -293.065889)
			(xy 264.205212 -293.069518) (xy 264.630408 -293.494714) (xy 264.934444 -293.494714) (xy 264.938515 -293.439092)
			(xy 264.950641 -293.384655) (xy 264.970564 -293.332564) (xy 264.99786 -293.283929) (xy 265.031946 -293.239786)
			(xy 265.072095 -293.201077) (xy 265.117453 -293.168626) (xy 265.167053 -293.143125) (xy 265.219837 -293.125118)
			(xy 265.27468 -293.114988) (xy 265.330414 -293.112951) (xy 265.385851 -293.119051) (xy 265.439808 -293.133157)
			(xy 265.491137 -293.154969) (xy 265.538743 -293.184023) (xy 265.581611 -293.219698) (xy 265.618828 -293.261235)
			(xy 265.649601 -293.307748) (xy 265.673273 -293.358245) (xy 265.689341 -293.411652) (xy 265.697461 -293.466828)
			(xy 265.69797 -293.494714) (xy 265.820904 -293.494714) (xy 265.824975 -293.439092) (xy 265.837101 -293.384655)
			(xy 265.857024 -293.332564) (xy 265.88432 -293.283929) (xy 265.918406 -293.239786) (xy 265.958555 -293.201077)
			(xy 266.003913 -293.168626) (xy 266.053513 -293.143125) (xy 266.106297 -293.125118) (xy 266.16114 -293.114988)
			(xy 266.216874 -293.112951) (xy 266.272311 -293.119051) (xy 266.326268 -293.133157) (xy 266.377597 -293.154969)
			(xy 266.425203 -293.184023) (xy 266.468071 -293.219698) (xy 266.505288 -293.261235) (xy 266.536061 -293.307748)
			(xy 266.559733 -293.358245) (xy 266.575801 -293.411652) (xy 266.583921 -293.466828) (xy 266.58443 -293.494714)
			(xy 266.583921 -293.5226) (xy 266.575801 -293.577776) (xy 266.559733 -293.631183) (xy 266.536061 -293.68168)
			(xy 266.505288 -293.728193) (xy 266.468071 -293.76973) (xy 266.425203 -293.805405) (xy 266.377597 -293.834459)
			(xy 266.326268 -293.856271) (xy 266.272311 -293.870377) (xy 266.216874 -293.876477) (xy 266.16114 -293.87444)
			(xy 266.106297 -293.86431) (xy 266.053513 -293.846303) (xy 266.003913 -293.820802) (xy 265.958555 -293.788351)
			(xy 265.918406 -293.749642) (xy 265.88432 -293.705499) (xy 265.857024 -293.656864) (xy 265.837101 -293.604773)
			(xy 265.824975 -293.550336) (xy 265.820904 -293.494714) (xy 265.69797 -293.494714) (xy 265.697461 -293.5226)
			(xy 265.689341 -293.577776) (xy 265.673273 -293.631183) (xy 265.649601 -293.68168) (xy 265.618828 -293.728193)
			(xy 265.581611 -293.76973) (xy 265.538743 -293.805405) (xy 265.491137 -293.834459) (xy 265.439808 -293.856271)
			(xy 265.385851 -293.870377) (xy 265.330414 -293.876477) (xy 265.27468 -293.87444) (xy 265.219837 -293.86431)
			(xy 265.167053 -293.846303) (xy 265.117453 -293.820802) (xy 265.072095 -293.788351) (xy 265.031946 -293.749642)
			(xy 264.99786 -293.705499) (xy 264.970564 -293.656864) (xy 264.950641 -293.604773) (xy 264.938515 -293.550336)
			(xy 264.934444 -293.494714) (xy 264.630408 -293.494714) (xy 265.610594 -294.4749) (xy 268.26897 -294.4749)
			(xy 268.27293 -294.425846) (xy 268.284707 -294.378062) (xy 268.303998 -294.332786) (xy 268.330301 -294.29119)
			(xy 268.362936 -294.254353) (xy 268.401057 -294.223228) (xy 268.443678 -294.198621) (xy 268.489694 -294.181169)
			(xy 268.537913 -294.171325) (xy 268.587088 -294.169344) (xy 268.635943 -294.175276) (xy 268.683214 -294.188968)
			(xy 268.727676 -294.210066) (xy 268.768179 -294.238022) (xy 268.803672 -294.272114) (xy 268.833237 -294.311458)
			(xy 268.856108 -294.355035) (xy 268.871692 -294.401716) (xy 268.879587 -294.450293) (xy 268.880082 -294.4749)
			(xy 269.21893 -294.4749) (xy 269.22289 -294.425846) (xy 269.234667 -294.378062) (xy 269.253958 -294.332786)
			(xy 269.280261 -294.29119) (xy 269.312896 -294.254353) (xy 269.351017 -294.223228) (xy 269.393638 -294.198621)
			(xy 269.439654 -294.181169) (xy 269.487873 -294.171325) (xy 269.537048 -294.169344) (xy 269.585903 -294.175276)
			(xy 269.633174 -294.188968) (xy 269.677636 -294.210066) (xy 269.718139 -294.238022) (xy 269.753632 -294.272114)
			(xy 269.783197 -294.311458) (xy 269.806068 -294.355035) (xy 269.821652 -294.401716) (xy 269.829547 -294.450293)
			(xy 269.830042 -294.4749) (xy 270.169144 -294.4749) (xy 270.173104 -294.425846) (xy 270.184881 -294.378062)
			(xy 270.204172 -294.332786) (xy 270.230475 -294.29119) (xy 270.26311 -294.254353) (xy 270.301231 -294.223228)
			(xy 270.343852 -294.198621) (xy 270.389868 -294.181169) (xy 270.438087 -294.171325) (xy 270.487262 -294.169344)
			(xy 270.536117 -294.175276) (xy 270.583388 -294.188968) (xy 270.62785 -294.210066) (xy 270.668353 -294.238022)
			(xy 270.703846 -294.272114) (xy 270.733411 -294.311458) (xy 270.756282 -294.355035) (xy 270.771866 -294.401716)
			(xy 270.779761 -294.450293) (xy 270.780256 -294.4749) (xy 270.779761 -294.499507) (xy 270.771866 -294.548084)
			(xy 270.756282 -294.594765) (xy 270.733411 -294.638342) (xy 270.703846 -294.677686) (xy 270.668353 -294.711778)
			(xy 270.62785 -294.739734) (xy 270.583388 -294.760832) (xy 270.536117 -294.774524) (xy 270.487262 -294.780456)
			(xy 270.438087 -294.778475) (xy 270.389868 -294.768631) (xy 270.343852 -294.751179) (xy 270.301231 -294.726572)
			(xy 270.26311 -294.695447) (xy 270.230475 -294.65861) (xy 270.204172 -294.617014) (xy 270.184881 -294.571738)
			(xy 270.173104 -294.523954) (xy 270.169144 -294.4749) (xy 269.830042 -294.4749) (xy 269.829547 -294.499507)
			(xy 269.821652 -294.548084) (xy 269.806068 -294.594765) (xy 269.783197 -294.638342) (xy 269.753632 -294.677686)
			(xy 269.718139 -294.711778) (xy 269.677636 -294.739734) (xy 269.633174 -294.760832) (xy 269.585903 -294.774524)
			(xy 269.537048 -294.780456) (xy 269.487873 -294.778475) (xy 269.439654 -294.768631) (xy 269.393638 -294.751179)
			(xy 269.351017 -294.726572) (xy 269.312896 -294.695447) (xy 269.280261 -294.65861) (xy 269.253958 -294.617014)
			(xy 269.234667 -294.571738) (xy 269.22289 -294.523954) (xy 269.21893 -294.4749) (xy 268.880082 -294.4749)
			(xy 268.879587 -294.499507) (xy 268.871692 -294.548084) (xy 268.856108 -294.594765) (xy 268.833237 -294.638342)
			(xy 268.803672 -294.677686) (xy 268.768179 -294.711778) (xy 268.727676 -294.739734) (xy 268.683214 -294.760832)
			(xy 268.635943 -294.774524) (xy 268.587088 -294.780456) (xy 268.537913 -294.778475) (xy 268.489694 -294.768631)
			(xy 268.443678 -294.751179) (xy 268.401057 -294.726572) (xy 268.362936 -294.695447) (xy 268.330301 -294.65861)
			(xy 268.303998 -294.617014) (xy 268.284707 -294.571738) (xy 268.27293 -294.523954) (xy 268.26897 -294.4749)
			(xy 265.610594 -294.4749) (xy 267.510514 -296.37482) (xy 269.219184 -296.37482) (xy 269.223144 -296.325766)
			(xy 269.234921 -296.277982) (xy 269.254212 -296.232706) (xy 269.280515 -296.19111) (xy 269.31315 -296.154273)
			(xy 269.351271 -296.123148) (xy 269.393892 -296.098541) (xy 269.439908 -296.081089) (xy 269.488127 -296.071245)
			(xy 269.537302 -296.069264) (xy 269.586157 -296.075196) (xy 269.633428 -296.088888) (xy 269.67789 -296.109986)
			(xy 269.718393 -296.137942) (xy 269.753886 -296.172034) (xy 269.783451 -296.211378) (xy 269.806322 -296.254955)
			(xy 269.821906 -296.301636) (xy 269.829801 -296.350213) (xy 269.830296 -296.37482) (xy 270.16889 -296.37482)
			(xy 270.17285 -296.325766) (xy 270.184627 -296.277982) (xy 270.203918 -296.232706) (xy 270.230221 -296.19111)
			(xy 270.262856 -296.154273) (xy 270.300977 -296.123148) (xy 270.343598 -296.098541) (xy 270.389614 -296.081089)
			(xy 270.437833 -296.071245) (xy 270.487008 -296.069264) (xy 270.535863 -296.075196) (xy 270.583134 -296.088888)
			(xy 270.627596 -296.109986) (xy 270.668099 -296.137942) (xy 270.703592 -296.172034) (xy 270.733157 -296.211378)
			(xy 270.756028 -296.254955) (xy 270.771612 -296.301636) (xy 270.779507 -296.350213) (xy 270.780002 -296.37482)
			(xy 271.119104 -296.37482) (xy 271.123064 -296.325766) (xy 271.134841 -296.277982) (xy 271.154132 -296.232706)
			(xy 271.180435 -296.19111) (xy 271.21307 -296.154273) (xy 271.251191 -296.123148) (xy 271.293812 -296.098541)
			(xy 271.339828 -296.081089) (xy 271.388047 -296.071245) (xy 271.437222 -296.069264) (xy 271.486077 -296.075196)
			(xy 271.533348 -296.088888) (xy 271.57781 -296.109986) (xy 271.618313 -296.137942) (xy 271.653806 -296.172034)
			(xy 271.683371 -296.211378) (xy 271.706242 -296.254955) (xy 271.721826 -296.301636) (xy 271.729721 -296.350213)
			(xy 271.730216 -296.37482) (xy 272.069064 -296.37482) (xy 272.073024 -296.325766) (xy 272.084801 -296.277982)
			(xy 272.104092 -296.232706) (xy 272.130395 -296.19111) (xy 272.16303 -296.154273) (xy 272.201151 -296.123148)
			(xy 272.243772 -296.098541) (xy 272.289788 -296.081089) (xy 272.338007 -296.071245) (xy 272.387182 -296.069264)
			(xy 272.436037 -296.075196) (xy 272.483308 -296.088888) (xy 272.52777 -296.109986) (xy 272.568273 -296.137942)
			(xy 272.603766 -296.172034) (xy 272.633331 -296.211378) (xy 272.656202 -296.254955) (xy 272.671786 -296.301636)
			(xy 272.679681 -296.350213) (xy 272.680176 -296.37482) (xy 272.679681 -296.399427) (xy 272.671786 -296.448004)
			(xy 272.656202 -296.494685) (xy 272.633331 -296.538262) (xy 272.603766 -296.577606) (xy 272.568273 -296.611698)
			(xy 272.52777 -296.639654) (xy 272.483308 -296.660752) (xy 272.436037 -296.674444) (xy 272.387182 -296.680376)
			(xy 272.338007 -296.678395) (xy 272.289788 -296.668551) (xy 272.243772 -296.651099) (xy 272.201151 -296.626492)
			(xy 272.16303 -296.595367) (xy 272.130395 -296.55853) (xy 272.104092 -296.516934) (xy 272.084801 -296.471658)
			(xy 272.073024 -296.423874) (xy 272.069064 -296.37482) (xy 271.730216 -296.37482) (xy 271.729721 -296.399427)
			(xy 271.721826 -296.448004) (xy 271.706242 -296.494685) (xy 271.683371 -296.538262) (xy 271.653806 -296.577606)
			(xy 271.618313 -296.611698) (xy 271.57781 -296.639654) (xy 271.533348 -296.660752) (xy 271.486077 -296.674444)
			(xy 271.437222 -296.680376) (xy 271.388047 -296.678395) (xy 271.339828 -296.668551) (xy 271.293812 -296.651099)
			(xy 271.251191 -296.626492) (xy 271.21307 -296.595367) (xy 271.180435 -296.55853) (xy 271.154132 -296.516934)
			(xy 271.134841 -296.471658) (xy 271.123064 -296.423874) (xy 271.119104 -296.37482) (xy 270.780002 -296.37482)
			(xy 270.779507 -296.399427) (xy 270.771612 -296.448004) (xy 270.756028 -296.494685) (xy 270.733157 -296.538262)
			(xy 270.703592 -296.577606) (xy 270.668099 -296.611698) (xy 270.627596 -296.639654) (xy 270.583134 -296.660752)
			(xy 270.535863 -296.674444) (xy 270.487008 -296.680376) (xy 270.437833 -296.678395) (xy 270.389614 -296.668551)
			(xy 270.343598 -296.651099) (xy 270.300977 -296.626492) (xy 270.262856 -296.595367) (xy 270.230221 -296.55853)
			(xy 270.203918 -296.516934) (xy 270.184627 -296.471658) (xy 270.17285 -296.423874) (xy 270.16889 -296.37482)
			(xy 269.830296 -296.37482) (xy 269.829801 -296.399427) (xy 269.821906 -296.448004) (xy 269.806322 -296.494685)
			(xy 269.783451 -296.538262) (xy 269.753886 -296.577606) (xy 269.718393 -296.611698) (xy 269.67789 -296.639654)
			(xy 269.633428 -296.660752) (xy 269.586157 -296.674444) (xy 269.537302 -296.680376) (xy 269.488127 -296.678395)
			(xy 269.439908 -296.668551) (xy 269.393892 -296.651099) (xy 269.351271 -296.626492) (xy 269.31315 -296.595367)
			(xy 269.280515 -296.55853) (xy 269.254212 -296.516934) (xy 269.234921 -296.471658) (xy 269.223144 -296.423874)
			(xy 269.219184 -296.37482) (xy 267.510514 -296.37482) (xy 268.212824 -297.07713) (xy 268.219936 -297.082972)
			(xy 268.225697 -297.086556) (xy 268.238573 -297.090813) (xy 268.245336 -297.091354) (xy 268.317726 -297.093132)
			(xy 268.322466 -297.093072) (xy 268.331797 -297.091406) (xy 268.336268 -297.08983) (xy 268.34465 -297.086528)
			(xy 268.352016 -297.079924) (xy 268.370366 -297.063859) (xy 268.410902 -297.036742) (xy 268.454979 -297.015868)
			(xy 268.501642 -297.001688) (xy 268.549881 -296.994511) (xy 268.574266 -296.994072) (xy 269.52448 -296.994072)
			(xy 269.550472 -296.994554) (xy 269.601816 -297.002683) (xy 269.651256 -297.018744) (xy 269.697575 -297.042342)
			(xy 269.739632 -297.072896) (xy 269.776391 -297.109653) (xy 269.806947 -297.151708) (xy 269.830548 -297.198025)
			(xy 269.846612 -297.247465) (xy 269.854745 -297.298808) (xy 269.854745 -297.32478) (xy 270.16889 -297.32478)
			(xy 270.17285 -297.275726) (xy 270.184627 -297.227942) (xy 270.203918 -297.182666) (xy 270.230221 -297.14107)
			(xy 270.262856 -297.104233) (xy 270.300977 -297.073108) (xy 270.343598 -297.048501) (xy 270.389614 -297.031049)
			(xy 270.437833 -297.021205) (xy 270.487008 -297.019224) (xy 270.535863 -297.025156) (xy 270.583134 -297.038848)
			(xy 270.627596 -297.059946) (xy 270.668099 -297.087902) (xy 270.703592 -297.121994) (xy 270.733157 -297.161338)
			(xy 270.756028 -297.204915) (xy 270.771612 -297.251596) (xy 270.779507 -297.300173) (xy 270.780002 -297.32478)
			(xy 271.119104 -297.32478) (xy 271.123064 -297.275726) (xy 271.134841 -297.227942) (xy 271.154132 -297.182666)
			(xy 271.180435 -297.14107) (xy 271.21307 -297.104233) (xy 271.251191 -297.073108) (xy 271.293812 -297.048501)
			(xy 271.339828 -297.031049) (xy 271.388047 -297.021205) (xy 271.437222 -297.019224) (xy 271.486077 -297.025156)
			(xy 271.533348 -297.038848) (xy 271.57781 -297.059946) (xy 271.618313 -297.087902) (xy 271.653806 -297.121994)
			(xy 271.683371 -297.161338) (xy 271.706242 -297.204915) (xy 271.721826 -297.251596) (xy 271.729721 -297.300173)
			(xy 271.730216 -297.32478) (xy 271.729721 -297.349387) (xy 271.721826 -297.397964) (xy 271.706242 -297.444645)
			(xy 271.683371 -297.488222) (xy 271.653806 -297.527566) (xy 271.618313 -297.561658) (xy 271.57781 -297.589614)
			(xy 271.533348 -297.610712) (xy 271.486077 -297.624404) (xy 271.437222 -297.630336) (xy 271.388047 -297.628355)
			(xy 271.339828 -297.618511) (xy 271.293812 -297.601059) (xy 271.251191 -297.576452) (xy 271.21307 -297.545327)
			(xy 271.180435 -297.50849) (xy 271.154132 -297.466894) (xy 271.134841 -297.421618) (xy 271.123064 -297.373834)
			(xy 271.119104 -297.32478) (xy 270.780002 -297.32478) (xy 270.779507 -297.349387) (xy 270.771612 -297.397964)
			(xy 270.756028 -297.444645) (xy 270.733157 -297.488222) (xy 270.703592 -297.527566) (xy 270.668099 -297.561658)
			(xy 270.627596 -297.589614) (xy 270.583134 -297.610712) (xy 270.535863 -297.624404) (xy 270.487008 -297.630336)
			(xy 270.437833 -297.628355) (xy 270.389614 -297.618511) (xy 270.343598 -297.601059) (xy 270.300977 -297.576452)
			(xy 270.262856 -297.545327) (xy 270.230221 -297.50849) (xy 270.203918 -297.466894) (xy 270.184627 -297.421618)
			(xy 270.17285 -297.373834) (xy 270.16889 -297.32478) (xy 269.854745 -297.32478) (xy 269.854745 -297.350792)
			(xy 269.846612 -297.402135) (xy 269.830548 -297.451575) (xy 269.806947 -297.497892) (xy 269.776391 -297.539947)
			(xy 269.739632 -297.576704) (xy 269.697575 -297.607258) (xy 269.651256 -297.630856) (xy 269.601816 -297.646917)
			(xy 269.550472 -297.655046) (xy 269.52448 -297.655488) (xy 268.913864 -297.655488) (xy 268.90391 -297.656022)
			(xy 268.885528 -297.663683) (xy 268.871415 -297.677732) (xy 268.867128 -297.68673) (xy 268.863583 -297.696174)
			(xy 268.863483 -297.716329) (xy 268.871203 -297.734948) (xy 268.87805 -297.742356) (xy 269.162784 -298.02709)
			(xy 269.169896 -298.032932) (xy 269.17566 -298.036505) (xy 269.188538 -298.040741) (xy 269.195296 -298.041314)
			(xy 269.263876 -298.043092) (xy 269.266924 -298.043092) (xy 269.271857 -298.043099) (xy 269.281578 -298.041435)
			(xy 269.286228 -298.03979) (xy 269.294864 -298.036488) (xy 269.30223 -298.029884) (xy 269.320579 -298.013817)
			(xy 269.361114 -297.986697) (xy 269.405191 -297.965821) (xy 269.451855 -297.951641) (xy 269.500095 -297.944464)
			(xy 269.52448 -297.944032) (xy 269.550469 -297.944514) (xy 269.601808 -297.952643) (xy 269.651242 -297.968704)
			(xy 269.697556 -297.992301) (xy 269.739606 -298.022854) (xy 269.776359 -298.059609) (xy 269.806909 -298.101662)
			(xy 269.830504 -298.147976) (xy 269.846562 -298.197412) (xy 269.854688 -298.248751) (xy 269.855188 -298.27474)
			(xy 270.16889 -298.27474) (xy 270.17285 -298.225686) (xy 270.184627 -298.177902) (xy 270.203918 -298.132626)
			(xy 270.230221 -298.09103) (xy 270.262856 -298.054193) (xy 270.300977 -298.023068) (xy 270.343598 -297.998461)
			(xy 270.389614 -297.981009) (xy 270.437833 -297.971165) (xy 270.487008 -297.969184) (xy 270.535863 -297.975116)
			(xy 270.583134 -297.988808) (xy 270.627596 -298.009906) (xy 270.668099 -298.037862) (xy 270.703592 -298.071954)
			(xy 270.733157 -298.111298) (xy 270.756028 -298.154875) (xy 270.771612 -298.201556) (xy 270.779507 -298.250133)
			(xy 270.780002 -298.27474) (xy 271.119104 -298.27474) (xy 271.123064 -298.225686) (xy 271.134841 -298.177902)
			(xy 271.154132 -298.132626) (xy 271.180435 -298.09103) (xy 271.21307 -298.054193) (xy 271.251191 -298.023068)
			(xy 271.293812 -297.998461) (xy 271.339828 -297.981009) (xy 271.388047 -297.971165) (xy 271.437222 -297.969184)
			(xy 271.486077 -297.975116) (xy 271.533348 -297.988808) (xy 271.57781 -298.009906) (xy 271.618313 -298.037862)
			(xy 271.653806 -298.071954) (xy 271.683371 -298.111298) (xy 271.706242 -298.154875) (xy 271.721826 -298.201556)
			(xy 271.729721 -298.250133) (xy 271.730216 -298.27474) (xy 272.069064 -298.27474) (xy 272.073024 -298.225686)
			(xy 272.084801 -298.177902) (xy 272.104092 -298.132626) (xy 272.130395 -298.09103) (xy 272.16303 -298.054193)
			(xy 272.201151 -298.023068) (xy 272.243772 -297.998461) (xy 272.289788 -297.981009) (xy 272.338007 -297.971165)
			(xy 272.387182 -297.969184) (xy 272.436037 -297.975116) (xy 272.483308 -297.988808) (xy 272.52777 -298.009906)
			(xy 272.568273 -298.037862) (xy 272.603766 -298.071954) (xy 272.633331 -298.111298) (xy 272.656202 -298.154875)
			(xy 272.671786 -298.201556) (xy 272.679681 -298.250133) (xy 272.680176 -298.27474) (xy 273.019024 -298.27474)
			(xy 273.022984 -298.225686) (xy 273.034761 -298.177902) (xy 273.054052 -298.132626) (xy 273.080355 -298.09103)
			(xy 273.11299 -298.054193) (xy 273.151111 -298.023068) (xy 273.193732 -297.998461) (xy 273.239748 -297.981009)
			(xy 273.287967 -297.971165) (xy 273.337142 -297.969184) (xy 273.385997 -297.975116) (xy 273.433268 -297.988808)
			(xy 273.47773 -298.009906) (xy 273.518233 -298.037862) (xy 273.553726 -298.071954) (xy 273.583291 -298.111298)
			(xy 273.606162 -298.154875) (xy 273.621746 -298.201556) (xy 273.629641 -298.250133) (xy 273.630136 -298.27474)
			(xy 273.968984 -298.27474) (xy 273.972944 -298.225686) (xy 273.984721 -298.177902) (xy 274.004012 -298.132626)
			(xy 274.030315 -298.09103) (xy 274.06295 -298.054193) (xy 274.101071 -298.023068) (xy 274.143692 -297.998461)
			(xy 274.189708 -297.981009) (xy 274.237927 -297.971165) (xy 274.287102 -297.969184) (xy 274.335957 -297.975116)
			(xy 274.383228 -297.988808) (xy 274.42769 -298.009906) (xy 274.468193 -298.037862) (xy 274.503686 -298.071954)
			(xy 274.533251 -298.111298) (xy 274.556122 -298.154875) (xy 274.571706 -298.201556) (xy 274.579601 -298.250133)
			(xy 274.580096 -298.27474) (xy 275.868904 -298.27474) (xy 275.872864 -298.225686) (xy 275.884641 -298.177902)
			(xy 275.903932 -298.132626) (xy 275.930235 -298.09103) (xy 275.96287 -298.054193) (xy 276.000991 -298.023068)
			(xy 276.043612 -297.998461) (xy 276.089628 -297.981009) (xy 276.137847 -297.971165) (xy 276.187022 -297.969184)
			(xy 276.235877 -297.975116) (xy 276.283148 -297.988808) (xy 276.32761 -298.009906) (xy 276.368113 -298.037862)
			(xy 276.403606 -298.071954) (xy 276.433171 -298.111298) (xy 276.456042 -298.154875) (xy 276.471626 -298.201556)
			(xy 276.479521 -298.250133) (xy 276.480016 -298.27474) (xy 276.819118 -298.27474) (xy 276.823078 -298.225686)
			(xy 276.834855 -298.177902) (xy 276.854146 -298.132626) (xy 276.880449 -298.09103) (xy 276.913084 -298.054193)
			(xy 276.951205 -298.023068) (xy 276.993826 -297.998461) (xy 277.039842 -297.981009) (xy 277.088061 -297.971165)
			(xy 277.137236 -297.969184) (xy 277.186091 -297.975116) (xy 277.233362 -297.988808) (xy 277.277824 -298.009906)
			(xy 277.318327 -298.037862) (xy 277.35382 -298.071954) (xy 277.383385 -298.111298) (xy 277.406256 -298.154875)
			(xy 277.42184 -298.201556) (xy 277.429735 -298.250133) (xy 277.43023 -298.27474) (xy 277.769078 -298.27474)
			(xy 277.773038 -298.225686) (xy 277.784815 -298.177902) (xy 277.804106 -298.132626) (xy 277.830409 -298.09103)
			(xy 277.863044 -298.054193) (xy 277.901165 -298.023068) (xy 277.943786 -297.998461) (xy 277.989802 -297.981009)
			(xy 278.038021 -297.971165) (xy 278.087196 -297.969184) (xy 278.136051 -297.975116) (xy 278.183322 -297.988808)
			(xy 278.227784 -298.009906) (xy 278.268287 -298.037862) (xy 278.30378 -298.071954) (xy 278.333345 -298.111298)
			(xy 278.356216 -298.154875) (xy 278.3718 -298.201556) (xy 278.379695 -298.250133) (xy 278.38019 -298.27474)
			(xy 278.379695 -298.299347) (xy 278.3718 -298.347924) (xy 278.356216 -298.394605) (xy 278.333345 -298.438182)
			(xy 278.30378 -298.477526) (xy 278.268287 -298.511618) (xy 278.227784 -298.539574) (xy 278.183322 -298.560672)
			(xy 278.136051 -298.574364) (xy 278.087196 -298.580296) (xy 278.038021 -298.578315) (xy 277.989802 -298.568471)
			(xy 277.943786 -298.551019) (xy 277.901165 -298.526412) (xy 277.863044 -298.495287) (xy 277.830409 -298.45845)
			(xy 277.804106 -298.416854) (xy 277.784815 -298.371578) (xy 277.773038 -298.323794) (xy 277.769078 -298.27474)
			(xy 277.43023 -298.27474) (xy 277.429735 -298.299347) (xy 277.42184 -298.347924) (xy 277.406256 -298.394605)
			(xy 277.383385 -298.438182) (xy 277.35382 -298.477526) (xy 277.318327 -298.511618) (xy 277.277824 -298.539574)
			(xy 277.233362 -298.560672) (xy 277.186091 -298.574364) (xy 277.137236 -298.580296) (xy 277.088061 -298.578315)
			(xy 277.039842 -298.568471) (xy 276.993826 -298.551019) (xy 276.951205 -298.526412) (xy 276.913084 -298.495287)
			(xy 276.880449 -298.45845) (xy 276.854146 -298.416854) (xy 276.834855 -298.371578) (xy 276.823078 -298.323794)
			(xy 276.819118 -298.27474) (xy 276.480016 -298.27474) (xy 276.479521 -298.299347) (xy 276.471626 -298.347924)
			(xy 276.456042 -298.394605) (xy 276.433171 -298.438182) (xy 276.403606 -298.477526) (xy 276.368113 -298.511618)
			(xy 276.32761 -298.539574) (xy 276.283148 -298.560672) (xy 276.235877 -298.574364) (xy 276.187022 -298.580296)
			(xy 276.137847 -298.578315) (xy 276.089628 -298.568471) (xy 276.043612 -298.551019) (xy 276.000991 -298.526412)
			(xy 275.96287 -298.495287) (xy 275.930235 -298.45845) (xy 275.903932 -298.416854) (xy 275.884641 -298.371578)
			(xy 275.872864 -298.323794) (xy 275.868904 -298.27474) (xy 274.580096 -298.27474) (xy 274.579601 -298.299347)
			(xy 274.571706 -298.347924) (xy 274.556122 -298.394605) (xy 274.533251 -298.438182) (xy 274.503686 -298.477526)
			(xy 274.468193 -298.511618) (xy 274.42769 -298.539574) (xy 274.383228 -298.560672) (xy 274.335957 -298.574364)
			(xy 274.287102 -298.580296) (xy 274.237927 -298.578315) (xy 274.189708 -298.568471) (xy 274.143692 -298.551019)
			(xy 274.101071 -298.526412) (xy 274.06295 -298.495287) (xy 274.030315 -298.45845) (xy 274.004012 -298.416854)
			(xy 273.984721 -298.371578) (xy 273.972944 -298.323794) (xy 273.968984 -298.27474) (xy 273.630136 -298.27474)
			(xy 273.629641 -298.299347) (xy 273.621746 -298.347924) (xy 273.606162 -298.394605) (xy 273.583291 -298.438182)
			(xy 273.553726 -298.477526) (xy 273.518233 -298.511618) (xy 273.47773 -298.539574) (xy 273.433268 -298.560672)
			(xy 273.385997 -298.574364) (xy 273.337142 -298.580296) (xy 273.287967 -298.578315) (xy 273.239748 -298.568471)
			(xy 273.193732 -298.551019) (xy 273.151111 -298.526412) (xy 273.11299 -298.495287) (xy 273.080355 -298.45845)
			(xy 273.054052 -298.416854) (xy 273.034761 -298.371578) (xy 273.022984 -298.323794) (xy 273.019024 -298.27474)
			(xy 272.680176 -298.27474) (xy 272.679681 -298.299347) (xy 272.671786 -298.347924) (xy 272.656202 -298.394605)
			(xy 272.633331 -298.438182) (xy 272.603766 -298.477526) (xy 272.568273 -298.511618) (xy 272.52777 -298.539574)
			(xy 272.483308 -298.560672) (xy 272.436037 -298.574364) (xy 272.387182 -298.580296) (xy 272.338007 -298.578315)
			(xy 272.289788 -298.568471) (xy 272.243772 -298.551019) (xy 272.201151 -298.526412) (xy 272.16303 -298.495287)
			(xy 272.130395 -298.45845) (xy 272.104092 -298.416854) (xy 272.084801 -298.371578) (xy 272.073024 -298.323794)
			(xy 272.069064 -298.27474) (xy 271.730216 -298.27474) (xy 271.729721 -298.299347) (xy 271.721826 -298.347924)
			(xy 271.706242 -298.394605) (xy 271.683371 -298.438182) (xy 271.653806 -298.477526) (xy 271.618313 -298.511618)
			(xy 271.57781 -298.539574) (xy 271.533348 -298.560672) (xy 271.486077 -298.574364) (xy 271.437222 -298.580296)
			(xy 271.388047 -298.578315) (xy 271.339828 -298.568471) (xy 271.293812 -298.551019) (xy 271.251191 -298.526412)
			(xy 271.21307 -298.495287) (xy 271.180435 -298.45845) (xy 271.154132 -298.416854) (xy 271.134841 -298.371578)
			(xy 271.123064 -298.323794) (xy 271.119104 -298.27474) (xy 270.780002 -298.27474) (xy 270.779507 -298.299347)
			(xy 270.771612 -298.347924) (xy 270.756028 -298.394605) (xy 270.733157 -298.438182) (xy 270.703592 -298.477526)
			(xy 270.668099 -298.511618) (xy 270.627596 -298.539574) (xy 270.583134 -298.560672) (xy 270.535863 -298.574364)
			(xy 270.487008 -298.580296) (xy 270.437833 -298.578315) (xy 270.389614 -298.568471) (xy 270.343598 -298.551019)
			(xy 270.300977 -298.526412) (xy 270.262856 -298.495287) (xy 270.230221 -298.45845) (xy 270.203918 -298.416854)
			(xy 270.184627 -298.371578) (xy 270.17285 -298.323794) (xy 270.16889 -298.27474) (xy 269.855188 -298.27474)
			(xy 269.854756 -298.299127) (xy 269.847597 -298.347372) (xy 269.833424 -298.394041) (xy 269.812546 -298.43812)
			(xy 269.785417 -298.478652) (xy 269.769336 -298.49699) (xy 269.762732 -298.504356) (xy 269.75943 -298.512992)
			(xy 269.757909 -298.51728) (xy 269.756245 -298.526224) (xy 269.756128 -298.530772) (xy 269.756636 -298.548298)
			(xy 269.75816 -298.605448) (xy 269.758845 -298.611648) (xy 269.762833 -298.623462) (xy 269.766034 -298.628816)
			(xy 269.769082 -298.63288) (xy 269.772638 -298.636944) (xy 270.132556 -298.996862) (xy 270.138931 -299.002096)
			(xy 270.154085 -299.008583) (xy 270.162274 -299.009562) (xy 270.235172 -299.01134) (xy 270.240041 -299.011328)
			(xy 270.249634 -299.009668) (xy 270.254222 -299.008038) (xy 270.262858 -299.004736) (xy 270.270224 -298.998132)
			(xy 270.287141 -298.983427) (xy 270.324474 -298.958621) (xy 270.365031 -298.939534) (xy 270.40794 -298.926577)
			(xy 270.452282 -298.920028) (xy 270.474694 -298.919646) (xy 270.498687 -298.920116) (xy 270.546082 -298.927621)
			(xy 270.59172 -298.942447) (xy 270.634477 -298.96423) (xy 270.6733 -298.992432) (xy 270.707234 -299.026361)
			(xy 270.735443 -299.065179) (xy 270.757233 -299.107932) (xy 270.772067 -299.153567) (xy 270.77958 -299.200961)
			(xy 270.780002 -299.224954) (xy 270.779427 -299.251502) (xy 270.770239 -299.303798) (xy 270.752148 -299.353718)
			(xy 270.7257 -299.399759) (xy 270.691691 -299.440535) (xy 270.671798 -299.458126) (xy 270.67002 -299.45965)
			(xy 270.668496 -299.461174) (xy 270.661814 -299.468588) (xy 270.654218 -299.487022) (xy 270.654215 -299.506961)
			(xy 270.661804 -299.525398) (xy 270.668496 -299.532802) (xy 270.70431 -299.568616) (xy 270.711721 -299.575297)
			(xy 270.730157 -299.582873) (xy 270.740124 -299.583348) (xy 271.10944 -299.583348) (xy 271.118538 -299.582932)
			(xy 271.135561 -299.576496) (xy 271.149265 -299.564522) (xy 271.15389 -299.556678) (xy 271.175226 -299.512736)
			(xy 271.175226 -299.512228) (xy 271.182846 -299.496226) (xy 271.186423 -299.487485) (xy 271.1875 -299.468642)
			(xy 271.181655 -299.450697) (xy 271.175988 -299.44314) (xy 271.174718 -299.441616) (xy 271.17421 -299.441108)
			(xy 271.158774 -299.422516) (xy 271.132899 -299.381706) (xy 271.11324 -299.337564) (xy 271.100215 -299.291031)
			(xy 271.09674 -299.267118) (xy 271.09674 -299.26661) (xy 271.095216 -299.25137) (xy 271.094454 -299.242226)
			(xy 271.093946 -299.224954) (xy 271.094459 -299.198962) (xy 271.102593 -299.147619) (xy 271.118655 -299.098179)
			(xy 271.14225 -299.051858) (xy 271.172796 -299.009795) (xy 271.209543 -298.973026) (xy 271.251587 -298.942454)
			(xy 271.297894 -298.918832) (xy 271.347324 -298.90274) (xy 271.398663 -298.894575) (xy 271.424654 -298.893992)
			(xy 272.374868 -298.893992) (xy 272.400844 -298.894498) (xy 272.452158 -298.902617) (xy 272.501571 -298.91866)
			(xy 272.547868 -298.942232) (xy 272.589909 -298.972753) (xy 272.626661 -299.009473) (xy 272.657219 -299.051488)
			(xy 272.680831 -299.097764) (xy 272.696916 -299.147163) (xy 272.705079 -299.19847) (xy 272.705576 -299.224446)
			(xy 272.705576 -299.224954) (xy 272.705204 -299.248509) (xy 272.698602 -299.295153) (xy 272.685438 -299.340386)
			(xy 272.665982 -299.383289) (xy 272.640626 -299.422992) (xy 272.625566 -299.441108) (xy 272.625058 -299.441616)
			(xy 272.623788 -299.44314) (xy 272.618197 -299.450728) (xy 272.612417 -299.468651) (xy 272.61348 -299.487452)
			(xy 272.61693 -299.496226) (xy 272.62455 -299.512228) (xy 272.62455 -299.512736) (xy 272.645886 -299.556678)
			(xy 272.650539 -299.564501) (xy 272.664232 -299.576473) (xy 272.681244 -299.582912) (xy 272.690336 -299.583348)
			(xy 273.00936 -299.583348) (xy 273.018919 -299.582961) (xy 273.036704 -299.575951) (xy 273.050643 -299.562868)
			(xy 273.05508 -299.554392) (xy 273.092926 -299.475144) (xy 273.092926 -299.474636) (xy 273.09445 -299.471588)
			(xy 273.097447 -299.464897) (xy 273.099887 -299.450447) (xy 273.099276 -299.44314) (xy 273.098514 -299.436536)
			(xy 273.092926 -299.423836) (xy 273.0881 -299.41774) (xy 273.072031 -299.397166) (xy 273.046428 -299.351675)
			(xy 273.028931 -299.302494) (xy 273.020049 -299.251054) (xy 273.01952 -299.224954) (xy 273.020042 -299.199699)
			(xy 273.028355 -299.149877) (xy 273.044756 -299.102103) (xy 273.068797 -299.05768) (xy 273.099821 -299.01782)
			(xy 273.136983 -298.98361) (xy 273.179269 -298.955984) (xy 273.225525 -298.935694) (xy 273.27449 -298.923294)
			(xy 273.324828 -298.919123) (xy 273.375166 -298.923294) (xy 273.424131 -298.935694) (xy 273.470387 -298.955984)
			(xy 273.512673 -298.98361) (xy 273.549835 -299.01782) (xy 273.580859 -299.05768) (xy 273.6049 -299.102103)
			(xy 273.621301 -299.149877) (xy 273.629614 -299.199699) (xy 273.630136 -299.224954) (xy 273.630136 -299.225462)
			(xy 273.629593 -299.250714) (xy 273.621239 -299.300522) (xy 273.604803 -299.348277) (xy 273.580732 -299.392676)
			(xy 273.56562 -299.412914) (xy 273.561556 -299.417994) (xy 273.55038 -299.444156) (xy 273.549618 -299.450506)
			(xy 273.551904 -299.464984) (xy 273.55673 -299.47489) (xy 273.594576 -299.554392) (xy 273.599059 -299.562827)
			(xy 273.613015 -299.575851) (xy 273.630754 -299.582903) (xy 273.640296 -299.583348) (xy 273.64817 -299.583348)
			(xy 273.692888 -299.58387) (xy 273.781937 -299.592181) (xy 273.869835 -299.608698) (xy 273.955827 -299.633277)
			(xy 274.039176 -299.66571) (xy 274.119165 -299.705716) (xy 274.195109 -299.752953) (xy 274.266356 -299.807016)
			(xy 274.29968 -299.83684) (xy 274.306284 -299.84319) (xy 274.33143 -299.85335) (xy 274.341082 -299.856144)
			(xy 274.350226 -299.856906)
		)
		(stroke
			(width 0)
			(type solid)
		)
		(fill yes)
		(layer "In7.Cu")
		(net "SYSPLL_VDDA18_PEX2")
	)
	(gr_poly
		(pts
			(xy 247.396 -321.31) (xy 247.396 -314.8584) (xy 248.553224 -313.701176) (xy 248.553224 -310.68518)
			(xy 248.552747 -310.675214) (xy 248.545174 -310.656775) (xy 248.538492 -310.649366) (xy 248.480834 -310.5912)
			(xy 248.462546 -310.58358) (xy 248.452386 -310.58358) (xy 248.425254 -310.582923) (xy 248.371582 -310.574878)
			(xy 248.319593 -310.559307) (xy 248.270334 -310.536526) (xy 248.224802 -310.506993) (xy 248.183914 -310.471306)
			(xy 248.148497 -310.430184) (xy 248.119265 -310.384458) (xy 248.096809 -310.33505) (xy 248.081581 -310.282959)
			(xy 248.07389 -310.229235) (xy 248.07389 -310.174964) (xy 248.081581 -310.121241) (xy 248.096809 -310.069149)
			(xy 248.119265 -310.019742) (xy 248.148497 -309.974016) (xy 248.183914 -309.932894) (xy 248.224802 -309.897207)
			(xy 248.270335 -309.867674) (xy 248.319593 -309.844893) (xy 248.371583 -309.829322) (xy 248.425254 -309.821277)
			(xy 248.452386 -309.820564) (xy 248.462546 -309.820564) (xy 248.480834 -309.812944) (xy 248.538492 -309.754778)
			(xy 248.545173 -309.747368) (xy 248.552749 -309.728931) (xy 248.553224 -309.718964) (xy 248.553224 -308.977284)
			(xy 248.52884 -308.948836) (xy 248.510044 -308.946042) (xy 248.483358 -308.941463) (xy 248.431543 -308.925757)
			(xy 248.382469 -308.902884) (xy 248.33712 -308.873304) (xy 248.296409 -308.83761) (xy 248.261151 -308.79652)
			(xy 248.232056 -308.750859) (xy 248.209708 -308.701543) (xy 248.194556 -308.649564) (xy 248.186903 -308.595964)
			(xy 248.186904 -308.541821) (xy 248.194559 -308.488222) (xy 248.209713 -308.436243) (xy 248.232063 -308.386928)
			(xy 248.26116 -308.341268) (xy 248.296419 -308.300179) (xy 248.337132 -308.264487) (xy 248.382482 -308.234909)
			(xy 248.431557 -308.212038) (xy 248.483373 -308.196334) (xy 248.510044 -308.191662) (xy 248.52884 -308.188868)
			(xy 248.553224 -308.16042) (xy 248.553224 -307.892704) (xy 248.52884 -307.864256) (xy 248.510044 -307.861462)
			(xy 248.483357 -307.856883) (xy 248.431539 -307.841176) (xy 248.382462 -307.818303) (xy 248.337111 -307.788722)
			(xy 248.296397 -307.753027) (xy 248.261137 -307.711935) (xy 248.23204 -307.666271) (xy 248.209691 -307.616953)
			(xy 248.194537 -307.564971) (xy 248.186884 -307.511369) (xy 248.186884 -307.457223) (xy 248.194539 -307.403621)
			(xy 248.209694 -307.351639) (xy 248.232044 -307.302321) (xy 248.261142 -307.256659) (xy 248.296403 -307.215567)
			(xy 248.337118 -307.179873) (xy 248.382469 -307.150293) (xy 248.431547 -307.127421) (xy 248.483365 -307.111715)
			(xy 248.510044 -307.107082) (xy 248.52884 -307.104288) (xy 248.553224 -307.07584) (xy 248.553224 -270.378174)
			(xy 248.552797 -270.368105) (xy 248.545078 -270.349505) (xy 248.538238 -270.342106) (xy 248.161556 -269.965424)
			(xy 248.154444 -269.958058) (xy 248.135648 -269.950438) (xy 234.814364 -269.950438) (xy 234.80435 -269.950864)
			(xy 234.785852 -269.958542) (xy 234.771701 -269.972714) (xy 234.76405 -269.991224) (xy 234.763564 -270.001238)
			(xy 234.763564 -272.842228) (xy 236.419898 -272.842228) (xy 236.420381 -272.814858) (xy 236.428195 -272.76068)
			(xy 236.44368 -272.708177) (xy 236.466518 -272.65843) (xy 236.496239 -272.612462) (xy 236.513878 -272.59153)
			(xy 236.519974 -272.584418) (xy 236.526324 -272.5674) (xy 236.526324 -272.482056) (xy 236.519974 -272.465038)
			(xy 236.513878 -272.457926) (xy 236.496234 -272.436998) (xy 236.466524 -272.391024) (xy 236.443689 -272.341275)
			(xy 236.428199 -272.288774) (xy 236.420372 -272.234597) (xy 236.419898 -272.207228) (xy 236.420381 -272.179976)
			(xy 236.428135 -272.126025) (xy 236.443487 -272.073727) (xy 236.466127 -272.024147) (xy 236.495593 -271.978293)
			(xy 236.531284 -271.9371) (xy 236.572476 -271.901406) (xy 236.618327 -271.871938) (xy 236.667907 -271.849295)
			(xy 236.720204 -271.833939) (xy 236.774154 -271.826183) (xy 236.801406 -271.82572) (xy 236.830144 -271.826261)
			(xy 236.88697 -271.834883) (xy 236.941859 -271.85193) (xy 236.993571 -271.877017) (xy 237.040936 -271.909576)
			(xy 237.062264 -271.928844) (xy 237.069376 -271.935448) (xy 237.086902 -271.94256) (xy 237.17631 -271.94256)
			(xy 237.193836 -271.935448) (xy 237.200948 -271.928844) (xy 237.222275 -271.909574) (xy 237.269638 -271.877009)
			(xy 237.321349 -271.851918) (xy 237.37624 -271.834868) (xy 237.433067 -271.826246) (xy 237.490545 -271.826246)
			(xy 237.547372 -271.834868) (xy 237.602263 -271.851918) (xy 237.653974 -271.877009) (xy 237.701337 -271.909574)
			(xy 237.722664 -271.928844) (xy 237.729776 -271.935448) (xy 237.747302 -271.94256) (xy 237.83671 -271.94256)
			(xy 237.854236 -271.935448) (xy 237.861348 -271.928844) (xy 237.882675 -271.909574) (xy 237.930038 -271.877009)
			(xy 237.981749 -271.851918) (xy 238.03664 -271.834868) (xy 238.093467 -271.826246) (xy 238.150945 -271.826246)
			(xy 238.207772 -271.834868) (xy 238.262663 -271.851918) (xy 238.314374 -271.877009) (xy 238.361737 -271.909574)
			(xy 238.383064 -271.928844) (xy 238.390176 -271.935448) (xy 238.407702 -271.94256) (xy 238.49711 -271.94256)
			(xy 238.514636 -271.935448) (xy 238.521748 -271.928844) (xy 238.543073 -271.909571) (xy 238.590436 -271.877005)
			(xy 238.642148 -271.851913) (xy 238.697039 -271.834863) (xy 238.753867 -271.826241) (xy 238.782606 -271.82572)
			(xy 238.80986 -271.82615) (xy 238.863814 -271.833908) (xy 238.916114 -271.849267) (xy 238.965696 -271.871912)
			(xy 239.01155 -271.901383) (xy 239.052744 -271.93708) (xy 239.088437 -271.978277) (xy 239.117905 -272.024134)
			(xy 239.140545 -272.073718) (xy 239.155899 -272.126019) (xy 239.163653 -272.179974) (xy 239.164114 -272.207228)
			(xy 239.163661 -272.234599) (xy 239.155839 -272.288778) (xy 239.140347 -272.341281) (xy 239.117503 -272.391028)
			(xy 239.087776 -272.436994) (xy 239.070134 -272.457926) (xy 239.064038 -272.465038) (xy 239.057688 -272.482056)
			(xy 239.057688 -272.5674) (xy 239.064038 -272.584418) (xy 239.070134 -272.59153) (xy 239.087759 -272.612473)
			(xy 239.117472 -272.658444) (xy 239.14031 -272.708188) (xy 239.155804 -272.760686) (xy 239.163637 -272.81486)
			(xy 239.163769 -272.822416) (xy 240.094516 -272.822416) (xy 240.094988 -272.795046) (xy 240.102803 -272.740867)
			(xy 240.118291 -272.688364) (xy 240.141132 -272.638617) (xy 240.170855 -272.59265) (xy 240.188496 -272.571718)
			(xy 240.194592 -272.564606) (xy 240.200942 -272.547588) (xy 240.200942 -272.462244) (xy 240.194592 -272.445226)
			(xy 240.188496 -272.438114) (xy 240.170849 -272.417188) (xy 240.141139 -272.371213) (xy 240.118304 -272.321464)
			(xy 240.102815 -272.268962) (xy 240.094989 -272.214786) (xy 240.094516 -272.187416) (xy 240.09497 -272.160162)
			(xy 240.102726 -272.10621) (xy 240.118081 -272.05391) (xy 240.140723 -272.004329) (xy 240.170192 -271.958474)
			(xy 240.205887 -271.917281) (xy 240.247081 -271.881587) (xy 240.292936 -271.852119) (xy 240.342518 -271.829478)
			(xy 240.394818 -271.814124) (xy 240.44877 -271.80637) (xy 240.476024 -271.805908) (xy 240.504764 -271.806415)
			(xy 240.561592 -271.815041) (xy 240.616483 -271.832095) (xy 240.668194 -271.857191) (xy 240.715556 -271.889759)
			(xy 240.736882 -271.909032) (xy 240.743994 -271.915636) (xy 240.76152 -271.922748) (xy 240.850928 -271.922748)
			(xy 240.868454 -271.915636) (xy 240.875566 -271.909032) (xy 240.896893 -271.889762) (xy 240.944256 -271.857197)
			(xy 240.995967 -271.832106) (xy 241.050858 -271.815056) (xy 241.107685 -271.806434) (xy 241.165163 -271.806434)
			(xy 241.22199 -271.815056) (xy 241.276881 -271.832106) (xy 241.328592 -271.857197) (xy 241.375955 -271.889762)
			(xy 241.397282 -271.909032) (xy 241.404394 -271.915636) (xy 241.42192 -271.922748) (xy 241.511328 -271.922748)
			(xy 241.528854 -271.915636) (xy 241.535966 -271.909032) (xy 241.557293 -271.889762) (xy 241.604656 -271.857197)
			(xy 241.656367 -271.832106) (xy 241.711258 -271.815056) (xy 241.768085 -271.806434) (xy 241.825563 -271.806434)
			(xy 241.88239 -271.815056) (xy 241.937281 -271.832106) (xy 241.988992 -271.857197) (xy 242.036355 -271.889762)
			(xy 242.057682 -271.909032) (xy 242.064794 -271.915636) (xy 242.08232 -271.922748) (xy 242.171728 -271.922748)
			(xy 242.189254 -271.915636) (xy 242.196366 -271.909032) (xy 242.217682 -271.889749) (xy 242.265047 -271.857185)
			(xy 242.316762 -271.832095) (xy 242.371655 -271.815047) (xy 242.428484 -271.806427) (xy 242.457224 -271.805908)
			(xy 242.484477 -271.806356) (xy 242.538427 -271.814116) (xy 242.590723 -271.829475) (xy 242.640301 -271.85212)
			(xy 242.686152 -271.88159) (xy 242.727343 -271.917286) (xy 242.763034 -271.95848) (xy 242.792499 -272.004334)
			(xy 242.815139 -272.053915) (xy 242.830493 -272.106213) (xy 242.838247 -272.160163) (xy 242.838732 -272.187416)
			(xy 242.838292 -272.214787) (xy 242.83047 -272.268968) (xy 242.814976 -272.321472) (xy 242.792128 -272.371219)
			(xy 242.762397 -272.417184) (xy 242.744752 -272.438114) (xy 242.738656 -272.445226) (xy 242.732306 -272.462244)
			(xy 242.732306 -272.547588) (xy 242.738656 -272.564606) (xy 242.744752 -272.571718) (xy 242.762359 -272.592676)
			(xy 242.792077 -272.638641) (xy 242.81492 -272.688382) (xy 242.830418 -272.740877) (xy 242.838254 -272.795048)
			(xy 242.838732 -272.822416) (xy 242.838237 -272.849667) (xy 242.830479 -272.903613) (xy 242.815123 -272.955906)
			(xy 242.792482 -273.005482) (xy 242.763016 -273.051331) (xy 242.727326 -273.09252) (xy 242.686137 -273.128211)
			(xy 242.640289 -273.157678) (xy 242.590713 -273.18032) (xy 242.538421 -273.195677) (xy 242.484475 -273.203437)
			(xy 242.457224 -273.203924) (xy 242.428486 -273.203379) (xy 242.37166 -273.194761) (xy 242.31677 -273.177715)
			(xy 242.265057 -273.152629) (xy 242.217694 -273.120068) (xy 242.196366 -273.1008) (xy 242.189254 -273.094196)
			(xy 242.171728 -273.087084) (xy 242.08232 -273.087084) (xy 242.064794 -273.094196) (xy 242.057682 -273.1008)
			(xy 242.036355 -273.12007) (xy 241.988992 -273.152635) (xy 241.937281 -273.177726) (xy 241.88239 -273.194776)
			(xy 241.825563 -273.203398) (xy 241.768085 -273.203398) (xy 241.711258 -273.194776) (xy 241.656367 -273.177726)
			(xy 241.604656 -273.152635) (xy 241.557293 -273.12007) (xy 241.535966 -273.1008) (xy 241.528854 -273.094196)
			(xy 241.511328 -273.087084) (xy 241.42192 -273.087084) (xy 241.404394 -273.094196) (xy 241.397282 -273.1008)
			(xy 241.375955 -273.12007) (xy 241.328592 -273.152635) (xy 241.276881 -273.177726) (xy 241.22199 -273.194776)
			(xy 241.165163 -273.203398) (xy 241.107685 -273.203398) (xy 241.050858 -273.194776) (xy 240.995967 -273.177726)
			(xy 240.944256 -273.152635) (xy 240.896893 -273.12007) (xy 240.875566 -273.1008) (xy 240.868454 -273.094196)
			(xy 240.850928 -273.087084) (xy 240.76152 -273.087084) (xy 240.743994 -273.094196) (xy 240.736882 -273.1008)
			(xy 240.715536 -273.120049) (xy 240.66818 -273.15262) (xy 240.616473 -273.177718) (xy 240.561586 -273.194773)
			(xy 240.504762 -273.203401) (xy 240.476024 -273.203924) (xy 240.448772 -273.203422) (xy 240.394824 -273.195669)
			(xy 240.342528 -273.180317) (xy 240.292949 -273.157678) (xy 240.247096 -273.128214) (xy 240.205904 -273.092525)
			(xy 240.17021 -273.051336) (xy 240.140741 -273.005487) (xy 240.118097 -272.95591) (xy 240.102739 -272.903615)
			(xy 240.09498 -272.849667) (xy 240.094516 -272.822416) (xy 239.163769 -272.822416) (xy 239.164114 -272.842228)
			(xy 239.163648 -272.86948) (xy 239.155888 -272.923428) (xy 239.14053 -272.975723) (xy 239.117886 -273.025299)
			(xy 239.088417 -273.071149) (xy 239.052724 -273.112339) (xy 239.011532 -273.14803) (xy 238.96568 -273.177496)
			(xy 238.916102 -273.200137) (xy 238.863806 -273.215493) (xy 238.809858 -273.22325) (xy 238.782606 -273.223736)
			(xy 238.753868 -273.223199) (xy 238.697041 -273.214578) (xy 238.642151 -273.197531) (xy 238.590439 -273.172442)
			(xy 238.543076 -273.139881) (xy 238.521748 -273.120612) (xy 238.514636 -273.114008) (xy 238.49711 -273.106896)
			(xy 238.407702 -273.106896) (xy 238.390176 -273.114008) (xy 238.383064 -273.120612) (xy 238.361737 -273.139882)
			(xy 238.314374 -273.172447) (xy 238.262663 -273.197538) (xy 238.207772 -273.214588) (xy 238.150945 -273.22321)
			(xy 238.093467 -273.22321) (xy 238.03664 -273.214588) (xy 237.981749 -273.197538) (xy 237.930038 -273.172447)
			(xy 237.882675 -273.139882) (xy 237.861348 -273.120612) (xy 237.854236 -273.114008) (xy 237.83671 -273.106896)
			(xy 237.747302 -273.106896) (xy 237.729776 -273.114008) (xy 237.722664 -273.120612) (xy 237.701337 -273.139882)
			(xy 237.653974 -273.172447) (xy 237.602263 -273.197538) (xy 237.547372 -273.214588) (xy 237.490545 -273.22321)
			(xy 237.433067 -273.22321) (xy 237.37624 -273.214588) (xy 237.321349 -273.197538) (xy 237.269638 -273.172447)
			(xy 237.222275 -273.139882) (xy 237.200948 -273.120612) (xy 237.193836 -273.114008) (xy 237.17631 -273.106896)
			(xy 237.086902 -273.106896) (xy 237.069376 -273.114008) (xy 237.062264 -273.120612) (xy 237.040927 -273.139872)
			(xy 236.993569 -273.172441) (xy 236.94186 -273.197537) (xy 236.886971 -273.21459) (xy 236.830144 -273.223214)
			(xy 236.801406 -273.223736) (xy 236.774156 -273.223217) (xy 236.720211 -273.215462) (xy 236.667919 -273.200109)
			(xy 236.618343 -273.17747) (xy 236.572494 -273.148007) (xy 236.531305 -273.112319) (xy 236.495613 -273.071133)
			(xy 236.466146 -273.025287) (xy 236.443503 -272.975713) (xy 236.428145 -272.923422) (xy 236.420386 -272.869478)
			(xy 236.419898 -272.842228) (xy 234.763564 -272.842228) (xy 234.763564 -274.632674) (xy 242.945156 -274.632674)
			(xy 242.949227 -274.577052) (xy 242.961353 -274.522615) (xy 242.981276 -274.470524) (xy 243.008572 -274.421889)
			(xy 243.042658 -274.377746) (xy 243.082807 -274.339037) (xy 243.128165 -274.306586) (xy 243.177765 -274.281085)
			(xy 243.230549 -274.263078) (xy 243.285392 -274.252948) (xy 243.341126 -274.250911) (xy 243.396563 -274.257011)
			(xy 243.45052 -274.271117) (xy 243.501849 -274.292929) (xy 243.549455 -274.321983) (xy 243.592323 -274.357658)
			(xy 243.62954 -274.399195) (xy 243.660313 -274.445708) (xy 243.683985 -274.496205) (xy 243.700053 -274.549612)
			(xy 243.708173 -274.604788) (xy 243.708682 -274.632674) (xy 243.708173 -274.66056) (xy 243.700053 -274.715736)
			(xy 243.684312 -274.768056) (xy 245.074946 -274.768056) (xy 245.079017 -274.712434) (xy 245.091143 -274.657997)
			(xy 245.111066 -274.605906) (xy 245.138362 -274.557271) (xy 245.172448 -274.513128) (xy 245.212597 -274.474419)
			(xy 245.257955 -274.441968) (xy 245.307555 -274.416467) (xy 245.360339 -274.39846) (xy 245.415182 -274.38833)
			(xy 245.470916 -274.386293) (xy 245.526353 -274.392393) (xy 245.58031 -274.406499) (xy 245.631639 -274.428311)
			(xy 245.679245 -274.457365) (xy 245.722113 -274.49304) (xy 245.75933 -274.534577) (xy 245.790103 -274.58109)
			(xy 245.813775 -274.631587) (xy 245.829843 -274.684994) (xy 245.837963 -274.74017) (xy 245.838472 -274.768056)
			(xy 245.837963 -274.795942) (xy 245.829843 -274.851118) (xy 245.813775 -274.904525) (xy 245.790103 -274.955022)
			(xy 245.75933 -275.001535) (xy 245.722113 -275.043072) (xy 245.679245 -275.078747) (xy 245.631639 -275.107801)
			(xy 245.58031 -275.129613) (xy 245.526353 -275.143719) (xy 245.470916 -275.149819) (xy 245.415182 -275.147782)
			(xy 245.360339 -275.137652) (xy 245.307555 -275.119645) (xy 245.257955 -275.094144) (xy 245.212597 -275.061693)
			(xy 245.172448 -275.022984) (xy 245.138362 -274.978841) (xy 245.111066 -274.930206) (xy 245.091143 -274.878115)
			(xy 245.079017 -274.823678) (xy 245.074946 -274.768056) (xy 243.684312 -274.768056) (xy 243.683985 -274.769143)
			(xy 243.660313 -274.81964) (xy 243.62954 -274.866153) (xy 243.592323 -274.90769) (xy 243.549455 -274.943365)
			(xy 243.501849 -274.972419) (xy 243.45052 -274.994231) (xy 243.396563 -275.008337) (xy 243.341126 -275.014437)
			(xy 243.285392 -275.0124) (xy 243.230549 -275.00227) (xy 243.177765 -274.984263) (xy 243.128165 -274.958762)
			(xy 243.082807 -274.926311) (xy 243.042658 -274.887602) (xy 243.008572 -274.843459) (xy 242.981276 -274.794824)
			(xy 242.961353 -274.742733) (xy 242.949227 -274.688296) (xy 242.945156 -274.632674) (xy 234.763564 -274.632674)
			(xy 234.763564 -275.532452) (xy 239.418342 -275.532452) (xy 239.418342 -275.477948) (xy 239.426098 -275.423998)
			(xy 239.441453 -275.3717) (xy 239.464094 -275.322121) (xy 239.49356 -275.276268) (xy 239.529252 -275.235074)
			(xy 239.570442 -275.199379) (xy 239.616293 -275.169909) (xy 239.66587 -275.147264) (xy 239.718166 -275.131905)
			(xy 239.772116 -275.124144) (xy 239.799368 -275.123656) (xy 239.826738 -275.124127) (xy 239.880918 -275.131942)
			(xy 239.933421 -275.147429) (xy 239.983168 -275.17027) (xy 240.029135 -275.199994) (xy 240.050066 -275.217636)
			(xy 240.057178 -275.223732) (xy 240.074196 -275.230082) (xy 240.15954 -275.230082) (xy 240.176558 -275.223732)
			(xy 240.18367 -275.217636) (xy 240.204607 -275.200003) (xy 240.250578 -275.170289) (xy 240.300324 -275.147451)
			(xy 240.352824 -275.131959) (xy 240.406999 -275.12413) (xy 240.434368 -275.123656) (xy 240.46162 -275.124189)
			(xy 240.515569 -275.131942) (xy 240.567866 -275.147293) (xy 240.617445 -275.169932) (xy 240.663298 -275.199396)
			(xy 240.669692 -275.204936) (xy 246.570752 -275.204936) (xy 246.574823 -275.149314) (xy 246.586949 -275.094877)
			(xy 246.606872 -275.042786) (xy 246.634168 -274.994151) (xy 246.668254 -274.950008) (xy 246.708403 -274.911299)
			(xy 246.753761 -274.878848) (xy 246.803361 -274.853347) (xy 246.856145 -274.83534) (xy 246.910988 -274.82521)
			(xy 246.966722 -274.823173) (xy 247.022159 -274.829273) (xy 247.076116 -274.843379) (xy 247.127445 -274.865191)
			(xy 247.175051 -274.894245) (xy 247.217919 -274.92992) (xy 247.255136 -274.971457) (xy 247.285909 -275.01797)
			(xy 247.309581 -275.068467) (xy 247.325649 -275.121874) (xy 247.333769 -275.17705) (xy 247.334278 -275.204936)
			(xy 247.333769 -275.232822) (xy 247.325649 -275.287998) (xy 247.309581 -275.341405) (xy 247.285909 -275.391902)
			(xy 247.255136 -275.438415) (xy 247.217919 -275.479952) (xy 247.175051 -275.515627) (xy 247.127445 -275.544681)
			(xy 247.076116 -275.566493) (xy 247.022159 -275.580599) (xy 246.966722 -275.586699) (xy 246.910988 -275.584662)
			(xy 246.856145 -275.574532) (xy 246.803361 -275.556525) (xy 246.753761 -275.531024) (xy 246.708403 -275.498573)
			(xy 246.668254 -275.459864) (xy 246.634168 -275.415721) (xy 246.606872 -275.367086) (xy 246.586949 -275.314995)
			(xy 246.574823 -275.260558) (xy 246.570752 -275.204936) (xy 240.669692 -275.204936) (xy 240.704491 -275.235087)
			(xy 240.740184 -275.276276) (xy 240.769653 -275.322127) (xy 240.792295 -275.371704) (xy 240.807652 -275.424)
			(xy 240.815409 -275.477948) (xy 240.815409 -275.532452) (xy 240.807652 -275.5864) (xy 240.792295 -275.638696)
			(xy 240.769653 -275.688273) (xy 240.740184 -275.734124) (xy 240.704491 -275.775313) (xy 240.663298 -275.811004)
			(xy 240.617445 -275.840468) (xy 240.567866 -275.863107) (xy 240.515569 -275.878458) (xy 240.46162 -275.886211)
			(xy 240.434368 -275.886672) (xy 240.406997 -275.886232) (xy 240.352816 -275.878409) (xy 240.300313 -275.862914)
			(xy 240.250566 -275.840066) (xy 240.204601 -275.810336) (xy 240.18367 -275.792692) (xy 240.176558 -275.786596)
			(xy 240.15954 -275.780246) (xy 240.074196 -275.780246) (xy 240.057178 -275.786596) (xy 240.050066 -275.792692)
			(xy 240.029119 -275.810312) (xy 239.98315 -275.840027) (xy 239.933407 -275.862867) (xy 239.880909 -275.878362)
			(xy 239.826736 -275.886195) (xy 239.799368 -275.886672) (xy 239.772116 -275.886256) (xy 239.718166 -275.878495)
			(xy 239.66587 -275.863136) (xy 239.616293 -275.840491) (xy 239.570442 -275.811021) (xy 239.529252 -275.775326)
			(xy 239.49356 -275.734132) (xy 239.464094 -275.688279) (xy 239.441453 -275.638699) (xy 239.426098 -275.586402)
			(xy 239.418342 -275.532452) (xy 234.763564 -275.532452) (xy 234.763564 -277.217886) (xy 236.252004 -277.217886)
			(xy 236.252461 -277.190515) (xy 236.260281 -277.136336) (xy 236.275772 -277.083833) (xy 236.298616 -277.034086)
			(xy 236.328342 -276.988119) (xy 236.345984 -276.967188) (xy 236.35208 -276.960076) (xy 236.35843 -276.943058)
			(xy 236.35843 -276.857714) (xy 236.35208 -276.840696) (xy 236.345984 -276.833584) (xy 236.328368 -276.812633)
			(xy 236.298654 -276.766665) (xy 236.275813 -276.716922) (xy 236.260317 -276.664426) (xy 236.252482 -276.610254)
			(xy 236.252004 -276.582886) (xy 236.252465 -276.555634) (xy 236.260224 -276.501685) (xy 236.275581 -276.449389)
			(xy 236.298225 -276.399811) (xy 236.327694 -276.35396) (xy 236.363388 -276.312769) (xy 236.404581 -276.277078)
			(xy 236.450433 -276.247612) (xy 236.500013 -276.224972) (xy 236.55231 -276.209618) (xy 236.60626 -276.201863)
			(xy 236.633512 -276.201378) (xy 236.662251 -276.2019) (xy 236.719078 -276.210524) (xy 236.773969 -276.227575)
			(xy 236.82568 -276.252667) (xy 236.873043 -276.285231) (xy 236.89437 -276.304502) (xy 236.901482 -276.311106)
			(xy 236.919008 -276.318218) (xy 237.008416 -276.318218) (xy 237.025942 -276.311106) (xy 237.033054 -276.304502)
			(xy 237.054381 -276.285232) (xy 237.101744 -276.252667) (xy 237.153455 -276.227576) (xy 237.208346 -276.210526)
			(xy 237.265173 -276.201904) (xy 237.322651 -276.201904) (xy 237.379478 -276.210526) (xy 237.434369 -276.227576)
			(xy 237.48608 -276.252667) (xy 237.533443 -276.285232) (xy 237.55477 -276.304502) (xy 237.561882 -276.311106)
			(xy 237.579408 -276.318218) (xy 237.668816 -276.318218) (xy 237.686342 -276.311106) (xy 237.693454 -276.304502)
			(xy 237.714781 -276.285232) (xy 237.762144 -276.252667) (xy 237.813855 -276.227576) (xy 237.868746 -276.210526)
			(xy 237.925573 -276.201904) (xy 237.983051 -276.201904) (xy 238.039878 -276.210526) (xy 238.094769 -276.227576)
			(xy 238.14648 -276.252667) (xy 238.193843 -276.285232) (xy 238.21517 -276.304502) (xy 238.222282 -276.311106)
			(xy 238.239808 -276.318218) (xy 238.329216 -276.318218) (xy 238.346742 -276.311106) (xy 238.353854 -276.304502)
			(xy 238.375186 -276.285237) (xy 238.422545 -276.252667) (xy 238.474256 -276.227573) (xy 238.529146 -276.210521)
			(xy 238.585973 -276.201899) (xy 238.614712 -276.201378) (xy 238.641963 -276.201867) (xy 238.69591 -276.209624)
			(xy 238.748204 -276.22498) (xy 238.79778 -276.247622) (xy 238.84363 -276.277088) (xy 238.884819 -276.312779)
			(xy 238.920511 -276.353969) (xy 238.930183 -276.369018) (xy 241.385088 -276.369018) (xy 241.389159 -276.313396)
			(xy 241.401285 -276.258959) (xy 241.421208 -276.206868) (xy 241.448504 -276.158233) (xy 241.48259 -276.11409)
			(xy 241.522739 -276.075381) (xy 241.568097 -276.04293) (xy 241.617697 -276.017429) (xy 241.670481 -275.999422)
			(xy 241.725324 -275.989292) (xy 241.781058 -275.987255) (xy 241.836495 -275.993355) (xy 241.890452 -276.007461)
			(xy 241.941781 -276.029273) (xy 241.989387 -276.058327) (xy 242.032255 -276.094002) (xy 242.069472 -276.135539)
			(xy 242.100245 -276.182052) (xy 242.123917 -276.232549) (xy 242.139985 -276.285956) (xy 242.148105 -276.341132)
			(xy 242.148614 -276.369018) (xy 242.148105 -276.396904) (xy 242.139985 -276.45208) (xy 242.123917 -276.505487)
			(xy 242.117401 -276.519386) (xy 246.703086 -276.519386) (xy 246.707157 -276.463764) (xy 246.719283 -276.409327)
			(xy 246.739206 -276.357236) (xy 246.766502 -276.308601) (xy 246.800588 -276.264458) (xy 246.840737 -276.225749)
			(xy 246.886095 -276.193298) (xy 246.935695 -276.167797) (xy 246.988479 -276.14979) (xy 247.043322 -276.13966)
			(xy 247.099056 -276.137623) (xy 247.154493 -276.143723) (xy 247.20845 -276.157829) (xy 247.259779 -276.179641)
			(xy 247.307385 -276.208695) (xy 247.350253 -276.24437) (xy 247.38747 -276.285907) (xy 247.418243 -276.33242)
			(xy 247.441915 -276.382917) (xy 247.457983 -276.436324) (xy 247.466103 -276.4915) (xy 247.466612 -276.519386)
			(xy 247.466103 -276.547272) (xy 247.457983 -276.602448) (xy 247.441915 -276.655855) (xy 247.418243 -276.706352)
			(xy 247.38747 -276.752865) (xy 247.350253 -276.794402) (xy 247.307385 -276.830077) (xy 247.259779 -276.859131)
			(xy 247.20845 -276.880943) (xy 247.154493 -276.895049) (xy 247.099056 -276.901149) (xy 247.043322 -276.899112)
			(xy 246.988479 -276.888982) (xy 246.935695 -276.870975) (xy 246.886095 -276.845474) (xy 246.840737 -276.813023)
			(xy 246.800588 -276.774314) (xy 246.766502 -276.730171) (xy 246.739206 -276.681536) (xy 246.719283 -276.629445)
			(xy 246.707157 -276.575008) (xy 246.703086 -276.519386) (xy 242.117401 -276.519386) (xy 242.100245 -276.555984)
			(xy 242.069472 -276.602497) (xy 242.032255 -276.644034) (xy 241.989387 -276.679709) (xy 241.941781 -276.708763)
			(xy 241.890452 -276.730575) (xy 241.836495 -276.744681) (xy 241.781058 -276.750781) (xy 241.725324 -276.748744)
			(xy 241.670481 -276.738614) (xy 241.617697 -276.720607) (xy 241.568097 -276.695106) (xy 241.522739 -276.662655)
			(xy 241.48259 -276.623946) (xy 241.448504 -276.579803) (xy 241.421208 -276.531168) (xy 241.401285 -276.479077)
			(xy 241.389159 -276.42464) (xy 241.385088 -276.369018) (xy 238.930183 -276.369018) (xy 238.949977 -276.399818)
			(xy 238.972619 -276.449394) (xy 238.987975 -276.501688) (xy 238.995733 -276.555635) (xy 238.99622 -276.582886)
			(xy 238.995765 -276.610257) (xy 238.987948 -276.664437) (xy 238.972457 -276.716941) (xy 238.949612 -276.766688)
			(xy 238.919884 -276.812654) (xy 238.90224 -276.833584) (xy 238.896144 -276.840696) (xy 238.889794 -276.857714)
			(xy 238.889794 -276.943058) (xy 238.896144 -276.960076) (xy 238.90224 -276.967188) (xy 238.919894 -276.988108)
			(xy 238.949602 -277.034085) (xy 238.972435 -277.083836) (xy 238.987922 -277.136339) (xy 238.995748 -277.190516)
			(xy 238.99622 -277.217886) (xy 238.995732 -277.245138) (xy 238.987977 -277.299087) (xy 238.972623 -277.351384)
			(xy 238.949983 -277.400963) (xy 238.920518 -277.446816) (xy 238.884827 -277.488008) (xy 238.843637 -277.523702)
			(xy 238.797786 -277.553171) (xy 238.748208 -277.575814) (xy 238.695913 -277.591171) (xy 238.641964 -277.59893)
			(xy 238.614712 -277.599394) (xy 238.585973 -277.598865) (xy 238.529146 -277.590244) (xy 238.474255 -277.573195)
			(xy 238.422543 -277.548105) (xy 238.375181 -277.51554) (xy 238.353854 -277.49627) (xy 238.346742 -277.489666)
			(xy 238.329216 -277.482554) (xy 238.239808 -277.482554) (xy 238.222282 -277.489666) (xy 238.21517 -277.49627)
			(xy 238.193843 -277.51554) (xy 238.14648 -277.548105) (xy 238.094769 -277.573196) (xy 238.039878 -277.590246)
			(xy 237.983051 -277.598868) (xy 237.925573 -277.598868) (xy 237.868746 -277.590246) (xy 237.813855 -277.573196)
			(xy 237.762144 -277.548105) (xy 237.714781 -277.51554) (xy 237.693454 -277.49627) (xy 237.686342 -277.489666)
			(xy 237.668816 -277.482554) (xy 237.579408 -277.482554) (xy 237.561882 -277.489666) (xy 237.55477 -277.49627)
			(xy 237.533443 -277.51554) (xy 237.48608 -277.548105) (xy 237.434369 -277.573196) (xy 237.379478 -277.590246)
			(xy 237.322651 -277.598868) (xy 237.265173 -277.598868) (xy 237.208346 -277.590246) (xy 237.153455 -277.573196)
			(xy 237.101744 -277.548105) (xy 237.054381 -277.51554) (xy 237.033054 -277.49627) (xy 237.025942 -277.489666)
			(xy 237.008416 -277.482554) (xy 236.919008 -277.482554) (xy 236.901482 -277.489666) (xy 236.89437 -277.49627)
			(xy 236.873039 -277.515536) (xy 236.825678 -277.548103) (xy 236.773967 -277.573196) (xy 236.719077 -277.590248)
			(xy 236.662251 -277.598872) (xy 236.633512 -277.599394) (xy 236.606259 -277.598933) (xy 236.552307 -277.591178)
			(xy 236.500008 -277.575823) (xy 236.450427 -277.55318) (xy 236.404573 -277.523712) (xy 236.36338 -277.488018)
			(xy 236.327686 -277.446825) (xy 236.298219 -277.400971) (xy 236.275577 -277.35139) (xy 236.260222 -277.299091)
			(xy 236.252466 -277.245139) (xy 236.252004 -277.217886) (xy 234.763564 -277.217886) (xy 234.763564 -278.551386)
			(xy 246.703596 -278.551386) (xy 246.70414 -278.52247) (xy 246.712858 -278.465298) (xy 246.730109 -278.410098)
			(xy 246.755496 -278.358135) (xy 246.788437 -278.310601) (xy 246.828177 -278.268585) (xy 246.850662 -278.250396)
			(xy 246.859432 -278.242842) (xy 246.869608 -278.222077) (xy 246.87022 -278.210518) (xy 246.87022 -278.130254)
			(xy 246.869612 -278.118691) (xy 246.859443 -278.09792) (xy 246.850662 -278.090376) (xy 246.828159 -278.072208)
			(xy 246.788427 -278.030182) (xy 246.755491 -277.982642) (xy 246.730107 -277.930677) (xy 246.712854 -277.875476)
			(xy 246.704129 -277.818303) (xy 246.703596 -277.789386) (xy 246.704082 -277.762135) (xy 246.711838 -277.708187)
			(xy 246.727193 -277.655892) (xy 246.749835 -277.606315) (xy 246.779301 -277.560465) (xy 246.814992 -277.519274)
			(xy 246.856183 -277.483583) (xy 246.902033 -277.454117) (xy 246.95161 -277.431475) (xy 247.003905 -277.41612)
			(xy 247.057853 -277.408364) (xy 247.112355 -277.408364) (xy 247.166303 -277.41612) (xy 247.218598 -277.431475)
			(xy 247.268175 -277.454117) (xy 247.314025 -277.483583) (xy 247.355216 -277.519274) (xy 247.390907 -277.560465)
			(xy 247.420373 -277.606315) (xy 247.443015 -277.655892) (xy 247.45837 -277.708187) (xy 247.466126 -277.762135)
			(xy 247.466612 -277.789386) (xy 247.466117 -277.818304) (xy 247.457388 -277.875478) (xy 247.440128 -277.930679)
			(xy 247.414732 -277.982641) (xy 247.381782 -278.030174) (xy 247.342035 -278.072188) (xy 247.319546 -278.090376)
			(xy 247.31079 -278.097943) (xy 247.300606 -278.118698) (xy 247.299988 -278.130254) (xy 247.299988 -278.210518)
			(xy 247.300553 -278.222086) (xy 247.310752 -278.242857) (xy 247.319546 -278.250396) (xy 247.342037 -278.268578)
			(xy 247.38177 -278.310601) (xy 247.414707 -278.358138) (xy 247.440093 -278.410101) (xy 247.457348 -278.465299)
			(xy 247.466077 -278.52247) (xy 247.466612 -278.551386) (xy 247.466126 -278.578637) (xy 247.45837 -278.632585)
			(xy 247.443015 -278.68488) (xy 247.420373 -278.734457) (xy 247.390907 -278.780307) (xy 247.355216 -278.821498)
			(xy 247.314025 -278.857189) (xy 247.268175 -278.886655) (xy 247.218598 -278.909297) (xy 247.166303 -278.924652)
			(xy 247.112355 -278.932408) (xy 247.057853 -278.932408) (xy 247.003905 -278.924652) (xy 246.95161 -278.909297)
			(xy 246.902033 -278.886655) (xy 246.856183 -278.857189) (xy 246.814992 -278.821498) (xy 246.779301 -278.780307)
			(xy 246.749835 -278.734457) (xy 246.727193 -278.68488) (xy 246.711838 -278.632585) (xy 246.704082 -278.578637)
			(xy 246.703596 -278.551386) (xy 234.763564 -278.551386) (xy 234.763564 -279.567386) (xy 246.703086 -279.567386)
			(xy 246.707157 -279.511764) (xy 246.719283 -279.457327) (xy 246.739206 -279.405236) (xy 246.766502 -279.356601)
			(xy 246.800588 -279.312458) (xy 246.840737 -279.273749) (xy 246.886095 -279.241298) (xy 246.935695 -279.215797)
			(xy 246.988479 -279.19779) (xy 247.043322 -279.18766) (xy 247.099056 -279.185623) (xy 247.154493 -279.191723)
			(xy 247.20845 -279.205829) (xy 247.259779 -279.227641) (xy 247.307385 -279.256695) (xy 247.350253 -279.29237)
			(xy 247.38747 -279.333907) (xy 247.418243 -279.38042) (xy 247.441915 -279.430917) (xy 247.457983 -279.484324)
			(xy 247.466103 -279.5395) (xy 247.466612 -279.567386) (xy 247.466103 -279.595272) (xy 247.457983 -279.650448)
			(xy 247.441915 -279.703855) (xy 247.418243 -279.754352) (xy 247.38747 -279.800865) (xy 247.350253 -279.842402)
			(xy 247.307385 -279.878077) (xy 247.259779 -279.907131) (xy 247.20845 -279.928943) (xy 247.154493 -279.943049)
			(xy 247.099056 -279.949149) (xy 247.043322 -279.947112) (xy 246.988479 -279.936982) (xy 246.935695 -279.918975)
			(xy 246.886095 -279.893474) (xy 246.840737 -279.861023) (xy 246.800588 -279.822314) (xy 246.766502 -279.778171)
			(xy 246.739206 -279.729536) (xy 246.719283 -279.677445) (xy 246.707157 -279.623008) (xy 246.703086 -279.567386)
			(xy 234.763564 -279.567386) (xy 234.763564 -280.10104) (xy 242.653564 -280.10104) (xy 242.657635 -280.045418)
			(xy 242.669761 -279.990981) (xy 242.689684 -279.93889) (xy 242.71698 -279.890255) (xy 242.751066 -279.846112)
			(xy 242.791215 -279.807403) (xy 242.836573 -279.774952) (xy 242.886173 -279.749451) (xy 242.938957 -279.731444)
			(xy 242.9938 -279.721314) (xy 243.049534 -279.719277) (xy 243.104971 -279.725377) (xy 243.158928 -279.739483)
			(xy 243.210257 -279.761295) (xy 243.257863 -279.790349) (xy 243.300731 -279.826024) (xy 243.337948 -279.867561)
			(xy 243.368721 -279.914074) (xy 243.392393 -279.964571) (xy 243.408461 -280.017978) (xy 243.416581 -280.073154)
			(xy 243.41709 -280.10104) (xy 243.416581 -280.128926) (xy 243.408461 -280.184102) (xy 243.392393 -280.237509)
			(xy 243.368721 -280.288006) (xy 243.337948 -280.334519) (xy 243.300731 -280.376056) (xy 243.257863 -280.411731)
			(xy 243.210257 -280.440785) (xy 243.158928 -280.462597) (xy 243.104971 -280.476703) (xy 243.049534 -280.482803)
			(xy 242.9938 -280.480766) (xy 242.938957 -280.470636) (xy 242.886173 -280.452629) (xy 242.836573 -280.427128)
			(xy 242.791215 -280.394677) (xy 242.751066 -280.355968) (xy 242.71698 -280.311825) (xy 242.689684 -280.26319)
			(xy 242.669761 -280.211099) (xy 242.657635 -280.156662) (xy 242.653564 -280.10104) (xy 234.763564 -280.10104)
			(xy 234.763564 -280.500582) (xy 245.065802 -280.500582) (xy 245.069873 -280.44496) (xy 245.081999 -280.390523)
			(xy 245.101922 -280.338432) (xy 245.129218 -280.289797) (xy 245.163304 -280.245654) (xy 245.203453 -280.206945)
			(xy 245.248811 -280.174494) (xy 245.298411 -280.148993) (xy 245.351195 -280.130986) (xy 245.406038 -280.120856)
			(xy 245.461772 -280.118819) (xy 245.517209 -280.124919) (xy 245.571166 -280.139025) (xy 245.622495 -280.160837)
			(xy 245.670101 -280.189891) (xy 245.712969 -280.225566) (xy 245.750186 -280.267103) (xy 245.780959 -280.313616)
			(xy 245.804631 -280.364113) (xy 245.820699 -280.41752) (xy 245.828819 -280.472696) (xy 245.829328 -280.500582)
			(xy 245.828819 -280.528468) (xy 245.820699 -280.583644) (xy 245.804631 -280.637051) (xy 245.780959 -280.687548)
			(xy 245.750186 -280.734061) (xy 245.712969 -280.775598) (xy 245.670101 -280.811273) (xy 245.622495 -280.840327)
			(xy 245.571166 -280.862139) (xy 245.517209 -280.876245) (xy 245.461772 -280.882345) (xy 245.406038 -280.880308)
			(xy 245.351195 -280.870178) (xy 245.298411 -280.852171) (xy 245.248811 -280.82667) (xy 245.203453 -280.794219)
			(xy 245.163304 -280.75551) (xy 245.129218 -280.711367) (xy 245.101922 -280.662732) (xy 245.081999 -280.610641)
			(xy 245.069873 -280.556204) (xy 245.065802 -280.500582) (xy 234.763564 -280.500582) (xy 234.763564 -283.009456)
			(xy 241.001717 -283.009456) (xy 241.001717 -282.954944) (xy 241.009475 -282.900988) (xy 241.024833 -282.848684)
			(xy 241.047478 -282.799099) (xy 241.076949 -282.753241) (xy 241.112647 -282.712044) (xy 241.153844 -282.676347)
			(xy 241.199702 -282.646876) (xy 241.249288 -282.624231) (xy 241.301591 -282.608874) (xy 241.355548 -282.601117)
			(xy 241.382804 -282.600654) (xy 241.411542 -282.601188) (xy 241.468369 -282.60981) (xy 241.523259 -282.626858)
			(xy 241.574971 -282.651947) (xy 241.622334 -282.684509) (xy 241.643662 -282.703778) (xy 241.650774 -282.710382)
			(xy 241.6683 -282.717494) (xy 241.757708 -282.717494) (xy 241.775234 -282.710382) (xy 241.782346 -282.703778)
			(xy 241.803673 -282.684508) (xy 241.851036 -282.651943) (xy 241.902747 -282.626852) (xy 241.957638 -282.609802)
			(xy 242.014465 -282.60118) (xy 242.071943 -282.60118) (xy 242.12877 -282.609802) (xy 242.183661 -282.626852)
			(xy 242.235372 -282.651943) (xy 242.282735 -282.684508) (xy 242.304062 -282.703778) (xy 242.311174 -282.710382)
			(xy 242.3287 -282.717494) (xy 242.418108 -282.717494) (xy 242.435634 -282.710382) (xy 242.442746 -282.703778)
			(xy 242.464077 -282.684512) (xy 242.511437 -282.651944) (xy 242.563148 -282.626849) (xy 242.618038 -282.609798)
			(xy 242.674865 -282.601175) (xy 242.703604 -282.600654) (xy 242.733728 -282.601221) (xy 242.793224 -282.610703)
			(xy 242.850492 -282.629414) (xy 242.904109 -282.656891) (xy 242.952743 -282.692451) (xy 242.974368 -282.71343)
			(xy 242.98148 -282.720796) (xy 243.000276 -282.728416) (xy 243.092732 -282.728416) (xy 243.111528 -282.720796)
			(xy 243.11864 -282.71343) (xy 243.140273 -282.692459) (xy 243.188899 -282.656888) (xy 243.242513 -282.629406)
			(xy 243.299782 -282.610696) (xy 243.35928 -282.601223) (xy 243.389404 -282.600654) (xy 243.416652 -282.601216)
			(xy 243.470594 -282.608973) (xy 243.522883 -282.624327) (xy 243.572455 -282.646966) (xy 243.6183 -282.676429)
			(xy 243.659486 -282.712117) (xy 243.695173 -282.753303) (xy 243.724636 -282.799149) (xy 243.747275 -282.848721)
			(xy 243.762628 -282.90101) (xy 243.770384 -282.954952) (xy 243.770384 -283.009448) (xy 243.762628 -283.06339)
			(xy 243.747275 -283.115679) (xy 243.724636 -283.165251) (xy 243.695173 -283.211097) (xy 243.659486 -283.252283)
			(xy 243.6183 -283.287971) (xy 243.572455 -283.317434) (xy 243.522883 -283.340073) (xy 243.470594 -283.355427)
			(xy 243.416652 -283.363184) (xy 243.389404 -283.36367) (xy 243.359281 -283.363091) (xy 243.299785 -283.353611)
			(xy 243.242518 -283.334902) (xy 243.1889 -283.307428) (xy 243.140265 -283.271872) (xy 243.11864 -283.250894)
			(xy 243.111528 -283.243528) (xy 243.092732 -283.235908) (xy 243.000276 -283.235908) (xy 242.98148 -283.243528)
			(xy 242.974368 -283.250894) (xy 242.952735 -283.271866) (xy 242.904109 -283.307435) (xy 242.850494 -283.334917)
			(xy 242.793226 -283.353627) (xy 242.733728 -283.363101) (xy 242.703604 -283.36367) (xy 242.674866 -283.363125)
			(xy 242.618041 -283.354505) (xy 242.563151 -283.337459) (xy 242.511439 -283.312372) (xy 242.464074 -283.279813)
			(xy 242.442746 -283.260546) (xy 242.435634 -283.253942) (xy 242.418108 -283.24683) (xy 242.3287 -283.24683)
			(xy 242.311174 -283.253942) (xy 242.304062 -283.260546) (xy 242.282735 -283.279816) (xy 242.235372 -283.312381)
			(xy 242.183661 -283.337472) (xy 242.12877 -283.354522) (xy 242.071943 -283.363144) (xy 242.014465 -283.363144)
			(xy 241.957638 -283.354522) (xy 241.902747 -283.337472) (xy 241.851036 -283.312381) (xy 241.803673 -283.279816)
			(xy 241.782346 -283.260546) (xy 241.775234 -283.253942) (xy 241.757708 -283.24683) (xy 241.6683 -283.24683)
			(xy 241.650774 -283.253942) (xy 241.643662 -283.260546) (xy 241.622331 -283.279812) (xy 241.57497 -283.31238)
			(xy 241.52326 -283.337473) (xy 241.46837 -283.354525) (xy 241.411543 -283.363149) (xy 241.382804 -283.36367)
			(xy 241.355548 -283.363283) (xy 241.301591 -283.355526) (xy 241.249288 -283.340169) (xy 241.199702 -283.317524)
			(xy 241.153844 -283.288053) (xy 241.112647 -283.252356) (xy 241.076949 -283.211159) (xy 241.047478 -283.165301)
			(xy 241.024833 -283.115716) (xy 241.009475 -283.063412) (xy 241.001717 -283.009456) (xy 234.763564 -283.009456)
			(xy 234.763564 -284.66875) (xy 237.195599 -284.66875) (xy 237.195599 -284.61425) (xy 237.203356 -284.560304)
			(xy 237.218711 -284.508011) (xy 237.241352 -284.458435) (xy 237.270817 -284.412587) (xy 237.306509 -284.371399)
			(xy 237.347698 -284.335709) (xy 237.393548 -284.306245) (xy 237.443124 -284.283606) (xy 237.495417 -284.268253)
			(xy 237.549364 -284.260498) (xy 237.576614 -284.260036) (xy 237.605352 -284.260568) (xy 237.662179 -284.269191)
			(xy 237.717069 -284.28624) (xy 237.76878 -284.31133) (xy 237.816144 -284.343891) (xy 237.837472 -284.36316)
			(xy 237.844584 -284.369764) (xy 237.86211 -284.376876) (xy 237.951518 -284.376876) (xy 237.969044 -284.369764)
			(xy 237.976156 -284.36316) (xy 237.997483 -284.34389) (xy 238.044846 -284.311325) (xy 238.096557 -284.286234)
			(xy 238.151448 -284.269184) (xy 238.208275 -284.260562) (xy 238.265753 -284.260562) (xy 238.32258 -284.269184)
			(xy 238.377471 -284.286234) (xy 238.429182 -284.311325) (xy 238.476545 -284.34389) (xy 238.497872 -284.36316)
			(xy 238.504984 -284.369764) (xy 238.52251 -284.376876) (xy 238.611918 -284.376876) (xy 238.629444 -284.369764)
			(xy 238.636556 -284.36316) (xy 238.657881 -284.343886) (xy 238.705243 -284.31132) (xy 238.756955 -284.286227)
			(xy 238.811847 -284.269177) (xy 238.868675 -284.260556) (xy 238.897414 -284.260036) (xy 238.927538 -284.260602)
			(xy 238.987034 -284.270085) (xy 239.044302 -284.288797) (xy 239.097919 -284.316274) (xy 239.146553 -284.351833)
			(xy 239.168178 -284.372812) (xy 239.17529 -284.380178) (xy 239.194086 -284.387798) (xy 239.286542 -284.387798)
			(xy 239.305338 -284.380178) (xy 239.31245 -284.372812) (xy 239.334076 -284.351833) (xy 239.382704 -284.316264)
			(xy 239.43632 -284.288783) (xy 239.49359 -284.270075) (xy 239.55309 -284.260604) (xy 239.583214 -284.260036)
			(xy 239.610468 -284.260435) (xy 239.66442 -284.268194) (xy 239.716719 -284.283552) (xy 239.7663 -284.306197)
			(xy 239.812154 -284.335667) (xy 239.853348 -284.371362) (xy 239.889042 -284.412557) (xy 239.91851 -284.458412)
			(xy 239.941153 -284.507994) (xy 239.956509 -284.560294) (xy 239.964266 -284.614246) (xy 239.964266 -284.668754)
			(xy 239.956509 -284.722706) (xy 239.941153 -284.775006) (xy 239.91851 -284.824588) (xy 239.889042 -284.870443)
			(xy 239.853348 -284.911638) (xy 239.812154 -284.947333) (xy 239.7663 -284.976803) (xy 239.716719 -284.999448)
			(xy 239.66442 -285.014806) (xy 239.610468 -285.022565) (xy 239.583214 -285.023052) (xy 239.553091 -285.022472)
			(xy 239.493595 -285.012993) (xy 239.436327 -284.994284) (xy 239.38271 -284.966811) (xy 239.334075 -284.931254)
			(xy 239.31245 -284.910276) (xy 239.305338 -284.90291) (xy 239.286542 -284.89529) (xy 239.194086 -284.89529)
			(xy 239.17529 -284.90291) (xy 239.168178 -284.910276) (xy 239.146538 -284.93124) (xy 239.097914 -284.966811)
			(xy 239.044301 -284.994295) (xy 238.987034 -285.013007) (xy 238.927537 -285.022482) (xy 238.897414 -285.023052)
			(xy 238.868676 -285.022506) (xy 238.81185 -285.013887) (xy 238.75696 -284.996841) (xy 238.705248 -284.971755)
			(xy 238.657884 -284.939196) (xy 238.636556 -284.919928) (xy 238.629444 -284.913324) (xy 238.611918 -284.906212)
			(xy 238.52251 -284.906212) (xy 238.504984 -284.913324) (xy 238.497872 -284.919928) (xy 238.476545 -284.939198)
			(xy 238.429182 -284.971763) (xy 238.377471 -284.996854) (xy 238.32258 -285.013904) (xy 238.265753 -285.022526)
			(xy 238.208275 -285.022526) (xy 238.151448 -285.013904) (xy 238.096557 -284.996854) (xy 238.044846 -284.971763)
			(xy 237.997483 -284.939198) (xy 237.976156 -284.919928) (xy 237.969044 -284.913324) (xy 237.951518 -284.906212)
			(xy 237.86211 -284.906212) (xy 237.844584 -284.913324) (xy 237.837472 -284.919928) (xy 237.816134 -284.939186)
			(xy 237.768776 -284.971756) (xy 237.717067 -284.996851) (xy 237.662178 -285.013905) (xy 237.605352 -285.02253)
			(xy 237.576614 -285.023052) (xy 237.549364 -285.022502) (xy 237.495417 -285.014747) (xy 237.443124 -284.999394)
			(xy 237.393548 -284.976755) (xy 237.347698 -284.947291) (xy 237.306509 -284.911601) (xy 237.270817 -284.870413)
			(xy 237.241352 -284.824565) (xy 237.218711 -284.774989) (xy 237.203356 -284.722696) (xy 237.195599 -284.66875)
			(xy 234.763564 -284.66875) (xy 234.763564 -285.473256) (xy 241.001717 -285.473256) (xy 241.001717 -285.418744)
			(xy 241.009475 -285.364788) (xy 241.024833 -285.312484) (xy 241.047478 -285.262899) (xy 241.076949 -285.217041)
			(xy 241.112647 -285.175844) (xy 241.153844 -285.140147) (xy 241.199702 -285.110676) (xy 241.249288 -285.088031)
			(xy 241.301591 -285.072674) (xy 241.355548 -285.064917) (xy 241.382804 -285.064454) (xy 241.411542 -285.064988)
			(xy 241.468369 -285.07361) (xy 241.523259 -285.090658) (xy 241.574971 -285.115747) (xy 241.622334 -285.148309)
			(xy 241.643662 -285.167578) (xy 241.650774 -285.174182) (xy 241.6683 -285.181294) (xy 241.757708 -285.181294)
			(xy 241.775234 -285.174182) (xy 241.782346 -285.167578) (xy 241.803673 -285.148308) (xy 241.851036 -285.115743)
			(xy 241.902747 -285.090652) (xy 241.957638 -285.073602) (xy 242.014465 -285.06498) (xy 242.071943 -285.06498)
			(xy 242.12877 -285.073602) (xy 242.183661 -285.090652) (xy 242.235372 -285.115743) (xy 242.282735 -285.148308)
			(xy 242.304062 -285.167578) (xy 242.311174 -285.174182) (xy 242.3287 -285.181294) (xy 242.418108 -285.181294)
			(xy 242.435634 -285.174182) (xy 242.442746 -285.167578) (xy 242.464077 -285.148312) (xy 242.511437 -285.115744)
			(xy 242.563148 -285.090649) (xy 242.618038 -285.073598) (xy 242.674865 -285.064975) (xy 242.703604 -285.064454)
			(xy 242.733728 -285.065021) (xy 242.793224 -285.074503) (xy 242.850492 -285.093214) (xy 242.904109 -285.120691)
			(xy 242.952743 -285.156251) (xy 242.974368 -285.17723) (xy 242.98148 -285.184596) (xy 243.000276 -285.192216)
			(xy 243.092732 -285.192216) (xy 243.111528 -285.184596) (xy 243.11864 -285.17723) (xy 243.140273 -285.156259)
			(xy 243.188899 -285.120688) (xy 243.242513 -285.093206) (xy 243.299782 -285.074496) (xy 243.35928 -285.065023)
			(xy 243.389404 -285.064454) (xy 243.416652 -285.065016) (xy 243.470594 -285.072773) (xy 243.522883 -285.088127)
			(xy 243.572455 -285.110766) (xy 243.6183 -285.140229) (xy 243.659486 -285.175917) (xy 243.695173 -285.217103)
			(xy 243.724636 -285.262949) (xy 243.747275 -285.312521) (xy 243.762628 -285.36481) (xy 243.770384 -285.418752)
			(xy 243.770384 -285.473248) (xy 243.762628 -285.52719) (xy 243.747275 -285.579479) (xy 243.724636 -285.629051)
			(xy 243.695173 -285.674897) (xy 243.659486 -285.716083) (xy 243.6183 -285.751771) (xy 243.572455 -285.781234)
			(xy 243.522883 -285.803873) (xy 243.470594 -285.819227) (xy 243.416652 -285.826984) (xy 243.389404 -285.82747)
			(xy 243.359281 -285.826891) (xy 243.299785 -285.817411) (xy 243.242518 -285.798702) (xy 243.1889 -285.771228)
			(xy 243.140265 -285.735672) (xy 243.11864 -285.714694) (xy 243.111528 -285.707328) (xy 243.092732 -285.699708)
			(xy 243.000276 -285.699708) (xy 242.98148 -285.707328) (xy 242.974368 -285.714694) (xy 242.952735 -285.735666)
			(xy 242.904109 -285.771235) (xy 242.850494 -285.798717) (xy 242.793226 -285.817427) (xy 242.733728 -285.826901)
			(xy 242.703604 -285.82747) (xy 242.674866 -285.826925) (xy 242.618041 -285.818305) (xy 242.563151 -285.801259)
			(xy 242.511439 -285.776172) (xy 242.464074 -285.743613) (xy 242.442746 -285.724346) (xy 242.435634 -285.717742)
			(xy 242.418108 -285.71063) (xy 242.3287 -285.71063) (xy 242.311174 -285.717742) (xy 242.304062 -285.724346)
			(xy 242.282735 -285.743616) (xy 242.235372 -285.776181) (xy 242.183661 -285.801272) (xy 242.12877 -285.818322)
			(xy 242.071943 -285.826944) (xy 242.014465 -285.826944) (xy 241.957638 -285.818322) (xy 241.902747 -285.801272)
			(xy 241.851036 -285.776181) (xy 241.803673 -285.743616) (xy 241.782346 -285.724346) (xy 241.775234 -285.717742)
			(xy 241.757708 -285.71063) (xy 241.6683 -285.71063) (xy 241.650774 -285.717742) (xy 241.643662 -285.724346)
			(xy 241.622331 -285.743612) (xy 241.57497 -285.77618) (xy 241.52326 -285.801273) (xy 241.46837 -285.818325)
			(xy 241.411543 -285.826949) (xy 241.382804 -285.82747) (xy 241.355548 -285.827083) (xy 241.301591 -285.819326)
			(xy 241.249288 -285.803969) (xy 241.199702 -285.781324) (xy 241.153844 -285.751853) (xy 241.112647 -285.716156)
			(xy 241.076949 -285.674959) (xy 241.047478 -285.629101) (xy 241.024833 -285.579516) (xy 241.009475 -285.527212)
			(xy 241.001717 -285.473256) (xy 234.763564 -285.473256) (xy 234.763564 -287.13255) (xy 237.195599 -287.13255)
			(xy 237.195599 -287.07805) (xy 237.203356 -287.024104) (xy 237.218711 -286.971811) (xy 237.241352 -286.922235)
			(xy 237.270817 -286.876387) (xy 237.306509 -286.835199) (xy 237.347698 -286.799509) (xy 237.393548 -286.770045)
			(xy 237.443124 -286.747406) (xy 237.495417 -286.732053) (xy 237.549364 -286.724298) (xy 237.576614 -286.723836)
			(xy 237.605352 -286.724368) (xy 237.662179 -286.732991) (xy 237.717069 -286.75004) (xy 237.76878 -286.77513)
			(xy 237.816144 -286.807691) (xy 237.837472 -286.82696) (xy 237.844584 -286.833564) (xy 237.86211 -286.840676)
			(xy 237.951518 -286.840676) (xy 237.969044 -286.833564) (xy 237.976156 -286.82696) (xy 237.997483 -286.80769)
			(xy 238.044846 -286.775125) (xy 238.096557 -286.750034) (xy 238.151448 -286.732984) (xy 238.208275 -286.724362)
			(xy 238.265753 -286.724362) (xy 238.32258 -286.732984) (xy 238.377471 -286.750034) (xy 238.429182 -286.775125)
			(xy 238.476545 -286.80769) (xy 238.497872 -286.82696) (xy 238.504984 -286.833564) (xy 238.52251 -286.840676)
			(xy 238.611918 -286.840676) (xy 238.629444 -286.833564) (xy 238.636556 -286.82696) (xy 238.657881 -286.807686)
			(xy 238.705243 -286.77512) (xy 238.756955 -286.750027) (xy 238.811847 -286.732977) (xy 238.868675 -286.724356)
			(xy 238.897414 -286.723836) (xy 238.927538 -286.724402) (xy 238.987034 -286.733885) (xy 239.044302 -286.752597)
			(xy 239.097919 -286.780074) (xy 239.146553 -286.815633) (xy 239.168178 -286.836612) (xy 239.17529 -286.843978)
			(xy 239.194086 -286.851598) (xy 239.286542 -286.851598) (xy 239.305338 -286.843978) (xy 239.31245 -286.836612)
			(xy 239.334076 -286.815633) (xy 239.382704 -286.780064) (xy 239.43632 -286.752583) (xy 239.49359 -286.733875)
			(xy 239.55309 -286.724404) (xy 239.583214 -286.723836) (xy 239.610468 -286.724235) (xy 239.66442 -286.731994)
			(xy 239.716719 -286.747352) (xy 239.7663 -286.769997) (xy 239.812154 -286.799467) (xy 239.853348 -286.835162)
			(xy 239.889042 -286.876357) (xy 239.91851 -286.922212) (xy 239.941153 -286.971794) (xy 239.956509 -287.024094)
			(xy 239.964266 -287.078046) (xy 239.964266 -287.132554) (xy 239.956509 -287.186506) (xy 239.941153 -287.238806)
			(xy 239.91851 -287.288388) (xy 239.889042 -287.334243) (xy 239.853348 -287.375438) (xy 239.812154 -287.411133)
			(xy 239.7663 -287.440603) (xy 239.716719 -287.463248) (xy 239.66442 -287.478606) (xy 239.610468 -287.486365)
			(xy 239.583214 -287.486852) (xy 239.553091 -287.486272) (xy 239.493595 -287.476793) (xy 239.436327 -287.458084)
			(xy 239.38271 -287.430611) (xy 239.334075 -287.395054) (xy 239.31245 -287.374076) (xy 239.305338 -287.36671)
			(xy 239.286542 -287.35909) (xy 239.194086 -287.35909) (xy 239.17529 -287.36671) (xy 239.168178 -287.374076)
			(xy 239.146538 -287.39504) (xy 239.097914 -287.430611) (xy 239.044301 -287.458095) (xy 238.987034 -287.476807)
			(xy 238.927537 -287.486282) (xy 238.897414 -287.486852) (xy 238.868676 -287.486306) (xy 238.81185 -287.477687)
			(xy 238.75696 -287.460641) (xy 238.705248 -287.435555) (xy 238.657884 -287.402996) (xy 238.636556 -287.383728)
			(xy 238.629444 -287.377124) (xy 238.611918 -287.370012) (xy 238.52251 -287.370012) (xy 238.504984 -287.377124)
			(xy 238.497872 -287.383728) (xy 238.476545 -287.402998) (xy 238.429182 -287.435563) (xy 238.377471 -287.460654)
			(xy 238.32258 -287.477704) (xy 238.265753 -287.486326) (xy 238.208275 -287.486326) (xy 238.151448 -287.477704)
			(xy 238.096557 -287.460654) (xy 238.044846 -287.435563) (xy 237.997483 -287.402998) (xy 237.976156 -287.383728)
			(xy 237.969044 -287.377124) (xy 237.951518 -287.370012) (xy 237.86211 -287.370012) (xy 237.844584 -287.377124)
			(xy 237.837472 -287.383728) (xy 237.816134 -287.402986) (xy 237.768776 -287.435556) (xy 237.717067 -287.460651)
			(xy 237.662178 -287.477705) (xy 237.605352 -287.48633) (xy 237.576614 -287.486852) (xy 237.549364 -287.486302)
			(xy 237.495417 -287.478547) (xy 237.443124 -287.463194) (xy 237.393548 -287.440555) (xy 237.347698 -287.411091)
			(xy 237.306509 -287.375401) (xy 237.270817 -287.334213) (xy 237.241352 -287.288365) (xy 237.218711 -287.238789)
			(xy 237.203356 -287.186496) (xy 237.195599 -287.13255) (xy 234.763564 -287.13255) (xy 234.763564 -287.776255)
			(xy 242.583135 -287.776255) (xy 242.583135 -287.721745) (xy 242.590893 -287.667791) (xy 242.60625 -287.61549)
			(xy 242.628894 -287.565906) (xy 242.658364 -287.52005) (xy 242.694061 -287.478855) (xy 242.735257 -287.44316)
			(xy 242.781113 -287.41369) (xy 242.830697 -287.391047) (xy 242.882999 -287.375691) (xy 242.936953 -287.367934)
			(xy 242.964208 -287.367472) (xy 242.994332 -287.368031) (xy 243.053829 -287.377514) (xy 243.111097 -287.396227)
			(xy 243.164714 -287.423706) (xy 243.213348 -287.459267) (xy 243.234972 -287.480248) (xy 243.242084 -287.487614)
			(xy 243.26088 -287.495234) (xy 243.353336 -287.495234) (xy 243.372132 -287.487614) (xy 243.379244 -287.480248)
			(xy 243.400878 -287.459278) (xy 243.449504 -287.423706) (xy 243.503118 -287.396223) (xy 243.560386 -287.377513)
			(xy 243.619884 -287.368041) (xy 243.650008 -287.367472) (xy 243.677257 -287.367999) (xy 243.731201 -287.375756)
			(xy 243.783492 -287.391111) (xy 243.833066 -287.413751) (xy 243.878913 -287.443216) (xy 243.9201 -287.478906)
			(xy 243.955789 -287.520094) (xy 243.985253 -287.565941) (xy 244.007892 -287.615515) (xy 244.023246 -287.667806)
			(xy 244.031002 -287.721751) (xy 244.031002 -287.776249) (xy 244.023246 -287.830194) (xy 244.007892 -287.882485)
			(xy 243.985253 -287.932059) (xy 243.955789 -287.977906) (xy 243.9201 -288.019094) (xy 243.878913 -288.054784)
			(xy 243.833066 -288.084249) (xy 243.783492 -288.106889) (xy 243.731201 -288.122244) (xy 243.677257 -288.130001)
			(xy 243.650008 -288.130488) (xy 243.619884 -288.12993) (xy 243.560386 -288.120448) (xy 243.503117 -288.101736)
			(xy 243.449501 -288.074256) (xy 243.400868 -288.038693) (xy 243.379244 -288.017712) (xy 243.372132 -288.010346)
			(xy 243.353336 -288.002726) (xy 243.26088 -288.002726) (xy 243.242084 -288.010346) (xy 243.234972 -288.017712)
			(xy 243.213341 -288.038685) (xy 243.164713 -288.074254) (xy 243.111098 -288.101735) (xy 243.05383 -288.120445)
			(xy 242.994332 -288.129918) (xy 242.964208 -288.130488) (xy 242.936953 -288.130066) (xy 242.882999 -288.122309)
			(xy 242.830697 -288.106953) (xy 242.781113 -288.08431) (xy 242.735257 -288.05484) (xy 242.694061 -288.019145)
			(xy 242.658364 -287.97795) (xy 242.628894 -287.932094) (xy 242.60625 -287.88251) (xy 242.590893 -287.830209)
			(xy 242.583135 -287.776255) (xy 234.763564 -287.776255) (xy 234.763564 -288.652204) (xy 244.030752 -288.652204)
			(xy 244.034823 -288.596582) (xy 244.046949 -288.542145) (xy 244.066872 -288.490054) (xy 244.094168 -288.441419)
			(xy 244.128254 -288.397276) (xy 244.168403 -288.358567) (xy 244.213761 -288.326116) (xy 244.263361 -288.300615)
			(xy 244.316145 -288.282608) (xy 244.370988 -288.272478) (xy 244.426722 -288.270441) (xy 244.482159 -288.276541)
			(xy 244.536116 -288.290647) (xy 244.587445 -288.312459) (xy 244.635051 -288.341513) (xy 244.677919 -288.377188)
			(xy 244.715136 -288.418725) (xy 244.745909 -288.465238) (xy 244.769581 -288.515735) (xy 244.785649 -288.569142)
			(xy 244.793769 -288.624318) (xy 244.794278 -288.652204) (xy 244.793769 -288.68009) (xy 244.785649 -288.735266)
			(xy 244.769581 -288.788673) (xy 244.745909 -288.83917) (xy 244.715136 -288.885683) (xy 244.677919 -288.92722)
			(xy 244.635051 -288.962895) (xy 244.587445 -288.991949) (xy 244.536116 -289.013761) (xy 244.482159 -289.027867)
			(xy 244.426722 -289.033967) (xy 244.370988 -289.03193) (xy 244.316145 -289.0218) (xy 244.263361 -289.003793)
			(xy 244.213761 -288.978292) (xy 244.168403 -288.945841) (xy 244.128254 -288.907132) (xy 244.094168 -288.862989)
			(xy 244.066872 -288.814354) (xy 244.046949 -288.762263) (xy 244.034823 -288.707826) (xy 244.030752 -288.652204)
			(xy 234.763564 -288.652204) (xy 234.763564 -289.41855) (xy 236.509799 -289.41855) (xy 236.509799 -289.36405)
			(xy 236.517556 -289.310104) (xy 236.532911 -289.257811) (xy 236.555552 -289.208235) (xy 236.585017 -289.162387)
			(xy 236.620709 -289.121199) (xy 236.661898 -289.085509) (xy 236.707748 -289.056045) (xy 236.757324 -289.033406)
			(xy 236.809617 -289.018053) (xy 236.863564 -289.010298) (xy 236.890814 -289.009836) (xy 236.920938 -289.010402)
			(xy 236.980434 -289.019885) (xy 237.037702 -289.038597) (xy 237.091319 -289.066074) (xy 237.139953 -289.101633)
			(xy 237.161578 -289.122612) (xy 237.16869 -289.129978) (xy 237.187486 -289.137598) (xy 237.279942 -289.137598)
			(xy 237.298738 -289.129978) (xy 237.30585 -289.122612) (xy 237.327476 -289.101633) (xy 237.376104 -289.066064)
			(xy 237.42972 -289.038583) (xy 237.48699 -289.019875) (xy 237.54649 -289.010404) (xy 237.576614 -289.009836)
			(xy 237.603868 -289.010235) (xy 237.65782 -289.017994) (xy 237.710119 -289.033352) (xy 237.7597 -289.055997)
			(xy 237.805554 -289.085467) (xy 237.846748 -289.121162) (xy 237.882442 -289.162357) (xy 237.91191 -289.208212)
			(xy 237.934553 -289.257794) (xy 237.949909 -289.310094) (xy 237.957666 -289.364046) (xy 237.957666 -289.418554)
			(xy 237.949909 -289.472506) (xy 237.934553 -289.524806) (xy 237.91191 -289.574388) (xy 237.882442 -289.620243)
			(xy 237.846748 -289.661438) (xy 237.805554 -289.697133) (xy 237.7597 -289.726603) (xy 237.710119 -289.749248)
			(xy 237.65782 -289.764606) (xy 237.603868 -289.772365) (xy 237.576614 -289.772852) (xy 237.546491 -289.772272)
			(xy 237.486995 -289.762793) (xy 237.429727 -289.744084) (xy 237.37611 -289.716611) (xy 237.327475 -289.681054)
			(xy 237.30585 -289.660076) (xy 237.298738 -289.65271) (xy 237.279942 -289.64509) (xy 237.187486 -289.64509)
			(xy 237.16869 -289.65271) (xy 237.161578 -289.660076) (xy 237.139938 -289.68104) (xy 237.091314 -289.716611)
			(xy 237.037701 -289.744095) (xy 236.980434 -289.762807) (xy 236.920937 -289.772282) (xy 236.890814 -289.772852)
			(xy 236.863564 -289.772302) (xy 236.809617 -289.764547) (xy 236.757324 -289.749194) (xy 236.707748 -289.726555)
			(xy 236.661898 -289.697091) (xy 236.620709 -289.661401) (xy 236.585017 -289.620213) (xy 236.555552 -289.574365)
			(xy 236.532911 -289.524789) (xy 236.517556 -289.472496) (xy 236.509799 -289.41855) (xy 234.763564 -289.41855)
			(xy 234.763564 -290.900149) (xy 243.338104 -290.900149) (xy 243.338104 -290.845651) (xy 243.34586 -290.791707)
			(xy 243.361214 -290.739416) (xy 243.383853 -290.689843) (xy 243.413317 -290.643996) (xy 243.449006 -290.602809)
			(xy 243.490193 -290.567119) (xy 243.536039 -290.537655) (xy 243.585613 -290.515015) (xy 243.637903 -290.499661)
			(xy 243.691847 -290.491904) (xy 243.719096 -290.491418) (xy 243.746466 -290.491882) (xy 243.800646 -290.4997)
			(xy 243.853149 -290.515189) (xy 243.902896 -290.538031) (xy 243.948862 -290.567756) (xy 243.969794 -290.585398)
			(xy 243.976906 -290.591494) (xy 243.993924 -290.597844) (xy 244.079268 -290.597844) (xy 244.096286 -290.591494)
			(xy 244.103398 -290.585398) (xy 244.12432 -290.567746) (xy 244.170295 -290.538036) (xy 244.220046 -290.515203)
			(xy 244.272549 -290.499715) (xy 244.326726 -290.49189) (xy 244.354096 -290.491418) (xy 244.381351 -290.491829)
			(xy 244.435306 -290.499586) (xy 244.487608 -290.514942) (xy 244.537192 -290.537586) (xy 244.583049 -290.567056)
			(xy 244.624245 -290.602752) (xy 244.659941 -290.643948) (xy 244.689412 -290.689804) (xy 244.712056 -290.739388)
			(xy 244.727413 -290.79169) (xy 244.735171 -290.845645) (xy 244.735171 -290.900155) (xy 244.727413 -290.95411)
			(xy 244.712056 -291.006412) (xy 244.689412 -291.055996) (xy 244.659941 -291.101852) (xy 244.624245 -291.143048)
			(xy 244.583049 -291.178744) (xy 244.537192 -291.208214) (xy 244.487608 -291.230858) (xy 244.435306 -291.246214)
			(xy 244.381351 -291.253971) (xy 244.354096 -291.254434) (xy 244.326725 -291.253986) (xy 244.272544 -291.246167)
			(xy 244.22004 -291.230674) (xy 244.170294 -291.207828) (xy 244.124328 -291.178098) (xy 244.103398 -291.160454)
			(xy 244.096286 -291.154358) (xy 244.079268 -291.148008) (xy 243.993924 -291.148008) (xy 243.976906 -291.154358)
			(xy 243.969794 -291.160454) (xy 243.948869 -291.178102) (xy 243.902895 -291.207814) (xy 243.853146 -291.230649)
			(xy 243.800643 -291.246138) (xy 243.746466 -291.253962) (xy 243.719096 -291.254434) (xy 243.691847 -291.253896)
			(xy 243.637903 -291.246139) (xy 243.585613 -291.230785) (xy 243.536039 -291.208145) (xy 243.490193 -291.178681)
			(xy 243.449006 -291.142991) (xy 243.413317 -291.101804) (xy 243.383853 -291.055957) (xy 243.361214 -291.006384)
			(xy 243.34586 -290.954093) (xy 243.338104 -290.900149) (xy 234.763564 -290.900149) (xy 234.763564 -291.545049)
			(xy 236.34701 -291.545049) (xy 236.34701 -291.490551) (xy 236.354766 -291.436608) (xy 236.37012 -291.384318)
			(xy 236.392759 -291.334745) (xy 236.422223 -291.288898) (xy 236.457911 -291.247711) (xy 236.499098 -291.212023)
			(xy 236.544945 -291.182559) (xy 236.594518 -291.15992) (xy 236.646808 -291.144566) (xy 236.700751 -291.13681)
			(xy 236.728 -291.136324) (xy 236.755371 -291.136784) (xy 236.80955 -291.144603) (xy 236.862053 -291.160093)
			(xy 236.9118 -291.182936) (xy 236.957767 -291.212662) (xy 236.978698 -291.230304) (xy 236.98581 -291.2364)
			(xy 237.002828 -291.24275) (xy 237.088172 -291.24275) (xy 237.10519 -291.2364) (xy 237.112302 -291.230304)
			(xy 237.133223 -291.212651) (xy 237.179199 -291.182941) (xy 237.228949 -291.160108) (xy 237.281452 -291.14462)
			(xy 237.33563 -291.136796) (xy 237.363 -291.136324) (xy 237.390254 -291.136746) (xy 237.444206 -291.144503)
			(xy 237.496505 -291.159859) (xy 237.546086 -291.182502) (xy 237.591941 -291.211971) (xy 237.633134 -291.247666)
			(xy 237.668829 -291.288859) (xy 237.698298 -291.334714) (xy 237.720941 -291.384295) (xy 237.736297 -291.436594)
			(xy 237.744054 -291.490546) (xy 237.744054 -291.545054) (xy 237.736297 -291.599006) (xy 237.720941 -291.651305)
			(xy 237.698298 -291.700886) (xy 237.668829 -291.746741) (xy 237.633134 -291.787934) (xy 237.591941 -291.823629)
			(xy 237.546086 -291.853098) (xy 237.496505 -291.875741) (xy 237.444206 -291.891097) (xy 237.390254 -291.898854)
			(xy 237.363 -291.89934) (xy 237.335629 -291.898889) (xy 237.281449 -291.891069) (xy 237.228945 -291.875578)
			(xy 237.179198 -291.852732) (xy 237.133233 -291.823004) (xy 237.112302 -291.80536) (xy 237.10519 -291.799264)
			(xy 237.088172 -291.792914) (xy 237.002828 -291.792914) (xy 236.98581 -291.799264) (xy 236.978698 -291.80536)
			(xy 236.957772 -291.823007) (xy 236.911798 -291.852719) (xy 236.862049 -291.875554) (xy 236.809547 -291.891043)
			(xy 236.75537 -291.898868) (xy 236.728 -291.89934) (xy 236.700751 -291.89879) (xy 236.646808 -291.891034)
			(xy 236.594518 -291.87568) (xy 236.544945 -291.853041) (xy 236.499098 -291.823577) (xy 236.457911 -291.787889)
			(xy 236.422223 -291.746702) (xy 236.392759 -291.700855) (xy 236.37012 -291.651282) (xy 236.354766 -291.598992)
			(xy 236.34701 -291.545049) (xy 234.763564 -291.545049) (xy 234.763564 -306.744116) (xy 238.199674 -306.744116)
			(xy 238.203745 -306.688494) (xy 238.215871 -306.634057) (xy 238.235794 -306.581966) (xy 238.26309 -306.533331)
			(xy 238.297176 -306.489188) (xy 238.337325 -306.450479) (xy 238.382683 -306.418028) (xy 238.432283 -306.392527)
			(xy 238.485067 -306.37452) (xy 238.53991 -306.36439) (xy 238.595644 -306.362353) (xy 238.651081 -306.368453)
			(xy 238.705038 -306.382559) (xy 238.756367 -306.404371) (xy 238.803973 -306.433425) (xy 238.846841 -306.4691)
			(xy 238.884058 -306.510637) (xy 238.914831 -306.55715) (xy 238.938503 -306.607647) (xy 238.954571 -306.661054)
			(xy 238.962691 -306.71623) (xy 238.9632 -306.744116) (xy 238.962691 -306.772002) (xy 238.960478 -306.787042)
			(xy 245.473726 -306.787042) (xy 245.477797 -306.73142) (xy 245.489923 -306.676983) (xy 245.509846 -306.624892)
			(xy 245.537142 -306.576257) (xy 245.571228 -306.532114) (xy 245.611377 -306.493405) (xy 245.656735 -306.460954)
			(xy 245.706335 -306.435453) (xy 245.759119 -306.417446) (xy 245.813962 -306.407316) (xy 245.869696 -306.405279)
			(xy 245.925133 -306.411379) (xy 245.97909 -306.425485) (xy 246.030419 -306.447297) (xy 246.078025 -306.476351)
			(xy 246.120893 -306.512026) (xy 246.15811 -306.553563) (xy 246.188883 -306.600076) (xy 246.212555 -306.650573)
			(xy 246.228623 -306.70398) (xy 246.236743 -306.759156) (xy 246.237252 -306.787042) (xy 246.236743 -306.814928)
			(xy 246.228623 -306.870104) (xy 246.212555 -306.923511) (xy 246.188883 -306.974008) (xy 246.15811 -307.020521)
			(xy 246.120893 -307.062058) (xy 246.078025 -307.097733) (xy 246.030419 -307.126787) (xy 245.97909 -307.148599)
			(xy 245.925133 -307.162705) (xy 245.869696 -307.168805) (xy 245.813962 -307.166768) (xy 245.759119 -307.156638)
			(xy 245.706335 -307.138631) (xy 245.656735 -307.11313) (xy 245.611377 -307.080679) (xy 245.571228 -307.04197)
			(xy 245.537142 -306.997827) (xy 245.509846 -306.949192) (xy 245.489923 -306.897101) (xy 245.477797 -306.842664)
			(xy 245.473726 -306.787042) (xy 238.960478 -306.787042) (xy 238.954571 -306.827178) (xy 238.938503 -306.880585)
			(xy 238.914831 -306.931082) (xy 238.884058 -306.977595) (xy 238.846841 -307.019132) (xy 238.803973 -307.054807)
			(xy 238.756367 -307.083861) (xy 238.705038 -307.105673) (xy 238.651081 -307.119779) (xy 238.595644 -307.125879)
			(xy 238.53991 -307.123842) (xy 238.485067 -307.113712) (xy 238.432283 -307.095705) (xy 238.382683 -307.070204)
			(xy 238.337325 -307.037753) (xy 238.297176 -306.999044) (xy 238.26309 -306.954901) (xy 238.235794 -306.906266)
			(xy 238.215871 -306.854175) (xy 238.203745 -306.799738) (xy 238.199674 -306.744116) (xy 234.763564 -306.744116)
			(xy 234.763564 -307.446426) (xy 243.125242 -307.446426) (xy 243.129313 -307.390804) (xy 243.141439 -307.336367)
			(xy 243.161362 -307.284276) (xy 243.188658 -307.235641) (xy 243.222744 -307.191498) (xy 243.262893 -307.152789)
			(xy 243.308251 -307.120338) (xy 243.357851 -307.094837) (xy 243.410635 -307.07683) (xy 243.465478 -307.0667)
			(xy 243.521212 -307.064663) (xy 243.576649 -307.070763) (xy 243.630606 -307.084869) (xy 243.681935 -307.106681)
			(xy 243.729541 -307.135735) (xy 243.772409 -307.17141) (xy 243.809626 -307.212947) (xy 243.840399 -307.25946)
			(xy 243.864071 -307.309957) (xy 243.880139 -307.363364) (xy 243.888259 -307.41854) (xy 243.888768 -307.446426)
			(xy 243.888259 -307.474312) (xy 243.880139 -307.529488) (xy 243.864071 -307.582895) (xy 243.840399 -307.633392)
			(xy 243.809626 -307.679905) (xy 243.772409 -307.721442) (xy 243.729541 -307.757117) (xy 243.681935 -307.786171)
			(xy 243.630606 -307.807983) (xy 243.576649 -307.822089) (xy 243.521212 -307.828189) (xy 243.465478 -307.826152)
			(xy 243.410635 -307.816022) (xy 243.357851 -307.798015) (xy 243.308251 -307.772514) (xy 243.262893 -307.740063)
			(xy 243.222744 -307.701354) (xy 243.188658 -307.657211) (xy 243.161362 -307.608576) (xy 243.141439 -307.556485)
			(xy 243.129313 -307.502048) (xy 243.125242 -307.446426) (xy 234.763564 -307.446426) (xy 234.763564 -308.402228)
			(xy 244.183152 -308.402228) (xy 244.187223 -308.346606) (xy 244.199349 -308.292169) (xy 244.219272 -308.240078)
			(xy 244.246568 -308.191443) (xy 244.280654 -308.1473) (xy 244.320803 -308.108591) (xy 244.366161 -308.07614)
			(xy 244.415761 -308.050639) (xy 244.468545 -308.032632) (xy 244.523388 -308.022502) (xy 244.579122 -308.020465)
			(xy 244.634559 -308.026565) (xy 244.688516 -308.040671) (xy 244.739845 -308.062483) (xy 244.787451 -308.091537)
			(xy 244.830319 -308.127212) (xy 244.867536 -308.168749) (xy 244.898309 -308.215262) (xy 244.921981 -308.265759)
			(xy 244.938049 -308.319166) (xy 244.946169 -308.374342) (xy 244.946678 -308.402228) (xy 244.946169 -308.430114)
			(xy 244.938049 -308.48529) (xy 244.921981 -308.538697) (xy 244.898309 -308.589194) (xy 244.867536 -308.635707)
			(xy 244.830319 -308.677244) (xy 244.787451 -308.712919) (xy 244.739845 -308.741973) (xy 244.688516 -308.763785)
			(xy 244.634559 -308.777891) (xy 244.579122 -308.783991) (xy 244.523388 -308.781954) (xy 244.468545 -308.771824)
			(xy 244.415761 -308.753817) (xy 244.366161 -308.728316) (xy 244.320803 -308.695865) (xy 244.280654 -308.657156)
			(xy 244.246568 -308.613013) (xy 244.219272 -308.564378) (xy 244.199349 -308.512287) (xy 244.187223 -308.45785)
			(xy 244.183152 -308.402228) (xy 234.763564 -308.402228) (xy 234.763564 -309.018178) (xy 246.191276 -309.018178)
			(xy 246.195347 -308.962556) (xy 246.207473 -308.908119) (xy 246.227396 -308.856028) (xy 246.254692 -308.807393)
			(xy 246.288778 -308.76325) (xy 246.328927 -308.724541) (xy 246.374285 -308.69209) (xy 246.423885 -308.666589)
			(xy 246.476669 -308.648582) (xy 246.531512 -308.638452) (xy 246.587246 -308.636415) (xy 246.642683 -308.642515)
			(xy 246.69664 -308.656621) (xy 246.747969 -308.678433) (xy 246.795575 -308.707487) (xy 246.838443 -308.743162)
			(xy 246.87566 -308.784699) (xy 246.906433 -308.831212) (xy 246.930105 -308.881709) (xy 246.946173 -308.935116)
			(xy 246.954293 -308.990292) (xy 246.954802 -309.018178) (xy 246.954293 -309.046064) (xy 246.946173 -309.10124)
			(xy 246.930105 -309.154647) (xy 246.906433 -309.205144) (xy 246.87566 -309.251657) (xy 246.838443 -309.293194)
			(xy 246.795575 -309.328869) (xy 246.747969 -309.357923) (xy 246.69664 -309.379735) (xy 246.642683 -309.393841)
			(xy 246.587246 -309.399941) (xy 246.531512 -309.397904) (xy 246.476669 -309.387774) (xy 246.423885 -309.369767)
			(xy 246.374285 -309.344266) (xy 246.328927 -309.311815) (xy 246.288778 -309.273106) (xy 246.254692 -309.228963)
			(xy 246.227396 -309.180328) (xy 246.207473 -309.128237) (xy 246.195347 -309.0738) (xy 246.191276 -309.018178)
			(xy 234.763564 -309.018178) (xy 234.763564 -309.908448) (xy 242.571268 -309.908448) (xy 242.575339 -309.852826)
			(xy 242.587465 -309.798389) (xy 242.607388 -309.746298) (xy 242.634684 -309.697663) (xy 242.66877 -309.65352)
			(xy 242.708919 -309.614811) (xy 242.754277 -309.58236) (xy 242.803877 -309.556859) (xy 242.856661 -309.538852)
			(xy 242.911504 -309.528722) (xy 242.967238 -309.526685) (xy 243.022675 -309.532785) (xy 243.076632 -309.546891)
			(xy 243.127961 -309.568703) (xy 243.175567 -309.597757) (xy 243.218435 -309.633432) (xy 243.255652 -309.674969)
			(xy 243.286425 -309.721482) (xy 243.297509 -309.745126) (xy 244.286784 -309.745126) (xy 244.290855 -309.689504)
			(xy 244.302981 -309.635067) (xy 244.322904 -309.582976) (xy 244.3502 -309.534341) (xy 244.384286 -309.490198)
			(xy 244.424435 -309.451489) (xy 244.469793 -309.419038) (xy 244.519393 -309.393537) (xy 244.572177 -309.37553)
			(xy 244.62702 -309.3654) (xy 244.682754 -309.363363) (xy 244.738191 -309.369463) (xy 244.792148 -309.383569)
			(xy 244.843477 -309.405381) (xy 244.891083 -309.434435) (xy 244.933951 -309.47011) (xy 244.971168 -309.511647)
			(xy 245.001941 -309.55816) (xy 245.025613 -309.608657) (xy 245.041681 -309.662064) (xy 245.049801 -309.71724)
			(xy 245.05031 -309.745126) (xy 245.049801 -309.773012) (xy 245.041681 -309.828188) (xy 245.025613 -309.881595)
			(xy 245.001941 -309.932092) (xy 244.971168 -309.978605) (xy 244.933951 -310.020142) (xy 244.891083 -310.055817)
			(xy 244.843477 -310.084871) (xy 244.792148 -310.106683) (xy 244.738191 -310.120789) (xy 244.682754 -310.126889)
			(xy 244.62702 -310.124852) (xy 244.572177 -310.114722) (xy 244.519393 -310.096715) (xy 244.469793 -310.071214)
			(xy 244.424435 -310.038763) (xy 244.384286 -310.000054) (xy 244.3502 -309.955911) (xy 244.322904 -309.907276)
			(xy 244.302981 -309.855185) (xy 244.290855 -309.800748) (xy 244.286784 -309.745126) (xy 243.297509 -309.745126)
			(xy 243.310097 -309.771979) (xy 243.326165 -309.825386) (xy 243.334285 -309.880562) (xy 243.334794 -309.908448)
			(xy 243.334285 -309.936334) (xy 243.326165 -309.99151) (xy 243.310097 -310.044917) (xy 243.286425 -310.095414)
			(xy 243.255652 -310.141927) (xy 243.218435 -310.183464) (xy 243.175567 -310.219139) (xy 243.127961 -310.248193)
			(xy 243.076632 -310.270005) (xy 243.022675 -310.284111) (xy 242.967238 -310.290211) (xy 242.911504 -310.288174)
			(xy 242.856661 -310.278044) (xy 242.803877 -310.260037) (xy 242.754277 -310.234536) (xy 242.708919 -310.202085)
			(xy 242.66877 -310.163376) (xy 242.634684 -310.119233) (xy 242.607388 -310.070598) (xy 242.587465 -310.018507)
			(xy 242.575339 -309.96407) (xy 242.571268 -309.908448) (xy 234.763564 -309.908448) (xy 234.763564 -311.215786)
			(xy 243.749066 -311.215786) (xy 243.753137 -311.160164) (xy 243.765263 -311.105727) (xy 243.785186 -311.053636)
			(xy 243.812482 -311.005001) (xy 243.846568 -310.960858) (xy 243.886717 -310.922149) (xy 243.932075 -310.889698)
			(xy 243.981675 -310.864197) (xy 244.034459 -310.84619) (xy 244.089302 -310.83606) (xy 244.145036 -310.834023)
			(xy 244.200473 -310.840123) (xy 244.25443 -310.854229) (xy 244.305759 -310.876041) (xy 244.353365 -310.905095)
			(xy 244.396233 -310.94077) (xy 244.43345 -310.982307) (xy 244.464223 -311.02882) (xy 244.487895 -311.079317)
			(xy 244.503963 -311.132724) (xy 244.512083 -311.1879) (xy 244.512592 -311.215786) (xy 244.512083 -311.243672)
			(xy 244.503963 -311.298848) (xy 244.487895 -311.352255) (xy 244.464223 -311.402752) (xy 244.43345 -311.449265)
			(xy 244.396233 -311.490802) (xy 244.353365 -311.526477) (xy 244.305759 -311.555531) (xy 244.25443 -311.577343)
			(xy 244.200473 -311.591449) (xy 244.145036 -311.597549) (xy 244.089302 -311.595512) (xy 244.034459 -311.585382)
			(xy 243.981675 -311.567375) (xy 243.932075 -311.541874) (xy 243.886717 -311.509423) (xy 243.846568 -311.470714)
			(xy 243.812482 -311.426571) (xy 243.785186 -311.377936) (xy 243.765263 -311.325845) (xy 243.753137 -311.271408)
			(xy 243.749066 -311.215786) (xy 234.763564 -311.215786) (xy 234.763564 -320.816732) (xy 241.138202 -320.816732)
			(xy 241.138686 -320.789362) (xy 241.1465 -320.735184) (xy 241.161984 -320.682681) (xy 241.184822 -320.632934)
			(xy 241.214543 -320.586966) (xy 241.232182 -320.566034) (xy 241.238278 -320.558922) (xy 241.244628 -320.541904)
			(xy 241.244628 -320.45656) (xy 241.238278 -320.439542) (xy 241.232182 -320.43243) (xy 241.214541 -320.4115)
			(xy 241.18483 -320.365526) (xy 241.161995 -320.315778) (xy 241.146504 -320.263277) (xy 241.138676 -320.209101)
			(xy 241.138202 -320.181732) (xy 241.138685 -320.154479) (xy 241.146438 -320.100529) (xy 241.16179 -320.048231)
			(xy 241.18443 -319.99865) (xy 241.213896 -319.952796) (xy 241.249587 -319.911603) (xy 241.290779 -319.875909)
			(xy 241.336631 -319.846441) (xy 241.38621 -319.823798) (xy 241.438507 -319.808443) (xy 241.492458 -319.800687)
			(xy 241.51971 -319.800224) (xy 241.547081 -319.800678) (xy 241.601261 -319.808498) (xy 241.653764 -319.82399)
			(xy 241.703511 -319.846834) (xy 241.749477 -319.876561) (xy 241.770408 -319.894204) (xy 241.77752 -319.9003)
			(xy 241.794538 -319.90665) (xy 241.879882 -319.90665) (xy 241.8969 -319.9003) (xy 241.904012 -319.894204)
			(xy 241.924945 -319.876563) (xy 241.970913 -319.846839) (xy 242.020659 -319.823993) (xy 242.073161 -319.808497)
			(xy 242.127339 -319.800668) (xy 242.182081 -319.800668) (xy 242.236259 -319.808497) (xy 242.288761 -319.823993)
			(xy 242.338507 -319.846839) (xy 242.384475 -319.876563) (xy 242.405408 -319.894204) (xy 242.41252 -319.9003)
			(xy 242.429538 -319.90665) (xy 242.514882 -319.90665) (xy 242.5319 -319.9003) (xy 242.539012 -319.894204)
			(xy 242.559967 -319.876593) (xy 242.605933 -319.846877) (xy 242.655675 -319.824036) (xy 242.708171 -319.808538)
			(xy 242.762342 -319.800702) (xy 242.78971 -319.800224) (xy 242.816965 -319.800646) (xy 242.870919 -319.808405)
			(xy 242.923219 -319.823764) (xy 242.972802 -319.84641) (xy 243.018656 -319.875882) (xy 243.05985 -319.91158)
			(xy 243.095543 -319.952777) (xy 243.12501 -319.998635) (xy 243.147651 -320.04822) (xy 243.163004 -320.100522)
			(xy 243.170757 -320.154477) (xy 243.171218 -320.181732) (xy 243.170791 -320.209104) (xy 243.162967 -320.263285)
			(xy 243.14747 -320.31579) (xy 243.124619 -320.365536) (xy 243.094884 -320.4115) (xy 243.077238 -320.43243)
			(xy 243.071142 -320.439542) (xy 243.064792 -320.45656) (xy 243.064792 -320.541904) (xy 243.071142 -320.558922)
			(xy 243.077238 -320.566034) (xy 243.094866 -320.586975) (xy 243.124578 -320.632946) (xy 243.147416 -320.682691)
			(xy 243.16291 -320.73519) (xy 243.170742 -320.789364) (xy 243.171218 -320.816732) (xy 243.170752 -320.843984)
			(xy 243.162991 -320.897931) (xy 243.147633 -320.950226) (xy 243.124989 -320.999803) (xy 243.09552 -321.045652)
			(xy 243.059826 -321.086842) (xy 243.018635 -321.122533) (xy 242.972783 -321.151999) (xy 242.923205 -321.17464)
			(xy 242.87091 -321.189996) (xy 242.816962 -321.197754) (xy 242.78971 -321.19824) (xy 242.762339 -321.197783)
			(xy 242.708159 -321.189965) (xy 242.655655 -321.174475) (xy 242.605909 -321.151631) (xy 242.559943 -321.121903)
			(xy 242.539012 -321.10426) (xy 242.5319 -321.098164) (xy 242.514882 -321.091814) (xy 242.429538 -321.091814)
			(xy 242.41252 -321.098164) (xy 242.405408 -321.10426) (xy 242.384475 -321.121901) (xy 242.338507 -321.151625)
			(xy 242.288761 -321.174471) (xy 242.236259 -321.189967) (xy 242.182081 -321.197796) (xy 242.127339 -321.197796)
			(xy 242.073161 -321.189967) (xy 242.020659 -321.174471) (xy 241.970913 -321.151625) (xy 241.924945 -321.121901)
			(xy 241.904012 -321.10426) (xy 241.8969 -321.098164) (xy 241.879882 -321.091814) (xy 241.794538 -321.091814)
			(xy 241.77752 -321.098164) (xy 241.770408 -321.10426) (xy 241.749479 -321.121903) (xy 241.703506 -321.151615)
			(xy 241.653758 -321.174451) (xy 241.601256 -321.189941) (xy 241.547079 -321.197767) (xy 241.51971 -321.19824)
			(xy 241.49246 -321.197713) (xy 241.438516 -321.189958) (xy 241.386224 -321.174606) (xy 241.336649 -321.151968)
			(xy 241.2908 -321.122506) (xy 241.249611 -321.086819) (xy 241.213919 -321.045634) (xy 241.184452 -320.999788)
			(xy 241.161809 -320.950215) (xy 241.146451 -320.897925) (xy 241.13869 -320.843981) (xy 241.138202 -320.816732)
			(xy 234.763564 -320.816732) (xy 234.763564 -321.431412) (xy 234.765088 -321.432682) (xy 234.771828 -321.437352)
			(xy 234.787374 -321.442539) (xy 234.795568 -321.442842) (xy 247.263158 -321.442842)
		)
		(stroke
			(width 0)
			(type solid)
		)
		(fill yes)
		(layer "In7.Cu")
		(net "GND")
	)
	(gr_poly
		(pts
			(xy 252.03785 -190.160656) (xy 252.047559 -190.166559) (xy 252.069971 -190.17012) (xy 252.08103 -190.167514)
			(xy 252.086364 -190.165482) (xy 252.093341 -190.1623) (xy 252.105105 -190.152477) (xy 252.109478 -190.146178)
			(xy 252.113288 -190.14059) (xy 252.117352 -190.12662) (xy 252.117352 -181.154324) (xy 252.116844 -181.147212)
			(xy 248.304558 -177.334926) (xy 248.300308 -177.334406) (xy 248.291751 -177.33466) (xy 248.28754 -177.335434)
			(xy 248.282968 -177.33645) (xy 248.229628 -177.352198) (xy 248.197116 -177.36185) (xy 248.190719 -177.363964)
			(xy 248.179262 -177.371044) (xy 248.17451 -177.37582) (xy 248.170192 -177.380646) (xy 248.163842 -177.392584)
			(xy 248.162318 -177.39995) (xy 248.152653 -177.442721) (xy 248.126108 -177.5263) (xy 248.091578 -177.606909)
			(xy 248.049389 -177.683787) (xy 247.999939 -177.756208) (xy 247.943695 -177.823488) (xy 247.881188 -177.884994)
			(xy 247.813007 -177.940144) (xy 247.739797 -177.988417) (xy 247.662248 -178.029359) (xy 247.581092 -178.062582)
			(xy 247.497095 -178.087773) (xy 247.41105 -178.104695) (xy 247.323769 -178.113187) (xy 247.279922 -178.11369)
			(xy 247.238232 -178.113224) (xy 247.155206 -178.105533) (xy 247.073245 -178.090213) (xy 246.993047 -178.067396)
			(xy 246.915296 -178.037277) (xy 246.840657 -178.000112) (xy 246.769765 -177.956218) (xy 246.703225 -177.90597)
			(xy 246.641606 -177.849797) (xy 246.585432 -177.788178) (xy 246.535184 -177.721639) (xy 246.49129 -177.650747)
			(xy 246.454125 -177.576107) (xy 246.424005 -177.498357) (xy 246.401188 -177.418159) (xy 246.385868 -177.336198)
			(xy 246.378176 -177.253172) (xy 246.377714 -177.211482) (xy 246.378241 -177.16764) (xy 246.386757 -177.080371)
			(xy 246.403698 -176.99434) (xy 246.428904 -176.910357) (xy 246.462136 -176.829215) (xy 246.503083 -176.75168)
			(xy 246.551357 -176.678481) (xy 246.606503 -176.61031) (xy 246.668002 -176.547809) (xy 246.735272 -176.491568)
			(xy 246.807681 -176.442118) (xy 246.884545 -176.399923) (xy 246.965139 -176.365384) (xy 247.048703 -176.338824)
			(xy 247.091454 -176.329086) (xy 247.091962 -176.329086) (xy 247.098685 -176.327439) (xy 247.11093 -176.320997)
			(xy 247.116092 -176.316386) (xy 247.12041 -176.312068) (xy 247.127522 -176.300892) (xy 247.139206 -176.261776)
			(xy 247.154954 -176.208436) (xy 247.15597 -176.203864) (xy 247.156713 -176.19965) (xy 247.156973 -176.191097)
			(xy 247.156478 -176.186846) (xy 241.431826 -170.462194) (xy 241.424423 -170.45536) (xy 241.405825 -170.447653)
			(xy 241.395758 -170.447208) (xy 236.154976 -170.447208) (xy 236.128889 -170.44672) (xy 236.077359 -170.438551)
			(xy 236.027742 -170.422418) (xy 235.981261 -170.398719) (xy 235.939062 -170.368037) (xy 235.92028 -170.349926)
			(xy 235.350304 -169.77995) (xy 235.332271 -169.761179) (xy 235.301688 -169.719063) (xy 235.278058 -169.672687)
			(xy 235.261961 -169.62319) (xy 235.253792 -169.571786) (xy 235.253276 -169.545762) (xy 235.253276 -168.3766)
			(xy 235.253691 -168.353017) (xy 235.260372 -168.306326) (xy 235.273599 -168.261052) (xy 235.293105 -168.218109)
			(xy 235.318498 -168.178361) (xy 235.33354 -168.160192) (xy 235.33912 -168.153103) (xy 235.345355 -168.136187)
			(xy 235.345732 -168.127172) (xy 235.345732 -156.020008) (xy 235.345732 -156.017722) (xy 235.344836 -156.007899)
			(xy 235.336609 -155.989993) (xy 235.32973 -155.982924) (xy 235.272326 -155.93187) (xy 235.26832 -155.928479)
			(xy 235.259229 -155.923238) (xy 235.254292 -155.921456) (xy 235.244132 -155.918154) (xy 235.232956 -155.919424)
			(xy 235.222954 -155.920454) (xy 235.202878 -155.921596) (xy 235.192824 -155.92171) (xy 235.189776 -155.92171)
			(xy 235.162582 -155.921141) (xy 235.108766 -155.913243) (xy 235.056618 -155.897782) (xy 235.007195 -155.875072)
			(xy 234.961498 -155.845572) (xy 234.920453 -155.809881) (xy 234.884894 -155.768723) (xy 234.855541 -155.722932)
			(xy 234.832989 -155.673436) (xy 234.817695 -155.621238) (xy 234.80997 -155.567398) (xy 234.809538 -155.540202)
			(xy 234.810001 -155.51295) (xy 234.817758 -155.459002) (xy 234.833115 -155.406706) (xy 234.855758 -155.357129)
			(xy 234.885226 -155.311279) (xy 234.920921 -155.270089) (xy 234.962114 -155.2344) (xy 235.007967 -155.204936)
			(xy 235.057547 -155.182299) (xy 235.109845 -155.166949) (xy 235.163794 -155.159198) (xy 235.191046 -155.158694)
			(xy 235.214204 -155.159031) (xy 235.260181 -155.164629) (xy 235.28274 -155.16987) (xy 235.288836 -155.171394)
			(xy 235.294932 -155.171394) (xy 235.304935 -155.1709) (xy 235.323415 -155.163235) (xy 235.337556 -155.149083)
			(xy 235.345208 -155.130597) (xy 235.345732 -155.120594) (xy 235.345732 -155.07081) (xy 235.345246 -155.060799)
			(xy 235.33759 -155.042298) (xy 235.323437 -155.028134) (xy 235.304943 -155.020462) (xy 235.294932 -155.02001)
			(xy 235.288836 -155.02001) (xy 235.28274 -155.021534) (xy 235.260179 -155.026769) (xy 235.214204 -155.032377)
			(xy 235.191046 -155.03271) (xy 235.163791 -155.03225) (xy 235.109835 -155.024498) (xy 235.057531 -155.009146)
			(xy 235.007945 -154.986506) (xy 234.962086 -154.957039) (xy 234.920887 -154.921345) (xy 234.885189 -154.880151)
			(xy 234.855716 -154.834296) (xy 234.83307 -154.784712) (xy 234.817712 -154.73241) (xy 234.809953 -154.678455)
			(xy 234.809953 -154.623945) (xy 234.817712 -154.56999) (xy 234.83307 -154.517688) (xy 234.855716 -154.468104)
			(xy 234.885189 -154.422249) (xy 234.920887 -154.381055) (xy 234.962086 -154.345361) (xy 235.007945 -154.315894)
			(xy 235.057531 -154.293254) (xy 235.109835 -154.277902) (xy 235.163791 -154.27015) (xy 235.191046 -154.269694)
			(xy 235.191554 -154.269694) (xy 235.201926 -154.269771) (xy 235.222638 -154.270917) (xy 235.232956 -154.27198)
			(xy 235.244132 -154.27325) (xy 235.254292 -154.269948) (xy 235.259248 -154.268209) (xy 235.268347 -154.262963)
			(xy 235.272326 -154.259534) (xy 235.32973 -154.20848) (xy 235.336599 -154.201404) (xy 235.344826 -154.183502)
			(xy 235.345732 -154.173682) (xy 235.345732 -126.768098) (xy 235.345732 -126.767082) (xy 235.345503 -126.7619)
			(xy 235.343196 -126.751787) (xy 235.34116 -126.747016) (xy 235.31449 -126.73584) (xy 235.305022 -126.732365)
			(xy 235.284869 -126.732387) (xy 235.266284 -126.740181) (xy 235.258864 -126.747016) (xy 235.0516 -126.954534)
			(xy 235.03282 -126.972648) (xy 234.990623 -127.003335) (xy 234.944142 -127.027038) (xy 234.894524 -127.043173)
			(xy 234.842992 -127.051341) (xy 234.816904 -127.051816) (xy 234.134406 -127.051816) (xy 234.129072 -127.056388)
			(xy 226.374198 -134.811262) (xy 228.099112 -134.811262) (xy 228.099598 -134.784011) (xy 228.107354 -134.730063)
			(xy 228.122709 -134.677768) (xy 228.145351 -134.628191) (xy 228.174817 -134.582341) (xy 228.210508 -134.54115)
			(xy 228.251699 -134.505459) (xy 228.297549 -134.475993) (xy 228.347126 -134.453351) (xy 228.399421 -134.437996)
			(xy 228.453369 -134.43024) (xy 228.507871 -134.43024) (xy 228.561819 -134.437996) (xy 228.614114 -134.453351)
			(xy 228.663691 -134.475993) (xy 228.709541 -134.505459) (xy 228.750732 -134.54115) (xy 228.786423 -134.582341)
			(xy 228.815889 -134.628191) (xy 228.838531 -134.677768) (xy 228.853886 -134.730063) (xy 228.861642 -134.784011)
			(xy 228.862128 -134.811262) (xy 228.861712 -134.837579) (xy 228.854481 -134.889714) (xy 228.840151 -134.940359)
			(xy 228.818993 -134.988553) (xy 228.791411 -135.033381) (xy 228.757927 -135.073991) (xy 228.719178 -135.109611)
			(xy 228.69779 -135.124952) (xy 228.68662 -135.133118) (xy 228.668872 -135.154336) (xy 228.657474 -135.17954)
			(xy 228.653263 -135.206879) (xy 228.65655 -135.234345) (xy 228.667091 -135.25992) (xy 228.684114 -135.281723)
			(xy 228.706367 -135.298155) (xy 228.719126 -135.303514) (xy 228.745788 -135.314237) (xy 228.795756 -135.342623)
			(xy 228.840898 -135.378186) (xy 228.880192 -135.420121) (xy 228.912748 -135.467477) (xy 228.937827 -135.519184)
			(xy 228.954863 -135.574068) (xy 228.96347 -135.630888) (xy 228.963982 -135.659622) (xy 228.963496 -135.686873)
			(xy 228.95574 -135.740821) (xy 228.940385 -135.793116) (xy 228.917743 -135.842693) (xy 228.888277 -135.888543)
			(xy 228.852586 -135.929734) (xy 228.811395 -135.965425) (xy 228.765545 -135.994891) (xy 228.715968 -136.017533)
			(xy 228.663673 -136.032888) (xy 228.609725 -136.040644) (xy 228.555223 -136.040644) (xy 228.501275 -136.032888)
			(xy 228.44898 -136.017533) (xy 228.399403 -135.994891) (xy 228.353553 -135.965425) (xy 228.312362 -135.929734)
			(xy 228.276671 -135.888543) (xy 228.247205 -135.842693) (xy 228.224563 -135.793116) (xy 228.209208 -135.740821)
			(xy 228.201452 -135.686873) (xy 228.200966 -135.659622) (xy 228.201372 -135.633305) (xy 228.208605 -135.58117)
			(xy 228.222937 -135.530524) (xy 228.244096 -135.48233) (xy 228.27168 -135.437502) (xy 228.305165 -135.396893)
			(xy 228.343916 -135.361273) (xy 228.365304 -135.345932) (xy 228.376388 -135.337656) (xy 228.394134 -135.316461)
			(xy 228.405536 -135.291279) (xy 228.409755 -135.263959) (xy 228.406481 -135.236511) (xy 228.395955 -135.21095)
			(xy 228.37895 -135.189155) (xy 228.356717 -135.172729) (xy 228.343968 -135.16737) (xy 228.317335 -135.15658)
			(xy 228.26737 -135.128202) (xy 228.222229 -135.092648) (xy 228.182935 -135.050723) (xy 228.150376 -135.003376)
			(xy 228.125291 -134.951679) (xy 228.108247 -134.896804) (xy 228.099631 -134.839993) (xy 228.099112 -134.811262)
			(xy 226.374198 -134.811262) (xy 225.525838 -135.659622) (xy 226.422456 -135.659622) (xy 226.426527 -135.604)
			(xy 226.438653 -135.549563) (xy 226.458576 -135.497472) (xy 226.485872 -135.448837) (xy 226.519958 -135.404694)
			(xy 226.560107 -135.365985) (xy 226.605465 -135.333534) (xy 226.655065 -135.308033) (xy 226.707849 -135.290026)
			(xy 226.762692 -135.279896) (xy 226.818426 -135.277859) (xy 226.873863 -135.283959) (xy 226.92782 -135.298065)
			(xy 226.979149 -135.319877) (xy 227.026755 -135.348931) (xy 227.069623 -135.384606) (xy 227.10684 -135.426143)
			(xy 227.137613 -135.472656) (xy 227.161285 -135.523153) (xy 227.177353 -135.57656) (xy 227.185473 -135.631736)
			(xy 227.185982 -135.659622) (xy 227.185473 -135.687508) (xy 227.177353 -135.742684) (xy 227.161285 -135.796091)
			(xy 227.137613 -135.846588) (xy 227.10684 -135.893101) (xy 227.069623 -135.934638) (xy 227.026755 -135.970313)
			(xy 226.979149 -135.999367) (xy 226.92782 -136.021179) (xy 226.873863 -136.035285) (xy 226.818426 -136.041385)
			(xy 226.762692 -136.039348) (xy 226.707849 -136.029218) (xy 226.655065 -136.011211) (xy 226.605465 -135.98571)
			(xy 226.560107 -135.953259) (xy 226.519958 -135.91455) (xy 226.485872 -135.870407) (xy 226.458576 -135.821772)
			(xy 226.438653 -135.769681) (xy 226.426527 -135.715244) (xy 226.422456 -135.659622) (xy 225.525838 -135.659622)
			(xy 225.378518 -135.806942) (xy 225.374708 -135.815578) (xy 225.362878 -135.840757) (xy 225.333004 -135.887685)
			(xy 225.296633 -135.929778) (xy 225.254534 -135.966142) (xy 225.207601 -135.996008) (xy 225.18243 -136.007856)
			(xy 225.173794 -136.011666) (xy 224.755202 -136.430258) (xy 224.748078 -136.438227) (xy 224.740474 -136.458176)
			(xy 224.74047 -136.468866) (xy 224.744534 -136.544558) (xy 224.744938 -136.549838) (xy 224.747633 -136.560077)
			(xy 224.749868 -136.564878) (xy 224.754694 -136.574276) (xy 224.76333 -136.581134) (xy 224.784975 -136.59934)
			(xy 224.823172 -136.641051) (xy 224.854789 -136.687946) (xy 224.879133 -136.738997) (xy 224.895671 -136.793083)
			(xy 224.904039 -136.849019) (xy 224.904554 -136.877298) (xy 224.904554 -136.877552) (xy 224.904094 -136.904808)
			(xy 224.896343 -136.958767) (xy 224.880992 -137.011073) (xy 224.858353 -137.060662) (xy 224.828887 -137.106525)
			(xy 224.793194 -137.147727) (xy 224.752 -137.18343) (xy 224.706145 -137.212908) (xy 224.656561 -137.235559)
			(xy 224.604259 -137.250923) (xy 224.550302 -137.258688) (xy 224.523046 -137.25906) (xy 224.522792 -137.25906)
			(xy 224.499125 -137.258704) (xy 224.452156 -137.252838) (xy 224.40628 -137.241184) (xy 224.384108 -137.232898)
			(xy 224.375224 -137.229761) (xy 224.356399 -137.229606) (xy 224.338804 -137.236305) (xy 224.33153 -137.242296)
			(xy 224.310461 -137.260463) (xy 224.264044 -137.291128) (xy 224.213662 -137.314717) (xy 224.160385 -137.330729)
			(xy 224.105346 -137.338823) (xy 224.07753 -137.339324) (xy 224.077276 -137.339324) (xy 224.061324 -137.339164)
			(xy 224.029531 -137.336494) (xy 224.013776 -137.33399) (xy 224.002854 -137.331958) (xy 223.981264 -137.338054)
			(xy 223.913446 -137.395204) (xy 223.905307 -137.402793) (xy 223.895941 -137.422951) (xy 223.895412 -137.434066)
			(xy 223.895412 -138.090656) (xy 224.549206 -138.090656) (xy 224.553277 -138.035034) (xy 224.565403 -137.980597)
			(xy 224.585326 -137.928506) (xy 224.612622 -137.879871) (xy 224.646708 -137.835728) (xy 224.686857 -137.797019)
			(xy 224.732215 -137.764568) (xy 224.781815 -137.739067) (xy 224.834599 -137.72106) (xy 224.889442 -137.71093)
			(xy 224.945176 -137.708893) (xy 225.000613 -137.714993) (xy 225.05457 -137.729099) (xy 225.105899 -137.750911)
			(xy 225.153505 -137.779965) (xy 225.196373 -137.81564) (xy 225.23359 -137.857177) (xy 225.264363 -137.90369)
			(xy 225.288035 -137.954187) (xy 225.304103 -138.007594) (xy 225.312223 -138.06277) (xy 225.312732 -138.090656)
			(xy 225.312223 -138.118542) (xy 225.304103 -138.173718) (xy 225.288035 -138.227125) (xy 225.273304 -138.25855)
			(xy 232.741976 -138.25855) (xy 232.746047 -138.202928) (xy 232.758173 -138.148491) (xy 232.778096 -138.0964)
			(xy 232.805392 -138.047765) (xy 232.839478 -138.003622) (xy 232.879627 -137.964913) (xy 232.924985 -137.932462)
			(xy 232.974585 -137.906961) (xy 233.027369 -137.888954) (xy 233.082212 -137.878824) (xy 233.137946 -137.876787)
			(xy 233.193383 -137.882887) (xy 233.24734 -137.896993) (xy 233.298669 -137.918805) (xy 233.346275 -137.947859)
			(xy 233.389143 -137.983534) (xy 233.42636 -138.025071) (xy 233.457133 -138.071584) (xy 233.480805 -138.122081)
			(xy 233.496873 -138.175488) (xy 233.504993 -138.230664) (xy 233.505502 -138.25855) (xy 233.504993 -138.286436)
			(xy 233.496873 -138.341612) (xy 233.480805 -138.395019) (xy 233.457133 -138.445516) (xy 233.42636 -138.492029)
			(xy 233.389143 -138.533566) (xy 233.346275 -138.569241) (xy 233.298669 -138.598295) (xy 233.24734 -138.620107)
			(xy 233.193383 -138.634213) (xy 233.137946 -138.640313) (xy 233.082212 -138.638276) (xy 233.027369 -138.628146)
			(xy 232.974585 -138.610139) (xy 232.924985 -138.584638) (xy 232.879627 -138.552187) (xy 232.839478 -138.513478)
			(xy 232.805392 -138.469335) (xy 232.778096 -138.4207) (xy 232.758173 -138.368609) (xy 232.746047 -138.314172)
			(xy 232.741976 -138.25855) (xy 225.273304 -138.25855) (xy 225.264363 -138.277622) (xy 225.23359 -138.324135)
			(xy 225.196373 -138.365672) (xy 225.153505 -138.401347) (xy 225.105899 -138.430401) (xy 225.05457 -138.452213)
			(xy 225.000613 -138.466319) (xy 224.945176 -138.472419) (xy 224.889442 -138.470382) (xy 224.834599 -138.460252)
			(xy 224.781815 -138.442245) (xy 224.732215 -138.416744) (xy 224.686857 -138.384293) (xy 224.646708 -138.345584)
			(xy 224.612622 -138.301441) (xy 224.585326 -138.252806) (xy 224.565403 -138.200715) (xy 224.553277 -138.146278)
			(xy 224.549206 -138.090656) (xy 223.895412 -138.090656) (xy 223.895412 -139.057455) (xy 226.046957 -139.057455)
			(xy 226.046957 -139.002945) (xy 226.054716 -138.948991) (xy 226.070074 -138.896689) (xy 226.09272 -138.847106)
			(xy 226.122192 -138.801251) (xy 226.15789 -138.760058) (xy 226.199088 -138.724364) (xy 226.244947 -138.694898)
			(xy 226.294532 -138.672258) (xy 226.346836 -138.656906) (xy 226.400791 -138.649154) (xy 226.428046 -138.648694)
			(xy 226.455415 -138.649193) (xy 226.509593 -138.657003) (xy 226.562095 -138.672485) (xy 226.611843 -138.695319)
			(xy 226.657811 -138.725036) (xy 226.678744 -138.742674) (xy 226.678998 -138.742928) (xy 226.686079 -138.748523)
			(xy 226.703 -138.754764) (xy 226.712018 -138.75512) (xy 226.779074 -138.75512) (xy 226.788089 -138.754746)
			(xy 226.805006 -138.74851) (xy 226.812094 -138.742928) (xy 226.812094 -138.742674) (xy 226.812348 -138.742674)
			(xy 226.833286 -138.725042) (xy 226.879257 -138.69533) (xy 226.929003 -138.672493) (xy 226.981503 -138.657)
			(xy 227.035677 -138.64917) (xy 227.063046 -138.648694) (xy 227.090295 -138.649179) (xy 227.144238 -138.656941)
			(xy 227.196528 -138.6723) (xy 227.246099 -138.694944) (xy 227.291944 -138.724412) (xy 227.333129 -138.760103)
			(xy 227.368816 -138.801293) (xy 227.398278 -138.847141) (xy 227.420916 -138.896715) (xy 227.436269 -138.949007)
			(xy 227.444024 -139.002951) (xy 227.444024 -139.057449) (xy 227.436269 -139.111393) (xy 227.420916 -139.163685)
			(xy 227.398278 -139.213259) (xy 227.368816 -139.259107) (xy 227.333129 -139.300297) (xy 227.291944 -139.335988)
			(xy 227.246099 -139.365456) (xy 227.196528 -139.3881) (xy 227.144238 -139.403459) (xy 227.090295 -139.411221)
			(xy 227.063046 -139.41171) (xy 227.035677 -139.411215) (xy 226.981499 -139.403403) (xy 226.928996 -139.387921)
			(xy 226.879249 -139.365086) (xy 226.833281 -139.335368) (xy 226.812348 -139.31773) (xy 226.812094 -139.317476)
			(xy 226.805015 -139.311878) (xy 226.788092 -139.305639) (xy 226.779074 -139.305284) (xy 226.712018 -139.305284)
			(xy 226.703002 -139.305653) (xy 226.686086 -139.311893) (xy 226.678998 -139.317476) (xy 226.678998 -139.31773)
			(xy 226.678744 -139.31773) (xy 226.65781 -139.335367) (xy 226.611837 -139.365078) (xy 226.56209 -139.387914)
			(xy 226.50959 -139.403405) (xy 226.455415 -139.411235) (xy 226.428046 -139.41171) (xy 226.400791 -139.411246)
			(xy 226.346836 -139.403494) (xy 226.294532 -139.388142) (xy 226.244947 -139.365502) (xy 226.199088 -139.336036)
			(xy 226.15789 -139.300342) (xy 226.122192 -139.259149) (xy 226.09272 -139.213294) (xy 226.070074 -139.163711)
			(xy 226.054716 -139.111409) (xy 226.046957 -139.057455) (xy 223.895412 -139.057455) (xy 223.895412 -139.196064)
			(xy 223.894929 -139.222153) (xy 223.886768 -139.273688) (xy 223.870642 -139.323311) (xy 223.846948 -139.369799)
			(xy 223.816271 -139.412005) (xy 223.79813 -139.43076) (xy 223.403098 -139.82573) (xy 231.704894 -139.82573)
			(xy 231.708965 -139.770108) (xy 231.721091 -139.715671) (xy 231.741014 -139.66358) (xy 231.76831 -139.614945)
			(xy 231.802396 -139.570802) (xy 231.842545 -139.532093) (xy 231.887903 -139.499642) (xy 231.937503 -139.474141)
			(xy 231.990287 -139.456134) (xy 232.04513 -139.446004) (xy 232.100864 -139.443967) (xy 232.156301 -139.450067)
			(xy 232.210258 -139.464173) (xy 232.261587 -139.485985) (xy 232.309193 -139.515039) (xy 232.352061 -139.550714)
			(xy 232.389278 -139.592251) (xy 232.420051 -139.638764) (xy 232.443723 -139.689261) (xy 232.459791 -139.742668)
			(xy 232.467911 -139.797844) (xy 232.46842 -139.82573) (xy 232.467911 -139.853616) (xy 232.459791 -139.908792)
			(xy 232.443723 -139.962199) (xy 232.420051 -140.012696) (xy 232.389278 -140.059209) (xy 232.352061 -140.100746)
			(xy 232.309193 -140.136421) (xy 232.261587 -140.165475) (xy 232.210258 -140.187287) (xy 232.156301 -140.201393)
			(xy 232.100864 -140.207493) (xy 232.04513 -140.205456) (xy 231.990287 -140.195326) (xy 231.937503 -140.177319)
			(xy 231.887903 -140.151818) (xy 231.842545 -140.119367) (xy 231.802396 -140.080658) (xy 231.76831 -140.036515)
			(xy 231.741014 -139.98788) (xy 231.721091 -139.935789) (xy 231.708965 -139.881352) (xy 231.704894 -139.82573)
			(xy 223.403098 -139.82573) (xy 222.17507 -141.053566) (xy 222.168238 -141.060974) (xy 222.160507 -141.079569)
			(xy 222.160482 -141.099707) (xy 222.163894 -141.109192) (xy 222.175578 -141.136878) (xy 222.180912 -141.140434)
			(xy 222.633286 -141.140434) (xy 222.634556 -141.140434) (xy 222.643065 -141.139897) (xy 222.659025 -141.133927)
			(xy 222.665798 -141.12875) (xy 222.672402 -141.122146) (xy 222.722186 -141.062456) (xy 222.725634 -141.058093)
			(xy 222.730763 -141.048229) (xy 222.732346 -141.042898) (xy 222.73514 -141.032484) (xy 222.733362 -141.021308)
			(xy 222.730643 -141.004933) (xy 222.72772 -140.971866) (xy 222.72752 -140.955268) (xy 222.728008 -140.92802)
			(xy 222.735768 -140.874078) (xy 222.751126 -140.82179) (xy 222.773768 -140.77222) (xy 222.803234 -140.726377)
			(xy 222.838924 -140.685193) (xy 222.880112 -140.649508) (xy 222.925959 -140.620047) (xy 222.975532 -140.59741)
			(xy 223.027821 -140.582059) (xy 223.081764 -140.574305) (xy 223.13626 -140.574307) (xy 223.190202 -140.582064)
			(xy 223.242491 -140.597419) (xy 223.292062 -140.620058) (xy 223.337907 -140.649522) (xy 223.379093 -140.68521)
			(xy 223.397629 -140.706602) (xy 224.801428 -140.706602) (xy 224.805499 -140.65098) (xy 224.817625 -140.596543)
			(xy 224.837548 -140.544452) (xy 224.864844 -140.495817) (xy 224.89893 -140.451674) (xy 224.939079 -140.412965)
			(xy 224.984437 -140.380514) (xy 225.034037 -140.355013) (xy 225.086821 -140.337006) (xy 225.141664 -140.326876)
			(xy 225.197398 -140.324839) (xy 225.252835 -140.330939) (xy 225.306792 -140.345045) (xy 225.358121 -140.366857)
			(xy 225.405727 -140.395911) (xy 225.448595 -140.431586) (xy 225.485812 -140.473123) (xy 225.516585 -140.519636)
			(xy 225.540257 -140.570133) (xy 225.556325 -140.62354) (xy 225.564445 -140.678716) (xy 225.564954 -140.706602)
			(xy 225.564445 -140.734488) (xy 225.556325 -140.789664) (xy 225.540257 -140.843071) (xy 225.516585 -140.893568)
			(xy 225.485812 -140.940081) (xy 225.448595 -140.981618) (xy 225.405727 -141.017293) (xy 225.358121 -141.046347)
			(xy 225.306792 -141.068159) (xy 225.252835 -141.082265) (xy 225.197398 -141.088365) (xy 225.141664 -141.086328)
			(xy 225.086821 -141.076198) (xy 225.034037 -141.058191) (xy 224.984437 -141.03269) (xy 224.939079 -141.000239)
			(xy 224.89893 -140.96153) (xy 224.864844 -140.917387) (xy 224.837548 -140.868752) (xy 224.817625 -140.816661)
			(xy 224.805499 -140.762224) (xy 224.801428 -140.706602) (xy 223.397629 -140.706602) (xy 223.41478 -140.726396)
			(xy 223.444244 -140.772241) (xy 223.466883 -140.821813) (xy 223.482237 -140.874102) (xy 223.489993 -140.928044)
			(xy 223.489994 -140.98254) (xy 223.48224 -141.036482) (xy 223.466888 -141.088772) (xy 223.444251 -141.138345)
			(xy 223.41479 -141.184191) (xy 223.379104 -141.225379) (xy 223.33792 -141.261068) (xy 223.292076 -141.290534)
			(xy 223.242506 -141.313176) (xy 223.190218 -141.328532) (xy 223.136276 -141.336292) (xy 223.109028 -141.336776)
			(xy 223.078852 -141.336162) (xy 223.01926 -141.326594) (xy 222.99041 -141.317726) (xy 222.989902 -141.317726)
			(xy 222.989394 -141.317472) (xy 222.983824 -141.315888) (xy 222.972282 -141.314991) (xy 222.966534 -141.315694)
			(xy 222.954596 -141.317472) (xy 222.877888 -141.373098) (xy 222.868506 -141.380711) (xy 222.857503 -141.402184)
			(xy 222.856806 -141.414246) (xy 222.856806 -141.768322) (xy 231.849166 -141.768322) (xy 231.853237 -141.7127)
			(xy 231.865363 -141.658263) (xy 231.885286 -141.606172) (xy 231.912582 -141.557537) (xy 231.946668 -141.513394)
			(xy 231.986817 -141.474685) (xy 232.032175 -141.442234) (xy 232.081775 -141.416733) (xy 232.134559 -141.398726)
			(xy 232.189402 -141.388596) (xy 232.245136 -141.386559) (xy 232.300573 -141.392659) (xy 232.35453 -141.406765)
			(xy 232.405859 -141.428577) (xy 232.453465 -141.457631) (xy 232.496333 -141.493306) (xy 232.53355 -141.534843)
			(xy 232.564323 -141.581356) (xy 232.587995 -141.631853) (xy 232.604063 -141.68526) (xy 232.612183 -141.740436)
			(xy 232.612692 -141.768322) (xy 232.612183 -141.796208) (xy 232.604063 -141.851384) (xy 232.587995 -141.904791)
			(xy 232.564323 -141.955288) (xy 232.53355 -142.001801) (xy 232.496333 -142.043338) (xy 232.453465 -142.079013)
			(xy 232.405859 -142.108067) (xy 232.35453 -142.129879) (xy 232.300573 -142.143985) (xy 232.245136 -142.150085)
			(xy 232.189402 -142.148048) (xy 232.134559 -142.137918) (xy 232.081775 -142.119911) (xy 232.032175 -142.09441)
			(xy 231.986817 -142.061959) (xy 231.946668 -142.02325) (xy 231.912582 -141.979107) (xy 231.885286 -141.930472)
			(xy 231.865363 -141.878381) (xy 231.853237 -141.823944) (xy 231.849166 -141.768322) (xy 222.856806 -141.768322)
			(xy 222.856806 -142.244826) (xy 228.06736 -142.244826) (xy 228.071431 -142.189204) (xy 228.083557 -142.134767)
			(xy 228.10348 -142.082676) (xy 228.130776 -142.034041) (xy 228.164862 -141.989898) (xy 228.205011 -141.951189)
			(xy 228.250369 -141.918738) (xy 228.299969 -141.893237) (xy 228.352753 -141.87523) (xy 228.407596 -141.8651)
			(xy 228.46333 -141.863063) (xy 228.518767 -141.869163) (xy 228.572724 -141.883269) (xy 228.624053 -141.905081)
			(xy 228.671659 -141.934135) (xy 228.714527 -141.96981) (xy 228.751744 -142.011347) (xy 228.782517 -142.05786)
			(xy 228.806189 -142.108357) (xy 228.822257 -142.161764) (xy 228.830377 -142.21694) (xy 228.830886 -142.244826)
			(xy 228.830399 -142.271496) (xy 230.464866 -142.271496) (xy 230.468937 -142.215874) (xy 230.481063 -142.161437)
			(xy 230.500986 -142.109346) (xy 230.528282 -142.060711) (xy 230.562368 -142.016568) (xy 230.602517 -141.977859)
			(xy 230.647875 -141.945408) (xy 230.697475 -141.919907) (xy 230.750259 -141.9019) (xy 230.805102 -141.89177)
			(xy 230.860836 -141.889733) (xy 230.916273 -141.895833) (xy 230.97023 -141.909939) (xy 231.021559 -141.931751)
			(xy 231.069165 -141.960805) (xy 231.112033 -141.99648) (xy 231.14925 -142.038017) (xy 231.180023 -142.08453)
			(xy 231.203695 -142.135027) (xy 231.219763 -142.188434) (xy 231.227883 -142.24361) (xy 231.228392 -142.271496)
			(xy 231.227883 -142.299382) (xy 231.219763 -142.354558) (xy 231.203695 -142.407965) (xy 231.180023 -142.458462)
			(xy 231.14925 -142.504975) (xy 231.112033 -142.546512) (xy 231.069165 -142.582187) (xy 231.021559 -142.611241)
			(xy 230.97023 -142.633053) (xy 230.940551 -142.640812) (xy 234.22305 -142.640812) (xy 234.227121 -142.58519)
			(xy 234.239247 -142.530753) (xy 234.25917 -142.478662) (xy 234.286466 -142.430027) (xy 234.320552 -142.385884)
			(xy 234.360701 -142.347175) (xy 234.406059 -142.314724) (xy 234.455659 -142.289223) (xy 234.508443 -142.271216)
			(xy 234.563286 -142.261086) (xy 234.61902 -142.259049) (xy 234.674457 -142.265149) (xy 234.728414 -142.279255)
			(xy 234.779743 -142.301067) (xy 234.827349 -142.330121) (xy 234.870217 -142.365796) (xy 234.907434 -142.407333)
			(xy 234.938207 -142.453846) (xy 234.961879 -142.504343) (xy 234.977947 -142.55775) (xy 234.986067 -142.612926)
			(xy 234.986576 -142.640812) (xy 234.986067 -142.668698) (xy 234.977947 -142.723874) (xy 234.961879 -142.777281)
			(xy 234.938207 -142.827778) (xy 234.907434 -142.874291) (xy 234.870217 -142.915828) (xy 234.827349 -142.951503)
			(xy 234.779743 -142.980557) (xy 234.728414 -143.002369) (xy 234.674457 -143.016475) (xy 234.61902 -143.022575)
			(xy 234.563286 -143.020538) (xy 234.508443 -143.010408) (xy 234.455659 -142.992401) (xy 234.406059 -142.9669)
			(xy 234.360701 -142.934449) (xy 234.320552 -142.89574) (xy 234.286466 -142.851597) (xy 234.25917 -142.802962)
			(xy 234.239247 -142.750871) (xy 234.227121 -142.696434) (xy 234.22305 -142.640812) (xy 230.940551 -142.640812)
			(xy 230.916273 -142.647159) (xy 230.860836 -142.653259) (xy 230.805102 -142.651222) (xy 230.750259 -142.641092)
			(xy 230.697475 -142.623085) (xy 230.647875 -142.597584) (xy 230.602517 -142.565133) (xy 230.562368 -142.526424)
			(xy 230.528282 -142.482281) (xy 230.500986 -142.433646) (xy 230.481063 -142.381555) (xy 230.468937 -142.327118)
			(xy 230.464866 -142.271496) (xy 228.830399 -142.271496) (xy 228.830377 -142.272712) (xy 228.822257 -142.327888)
			(xy 228.806189 -142.381295) (xy 228.782517 -142.431792) (xy 228.751744 -142.478305) (xy 228.714527 -142.519842)
			(xy 228.671659 -142.555517) (xy 228.624053 -142.584571) (xy 228.572724 -142.606383) (xy 228.518767 -142.620489)
			(xy 228.46333 -142.626589) (xy 228.407596 -142.624552) (xy 228.352753 -142.614422) (xy 228.299969 -142.596415)
			(xy 228.250369 -142.570914) (xy 228.205011 -142.538463) (xy 228.164862 -142.499754) (xy 228.130776 -142.455611)
			(xy 228.10348 -142.406976) (xy 228.083557 -142.354885) (xy 228.071431 -142.300448) (xy 228.06736 -142.244826)
			(xy 222.856806 -142.244826) (xy 222.856806 -142.700756) (xy 222.856373 -142.710822) (xy 222.848645 -142.729412)
			(xy 222.84182 -142.736824) (xy 222.209106 -143.369538) (xy 222.206403 -143.372391) (xy 222.201817 -143.378773)
			(xy 222.199962 -143.382238) (xy 222.197375 -143.387664) (xy 222.194547 -143.399344) (xy 222.194374 -143.405352)
			(xy 222.194374 -143.945102) (xy 225.0219 -143.945102) (xy 225.025971 -143.88948) (xy 225.038097 -143.835043)
			(xy 225.05802 -143.782952) (xy 225.085316 -143.734317) (xy 225.119402 -143.690174) (xy 225.159551 -143.651465)
			(xy 225.204909 -143.619014) (xy 225.254509 -143.593513) (xy 225.307293 -143.575506) (xy 225.362136 -143.565376)
			(xy 225.41787 -143.563339) (xy 225.473307 -143.569439) (xy 225.527264 -143.583545) (xy 225.578593 -143.605357)
			(xy 225.626199 -143.634411) (xy 225.669067 -143.670086) (xy 225.706284 -143.711623) (xy 225.737057 -143.758136)
			(xy 225.760729 -143.808633) (xy 225.776797 -143.86204) (xy 225.784917 -143.917216) (xy 225.785426 -143.945102)
			(xy 225.784917 -143.972988) (xy 225.776797 -144.028164) (xy 225.760729 -144.081571) (xy 225.737057 -144.132068)
			(xy 225.706284 -144.178581) (xy 225.669067 -144.220118) (xy 225.626199 -144.255793) (xy 225.578593 -144.284847)
			(xy 225.527264 -144.306659) (xy 225.473307 -144.320765) (xy 225.41787 -144.326865) (xy 225.362136 -144.324828)
			(xy 225.307293 -144.314698) (xy 225.254509 -144.296691) (xy 225.204909 -144.27119) (xy 225.159551 -144.238739)
			(xy 225.119402 -144.20003) (xy 225.085316 -144.155887) (xy 225.05802 -144.107252) (xy 225.038097 -144.055161)
			(xy 225.025971 -144.000724) (xy 225.0219 -143.945102) (xy 222.194374 -143.945102) (xy 222.194374 -144.672812)
			(xy 234.175044 -144.672812) (xy 234.179115 -144.61719) (xy 234.191241 -144.562753) (xy 234.211164 -144.510662)
			(xy 234.23846 -144.462027) (xy 234.272546 -144.417884) (xy 234.312695 -144.379175) (xy 234.358053 -144.346724)
			(xy 234.407653 -144.321223) (xy 234.460437 -144.303216) (xy 234.51528 -144.293086) (xy 234.571014 -144.291049)
			(xy 234.626451 -144.297149) (xy 234.680408 -144.311255) (xy 234.731737 -144.333067) (xy 234.779343 -144.362121)
			(xy 234.822211 -144.397796) (xy 234.859428 -144.439333) (xy 234.890201 -144.485846) (xy 234.913873 -144.536343)
			(xy 234.929941 -144.58975) (xy 234.938061 -144.644926) (xy 234.93857 -144.672812) (xy 234.938061 -144.700698)
			(xy 234.929941 -144.755874) (xy 234.913873 -144.809281) (xy 234.890201 -144.859778) (xy 234.859428 -144.906291)
			(xy 234.822211 -144.947828) (xy 234.779343 -144.983503) (xy 234.731737 -145.012557) (xy 234.680408 -145.034369)
			(xy 234.626451 -145.048475) (xy 234.571014 -145.054575) (xy 234.51528 -145.052538) (xy 234.460437 -145.042408)
			(xy 234.407653 -145.024401) (xy 234.358053 -144.9989) (xy 234.312695 -144.966449) (xy 234.272546 -144.92774)
			(xy 234.23846 -144.883597) (xy 234.211164 -144.834962) (xy 234.191241 -144.782871) (xy 234.179115 -144.728434)
			(xy 234.175044 -144.672812) (xy 222.194374 -144.672812) (xy 222.194374 -145.140426) (xy 222.363028 -145.140426)
			(xy 222.367099 -145.084804) (xy 222.379225 -145.030367) (xy 222.399148 -144.978276) (xy 222.426444 -144.929641)
			(xy 222.46053 -144.885498) (xy 222.500679 -144.846789) (xy 222.546037 -144.814338) (xy 222.595637 -144.788837)
			(xy 222.648421 -144.77083) (xy 222.703264 -144.7607) (xy 222.758998 -144.758663) (xy 222.814435 -144.764763)
			(xy 222.868392 -144.778869) (xy 222.919721 -144.800681) (xy 222.967327 -144.829735) (xy 223.010195 -144.86541)
			(xy 223.047412 -144.906947) (xy 223.078185 -144.95346) (xy 223.101857 -145.003957) (xy 223.117925 -145.057364)
			(xy 223.126045 -145.11254) (xy 223.126554 -145.140426) (xy 223.126045 -145.168312) (xy 223.117925 -145.223488)
			(xy 223.101857 -145.276895) (xy 223.078185 -145.327392) (xy 223.047412 -145.373905) (xy 223.010195 -145.415442)
			(xy 222.967327 -145.451117) (xy 222.919721 -145.480171) (xy 222.868392 -145.501983) (xy 222.814435 -145.516089)
			(xy 222.758998 -145.522189) (xy 222.703264 -145.520152) (xy 222.648421 -145.510022) (xy 222.595637 -145.492015)
			(xy 222.546037 -145.466514) (xy 222.500679 -145.434063) (xy 222.46053 -145.395354) (xy 222.426444 -145.351211)
			(xy 222.399148 -145.302576) (xy 222.379225 -145.250485) (xy 222.367099 -145.196048) (xy 222.363028 -145.140426)
			(xy 222.194374 -145.140426) (xy 222.194374 -146.508216) (xy 222.194916 -146.518575) (xy 222.203172 -146.537583)
			(xy 222.210376 -146.545046) (xy 222.271844 -146.603212) (xy 222.291148 -146.61007) (xy 222.301816 -146.609562)
			(xy 222.32366 -146.609054) (xy 222.350917 -146.609514) (xy 222.404878 -146.617267) (xy 222.457186 -146.632621)
			(xy 222.487902 -146.646646) (xy 223.425256 -146.646646) (xy 223.429327 -146.591024) (xy 223.441453 -146.536587)
			(xy 223.461376 -146.484496) (xy 223.488672 -146.435861) (xy 223.522758 -146.391718) (xy 223.562907 -146.353009)
			(xy 223.608265 -146.320558) (xy 223.657865 -146.295057) (xy 223.710649 -146.27705) (xy 223.765492 -146.26692)
			(xy 223.821226 -146.264883) (xy 223.876663 -146.270983) (xy 223.93062 -146.285089) (xy 223.981949 -146.306901)
			(xy 224.029555 -146.335955) (xy 224.072423 -146.37163) (xy 224.10964 -146.413167) (xy 224.140413 -146.45968)
			(xy 224.164085 -146.510177) (xy 224.180153 -146.563584) (xy 224.188273 -146.61876) (xy 224.188782 -146.646646)
			(xy 224.188273 -146.674532) (xy 224.180153 -146.729708) (xy 224.164085 -146.783115) (xy 224.140413 -146.833612)
			(xy 224.10964 -146.880125) (xy 224.072423 -146.921662) (xy 224.029555 -146.957337) (xy 223.981949 -146.986391)
			(xy 223.93062 -147.008203) (xy 223.876663 -147.022309) (xy 223.821226 -147.028409) (xy 223.765492 -147.026372)
			(xy 223.710649 -147.016242) (xy 223.657865 -146.998235) (xy 223.608265 -146.972734) (xy 223.562907 -146.940283)
			(xy 223.522758 -146.901574) (xy 223.488672 -146.857431) (xy 223.461376 -146.808796) (xy 223.441453 -146.756705)
			(xy 223.429327 -146.702268) (xy 223.425256 -146.646646) (xy 222.487902 -146.646646) (xy 222.506776 -146.655264)
			(xy 222.552639 -146.684734) (xy 222.593841 -146.720431) (xy 222.629542 -146.761629) (xy 222.659017 -146.807489)
			(xy 222.681665 -146.857076) (xy 222.697024 -146.909383) (xy 222.704783 -146.963343) (xy 222.704783 -147.017857)
			(xy 222.697024 -147.071817) (xy 222.681665 -147.124124) (xy 222.659017 -147.173711) (xy 222.649031 -147.189248)
			(xy 233.05469 -147.189248) (xy 233.05469 -147.134752) (xy 233.062445 -147.08081) (xy 233.077797 -147.028521)
			(xy 233.100434 -146.978948) (xy 233.129895 -146.933102) (xy 233.16558 -146.891914) (xy 233.206763 -146.856224)
			(xy 233.252606 -146.826757) (xy 233.302176 -146.804114) (xy 233.354463 -146.788755) (xy 233.408404 -146.780994)
			(xy 233.435652 -146.780504) (xy 233.467273 -146.781113) (xy 233.529646 -146.791567) (xy 233.589436 -146.812179)
			(xy 233.617516 -146.826732) (xy 233.625869 -146.830746) (xy 233.644237 -146.833091) (xy 233.65333 -146.831304)
			(xy 233.728514 -146.813524) (xy 233.744262 -146.802856) (xy 233.749342 -146.795236) (xy 233.764731 -146.773932)
			(xy 233.80036 -146.735302) (xy 233.840952 -146.701925) (xy 233.885739 -146.674433) (xy 233.933874 -146.653344)
			(xy 233.984447 -146.639058) (xy 234.036502 -146.631846) (xy 234.062778 -146.631406) (xy 234.090033 -146.631839)
			(xy 234.143988 -146.639594) (xy 234.196291 -146.654949) (xy 234.245876 -146.677591) (xy 234.291733 -146.707059)
			(xy 234.33293 -146.742754) (xy 234.368627 -146.783949) (xy 234.398099 -146.829805) (xy 234.420743 -146.879389)
			(xy 234.436101 -146.93169) (xy 234.443859 -146.985645) (xy 234.443859 -147.040155) (xy 234.436101 -147.09411)
			(xy 234.420743 -147.146411) (xy 234.398099 -147.195995) (xy 234.368627 -147.241851) (xy 234.33293 -147.283046)
			(xy 234.291733 -147.318741) (xy 234.245876 -147.348209) (xy 234.196291 -147.370851) (xy 234.143988 -147.386206)
			(xy 234.090033 -147.393961) (xy 234.062778 -147.394422) (xy 234.031157 -147.393809) (xy 233.968784 -147.383359)
			(xy 233.908994 -147.362748) (xy 233.880914 -147.348194) (xy 233.872555 -147.344195) (xy 233.854192 -147.34184)
			(xy 233.8451 -147.343622) (xy 233.769916 -147.361402) (xy 233.754168 -147.37207) (xy 233.749088 -147.37969)
			(xy 233.733751 -147.401032) (xy 233.698112 -147.43966) (xy 233.657511 -147.473033) (xy 233.612715 -147.500521)
			(xy 233.564572 -147.521603) (xy 233.513991 -147.535881) (xy 233.461931 -147.543085) (xy 233.435652 -147.54352)
			(xy 233.408404 -147.543006) (xy 233.354463 -147.535245) (xy 233.302176 -147.519886) (xy 233.252606 -147.497243)
			(xy 233.206763 -147.467776) (xy 233.16558 -147.432086) (xy 233.129895 -147.390898) (xy 233.100434 -147.345052)
			(xy 233.077797 -147.295479) (xy 233.062445 -147.24319) (xy 233.05469 -147.189248) (xy 222.649031 -147.189248)
			(xy 222.629542 -147.219571) (xy 222.593841 -147.260769) (xy 222.552639 -147.296466) (xy 222.506776 -147.325936)
			(xy 222.457186 -147.348579) (xy 222.404878 -147.363933) (xy 222.350917 -147.371686) (xy 222.32366 -147.37207)
			(xy 222.301816 -147.371562) (xy 222.291148 -147.371054) (xy 222.271844 -147.377912) (xy 222.210376 -147.436078)
			(xy 222.203143 -147.443524) (xy 222.194869 -147.46254) (xy 222.194374 -147.472908) (xy 222.194374 -147.720812)
			(xy 234.212128 -147.720812) (xy 234.216199 -147.66519) (xy 234.228325 -147.610753) (xy 234.248248 -147.558662)
			(xy 234.275544 -147.510027) (xy 234.30963 -147.465884) (xy 234.349779 -147.427175) (xy 234.395137 -147.394724)
			(xy 234.444737 -147.369223) (xy 234.497521 -147.351216) (xy 234.552364 -147.341086) (xy 234.608098 -147.339049)
			(xy 234.663535 -147.345149) (xy 234.717492 -147.359255) (xy 234.768821 -147.381067) (xy 234.816427 -147.410121)
			(xy 234.859295 -147.445796) (xy 234.896512 -147.487333) (xy 234.927285 -147.533846) (xy 234.950957 -147.584343)
			(xy 234.967025 -147.63775) (xy 234.975145 -147.692926) (xy 234.975654 -147.720812) (xy 234.975145 -147.748698)
			(xy 234.967025 -147.803874) (xy 234.950957 -147.857281) (xy 234.927285 -147.907778) (xy 234.896512 -147.954291)
			(xy 234.859295 -147.995828) (xy 234.816427 -148.031503) (xy 234.768821 -148.060557) (xy 234.717492 -148.082369)
			(xy 234.663535 -148.096475) (xy 234.608098 -148.102575) (xy 234.552364 -148.100538) (xy 234.497521 -148.090408)
			(xy 234.444737 -148.072401) (xy 234.395137 -148.0469) (xy 234.349779 -148.014449) (xy 234.30963 -147.97574)
			(xy 234.275544 -147.931597) (xy 234.248248 -147.882962) (xy 234.228325 -147.830871) (xy 234.216199 -147.776434)
			(xy 234.212128 -147.720812) (xy 222.194374 -147.720812) (xy 222.194374 -149.403308) (xy 223.512886 -149.403308)
			(xy 223.516957 -149.347686) (xy 223.529083 -149.293249) (xy 223.549006 -149.241158) (xy 223.576302 -149.192523)
			(xy 223.610388 -149.14838) (xy 223.650537 -149.109671) (xy 223.695895 -149.07722) (xy 223.745495 -149.051719)
			(xy 223.798279 -149.033712) (xy 223.853122 -149.023582) (xy 223.908856 -149.021545) (xy 223.964293 -149.027645)
			(xy 224.01825 -149.041751) (xy 224.069579 -149.063563) (xy 224.117185 -149.092617) (xy 224.160053 -149.128292)
			(xy 224.19727 -149.169829) (xy 224.228043 -149.216342) (xy 224.251715 -149.266839) (xy 224.258038 -149.287857)
			(xy 233.065215 -149.287857) (xy 233.065215 -149.233343) (xy 233.072973 -149.179385) (xy 233.088332 -149.12708)
			(xy 233.110978 -149.077493) (xy 233.140451 -149.031634) (xy 233.176151 -148.990437) (xy 233.21735 -148.954739)
			(xy 233.263211 -148.925269) (xy 233.312799 -148.902625) (xy 233.365105 -148.887269) (xy 233.419063 -148.879514)
			(xy 233.44632 -148.879052) (xy 233.473193 -148.879488) (xy 233.526406 -148.887047) (xy 233.578032 -148.901998)
			(xy 233.627049 -148.924046) (xy 233.672487 -148.952753) (xy 233.713447 -148.987553) (xy 233.749118 -149.027757)
			(xy 233.778795 -149.072568) (xy 233.80189 -149.1211) (xy 233.817946 -149.172393) (xy 233.822748 -149.198838)
			(xy 233.824272 -149.208744) (xy 233.834686 -149.225508) (xy 233.899964 -149.273514) (xy 233.908092 -149.278969)
			(xy 233.927045 -149.283799) (xy 233.936794 -149.282912) (xy 233.937048 -149.282912) (xy 233.949938 -149.281253)
			(xy 233.975868 -149.279475) (xy 233.988864 -149.279356) (xy 233.989118 -149.279356) (xy 234.016366 -149.279915)
			(xy 234.070306 -149.287673) (xy 234.122594 -149.303028) (xy 234.172164 -149.325668) (xy 234.218008 -149.355132)
			(xy 234.259192 -149.390821) (xy 234.294878 -149.432006) (xy 234.32434 -149.477852) (xy 234.346978 -149.527423)
			(xy 234.362331 -149.579711) (xy 234.370086 -149.633652) (xy 234.370086 -149.688148) (xy 234.362331 -149.742089)
			(xy 234.346978 -149.794377) (xy 234.32434 -149.843948) (xy 234.294878 -149.889794) (xy 234.259192 -149.930979)
			(xy 234.218008 -149.966668) (xy 234.172164 -149.996131) (xy 234.122594 -150.018772) (xy 234.070306 -150.034127)
			(xy 234.016366 -150.041885) (xy 233.989118 -150.042372) (xy 233.962247 -150.041881) (xy 233.909037 -150.034328)
			(xy 233.857413 -150.019383) (xy 233.808398 -149.997342) (xy 233.762961 -149.96864) (xy 233.722001 -149.933846)
			(xy 233.686329 -149.893649) (xy 233.65665 -149.848843) (xy 233.633553 -149.800316) (xy 233.617494 -149.749029)
			(xy 233.61269 -149.722586) (xy 233.611166 -149.71268) (xy 233.600752 -149.695916) (xy 233.535474 -149.64791)
			(xy 233.527334 -149.642476) (xy 233.508391 -149.637632) (xy 233.498644 -149.638512) (xy 233.49839 -149.638512)
			(xy 233.4855 -149.640167) (xy 233.45957 -149.641948) (xy 233.446574 -149.642068) (xy 233.44632 -149.642068)
			(xy 233.419063 -149.641686) (xy 233.365105 -149.633931) (xy 233.312799 -149.618575) (xy 233.263211 -149.595931)
			(xy 233.21735 -149.566461) (xy 233.176151 -149.530763) (xy 233.140451 -149.489566) (xy 233.110978 -149.443707)
			(xy 233.088332 -149.39412) (xy 233.072973 -149.341815) (xy 233.065215 -149.287857) (xy 224.258038 -149.287857)
			(xy 224.267783 -149.320246) (xy 224.275903 -149.375422) (xy 224.276412 -149.403308) (xy 224.275903 -149.431194)
			(xy 224.267783 -149.48637) (xy 224.251715 -149.539777) (xy 224.228043 -149.590274) (xy 224.19727 -149.636787)
			(xy 224.160053 -149.678324) (xy 224.117185 -149.713999) (xy 224.069579 -149.743053) (xy 224.01825 -149.764865)
			(xy 223.964293 -149.778971) (xy 223.908856 -149.785071) (xy 223.853122 -149.783034) (xy 223.798279 -149.772904)
			(xy 223.745495 -149.754897) (xy 223.695895 -149.729396) (xy 223.650537 -149.696945) (xy 223.610388 -149.658236)
			(xy 223.576302 -149.614093) (xy 223.549006 -149.565458) (xy 223.529083 -149.513367) (xy 223.516957 -149.45893)
			(xy 223.512886 -149.403308) (xy 222.194374 -149.403308) (xy 222.194374 -151.664162) (xy 231.773474 -151.664162)
			(xy 231.777545 -151.60854) (xy 231.789671 -151.554103) (xy 231.809594 -151.502012) (xy 231.83689 -151.453377)
			(xy 231.870976 -151.409234) (xy 231.911125 -151.370525) (xy 231.956483 -151.338074) (xy 232.006083 -151.312573)
			(xy 232.058867 -151.294566) (xy 232.11371 -151.284436) (xy 232.169444 -151.282399) (xy 232.224881 -151.288499)
			(xy 232.278838 -151.302605) (xy 232.330167 -151.324417) (xy 232.377773 -151.353471) (xy 232.420641 -151.389146)
			(xy 232.457858 -151.430683) (xy 232.488631 -151.477196) (xy 232.512303 -151.527693) (xy 232.528371 -151.5811)
			(xy 232.536491 -151.636276) (xy 232.537 -151.664162) (xy 232.536491 -151.692048) (xy 232.528371 -151.747224)
			(xy 232.512303 -151.800631) (xy 232.488631 -151.851128) (xy 232.457858 -151.897641) (xy 232.420641 -151.939178)
			(xy 232.377773 -151.974853) (xy 232.330167 -152.003907) (xy 232.278838 -152.025719) (xy 232.224881 -152.039825)
			(xy 232.169444 -152.045925) (xy 232.11371 -152.043888) (xy 232.058867 -152.033758) (xy 232.006083 -152.015751)
			(xy 231.956483 -151.99025) (xy 231.911125 -151.957799) (xy 231.870976 -151.91909) (xy 231.83689 -151.874947)
			(xy 231.809594 -151.826312) (xy 231.789671 -151.774221) (xy 231.777545 -151.719784) (xy 231.773474 -151.664162)
			(xy 222.194374 -151.664162) (xy 222.194374 -152.412446) (xy 226.102924 -152.412446) (xy 226.106995 -152.356824)
			(xy 226.119121 -152.302387) (xy 226.139044 -152.250296) (xy 226.16634 -152.201661) (xy 226.200426 -152.157518)
			(xy 226.240575 -152.118809) (xy 226.285933 -152.086358) (xy 226.335533 -152.060857) (xy 226.388317 -152.04285)
			(xy 226.44316 -152.03272) (xy 226.498894 -152.030683) (xy 226.554331 -152.036783) (xy 226.608288 -152.050889)
			(xy 226.659617 -152.072701) (xy 226.707223 -152.101755) (xy 226.750091 -152.13743) (xy 226.787308 -152.178967)
			(xy 226.818081 -152.22548) (xy 226.841753 -152.275977) (xy 226.857821 -152.329384) (xy 226.864139 -152.372314)
			(xy 227.76256 -152.372314) (xy 227.766631 -152.316692) (xy 227.778757 -152.262255) (xy 227.79868 -152.210164)
			(xy 227.825976 -152.161529) (xy 227.860062 -152.117386) (xy 227.900211 -152.078677) (xy 227.945569 -152.046226)
			(xy 227.995169 -152.020725) (xy 228.047953 -152.002718) (xy 228.102796 -151.992588) (xy 228.15853 -151.990551)
			(xy 228.213967 -151.996651) (xy 228.267924 -152.010757) (xy 228.319253 -152.032569) (xy 228.366859 -152.061623)
			(xy 228.38462 -152.076404) (xy 230.958388 -152.076404) (xy 230.962459 -152.020782) (xy 230.974585 -151.966345)
			(xy 230.994508 -151.914254) (xy 231.021804 -151.865619) (xy 231.05589 -151.821476) (xy 231.096039 -151.782767)
			(xy 231.141397 -151.750316) (xy 231.190997 -151.724815) (xy 231.243781 -151.706808) (xy 231.298624 -151.696678)
			(xy 231.354358 -151.694641) (xy 231.409795 -151.700741) (xy 231.463752 -151.714847) (xy 231.515081 -151.736659)
			(xy 231.562687 -151.765713) (xy 231.605555 -151.801388) (xy 231.642772 -151.842925) (xy 231.673545 -151.889438)
			(xy 231.697217 -151.939935) (xy 231.713285 -151.993342) (xy 231.721405 -152.048518) (xy 231.721914 -152.076404)
			(xy 231.721405 -152.10429) (xy 231.713285 -152.159466) (xy 231.697217 -152.212873) (xy 231.673545 -152.26337)
			(xy 231.642772 -152.309883) (xy 231.605555 -152.35142) (xy 231.562687 -152.387095) (xy 231.515081 -152.416149)
			(xy 231.463752 -152.437961) (xy 231.409795 -152.452067) (xy 231.354358 -152.458167) (xy 231.298624 -152.45613)
			(xy 231.243781 -152.446) (xy 231.190997 -152.427993) (xy 231.141397 -152.402492) (xy 231.096039 -152.370041)
			(xy 231.05589 -152.331332) (xy 231.021804 -152.287189) (xy 230.994508 -152.238554) (xy 230.974585 -152.186463)
			(xy 230.962459 -152.132026) (xy 230.958388 -152.076404) (xy 228.38462 -152.076404) (xy 228.409727 -152.097298)
			(xy 228.446944 -152.138835) (xy 228.477717 -152.185348) (xy 228.501389 -152.235845) (xy 228.517457 -152.289252)
			(xy 228.525577 -152.344428) (xy 228.526086 -152.372314) (xy 228.525577 -152.4002) (xy 228.517457 -152.455376)
			(xy 228.501389 -152.508783) (xy 228.477717 -152.55928) (xy 228.446944 -152.605793) (xy 228.409727 -152.64733)
			(xy 228.366859 -152.683005) (xy 228.319253 -152.712059) (xy 228.267924 -152.733871) (xy 228.213967 -152.747977)
			(xy 228.15853 -152.754077) (xy 228.102796 -152.75204) (xy 228.047953 -152.74191) (xy 227.995169 -152.723903)
			(xy 227.945569 -152.698402) (xy 227.900211 -152.665951) (xy 227.860062 -152.627242) (xy 227.825976 -152.583099)
			(xy 227.79868 -152.534464) (xy 227.778757 -152.482373) (xy 227.766631 -152.427936) (xy 227.76256 -152.372314)
			(xy 226.864139 -152.372314) (xy 226.865941 -152.38456) (xy 226.86645 -152.412446) (xy 226.865941 -152.440332)
			(xy 226.857821 -152.495508) (xy 226.841753 -152.548915) (xy 226.818081 -152.599412) (xy 226.787308 -152.645925)
			(xy 226.750091 -152.687462) (xy 226.707223 -152.723137) (xy 226.659617 -152.752191) (xy 226.608288 -152.774003)
			(xy 226.554331 -152.788109) (xy 226.498894 -152.794209) (xy 226.44316 -152.792172) (xy 226.388317 -152.782042)
			(xy 226.335533 -152.764035) (xy 226.285933 -152.738534) (xy 226.240575 -152.706083) (xy 226.200426 -152.667374)
			(xy 226.16634 -152.623231) (xy 226.139044 -152.574596) (xy 226.119121 -152.522505) (xy 226.106995 -152.468068)
			(xy 226.102924 -152.412446) (xy 222.194374 -152.412446) (xy 222.194374 -153.295096) (xy 222.19478 -153.304097)
			(xy 222.201093 -153.320961) (xy 222.212838 -153.33461) (xy 222.220536 -153.339292) (xy 222.304864 -153.380694)
			(xy 222.311375 -153.383625) (xy 222.325433 -153.386088) (xy 222.33255 -153.38552) (xy 222.339433 -153.384589)
			(xy 222.352328 -153.379438) (xy 222.35795 -153.37536) (xy 222.358458 -153.375106) (xy 222.378642 -153.359859)
			(xy 222.422272 -153.33426) (xy 222.468904 -153.314659) (xy 222.51772 -153.301399) (xy 222.567862 -153.294714)
			(xy 222.593154 -153.294334) (xy 222.620406 -153.294794) (xy 222.674356 -153.302545) (xy 222.726654 -153.317895)
			(xy 222.776234 -153.340533) (xy 222.822088 -153.369996) (xy 222.863282 -153.405686) (xy 222.898976 -153.446875)
			(xy 222.928445 -153.492726) (xy 222.951089 -153.542303) (xy 222.966445 -153.594599) (xy 222.974203 -153.648548)
			(xy 222.974203 -153.703052) (xy 222.966445 -153.757001) (xy 222.951089 -153.809297) (xy 222.928445 -153.858874)
			(xy 222.898976 -153.904725) (xy 222.863282 -153.945914) (xy 222.822088 -153.981604) (xy 222.776234 -154.011067)
			(xy 222.726654 -154.033705) (xy 222.674356 -154.049055) (xy 222.620406 -154.056806) (xy 222.593154 -154.05735)
			(xy 222.567898 -154.056938) (xy 222.51783 -154.050269) (xy 222.469078 -154.037054) (xy 222.422495 -154.017523)
			(xy 222.378897 -153.992018) (xy 222.358712 -153.976832) (xy 222.358204 -153.976324) (xy 222.35795 -153.976324)
			(xy 222.352289 -153.972315) (xy 222.339415 -153.967163) (xy 222.33255 -153.966164) (xy 222.325434 -153.965651)
			(xy 222.31138 -153.968086) (xy 222.304864 -153.97099) (xy 222.220536 -154.012392) (xy 222.212828 -154.017066)
			(xy 222.201061 -154.030708) (xy 222.194748 -154.047582) (xy 222.194374 -154.056588) (xy 222.194374 -154.184096)
			(xy 222.19478 -154.193097) (xy 222.201093 -154.209961) (xy 222.212838 -154.22361) (xy 222.220536 -154.228292)
			(xy 222.304864 -154.269694) (xy 222.311375 -154.272625) (xy 222.325433 -154.275088) (xy 222.33255 -154.27452)
			(xy 222.339433 -154.273589) (xy 222.352328 -154.268438) (xy 222.35795 -154.26436) (xy 222.358458 -154.264106)
			(xy 222.378642 -154.248859) (xy 222.422272 -154.22326) (xy 222.468904 -154.203659) (xy 222.51772 -154.190399)
			(xy 222.567862 -154.183714) (xy 222.593154 -154.183334) (xy 222.620406 -154.183794) (xy 222.674356 -154.191545)
			(xy 222.726654 -154.206895) (xy 222.776234 -154.229533) (xy 222.822088 -154.258996) (xy 222.863282 -154.294686)
			(xy 222.898976 -154.335875) (xy 222.928445 -154.381726) (xy 222.951089 -154.431303) (xy 222.966445 -154.483599)
			(xy 222.974203 -154.537548) (xy 222.974203 -154.592052) (xy 222.966445 -154.646001) (xy 222.951089 -154.698297)
			(xy 222.928445 -154.747874) (xy 222.898976 -154.793725) (xy 222.863282 -154.834914) (xy 222.831114 -154.862784)
			(xy 227.184964 -154.862784) (xy 227.189035 -154.807162) (xy 227.201161 -154.752725) (xy 227.221084 -154.700634)
			(xy 227.24838 -154.651999) (xy 227.282466 -154.607856) (xy 227.322615 -154.569147) (xy 227.367973 -154.536696)
			(xy 227.417573 -154.511195) (xy 227.470357 -154.493188) (xy 227.5252 -154.483058) (xy 227.580934 -154.481021)
			(xy 227.636371 -154.487121) (xy 227.690328 -154.501227) (xy 227.741657 -154.523039) (xy 227.789263 -154.552093)
			(xy 227.832131 -154.587768) (xy 227.869348 -154.629305) (xy 227.900121 -154.675818) (xy 227.923793 -154.726315)
			(xy 227.939861 -154.779722) (xy 227.947981 -154.834898) (xy 227.94849 -154.862784) (xy 227.947981 -154.89067)
			(xy 227.939861 -154.945846) (xy 227.923793 -154.999253) (xy 227.900121 -155.04975) (xy 227.869348 -155.096263)
			(xy 227.832131 -155.1378) (xy 227.789263 -155.173475) (xy 227.741657 -155.202529) (xy 227.690328 -155.224341)
			(xy 227.636371 -155.238447) (xy 227.580934 -155.244547) (xy 227.5252 -155.24251) (xy 227.470357 -155.23238)
			(xy 227.417573 -155.214373) (xy 227.367973 -155.188872) (xy 227.322615 -155.156421) (xy 227.282466 -155.117712)
			(xy 227.24838 -155.073569) (xy 227.221084 -155.024934) (xy 227.201161 -154.972843) (xy 227.189035 -154.918406)
			(xy 227.184964 -154.862784) (xy 222.831114 -154.862784) (xy 222.822088 -154.870604) (xy 222.776234 -154.900067)
			(xy 222.726654 -154.922705) (xy 222.674356 -154.938055) (xy 222.620406 -154.945806) (xy 222.593154 -154.94635)
			(xy 222.567898 -154.945938) (xy 222.51783 -154.939269) (xy 222.469078 -154.926054) (xy 222.422495 -154.906523)
			(xy 222.378897 -154.881018) (xy 222.358712 -154.865832) (xy 222.358204 -154.865324) (xy 222.35795 -154.865324)
			(xy 222.352289 -154.861315) (xy 222.339415 -154.856163) (xy 222.33255 -154.855164) (xy 222.325434 -154.854651)
			(xy 222.31138 -154.857086) (xy 222.304864 -154.85999) (xy 222.220536 -154.901392) (xy 222.212828 -154.906066)
			(xy 222.201061 -154.919708) (xy 222.194748 -154.936582) (xy 222.194374 -154.945588) (xy 222.194374 -155.492704)
			(xy 222.194446 -155.497178) (xy 222.195981 -155.505993) (xy 222.197422 -155.51023) (xy 223.695514 -157.008322)
			(xy 226.168964 -157.008322) (xy 226.173035 -156.9527) (xy 226.185161 -156.898263) (xy 226.205084 -156.846172)
			(xy 226.23238 -156.797537) (xy 226.266466 -156.753394) (xy 226.306615 -156.714685) (xy 226.351973 -156.682234)
			(xy 226.401573 -156.656733) (xy 226.454357 -156.638726) (xy 226.5092 -156.628596) (xy 226.564934 -156.626559)
			(xy 226.620371 -156.632659) (xy 226.674328 -156.646765) (xy 226.725657 -156.668577) (xy 226.773263 -156.697631)
			(xy 226.816131 -156.733306) (xy 226.853348 -156.774843) (xy 226.884121 -156.821356) (xy 226.907793 -156.871853)
			(xy 226.923861 -156.92526) (xy 226.931981 -156.980436) (xy 226.93249 -157.008322) (xy 226.931981 -157.036208)
			(xy 226.923861 -157.091384) (xy 226.907793 -157.144791) (xy 226.884121 -157.195288) (xy 226.853348 -157.241801)
			(xy 226.816131 -157.283338) (xy 226.773263 -157.319013) (xy 226.725657 -157.348067) (xy 226.674328 -157.369879)
			(xy 226.620371 -157.383985) (xy 226.564934 -157.390085) (xy 226.5092 -157.388048) (xy 226.454357 -157.377918)
			(xy 226.401573 -157.359911) (xy 226.351973 -157.33441) (xy 226.306615 -157.301959) (xy 226.266466 -157.26325)
			(xy 226.23238 -157.219107) (xy 226.205084 -157.170472) (xy 226.185161 -157.118381) (xy 226.173035 -157.063944)
			(xy 226.168964 -157.008322) (xy 223.695514 -157.008322) (xy 224.587258 -157.900066) (xy 228.314505 -157.900066)
			(xy 228.314505 -157.840134) (xy 228.322328 -157.780714) (xy 228.33784 -157.722823) (xy 228.360775 -157.667453)
			(xy 228.390741 -157.61555) (xy 228.427226 -157.568002) (xy 228.469605 -157.525624) (xy 228.517153 -157.489139)
			(xy 228.569056 -157.459173) (xy 228.624427 -157.436238) (xy 228.682318 -157.420727) (xy 228.741738 -157.412905)
			(xy 228.771704 -157.412436) (xy 229.635304 -157.412436) (xy 229.665274 -157.412838) (xy 229.724702 -157.420663)
			(xy 229.7826 -157.436177) (xy 229.837978 -157.459116) (xy 229.889888 -157.489086) (xy 229.937442 -157.525576)
			(xy 229.979827 -157.567961) (xy 230.016316 -157.615515) (xy 230.046286 -157.667425) (xy 230.069224 -157.722803)
			(xy 230.084738 -157.780702) (xy 230.092562 -157.84013) (xy 230.092562 -157.90007) (xy 230.089876 -157.920473)
			(xy 230.557725 -157.920473) (xy 230.557725 -157.860527) (xy 230.56555 -157.801095) (xy 230.581066 -157.743192)
			(xy 230.604007 -157.68781) (xy 230.633981 -157.635897) (xy 230.670475 -157.58834) (xy 230.712864 -157.545953)
			(xy 230.760423 -157.509463) (xy 230.812339 -157.479493) (xy 230.867722 -157.456555) (xy 230.925626 -157.441044)
			(xy 230.985059 -157.433223) (xy 231.015032 -157.432756) (xy 231.878632 -157.432756) (xy 231.908596 -157.43332)
			(xy 231.968011 -157.441146) (xy 232.025896 -157.45666) (xy 232.081261 -157.479596) (xy 232.133158 -157.509563)
			(xy 232.180701 -157.546046) (xy 232.223075 -157.588423) (xy 232.259555 -157.635968) (xy 232.289518 -157.687868)
			(xy 232.31245 -157.743235) (xy 232.32796 -157.801121) (xy 232.335782 -157.860536) (xy 232.335782 -157.920464)
			(xy 232.32796 -157.979879) (xy 232.31245 -158.037765) (xy 232.289518 -158.093132) (xy 232.259555 -158.145032)
			(xy 232.223075 -158.192577) (xy 232.180701 -158.234954) (xy 232.133158 -158.271437) (xy 232.081261 -158.301404)
			(xy 232.025896 -158.32434) (xy 231.968011 -158.339854) (xy 231.908596 -158.34768) (xy 231.878632 -158.348172)
			(xy 231.015032 -158.348172) (xy 230.985059 -158.347777) (xy 230.925626 -158.339956) (xy 230.867722 -158.324445)
			(xy 230.812339 -158.301507) (xy 230.760423 -158.271537) (xy 230.712864 -158.235047) (xy 230.670475 -158.19266)
			(xy 230.633981 -158.145103) (xy 230.604007 -158.09319) (xy 230.581066 -158.037808) (xy 230.56555 -157.979905)
			(xy 230.557725 -157.920473) (xy 230.089876 -157.920473) (xy 230.084738 -157.959498) (xy 230.069224 -158.017397)
			(xy 230.046286 -158.072775) (xy 230.016316 -158.124685) (xy 229.979827 -158.172239) (xy 229.937442 -158.214624)
			(xy 229.889888 -158.251114) (xy 229.837978 -158.281084) (xy 229.7826 -158.304023) (xy 229.724702 -158.319537)
			(xy 229.665274 -158.327362) (xy 229.635304 -158.327852) (xy 228.771704 -158.327852) (xy 228.741738 -158.327295)
			(xy 228.682318 -158.319473) (xy 228.624427 -158.303962) (xy 228.569056 -158.281027) (xy 228.517153 -158.251061)
			(xy 228.469605 -158.214576) (xy 228.427226 -158.172198) (xy 228.390741 -158.12465) (xy 228.360775 -158.072747)
			(xy 228.33784 -158.017377) (xy 228.322328 -157.959486) (xy 228.314505 -157.900066) (xy 224.587258 -157.900066)
			(xy 224.745296 -158.058104) (xy 224.763326 -158.076876) (xy 224.793902 -158.118994) (xy 224.817524 -158.16537)
			(xy 224.833613 -158.214867) (xy 224.841774 -158.266269) (xy 224.842324 -158.292292) (xy 224.842324 -159.971051)
			(xy 232.232178 -159.971051) (xy 232.232178 -159.916549) (xy 232.239934 -159.862601) (xy 232.255289 -159.810306)
			(xy 232.277931 -159.760729) (xy 232.307397 -159.714879) (xy 232.343088 -159.673688) (xy 232.384279 -159.637997)
			(xy 232.430129 -159.608531) (xy 232.479706 -159.585889) (xy 232.532001 -159.570534) (xy 232.585949 -159.562778)
			(xy 232.6132 -159.562292) (xy 232.64057 -159.56276) (xy 232.694749 -159.570578) (xy 232.747252 -159.586066)
			(xy 232.796999 -159.608908) (xy 232.842966 -159.638631) (xy 232.863898 -159.656272) (xy 232.864152 -159.656526)
			(xy 232.871246 -159.662102) (xy 232.888157 -159.668354) (xy 232.897172 -159.668718) (xy 232.964228 -159.668718)
			(xy 232.973246 -159.668371) (xy 232.990163 -159.662116) (xy 232.997248 -159.656526) (xy 232.997248 -159.656272)
			(xy 232.997502 -159.656272) (xy 233.018419 -159.638614) (xy 233.064396 -159.608906) (xy 233.114148 -159.586074)
			(xy 233.166652 -159.570587) (xy 233.22083 -159.562764) (xy 233.2482 -159.562292) (xy 233.275451 -159.562778)
			(xy 233.329399 -159.570534) (xy 233.381694 -159.585889) (xy 233.431271 -159.608531) (xy 233.477121 -159.637997)
			(xy 233.518312 -159.673688) (xy 233.554003 -159.714879) (xy 233.583469 -159.760729) (xy 233.606111 -159.810306)
			(xy 233.621466 -159.862601) (xy 233.629222 -159.916549) (xy 233.629222 -159.971051) (xy 233.621466 -160.024999)
			(xy 233.606111 -160.077294) (xy 233.583469 -160.126871) (xy 233.554003 -160.172721) (xy 233.518312 -160.213912)
			(xy 233.477121 -160.249603) (xy 233.431271 -160.279069) (xy 233.381694 -160.301711) (xy 233.329399 -160.317066)
			(xy 233.275451 -160.324822) (xy 233.2482 -160.325308) (xy 233.22083 -160.32484) (xy 233.166651 -160.317022)
			(xy 233.114148 -160.301534) (xy 233.064401 -160.278692) (xy 233.018434 -160.248969) (xy 232.997502 -160.231328)
			(xy 232.997248 -160.231074) (xy 232.990154 -160.225498) (xy 232.973243 -160.219246) (xy 232.964228 -160.218882)
			(xy 232.897172 -160.218882) (xy 232.888154 -160.219229) (xy 232.871237 -160.225484) (xy 232.864152 -160.231074)
			(xy 232.864152 -160.231328) (xy 232.863898 -160.231328) (xy 232.842981 -160.248986) (xy 232.797004 -160.278694)
			(xy 232.747252 -160.301526) (xy 232.694748 -160.317013) (xy 232.64057 -160.324836) (xy 232.6132 -160.325308)
			(xy 232.585949 -160.324822) (xy 232.532001 -160.317066) (xy 232.479706 -160.301711) (xy 232.430129 -160.279069)
			(xy 232.384279 -160.249603) (xy 232.343088 -160.213912) (xy 232.307397 -160.172721) (xy 232.277931 -160.126871)
			(xy 232.255289 -160.077294) (xy 232.239934 -160.024999) (xy 232.232178 -159.971051) (xy 224.842324 -159.971051)
			(xy 224.842324 -162.945064) (xy 224.842759 -162.955129) (xy 224.850493 -162.973714) (xy 224.85731 -162.981132)
			(xy 228.443028 -166.56685) (xy 228.450335 -166.573453) (xy 228.4685 -166.581013) (xy 228.478334 -166.581582)
			(xy 228.498908 -166.581836) (xy 228.510084 -166.58209) (xy 228.51872 -166.581609) (xy 228.534939 -166.57563)
			(xy 228.541834 -166.570406) (xy 228.542342 -166.569898) (xy 228.563207 -166.552545) (xy 228.608921 -166.523302)
			(xy 228.658321 -166.500838) (xy 228.710408 -166.485608) (xy 228.764128 -166.477919) (xy 228.791262 -166.477442)
			(xy 228.818515 -166.477903) (xy 228.872468 -166.485656) (xy 228.924767 -166.501009) (xy 228.974349 -166.52365)
			(xy 229.020203 -166.553118) (xy 229.061396 -166.588812) (xy 229.09709 -166.630006) (xy 229.126556 -166.675862)
			(xy 229.149195 -166.725444) (xy 229.164547 -166.777744) (xy 229.172298 -166.831697) (xy 229.17277 -166.85895)
			(xy 229.172288 -166.886083) (xy 229.164589 -166.939799) (xy 229.149354 -166.991881) (xy 229.126889 -167.041278)
			(xy 229.09765 -167.086992) (xy 229.080314 -167.10787) (xy 229.079806 -167.108378) (xy 229.074544 -167.115249)
			(xy 229.068583 -167.131485) (xy 229.068122 -167.140128) (xy 229.068376 -167.151304) (xy 229.06863 -167.171878)
			(xy 229.069191 -167.181709) (xy 229.076778 -167.199861) (xy 229.083362 -167.207184) (xy 231.221534 -169.345356)
			(xy 233.321352 -169.345356) (xy 233.321945 -169.314552) (xy 233.331876 -169.253751) (xy 233.351457 -169.195338)
			(xy 233.365294 -169.16781) (xy 233.368005 -169.162284) (xy 233.370964 -169.15034) (xy 233.371136 -169.144188)
			(xy 233.371136 -161.621724) (xy 233.371626 -161.595699) (xy 233.379799 -161.544293) (xy 233.395901 -161.494795)
			(xy 233.419537 -161.448419) (xy 233.450127 -161.406305) (xy 233.468164 -161.387536) (xy 233.970322 -160.885378)
			(xy 233.974438 -160.880985) (xy 233.980723 -160.87072) (xy 233.982768 -160.865058) (xy 233.982768 -160.86455)
			(xy 233.991216 -160.839006) (xy 234.014286 -160.790401) (xy 234.043955 -160.74552) (xy 234.079636 -160.705252)
			(xy 234.12062 -160.670396) (xy 234.166094 -160.641644) (xy 234.215157 -160.619565) (xy 234.266835 -160.604599)
			(xy 234.320103 -160.597041) (xy 234.347004 -160.59658) (xy 234.374255 -160.597074) (xy 234.428202 -160.604831)
			(xy 234.480495 -160.620186) (xy 234.530072 -160.642827) (xy 234.575922 -160.672292) (xy 234.617112 -160.707983)
			(xy 234.652803 -160.749172) (xy 234.68227 -160.795021) (xy 234.704911 -160.844597) (xy 234.720268 -160.896891)
			(xy 234.728025 -160.950837) (xy 234.728512 -160.978088) (xy 234.727994 -161.004997) (xy 234.720419 -161.058278)
			(xy 234.705433 -161.109967) (xy 234.683332 -161.159037) (xy 234.654556 -161.204515) (xy 234.619674 -161.245498)
			(xy 234.57938 -161.281173) (xy 234.534473 -161.310832) (xy 234.485844 -161.333887) (xy 234.460288 -161.342324)
			(xy 234.460034 -161.342324) (xy 234.45434 -161.344302) (xy 234.444066 -161.3506) (xy 234.439714 -161.35477)
			(xy 234.04957 -161.74466) (xy 234.042751 -161.752076) (xy 234.03502 -161.770663) (xy 234.034584 -161.780728)
			(xy 234.034584 -169.144188) (xy 234.034776 -169.150338) (xy 234.03773 -169.162279) (xy 234.040426 -169.16781)
			(xy 234.054271 -169.195332) (xy 234.073832 -169.253751) (xy 234.083761 -169.314553) (xy 234.084368 -169.345356)
			(xy 234.083882 -169.372607) (xy 234.076126 -169.426555) (xy 234.060771 -169.47885) (xy 234.038129 -169.528427)
			(xy 234.008663 -169.574277) (xy 233.972972 -169.615468) (xy 233.931781 -169.651159) (xy 233.885931 -169.680625)
			(xy 233.836354 -169.703267) (xy 233.784059 -169.718622) (xy 233.730111 -169.726378) (xy 233.675609 -169.726378)
			(xy 233.621661 -169.718622) (xy 233.569366 -169.703267) (xy 233.519789 -169.680625) (xy 233.473939 -169.651159)
			(xy 233.432748 -169.615468) (xy 233.397057 -169.574277) (xy 233.367591 -169.528427) (xy 233.344949 -169.47885)
			(xy 233.329594 -169.426555) (xy 233.321838 -169.372607) (xy 233.321352 -169.345356) (xy 231.221534 -169.345356)
			(xy 234.325922 -172.449744) (xy 234.333335 -172.45642) (xy 234.351771 -172.463987) (xy 234.361736 -172.464476)
			(xy 234.863132 -172.464476) (xy 234.87507 -172.462952) (xy 234.894212 -172.458653) (xy 234.933177 -172.454064)
			(xy 234.952794 -172.453808) (xy 234.96905 -172.454316) (xy 235.702602 -172.454316) (xy 235.70946 -172.45076)
			(xy 235.737491 -172.436328) (xy 235.797115 -172.415853) (xy 235.859295 -172.405467) (xy 235.890816 -172.404786)
			(xy 235.918067 -172.405273) (xy 235.972014 -172.413031) (xy 236.024307 -172.428388) (xy 236.073883 -172.451031)
			(xy 236.119733 -172.480498) (xy 236.160922 -172.51619) (xy 236.196612 -172.55738) (xy 236.226077 -172.603231)
			(xy 236.248717 -172.652808) (xy 236.264072 -172.705102) (xy 236.271828 -172.759049) (xy 236.271828 -172.813551)
			(xy 236.264072 -172.867498) (xy 236.248717 -172.919792) (xy 236.230342 -172.96003) (xy 237.179356 -172.96003)
			(xy 237.183427 -172.904408) (xy 237.195553 -172.849971) (xy 237.215476 -172.79788) (xy 237.242772 -172.749245)
			(xy 237.276858 -172.705102) (xy 237.317007 -172.666393) (xy 237.362365 -172.633942) (xy 237.411965 -172.608441)
			(xy 237.464749 -172.590434) (xy 237.519592 -172.580304) (xy 237.575326 -172.578267) (xy 237.630763 -172.584367)
			(xy 237.68472 -172.598473) (xy 237.736049 -172.620285) (xy 237.783655 -172.649339) (xy 237.826523 -172.685014)
			(xy 237.86374 -172.726551) (xy 237.894513 -172.773064) (xy 237.918185 -172.823561) (xy 237.934253 -172.876968)
			(xy 237.942373 -172.932144) (xy 237.942882 -172.96003) (xy 237.942373 -172.987916) (xy 237.934253 -173.043092)
			(xy 237.918185 -173.096499) (xy 237.894513 -173.146996) (xy 237.86374 -173.193509) (xy 237.826523 -173.235046)
			(xy 237.783655 -173.270721) (xy 237.736049 -173.299775) (xy 237.68472 -173.321587) (xy 237.630763 -173.335693)
			(xy 237.575326 -173.341793) (xy 237.519592 -173.339756) (xy 237.464749 -173.329626) (xy 237.411965 -173.311619)
			(xy 237.362365 -173.286118) (xy 237.317007 -173.253667) (xy 237.276858 -173.214958) (xy 237.242772 -173.170815)
			(xy 237.215476 -173.12218) (xy 237.195553 -173.070089) (xy 237.183427 -173.015652) (xy 237.179356 -172.96003)
			(xy 236.230342 -172.96003) (xy 236.226077 -172.969369) (xy 236.196612 -173.01522) (xy 236.160922 -173.05641)
			(xy 236.119733 -173.092102) (xy 236.073883 -173.121569) (xy 236.024307 -173.144212) (xy 235.972014 -173.159569)
			(xy 235.918067 -173.167327) (xy 235.890816 -173.167802) (xy 235.890308 -173.167802) (xy 235.859506 -173.167191)
			(xy 235.798708 -173.157253) (xy 235.740295 -173.137684) (xy 235.712762 -173.12386) (xy 235.707682 -173.121066)
			(xy 235.695236 -173.117764) (xy 235.101638 -173.117764) (xy 235.08335 -173.12513) (xy 235.077 -173.13148)
			(xy 235.058458 -173.176438) (xy 235.059728 -173.18355) (xy 235.813346 -173.937168) (xy 235.816437 -173.940167)
			(xy 235.823466 -173.945142) (xy 235.827316 -173.947074) (xy 235.834936 -173.95063) (xy 235.843572 -173.951646)
			(xy 235.87197 -173.955304) (xy 235.927299 -173.970035) (xy 235.979807 -173.992867) (xy 236.028313 -174.023288)
			(xy 236.07173 -174.060615) (xy 236.109082 -174.10401) (xy 236.139531 -174.152499) (xy 236.162393 -174.204993)
			(xy 236.177155 -174.260314) (xy 236.180884 -174.288704) (xy 236.180884 -174.288958) (xy 236.1819 -174.297594)
			(xy 236.185456 -174.305214) (xy 236.187418 -174.309045) (xy 236.192397 -174.316064) (xy 236.195362 -174.319184)
			(xy 239.561878 -177.6857) (xy 240.297206 -177.6857) (xy 240.301277 -177.630078) (xy 240.313403 -177.575641)
			(xy 240.333326 -177.52355) (xy 240.360622 -177.474915) (xy 240.394708 -177.430772) (xy 240.434857 -177.392063)
			(xy 240.480215 -177.359612) (xy 240.529815 -177.334111) (xy 240.582599 -177.316104) (xy 240.637442 -177.305974)
			(xy 240.693176 -177.303937) (xy 240.748613 -177.310037) (xy 240.80257 -177.324143) (xy 240.853899 -177.345955)
			(xy 240.901505 -177.375009) (xy 240.944373 -177.410684) (xy 240.98159 -177.452221) (xy 241.012363 -177.498734)
			(xy 241.036035 -177.549231) (xy 241.052103 -177.602638) (xy 241.060223 -177.657814) (xy 241.060732 -177.6857)
			(xy 241.060223 -177.713586) (xy 241.052103 -177.768762) (xy 241.036035 -177.822169) (xy 241.012363 -177.872666)
			(xy 240.98159 -177.919179) (xy 240.944373 -177.960716) (xy 240.901505 -177.996391) (xy 240.853899 -178.025445)
			(xy 240.80257 -178.047257) (xy 240.748613 -178.061363) (xy 240.693176 -178.067463) (xy 240.637442 -178.065426)
			(xy 240.582599 -178.055296) (xy 240.529815 -178.037289) (xy 240.480215 -178.011788) (xy 240.434857 -177.979337)
			(xy 240.394708 -177.940628) (xy 240.360622 -177.896485) (xy 240.333326 -177.84785) (xy 240.313403 -177.795759)
			(xy 240.301277 -177.741322) (xy 240.297206 -177.6857) (xy 239.561878 -177.6857) (xy 241.430556 -179.554378)
			(xy 242.447824 -179.554378) (xy 242.451895 -179.498756) (xy 242.464021 -179.444319) (xy 242.483944 -179.392228)
			(xy 242.51124 -179.343593) (xy 242.545326 -179.29945) (xy 242.585475 -179.260741) (xy 242.630833 -179.22829)
			(xy 242.680433 -179.202789) (xy 242.733217 -179.184782) (xy 242.78806 -179.174652) (xy 242.843794 -179.172615)
			(xy 242.899231 -179.178715) (xy 242.953188 -179.192821) (xy 243.004517 -179.214633) (xy 243.052123 -179.243687)
			(xy 243.094991 -179.279362) (xy 243.132208 -179.320899) (xy 243.162981 -179.367412) (xy 243.186653 -179.417909)
			(xy 243.202721 -179.471316) (xy 243.210841 -179.526492) (xy 243.21135 -179.554378) (xy 244.924578 -179.554378)
			(xy 244.928649 -179.498756) (xy 244.940775 -179.444319) (xy 244.960698 -179.392228) (xy 244.987994 -179.343593)
			(xy 245.02208 -179.29945) (xy 245.062229 -179.260741) (xy 245.107587 -179.22829) (xy 245.157187 -179.202789)
			(xy 245.209971 -179.184782) (xy 245.264814 -179.174652) (xy 245.320548 -179.172615) (xy 245.375985 -179.178715)
			(xy 245.429942 -179.192821) (xy 245.481271 -179.214633) (xy 245.528877 -179.243687) (xy 245.571745 -179.279362)
			(xy 245.608962 -179.320899) (xy 245.639735 -179.367412) (xy 245.663407 -179.417909) (xy 245.679475 -179.471316)
			(xy 245.687595 -179.526492) (xy 245.688104 -179.554378) (xy 245.687595 -179.582264) (xy 245.679475 -179.63744)
			(xy 245.663407 -179.690847) (xy 245.639735 -179.741344) (xy 245.608962 -179.787857) (xy 245.571745 -179.829394)
			(xy 245.528877 -179.865069) (xy 245.481271 -179.894123) (xy 245.429942 -179.915935) (xy 245.375985 -179.930041)
			(xy 245.320548 -179.936141) (xy 245.264814 -179.934104) (xy 245.209971 -179.923974) (xy 245.157187 -179.905967)
			(xy 245.107587 -179.880466) (xy 245.062229 -179.848015) (xy 245.02208 -179.809306) (xy 244.987994 -179.765163)
			(xy 244.960698 -179.716528) (xy 244.940775 -179.664437) (xy 244.928649 -179.61) (xy 244.924578 -179.554378)
			(xy 243.21135 -179.554378) (xy 243.210841 -179.582264) (xy 243.202721 -179.63744) (xy 243.186653 -179.690847)
			(xy 243.162981 -179.741344) (xy 243.132208 -179.787857) (xy 243.094991 -179.829394) (xy 243.052123 -179.865069)
			(xy 243.004517 -179.894123) (xy 242.953188 -179.915935) (xy 242.899231 -179.930041) (xy 242.843794 -179.936141)
			(xy 242.78806 -179.934104) (xy 242.733217 -179.923974) (xy 242.680433 -179.905967) (xy 242.630833 -179.880466)
			(xy 242.585475 -179.848015) (xy 242.545326 -179.809306) (xy 242.51124 -179.765163) (xy 242.483944 -179.716528)
			(xy 242.464021 -179.664437) (xy 242.451895 -179.61) (xy 242.447824 -179.554378) (xy 241.430556 -179.554378)
			(xy 244.156992 -182.280814) (xy 250.214382 -182.280814) (xy 250.218453 -182.225192) (xy 250.230579 -182.170755)
			(xy 250.250502 -182.118664) (xy 250.277798 -182.070029) (xy 250.311884 -182.025886) (xy 250.352033 -181.987177)
			(xy 250.397391 -181.954726) (xy 250.446991 -181.929225) (xy 250.499775 -181.911218) (xy 250.554618 -181.901088)
			(xy 250.610352 -181.899051) (xy 250.665789 -181.905151) (xy 250.719746 -181.919257) (xy 250.771075 -181.941069)
			(xy 250.818681 -181.970123) (xy 250.861549 -182.005798) (xy 250.898766 -182.047335) (xy 250.929539 -182.093848)
			(xy 250.953211 -182.144345) (xy 250.969279 -182.197752) (xy 250.977399 -182.252928) (xy 250.977908 -182.280814)
			(xy 250.977399 -182.3087) (xy 250.969279 -182.363876) (xy 250.953211 -182.417283) (xy 250.929539 -182.46778)
			(xy 250.898766 -182.514293) (xy 250.861549 -182.55583) (xy 250.818681 -182.591505) (xy 250.771075 -182.620559)
			(xy 250.719746 -182.642371) (xy 250.665789 -182.656477) (xy 250.610352 -182.662577) (xy 250.554618 -182.66054)
			(xy 250.499775 -182.65041) (xy 250.446991 -182.632403) (xy 250.397391 -182.606902) (xy 250.352033 -182.574451)
			(xy 250.311884 -182.535742) (xy 250.277798 -182.491599) (xy 250.250502 -182.442964) (xy 250.230579 -182.390873)
			(xy 250.218453 -182.336436) (xy 250.214382 -182.280814) (xy 244.156992 -182.280814) (xy 244.949218 -183.07304)
			(xy 244.954364 -183.077796) (xy 244.9666 -183.084613) (xy 244.973348 -183.086502) (xy 244.980206 -183.08828)
			(xy 244.993922 -183.087518) (xy 245.001034 -183.085232) (xy 245.03012 -183.07623) (xy 245.090226 -183.066534)
			(xy 245.120668 -183.065928) (xy 245.147695 -183.066397) (xy 245.201208 -183.074027) (xy 245.253107 -183.089138)
			(xy 245.302351 -183.111428) (xy 245.347954 -183.14045) (xy 245.389 -183.175621) (xy 245.424668 -183.216238)
			(xy 245.454241 -183.261484) (xy 245.477127 -183.310454) (xy 245.485412 -183.336184) (xy 245.488714 -183.34609)
			(xy 245.53545 -183.392826) (xy 245.539575 -183.393275) (xy 245.547869 -183.393017) (xy 245.55196 -183.392318)
			(xy 245.63451 -183.376316) (xy 245.640444 -183.374949) (xy 245.651481 -183.369809) (xy 245.656354 -183.366156)
			(xy 245.656608 -183.366156) (xy 245.661374 -183.362137) (xy 245.668956 -183.352246) (xy 245.671594 -183.346598)
			(xy 245.683072 -183.321366) (xy 245.712242 -183.274231) (xy 245.747923 -183.231811) (xy 245.789366 -183.194999)
			(xy 245.835697 -183.164568) (xy 245.885943 -183.141159) (xy 245.939047 -183.125265) (xy 245.993891 -183.117219)
			(xy 246.021606 -183.116728) (xy 246.047005 -183.117147) (xy 246.097353 -183.123887) (xy 246.146361 -183.137249)
			(xy 246.193164 -183.156995) (xy 246.236932 -183.182776) (xy 246.276893 -183.214137) (xy 246.29491 -183.232044)
			(xy 246.301514 -183.238648) (xy 246.309134 -183.242458) (xy 246.313424 -183.24437) (xy 246.322497 -183.24679)
			(xy 246.327168 -183.247284) (xy 246.39397 -183.252618) (xy 246.398458 -183.252854) (xy 246.4074 -183.251966)
			(xy 246.41175 -183.25084) (xy 246.420386 -183.248554) (xy 246.428006 -183.242966) (xy 246.452754 -183.225392)
			(xy 246.506656 -183.197489) (xy 246.564299 -183.178485) (xy 246.624226 -183.168859) (xy 246.654574 -183.16829)
			(xy 246.681863 -183.168753) (xy 246.735885 -183.176525) (xy 246.788248 -183.191914) (xy 246.837886 -183.214605)
			(xy 246.861076 -183.228996) (xy 246.869712 -183.234584) (xy 246.879618 -183.236362) (xy 246.884547 -183.23714)
			(xy 246.894524 -183.237018) (xy 246.89943 -183.236108) (xy 246.969534 -183.220868) (xy 246.974511 -183.219626)
			(xy 246.983859 -183.215406) (xy 246.988076 -183.212486) (xy 246.996204 -183.206898) (xy 247.001538 -183.198516)
			(xy 247.016651 -183.175776) (xy 247.052346 -183.134461) (xy 247.093568 -183.098656) (xy 247.139472 -183.069095)
			(xy 247.189123 -183.04638) (xy 247.241505 -183.030977) (xy 247.295548 -183.023199) (xy 247.322848 -183.022748)
			(xy 247.350098 -183.023237) (xy 247.404043 -183.030999) (xy 247.456335 -183.046358) (xy 247.505909 -183.069001)
			(xy 247.551756 -183.098468) (xy 247.592944 -183.134159) (xy 247.628635 -183.175347) (xy 247.658101 -183.221195)
			(xy 247.680744 -183.270769) (xy 247.696102 -183.323061) (xy 247.703863 -183.377006) (xy 247.704356 -183.404256)
			(xy 247.703906 -183.430645) (xy 247.696626 -183.482919) (xy 247.682213 -183.533691) (xy 247.660941 -183.581992)
			(xy 247.633217 -183.626902) (xy 247.59957 -183.667564) (xy 247.56064 -183.703201) (xy 247.517172 -183.733135)
			(xy 247.49379 -183.745378) (xy 247.488375 -183.748211) (xy 247.479006 -183.756052) (xy 247.475248 -183.760872)
			(xy 247.471946 -183.765698) (xy 247.467374 -183.77662) (xy 247.458992 -183.828436) (xy 247.458992 -183.828944)
			(xy 247.45315 -183.866536) (xy 247.45315 -183.878982) (xy 247.706896 -184.132728) (xy 247.724925 -184.1515)
			(xy 247.755497 -184.193619) (xy 247.779116 -184.239996) (xy 247.795202 -184.289492) (xy 247.803359 -184.340894)
			(xy 247.803924 -184.366916) (xy 247.803924 -185.906664) (xy 247.804359 -185.916729) (xy 247.812093 -185.935314)
			(xy 247.81891 -185.942732) (xy 248.092976 -186.216798) (xy 248.096062 -186.219804) (xy 248.103084 -186.224795)
			(xy 248.106946 -186.226704) (xy 248.111772 -186.228736) (xy 248.138442 -186.21756) (xy 248.147507 -186.213358)
			(xy 248.161631 -186.199248) (xy 248.16928 -186.180806) (xy 248.169684 -186.170824) (xy 248.169684 -185.803286)
			(xy 248.16562 -185.795158) (xy 248.151286 -185.767232) (xy 248.130942 -185.707854) (xy 248.120592 -185.645947)
			(xy 248.1199 -185.614564) (xy 248.120386 -185.587313) (xy 248.128142 -185.533365) (xy 248.143497 -185.48107)
			(xy 248.166139 -185.431493) (xy 248.195605 -185.385643) (xy 248.231296 -185.344452) (xy 248.272487 -185.308761)
			(xy 248.318337 -185.279295) (xy 248.367914 -185.256653) (xy 248.420209 -185.241298) (xy 248.474157 -185.233542)
			(xy 248.528659 -185.233542) (xy 248.582607 -185.241298) (xy 248.634902 -185.256653) (xy 248.684479 -185.279295)
			(xy 248.730329 -185.308761) (xy 248.77152 -185.344452) (xy 248.807211 -185.385643) (xy 248.836677 -185.431493)
			(xy 248.859319 -185.48107) (xy 248.874674 -185.533365) (xy 248.88243 -185.587313) (xy 248.882916 -185.614564)
			(xy 248.882241 -185.645948) (xy 248.871891 -185.707858) (xy 248.851546 -185.767239) (xy 248.837196 -185.795158)
			(xy 248.833132 -185.803286) (xy 248.833132 -186.640978) (xy 248.832608 -186.667933) (xy 248.823897 -186.721134)
			(xy 248.806701 -186.772227) (xy 248.781471 -186.819869) (xy 248.765568 -186.841638) (xy 248.760234 -186.849343)
			(xy 248.755021 -186.867327) (xy 248.755408 -186.87669) (xy 248.755662 -186.879484) (xy 250.952254 -189.076076)
			(xy 250.961398 -189.079886) (xy 250.988795 -189.091893) (xy 251.039778 -189.123172) (xy 251.085255 -189.162024)
			(xy 251.124111 -189.207498) (xy 251.155394 -189.258479) (xy 251.167392 -189.28588) (xy 251.171202 -189.295024)
			(xy 252.030738 -190.15456)
		)
		(stroke
			(width 0)
			(type solid)
		)
		(fill yes)
		(layer "In7.Cu")
		(net "GND")
	)
	(gr_poly
		(pts
			(xy 226.991926 -253.5682) (xy 227.00188 -253.567667) (xy 227.020264 -253.560008) (xy 227.034378 -253.545958)
			(xy 227.038662 -253.536958) (xy 227.044758 -253.52248) (xy 227.038916 -253.492508) (xy 226.953064 -253.40691)
			(xy 226.945717 -253.400104) (xy 226.927255 -253.392383) (xy 226.91725 -253.391924) (xy 226.090734 -253.391924)
			(xy 226.064658 -253.391457) (xy 226.013142 -253.383333) (xy 225.963533 -253.367248) (xy 225.917052 -253.343599)
			(xy 225.874843 -253.312967) (xy 225.856038 -253.294896) (xy 225.556826 -252.995684) (xy 225.546158 -252.989334)
			(xy 225.540316 -252.987302) (xy 225.514757 -252.978866) (xy 225.466122 -252.955814) (xy 225.421208 -252.926156)
			(xy 225.380906 -252.890483) (xy 225.346017 -252.849501) (xy 225.317231 -252.804023) (xy 225.295121 -252.754952)
			(xy 225.280124 -252.703262) (xy 225.272539 -252.649977) (xy 225.272092 -252.623066) (xy 225.27258 -252.595816)
			(xy 225.280341 -252.541872) (xy 225.295699 -252.489582) (xy 225.318342 -252.440009) (xy 225.347809 -252.394163)
			(xy 225.3835 -252.352976) (xy 225.42469 -252.317289) (xy 225.470539 -252.287825) (xy 225.520114 -252.265187)
			(xy 225.572406 -252.249833) (xy 225.62635 -252.242078) (xy 225.6536 -252.241558) (xy 225.679651 -252.242022)
			(xy 225.731263 -252.24915) (xy 225.781426 -252.263235) (xy 225.829206 -252.284012) (xy 225.873716 -252.311097)
			(xy 225.914126 -252.343985) (xy 225.932238 -252.362716) (xy 225.940366 -252.371098) (xy 225.961194 -252.37948)
			(xy 226.063302 -252.372368) (xy 226.08286 -252.361446) (xy 226.089464 -252.351794) (xy 226.104874 -252.330782)
			(xy 226.140477 -252.292736) (xy 226.180924 -252.259885) (xy 226.225463 -252.232841) (xy 226.273266 -252.212107)
			(xy 226.323446 -252.198067) (xy 226.375069 -252.190983) (xy 226.401122 -252.190504) (xy 226.429857 -252.191031)
			(xy 226.486677 -252.199651) (xy 226.541566 -252.216679) (xy 226.593288 -252.241732) (xy 226.617276 -252.25756)
			(xy 226.625658 -252.263402) (xy 226.64547 -252.267466) (xy 226.736148 -252.250448) (xy 226.753166 -252.239272)
			(xy 226.758754 -252.23089) (xy 226.779242 -252.201647) (xy 226.826224 -252.147877) (xy 226.879395 -252.100218)
			(xy 226.937964 -252.059375) (xy 227.001065 -252.025956) (xy 227.06776 -252.000456) (xy 227.13706 -251.983252)
			(xy 227.207938 -251.974601) (xy 227.24364 -251.974096) (xy 227.276513 -251.974526) (xy 227.341848 -251.981862)
			(xy 227.40595 -251.996471) (xy 227.468012 -252.018168) (xy 227.527253 -252.046681) (xy 227.582927 -252.081651)
			(xy 227.634334 -252.122637) (xy 227.657914 -252.145546) (xy 227.78339 -252.271022) (xy 227.819458 -252.274578)
			(xy 227.834698 -252.264418) (xy 227.858411 -252.249064) (xy 227.909409 -252.224767) (xy 227.963435 -252.208265)
			(xy 228.019305 -252.199919) (xy 228.04755 -252.199394) (xy 228.074462 -252.199853) (xy 228.127753 -252.207415)
			(xy 228.179451 -252.222397) (xy 228.228528 -252.244499) (xy 228.274009 -252.273284) (xy 228.314991 -252.308178)
			(xy 228.350658 -252.348489) (xy 228.380301 -252.393415) (xy 228.403333 -252.442063) (xy 228.411786 -252.467618)
			(xy 228.413818 -252.47346) (xy 228.420168 -252.484128) (xy 228.459792 -252.523752) (xy 230.546146 -252.523752)
			(xy 230.550217 -252.46813) (xy 230.562343 -252.413693) (xy 230.582266 -252.361602) (xy 230.609562 -252.312967)
			(xy 230.643648 -252.268824) (xy 230.683797 -252.230115) (xy 230.729155 -252.197664) (xy 230.778755 -252.172163)
			(xy 230.831539 -252.154156) (xy 230.886382 -252.144026) (xy 230.942116 -252.141989) (xy 230.997553 -252.148089)
			(xy 231.05151 -252.162195) (xy 231.102839 -252.184007) (xy 231.150445 -252.213061) (xy 231.193313 -252.248736)
			(xy 231.23053 -252.290273) (xy 231.261303 -252.336786) (xy 231.284975 -252.387283) (xy 231.301043 -252.44069)
			(xy 231.309163 -252.495866) (xy 231.309672 -252.523752) (xy 231.309163 -252.551638) (xy 231.307211 -252.5649)
			(xy 231.441242 -252.5649) (xy 231.445313 -252.509278) (xy 231.457439 -252.454841) (xy 231.477362 -252.40275)
			(xy 231.504658 -252.354115) (xy 231.538744 -252.309972) (xy 231.578893 -252.271263) (xy 231.624251 -252.238812)
			(xy 231.673851 -252.213311) (xy 231.726635 -252.195304) (xy 231.781478 -252.185174) (xy 231.837212 -252.183137)
			(xy 231.892649 -252.189237) (xy 231.946606 -252.203343) (xy 231.997935 -252.225155) (xy 232.045541 -252.254209)
			(xy 232.088409 -252.289884) (xy 232.125626 -252.331421) (xy 232.156399 -252.377934) (xy 232.180071 -252.428431)
			(xy 232.196139 -252.481838) (xy 232.204259 -252.537014) (xy 232.204768 -252.5649) (xy 232.204259 -252.592786)
			(xy 232.196139 -252.647962) (xy 232.180071 -252.701369) (xy 232.156399 -252.751866) (xy 232.125626 -252.798379)
			(xy 232.088409 -252.839916) (xy 232.045541 -252.875591) (xy 231.997935 -252.904645) (xy 231.946606 -252.926457)
			(xy 231.892649 -252.940563) (xy 231.837212 -252.946663) (xy 231.781478 -252.944626) (xy 231.726635 -252.934496)
			(xy 231.673851 -252.916489) (xy 231.624251 -252.890988) (xy 231.578893 -252.858537) (xy 231.538744 -252.819828)
			(xy 231.504658 -252.775685) (xy 231.477362 -252.72705) (xy 231.457439 -252.674959) (xy 231.445313 -252.620522)
			(xy 231.441242 -252.5649) (xy 231.307211 -252.5649) (xy 231.301043 -252.606814) (xy 231.284975 -252.660221)
			(xy 231.261303 -252.710718) (xy 231.23053 -252.757231) (xy 231.193313 -252.798768) (xy 231.150445 -252.834443)
			(xy 231.102839 -252.863497) (xy 231.05151 -252.885309) (xy 230.997553 -252.899415) (xy 230.942116 -252.905515)
			(xy 230.886382 -252.903478) (xy 230.831539 -252.893348) (xy 230.778755 -252.875341) (xy 230.729155 -252.84984)
			(xy 230.683797 -252.817389) (xy 230.643648 -252.77868) (xy 230.609562 -252.734537) (xy 230.582266 -252.685902)
			(xy 230.562343 -252.633811) (xy 230.550217 -252.579374) (xy 230.546146 -252.523752) (xy 228.459792 -252.523752)
			(xy 229.489254 -253.553214) (xy 229.496651 -253.560061) (xy 229.515251 -253.567789) (xy 229.525322 -253.5682)
			(xy 232.963466 -253.5682) (xy 232.973531 -253.567765) (xy 232.992118 -253.560033) (xy 232.999534 -253.553214)
			(xy 233.166666 -253.386082) (xy 233.173385 -253.378645) (xy 233.181028 -253.36014) (xy 233.18104 -253.340118)
			(xy 233.173417 -253.321604) (xy 233.166666 -253.3142) (xy 232.803954 -252.951488) (xy 232.793286 -252.945138)
			(xy 232.787444 -252.943106) (xy 232.761884 -252.934672) (xy 232.713245 -252.911621) (xy 232.668327 -252.881966)
			(xy 232.628022 -252.846293) (xy 232.59313 -252.805311) (xy 232.564341 -252.759833) (xy 232.542228 -252.710761)
			(xy 232.52723 -252.659069) (xy 232.519644 -252.605782) (xy 232.51922 -252.57887) (xy 232.519708 -252.551621)
			(xy 232.527468 -252.497678) (xy 232.542826 -252.445388) (xy 232.56547 -252.395817) (xy 232.594937 -252.349972)
			(xy 232.630629 -252.308788) (xy 232.671819 -252.273102) (xy 232.717668 -252.243642) (xy 232.767243 -252.221006)
			(xy 232.819535 -252.205656) (xy 232.873479 -252.197904) (xy 232.900728 -252.197362) (xy 232.927642 -252.19782)
			(xy 232.980936 -252.205379) (xy 233.032637 -252.220358) (xy 233.081719 -252.242458) (xy 233.127204 -252.27124)
			(xy 233.168191 -252.306133) (xy 233.203863 -252.346443) (xy 233.233512 -252.391369) (xy 233.256549 -252.440018)
			(xy 233.264964 -252.465586) (xy 233.266996 -252.471428) (xy 233.273346 -252.482096) (xy 233.53014 -252.73889)
			(xy 233.537487 -252.745695) (xy 233.55595 -252.753415) (xy 233.565954 -252.753876) (xy 233.778044 -252.753876)
			(xy 233.788036 -252.753348) (xy 233.80648 -252.745646) (xy 233.813858 -252.73889) (xy 234.799124 -251.753624)
			(xy 234.805967 -251.746225) (xy 234.813685 -251.727626) (xy 234.81411 -251.717556) (xy 234.81411 -245.749064)
			(xy 234.813361 -245.736396) (xy 234.801236 -245.71414) (xy 234.790996 -245.706646) (xy 234.708446 -245.653052)
			(xy 234.683046 -245.65102) (xy 234.671108 -245.656354) (xy 234.646508 -245.666858) (xy 234.59511 -245.681666)
			(xy 234.54215 -245.689171) (xy 234.515406 -245.689628) (xy 234.488151 -245.689166) (xy 234.434197 -245.681409)
			(xy 234.381896 -245.666052) (xy 234.332312 -245.643409) (xy 234.286456 -245.61394) (xy 234.24526 -245.578244)
			(xy 234.209564 -245.537049) (xy 234.180094 -245.491193) (xy 234.15745 -245.44161) (xy 234.142092 -245.389309)
			(xy 234.134335 -245.335355) (xy 234.134335 -245.280845) (xy 234.142092 -245.226891) (xy 234.15745 -245.17459)
			(xy 234.180094 -245.125007) (xy 234.209564 -245.079151) (xy 234.24526 -245.037956) (xy 234.286456 -245.00226)
			(xy 234.332312 -244.972791) (xy 234.381896 -244.950148) (xy 234.434197 -244.934791) (xy 234.488151 -244.927034)
			(xy 234.515406 -244.926612) (xy 234.542152 -244.92706) (xy 234.595118 -244.934541) (xy 234.646513 -244.949368)
			(xy 234.671108 -244.959886) (xy 234.683046 -244.96522) (xy 234.708446 -244.963188) (xy 234.790996 -244.909594)
			(xy 234.801266 -244.902124) (xy 234.813402 -244.879855) (xy 234.81411 -244.867176) (xy 234.81411 -242.916202)
			(xy 234.813688 -242.906131) (xy 234.805975 -242.887525) (xy 234.799124 -242.880134) (xy 233.895138 -241.976148)
			(xy 233.885232 -241.972084) (xy 233.861398 -241.962121) (xy 233.816432 -241.936692) (xy 233.775309 -241.905428)
			(xy 233.73878 -241.868901) (xy 233.707515 -241.827779) (xy 233.682084 -241.782814) (xy 233.672126 -241.758978)
			(xy 233.668062 -241.749072) (xy 232.386124 -240.467134) (xy 232.356914 -240.461038) (xy 232.34269 -240.466626)
			(xy 232.320656 -240.474745) (xy 232.275106 -240.486162) (xy 232.228501 -240.491922) (xy 232.205022 -240.49228)
			(xy 232.177769 -240.491818) (xy 232.123817 -240.484064) (xy 232.071518 -240.468709) (xy 232.021937 -240.446068)
			(xy 231.976083 -240.4166) (xy 231.93489 -240.380906) (xy 231.899197 -240.339712) (xy 231.86973 -240.293858)
			(xy 231.847089 -240.244276) (xy 231.831735 -240.191977) (xy 231.823981 -240.138025) (xy 231.823514 -240.110772)
			(xy 231.82384 -240.08729) (xy 231.829578 -240.040677) (xy 231.841011 -239.995126) (xy 231.849168 -239.973104)
			(xy 231.854756 -239.95888) (xy 231.84866 -239.92967) (xy 227.137976 -235.218986) (xy 227.13058 -235.212134)
			(xy 227.111981 -235.204395) (xy 227.101908 -235.204) (xy 214.17788 -235.204) (xy 214.167188 -235.204563)
			(xy 214.147632 -235.213221) (xy 214.140034 -235.220764) (xy 214.082376 -235.28528) (xy 214.075772 -235.3056)
			(xy 214.077042 -235.316268) (xy 214.078027 -235.326399) (xy 214.079047 -235.34673) (xy 214.079074 -235.356908)
			(xy 214.078588 -235.384159) (xy 214.070832 -235.438107) (xy 214.055477 -235.490402) (xy 214.032835 -235.539979)
			(xy 214.003369 -235.585829) (xy 213.967678 -235.62702) (xy 213.926487 -235.662711) (xy 213.880637 -235.692177)
			(xy 213.83106 -235.714819) (xy 213.778765 -235.730174) (xy 213.724817 -235.73793) (xy 213.670315 -235.73793)
			(xy 213.616367 -235.730174) (xy 213.564072 -235.714819) (xy 213.514495 -235.692177) (xy 213.468645 -235.662711)
			(xy 213.427454 -235.62702) (xy 213.391763 -235.585829) (xy 213.362297 -235.539979) (xy 213.339655 -235.490402)
			(xy 213.3243 -235.438107) (xy 213.316544 -235.384159) (xy 213.316058 -235.356908) (xy 213.316093 -235.34673)
			(xy 213.317112 -235.326399) (xy 213.31809 -235.316268) (xy 213.31936 -235.3056) (xy 213.312756 -235.28528)
			(xy 213.255098 -235.220764) (xy 213.247582 -235.213101) (xy 213.227977 -235.204414) (xy 213.217252 -235.204)
			(xy 207.453992 -235.204) (xy 207.443922 -235.203575) (xy 207.42532 -235.195859) (xy 207.417924 -235.189014)
			(xy 199.065896 -226.836986) (xy 199.059052 -226.829586) (xy 199.051324 -226.810989) (xy 199.05091 -226.800918)
			(xy 199.05091 -225.576384) (xy 199.0471 -225.566986) (xy 199.033257 -225.531588) (xy 199.013796 -225.458114)
			(xy 199.004007 -225.38274) (xy 199.003412 -225.344736) (xy 199.003412 -199.32142) (xy 199.002878 -199.311431)
			(xy 198.995171 -199.292992) (xy 198.988426 -199.285606) (xy 198.091806 -198.388986) (xy 198.084412 -198.382129)
			(xy 198.065813 -198.374379) (xy 198.055738 -198.374) (xy 188.281056 -198.374) (xy 188.270989 -198.374431)
			(xy 188.252397 -198.382157) (xy 188.244988 -198.388986) (xy 187.70727 -198.926704) (xy 187.701929 -198.932407)
			(xy 187.694692 -198.946244) (xy 187.693046 -198.953882) (xy 186.312556 -206.880968) (xy 186.328304 -206.911194)
			(xy 186.344052 -206.91856) (xy 186.368308 -206.930454) (xy 186.413493 -206.960063) (xy 186.454048 -206.995751)
			(xy 186.489163 -207.036804) (xy 186.518133 -207.082401) (xy 186.54038 -207.13163) (xy 186.555459 -207.183505)
			(xy 186.563067 -207.236989) (xy 186.563508 -207.264) (xy 186.562994 -207.292192) (xy 186.554681 -207.347959)
			(xy 186.53825 -207.401895) (xy 186.51406 -207.452826) (xy 186.482637 -207.499642) (xy 186.444666 -207.541323)
			(xy 186.400974 -207.576961) (xy 186.352512 -207.605781) (xy 186.300337 -207.627154) (xy 186.245583 -207.640615)
			(xy 186.21756 -207.64373) (xy 186.200542 -207.645508) (xy 186.175396 -207.668622) (xy 185.742834 -210.151726)
			(xy 185.760868 -210.183222) (xy 185.77814 -210.189826) (xy 185.806846 -210.201303) (xy 185.86041 -210.232164)
			(xy 185.908313 -210.271238) (xy 185.92927 -210.293966) (xy 185.936382 -210.302094) (xy 185.955432 -210.31073)
			(xy 186.051952 -210.312508) (xy 186.071256 -210.304634) (xy 186.078876 -210.29676) (xy 186.096928 -210.278448)
			(xy 186.137101 -210.246349) (xy 186.181223 -210.21994) (xy 186.228494 -210.1997) (xy 186.278056 -210.185995)
			(xy 186.329009 -210.179075) (xy 186.35472 -210.17865) (xy 186.381973 -210.179137) (xy 186.435925 -210.186897)
			(xy 186.488223 -210.202255) (xy 186.537803 -210.2249) (xy 186.583656 -210.25437) (xy 186.624848 -210.290066)
			(xy 186.660542 -210.33126) (xy 186.690009 -210.377115) (xy 186.712652 -210.426696) (xy 186.728007 -210.478995)
			(xy 186.735764 -210.532947) (xy 186.735764 -210.587453) (xy 186.728007 -210.641405) (xy 186.712652 -210.693704)
			(xy 186.690009 -210.743285) (xy 186.660542 -210.78914) (xy 186.624848 -210.830334) (xy 186.583656 -210.86603)
			(xy 186.537803 -210.8955) (xy 186.488223 -210.918145) (xy 186.435925 -210.933503) (xy 186.381973 -210.941263)
			(xy 186.35472 -210.941666) (xy 186.327792 -210.941204) (xy 186.274471 -210.93363) (xy 186.222746 -210.918629)
			(xy 186.173645 -210.896501) (xy 186.128147 -210.867685) (xy 186.087155 -210.832754) (xy 186.06897 -210.812888)
			(xy 186.061858 -210.80476) (xy 186.042808 -210.796124) (xy 185.946288 -210.794346) (xy 185.926984 -210.80222)
			(xy 185.919364 -210.810094) (xy 185.898065 -210.83158) (xy 185.849918 -210.868209) (xy 185.796592 -210.89678)
			(xy 185.739425 -210.916574) (xy 185.67985 -210.927096) (xy 185.649616 -210.928204) (xy 185.631328 -210.928458)
			(xy 185.603642 -210.95208) (xy 184.569737 -216.88806) (xy 185.727084 -216.88806) (xy 185.731155 -216.832438)
			(xy 185.743281 -216.778001) (xy 185.763204 -216.72591) (xy 185.7905 -216.677275) (xy 185.824586 -216.633132)
			(xy 185.864735 -216.594423) (xy 185.910093 -216.561972) (xy 185.959693 -216.536471) (xy 186.012477 -216.518464)
			(xy 186.06732 -216.508334) (xy 186.123054 -216.506297) (xy 186.178491 -216.512397) (xy 186.232448 -216.526503)
			(xy 186.283777 -216.548315) (xy 186.331383 -216.577369) (xy 186.374251 -216.613044) (xy 186.411468 -216.654581)
			(xy 186.442241 -216.701094) (xy 186.465913 -216.751591) (xy 186.481981 -216.804998) (xy 186.490101 -216.860174)
			(xy 186.49061 -216.88806) (xy 186.490101 -216.915946) (xy 186.481981 -216.971122) (xy 186.465913 -217.024529)
			(xy 186.442241 -217.075026) (xy 186.411468 -217.121539) (xy 186.374251 -217.163076) (xy 186.331383 -217.198751)
			(xy 186.283777 -217.227805) (xy 186.232448 -217.249617) (xy 186.178491 -217.263723) (xy 186.123054 -217.269823)
			(xy 186.06732 -217.267786) (xy 186.012477 -217.257656) (xy 185.959693 -217.239649) (xy 185.910093 -217.214148)
			(xy 185.864735 -217.181697) (xy 185.824586 -217.142988) (xy 185.7905 -217.098845) (xy 185.763204 -217.05021)
			(xy 185.743281 -216.998119) (xy 185.731155 -216.943682) (xy 185.727084 -216.88806) (xy 184.569737 -216.88806)
			(xy 184.110696 -219.523564) (xy 186.561982 -219.523564) (xy 186.566053 -219.467942) (xy 186.578179 -219.413505)
			(xy 186.598102 -219.361414) (xy 186.625398 -219.312779) (xy 186.659484 -219.268636) (xy 186.699633 -219.229927)
			(xy 186.744991 -219.197476) (xy 186.794591 -219.171975) (xy 186.847375 -219.153968) (xy 186.902218 -219.143838)
			(xy 186.957952 -219.141801) (xy 187.013389 -219.147901) (xy 187.067346 -219.162007) (xy 187.118675 -219.183819)
			(xy 187.166281 -219.212873) (xy 187.209149 -219.248548) (xy 187.246366 -219.290085) (xy 187.277139 -219.336598)
			(xy 187.300811 -219.387095) (xy 187.316879 -219.440502) (xy 187.324999 -219.495678) (xy 187.325508 -219.523564)
			(xy 187.324999 -219.55145) (xy 187.316879 -219.606626) (xy 187.300811 -219.660033) (xy 187.277139 -219.71053)
			(xy 187.246366 -219.757043) (xy 187.209149 -219.79858) (xy 187.166281 -219.834255) (xy 187.118675 -219.863309)
			(xy 187.067346 -219.885121) (xy 187.013389 -219.899227) (xy 186.957952 -219.905327) (xy 186.902218 -219.90329)
			(xy 186.847375 -219.89316) (xy 186.794591 -219.875153) (xy 186.744991 -219.849652) (xy 186.699633 -219.817201)
			(xy 186.659484 -219.778492) (xy 186.625398 -219.734349) (xy 186.598102 -219.685714) (xy 186.578179 -219.633623)
			(xy 186.566053 -219.579186) (xy 186.561982 -219.523564) (xy 184.110696 -219.523564) (xy 183.899048 -220.7387)
			(xy 183.900064 -220.751146) (xy 183.902096 -220.757242) (xy 183.911354 -220.786672) (xy 183.921317 -220.847554)
			(xy 183.921908 -220.8784) (xy 183.921483 -220.903911) (xy 183.91469 -220.95448) (xy 183.901223 -221.003694)
			(xy 183.881323 -221.050676) (xy 183.855344 -221.094591) (xy 183.839866 -221.114874) (xy 183.835802 -221.119954)
			(xy 183.830722 -221.13113) (xy 183.120436 -225.209862) (xy 184.70575 -225.209862) (xy 184.709821 -225.15424)
			(xy 184.721947 -225.099803) (xy 184.74187 -225.047712) (xy 184.769166 -224.999077) (xy 184.803252 -224.954934)
			(xy 184.843401 -224.916225) (xy 184.888759 -224.883774) (xy 184.938359 -224.858273) (xy 184.991143 -224.840266)
			(xy 185.045986 -224.830136) (xy 185.10172 -224.828099) (xy 185.157157 -224.834199) (xy 185.211114 -224.848305)
			(xy 185.262443 -224.870117) (xy 185.310049 -224.899171) (xy 185.352917 -224.934846) (xy 185.390134 -224.976383)
			(xy 185.420907 -225.022896) (xy 185.444579 -225.073393) (xy 185.460647 -225.1268) (xy 185.468767 -225.181976)
			(xy 185.469276 -225.209862) (xy 185.468767 -225.237748) (xy 185.460647 -225.292924) (xy 185.444579 -225.346331)
			(xy 185.420907 -225.396828) (xy 185.390134 -225.443341) (xy 185.352917 -225.484878) (xy 185.310049 -225.520553)
			(xy 185.262443 -225.549607) (xy 185.211114 -225.571419) (xy 185.157157 -225.585525) (xy 185.10172 -225.591625)
			(xy 185.045986 -225.589588) (xy 184.991143 -225.579458) (xy 184.938359 -225.561451) (xy 184.888759 -225.53595)
			(xy 184.843401 -225.503499) (xy 184.803252 -225.46479) (xy 184.769166 -225.420647) (xy 184.74187 -225.372012)
			(xy 184.721947 -225.319921) (xy 184.709821 -225.265484) (xy 184.70575 -225.209862) (xy 183.120436 -225.209862)
			(xy 182.833367 -226.858322) (xy 183.69356 -226.858322) (xy 183.697631 -226.8027) (xy 183.709757 -226.748263)
			(xy 183.72968 -226.696172) (xy 183.756976 -226.647537) (xy 183.791062 -226.603394) (xy 183.831211 -226.564685)
			(xy 183.876569 -226.532234) (xy 183.926169 -226.506733) (xy 183.978953 -226.488726) (xy 184.033796 -226.478596)
			(xy 184.08953 -226.476559) (xy 184.144967 -226.482659) (xy 184.17216 -226.489768) (xy 184.657744 -226.489768)
			(xy 184.661815 -226.434146) (xy 184.673941 -226.379709) (xy 184.693864 -226.327618) (xy 184.72116 -226.278983)
			(xy 184.755246 -226.23484) (xy 184.795395 -226.196131) (xy 184.840753 -226.16368) (xy 184.890353 -226.138179)
			(xy 184.943137 -226.120172) (xy 184.99798 -226.110042) (xy 185.053714 -226.108005) (xy 185.109151 -226.114105)
			(xy 185.163108 -226.128211) (xy 185.214437 -226.150023) (xy 185.262043 -226.179077) (xy 185.286214 -226.199192)
			(xy 186.67679 -226.199192) (xy 186.680861 -226.14357) (xy 186.692987 -226.089133) (xy 186.71291 -226.037042)
			(xy 186.740206 -225.988407) (xy 186.774292 -225.944264) (xy 186.814441 -225.905555) (xy 186.859799 -225.873104)
			(xy 186.909399 -225.847603) (xy 186.962183 -225.829596) (xy 187.017026 -225.819466) (xy 187.07276 -225.817429)
			(xy 187.128197 -225.823529) (xy 187.182154 -225.837635) (xy 187.233483 -225.859447) (xy 187.281089 -225.888501)
			(xy 187.323957 -225.924176) (xy 187.361174 -225.965713) (xy 187.391947 -226.012226) (xy 187.415619 -226.062723)
			(xy 187.431687 -226.11613) (xy 187.439807 -226.171306) (xy 187.440316 -226.199192) (xy 187.439807 -226.227078)
			(xy 187.431687 -226.282254) (xy 187.415619 -226.335661) (xy 187.391947 -226.386158) (xy 187.361174 -226.432671)
			(xy 187.323957 -226.474208) (xy 187.281089 -226.509883) (xy 187.233483 -226.538937) (xy 187.182154 -226.560749)
			(xy 187.128197 -226.574855) (xy 187.07276 -226.580955) (xy 187.017026 -226.578918) (xy 186.962183 -226.568788)
			(xy 186.909399 -226.550781) (xy 186.859799 -226.52528) (xy 186.814441 -226.492829) (xy 186.774292 -226.45412)
			(xy 186.740206 -226.409977) (xy 186.71291 -226.361342) (xy 186.692987 -226.309251) (xy 186.680861 -226.254814)
			(xy 186.67679 -226.199192) (xy 185.286214 -226.199192) (xy 185.304911 -226.214752) (xy 185.342128 -226.256289)
			(xy 185.372901 -226.302802) (xy 185.396573 -226.353299) (xy 185.412641 -226.406706) (xy 185.420761 -226.461882)
			(xy 185.42127 -226.489768) (xy 185.420761 -226.517654) (xy 185.412641 -226.57283) (xy 185.396573 -226.626237)
			(xy 185.372901 -226.676734) (xy 185.342128 -226.723247) (xy 185.304911 -226.764784) (xy 185.262043 -226.800459)
			(xy 185.214437 -226.829513) (xy 185.163108 -226.851325) (xy 185.109151 -226.865431) (xy 185.053714 -226.871531)
			(xy 184.99798 -226.869494) (xy 184.943137 -226.859364) (xy 184.890353 -226.841357) (xy 184.840753 -226.815856)
			(xy 184.795395 -226.783405) (xy 184.755246 -226.744696) (xy 184.72116 -226.700553) (xy 184.693864 -226.651918)
			(xy 184.673941 -226.599827) (xy 184.661815 -226.54539) (xy 184.657744 -226.489768) (xy 184.17216 -226.489768)
			(xy 184.198924 -226.496765) (xy 184.250253 -226.518577) (xy 184.297859 -226.547631) (xy 184.340727 -226.583306)
			(xy 184.377944 -226.624843) (xy 184.408717 -226.671356) (xy 184.432389 -226.721853) (xy 184.448457 -226.77526)
			(xy 184.456577 -226.830436) (xy 184.457086 -226.858322) (xy 184.456577 -226.886208) (xy 184.448457 -226.941384)
			(xy 184.432389 -226.994791) (xy 184.408717 -227.045288) (xy 184.377944 -227.091801) (xy 184.340727 -227.133338)
			(xy 184.297859 -227.169013) (xy 184.250253 -227.198067) (xy 184.198924 -227.219879) (xy 184.144967 -227.233985)
			(xy 184.08953 -227.240085) (xy 184.033796 -227.238048) (xy 183.978953 -227.227918) (xy 183.926169 -227.209911)
			(xy 183.876569 -227.18441) (xy 183.831211 -227.151959) (xy 183.791062 -227.11325) (xy 183.756976 -227.069107)
			(xy 183.72968 -227.020472) (xy 183.709757 -226.968381) (xy 183.697631 -226.913944) (xy 183.69356 -226.858322)
			(xy 182.833367 -226.858322) (xy 182.380382 -229.459536) (xy 182.379119 -229.469873) (xy 182.384019 -229.490093)
			(xy 182.396518 -229.506725) (xy 182.405274 -229.512368) (xy 182.502302 -229.56774) (xy 182.534052 -229.564692)
			(xy 182.546498 -229.554278) (xy 182.567293 -229.537155) (xy 182.612792 -229.508319) (xy 182.661897 -229.486175)
			(xy 182.71363 -229.471162) (xy 182.76696 -229.463579) (xy 182.793894 -229.463092) (xy 182.821147 -229.463555)
			(xy 182.875099 -229.471311) (xy 182.927397 -229.486667) (xy 182.976978 -229.509309) (xy 183.022832 -229.538777)
			(xy 183.064025 -229.57447) (xy 183.09972 -229.615663) (xy 183.129188 -229.661517) (xy 183.151831 -229.711097)
			(xy 183.167188 -229.763395) (xy 183.174945 -229.817347) (xy 183.174945 -229.871853) (xy 183.167188 -229.925805)
			(xy 183.151831 -229.978103) (xy 183.129188 -230.027683) (xy 183.09972 -230.073537) (xy 183.064025 -230.11473)
			(xy 183.022832 -230.150423) (xy 182.976978 -230.179891) (xy 182.927397 -230.202533) (xy 182.875099 -230.217889)
			(xy 182.821147 -230.225645) (xy 182.793894 -230.226108) (xy 182.765247 -230.225592) (xy 182.7086 -230.217017)
			(xy 182.653873 -230.200062) (xy 182.6023 -230.175107) (xy 182.555042 -230.142716) (xy 182.513163 -230.103617)
			(xy 182.477608 -230.058692) (xy 182.462932 -230.034084) (xy 182.454804 -230.020114) (xy 182.425848 -230.006652)
			(xy 182.315866 -230.025956) (xy 182.305705 -230.028226) (xy 182.2883 -230.039614) (xy 182.276823 -230.056961)
			(xy 182.274464 -230.067104) (xy 181.331452 -235.48213) (xy 183.206388 -235.48213) (xy 183.210459 -235.426508)
			(xy 183.222585 -235.372071) (xy 183.242508 -235.31998) (xy 183.269804 -235.271345) (xy 183.30389 -235.227202)
			(xy 183.344039 -235.188493) (xy 183.389397 -235.156042) (xy 183.438997 -235.130541) (xy 183.491781 -235.112534)
			(xy 183.546624 -235.102404) (xy 183.602358 -235.100367) (xy 183.657795 -235.106467) (xy 183.711752 -235.120573)
			(xy 183.763081 -235.142385) (xy 183.810687 -235.171439) (xy 183.853555 -235.207114) (xy 183.890772 -235.248651)
			(xy 183.921545 -235.295164) (xy 183.945217 -235.345661) (xy 183.961285 -235.399068) (xy 183.969405 -235.454244)
			(xy 183.969914 -235.48213) (xy 183.969405 -235.510016) (xy 183.961285 -235.565192) (xy 183.945217 -235.618599)
			(xy 183.921545 -235.669096) (xy 183.890772 -235.715609) (xy 183.853555 -235.757146) (xy 183.810687 -235.792821)
			(xy 183.763081 -235.821875) (xy 183.711752 -235.843687) (xy 183.657795 -235.857793) (xy 183.602358 -235.863893)
			(xy 183.546624 -235.861856) (xy 183.491781 -235.851726) (xy 183.438997 -235.833719) (xy 183.389397 -235.808218)
			(xy 183.344039 -235.775767) (xy 183.30389 -235.737058) (xy 183.269804 -235.692915) (xy 183.242508 -235.64428)
			(xy 183.222585 -235.592189) (xy 183.210459 -235.537752) (xy 183.206388 -235.48213) (xy 181.331452 -235.48213)
			(xy 181.12643 -236.65942) (xy 182.566816 -236.65942) (xy 182.570887 -236.603798) (xy 182.583013 -236.549361)
			(xy 182.602936 -236.49727) (xy 182.630232 -236.448635) (xy 182.664318 -236.404492) (xy 182.704467 -236.365783)
			(xy 182.749825 -236.333332) (xy 182.799425 -236.307831) (xy 182.852209 -236.289824) (xy 182.907052 -236.279694)
			(xy 182.962786 -236.277657) (xy 183.018223 -236.283757) (xy 183.07218 -236.297863) (xy 183.123509 -236.319675)
			(xy 183.171115 -236.348729) (xy 183.213983 -236.384404) (xy 183.2512 -236.425941) (xy 183.281973 -236.472454)
			(xy 183.300201 -236.511338) (xy 207.013808 -236.511338) (xy 207.017879 -236.455716) (xy 207.030005 -236.401279)
			(xy 207.049928 -236.349188) (xy 207.077224 -236.300553) (xy 207.11131 -236.25641) (xy 207.151459 -236.217701)
			(xy 207.196817 -236.18525) (xy 207.246417 -236.159749) (xy 207.299201 -236.141742) (xy 207.354044 -236.131612)
			(xy 207.409778 -236.129575) (xy 207.465215 -236.135675) (xy 207.519172 -236.149781) (xy 207.570501 -236.171593)
			(xy 207.618107 -236.200647) (xy 207.660975 -236.236322) (xy 207.698192 -236.277859) (xy 207.728965 -236.324372)
			(xy 207.752637 -236.374869) (xy 207.759536 -236.3978) (xy 208.80019 -236.3978) (xy 208.804261 -236.342178)
			(xy 208.816387 -236.287741) (xy 208.83631 -236.23565) (xy 208.863606 -236.187015) (xy 208.897692 -236.142872)
			(xy 208.937841 -236.104163) (xy 208.983199 -236.071712) (xy 209.032799 -236.046211) (xy 209.085583 -236.028204)
			(xy 209.140426 -236.018074) (xy 209.19616 -236.016037) (xy 209.251597 -236.022137) (xy 209.305554 -236.036243)
			(xy 209.356883 -236.058055) (xy 209.404489 -236.087109) (xy 209.447357 -236.122784) (xy 209.484574 -236.164321)
			(xy 209.515347 -236.210834) (xy 209.539019 -236.261331) (xy 209.555087 -236.314738) (xy 209.563207 -236.369914)
			(xy 209.563716 -236.3978) (xy 209.563207 -236.425686) (xy 209.555087 -236.480862) (xy 209.539019 -236.534269)
			(xy 209.515347 -236.584766) (xy 209.484574 -236.631279) (xy 209.447357 -236.672816) (xy 209.404489 -236.708491)
			(xy 209.356883 -236.737545) (xy 209.305554 -236.759357) (xy 209.251597 -236.773463) (xy 209.19616 -236.779563)
			(xy 209.140426 -236.777526) (xy 209.085583 -236.767396) (xy 209.032799 -236.749389) (xy 208.983199 -236.723888)
			(xy 208.937841 -236.691437) (xy 208.897692 -236.652728) (xy 208.863606 -236.608585) (xy 208.83631 -236.55995)
			(xy 208.816387 -236.507859) (xy 208.804261 -236.453422) (xy 208.80019 -236.3978) (xy 207.759536 -236.3978)
			(xy 207.768705 -236.428276) (xy 207.776825 -236.483452) (xy 207.777334 -236.511338) (xy 207.776825 -236.539224)
			(xy 207.768705 -236.5944) (xy 207.752637 -236.647807) (xy 207.728965 -236.698304) (xy 207.698192 -236.744817)
			(xy 207.660975 -236.786354) (xy 207.618107 -236.822029) (xy 207.570501 -236.851083) (xy 207.519172 -236.872895)
			(xy 207.465215 -236.887001) (xy 207.409778 -236.893101) (xy 207.354044 -236.891064) (xy 207.299201 -236.880934)
			(xy 207.246417 -236.862927) (xy 207.196817 -236.837426) (xy 207.151459 -236.804975) (xy 207.11131 -236.766266)
			(xy 207.077224 -236.722123) (xy 207.049928 -236.673488) (xy 207.030005 -236.621397) (xy 207.017879 -236.56696)
			(xy 207.013808 -236.511338) (xy 183.300201 -236.511338) (xy 183.305645 -236.522951) (xy 183.321713 -236.576358)
			(xy 183.329833 -236.631534) (xy 183.330342 -236.65942) (xy 183.329833 -236.687306) (xy 183.321713 -236.742482)
			(xy 183.305645 -236.795889) (xy 183.281973 -236.846386) (xy 183.2512 -236.892899) (xy 183.213983 -236.934436)
			(xy 183.171115 -236.970111) (xy 183.123509 -236.999165) (xy 183.07218 -237.020977) (xy 183.018223 -237.035083)
			(xy 182.962786 -237.041183) (xy 182.907052 -237.039146) (xy 182.852209 -237.029016) (xy 182.799425 -237.011009)
			(xy 182.749825 -236.985508) (xy 182.704467 -236.953057) (xy 182.664318 -236.914348) (xy 182.630232 -236.870205)
			(xy 182.602936 -236.82157) (xy 182.583013 -236.769479) (xy 182.570887 -236.715042) (xy 182.566816 -236.65942)
			(xy 181.12643 -236.65942) (xy 180.995499 -237.41126) (xy 216.287602 -237.41126) (xy 216.291673 -237.355638)
			(xy 216.303799 -237.301201) (xy 216.323722 -237.24911) (xy 216.351018 -237.200475) (xy 216.385104 -237.156332)
			(xy 216.425253 -237.117623) (xy 216.470611 -237.085172) (xy 216.520211 -237.059671) (xy 216.572995 -237.041664)
			(xy 216.627838 -237.031534) (xy 216.683572 -237.029497) (xy 216.739009 -237.035597) (xy 216.792966 -237.049703)
			(xy 216.844295 -237.071515) (xy 216.891901 -237.100569) (xy 216.934769 -237.136244) (xy 216.971986 -237.177781)
			(xy 217.002759 -237.224294) (xy 217.026431 -237.274791) (xy 217.042499 -237.328198) (xy 217.047808 -237.36427)
			(xy 217.702636 -237.36427) (xy 217.706707 -237.308648) (xy 217.718833 -237.254211) (xy 217.738756 -237.20212)
			(xy 217.766052 -237.153485) (xy 217.800138 -237.109342) (xy 217.840287 -237.070633) (xy 217.885645 -237.038182)
			(xy 217.935245 -237.012681) (xy 217.988029 -236.994674) (xy 218.042872 -236.984544) (xy 218.098606 -236.982507)
			(xy 218.154043 -236.988607) (xy 218.208 -237.002713) (xy 218.259329 -237.024525) (xy 218.306935 -237.053579)
			(xy 218.349803 -237.089254) (xy 218.38702 -237.130791) (xy 218.417793 -237.177304) (xy 218.441465 -237.227801)
			(xy 218.457533 -237.281208) (xy 218.465653 -237.336384) (xy 218.466162 -237.36427) (xy 218.465653 -237.392156)
			(xy 218.457533 -237.447332) (xy 218.441465 -237.500739) (xy 218.417793 -237.551236) (xy 218.38702 -237.597749)
			(xy 218.349803 -237.639286) (xy 218.306935 -237.674961) (xy 218.259329 -237.704015) (xy 218.208 -237.725827)
			(xy 218.174435 -237.734602) (xy 219.860366 -237.734602) (xy 219.864437 -237.67898) (xy 219.876563 -237.624543)
			(xy 219.896486 -237.572452) (xy 219.923782 -237.523817) (xy 219.957868 -237.479674) (xy 219.998017 -237.440965)
			(xy 220.043375 -237.408514) (xy 220.092975 -237.383013) (xy 220.145759 -237.365006) (xy 220.200602 -237.354876)
			(xy 220.256336 -237.352839) (xy 220.311773 -237.358939) (xy 220.36573 -237.373045) (xy 220.417059 -237.394857)
			(xy 220.464665 -237.423911) (xy 220.472659 -237.430564) (xy 221.137986 -237.430564) (xy 221.142057 -237.374942)
			(xy 221.154183 -237.320505) (xy 221.174106 -237.268414) (xy 221.201402 -237.219779) (xy 221.235488 -237.175636)
			(xy 221.275637 -237.136927) (xy 221.320995 -237.104476) (xy 221.370595 -237.078975) (xy 221.423379 -237.060968)
			(xy 221.478222 -237.050838) (xy 221.533956 -237.048801) (xy 221.589393 -237.054901) (xy 221.64335 -237.069007)
			(xy 221.694679 -237.090819) (xy 221.712816 -237.101888) (xy 223.839784 -237.101888) (xy 223.843855 -237.046266)
			(xy 223.855981 -236.991829) (xy 223.875904 -236.939738) (xy 223.9032 -236.891103) (xy 223.937286 -236.84696)
			(xy 223.977435 -236.808251) (xy 224.022793 -236.7758) (xy 224.072393 -236.750299) (xy 224.125177 -236.732292)
			(xy 224.18002 -236.722162) (xy 224.235754 -236.720125) (xy 224.291191 -236.726225) (xy 224.345148 -236.740331)
			(xy 224.396477 -236.762143) (xy 224.444083 -236.791197) (xy 224.486951 -236.826872) (xy 224.524168 -236.868409)
			(xy 224.554941 -236.914922) (xy 224.578613 -236.965419) (xy 224.594681 -237.018826) (xy 224.602801 -237.074002)
			(xy 224.60331 -237.101888) (xy 224.602801 -237.129774) (xy 224.594681 -237.18495) (xy 224.578613 -237.238357)
			(xy 224.554941 -237.288854) (xy 224.524168 -237.335367) (xy 224.486951 -237.376904) (xy 224.444083 -237.412579)
			(xy 224.396477 -237.441633) (xy 224.345148 -237.463445) (xy 224.291191 -237.477551) (xy 224.235754 -237.483651)
			(xy 224.18002 -237.481614) (xy 224.125177 -237.471484) (xy 224.072393 -237.453477) (xy 224.022793 -237.427976)
			(xy 223.977435 -237.395525) (xy 223.937286 -237.356816) (xy 223.9032 -237.312673) (xy 223.875904 -237.264038)
			(xy 223.855981 -237.211947) (xy 223.843855 -237.15751) (xy 223.839784 -237.101888) (xy 221.712816 -237.101888)
			(xy 221.742285 -237.119873) (xy 221.785153 -237.155548) (xy 221.82237 -237.197085) (xy 221.853143 -237.243598)
			(xy 221.876815 -237.294095) (xy 221.892883 -237.347502) (xy 221.901003 -237.402678) (xy 221.901512 -237.430564)
			(xy 221.901003 -237.45845) (xy 221.892883 -237.513626) (xy 221.876815 -237.567033) (xy 221.853143 -237.61753)
			(xy 221.82237 -237.664043) (xy 221.785153 -237.70558) (xy 221.742285 -237.741255) (xy 221.694679 -237.770309)
			(xy 221.64335 -237.792121) (xy 221.589393 -237.806227) (xy 221.533956 -237.812327) (xy 221.478222 -237.81029)
			(xy 221.423379 -237.80016) (xy 221.370595 -237.782153) (xy 221.320995 -237.756652) (xy 221.275637 -237.724201)
			(xy 221.235488 -237.685492) (xy 221.201402 -237.641349) (xy 221.174106 -237.592714) (xy 221.154183 -237.540623)
			(xy 221.142057 -237.486186) (xy 221.137986 -237.430564) (xy 220.472659 -237.430564) (xy 220.507533 -237.459586)
			(xy 220.54475 -237.501123) (xy 220.575523 -237.547636) (xy 220.599195 -237.598133) (xy 220.615263 -237.65154)
			(xy 220.623383 -237.706716) (xy 220.623892 -237.734602) (xy 220.623383 -237.762488) (xy 220.615263 -237.817664)
			(xy 220.599195 -237.871071) (xy 220.575523 -237.921568) (xy 220.54475 -237.968081) (xy 220.507533 -238.009618)
			(xy 220.464665 -238.045293) (xy 220.417059 -238.074347) (xy 220.36573 -238.096159) (xy 220.311773 -238.110265)
			(xy 220.256336 -238.116365) (xy 220.200602 -238.114328) (xy 220.145759 -238.104198) (xy 220.092975 -238.086191)
			(xy 220.043375 -238.06069) (xy 219.998017 -238.028239) (xy 219.957868 -237.98953) (xy 219.923782 -237.945387)
			(xy 219.896486 -237.896752) (xy 219.876563 -237.844661) (xy 219.864437 -237.790224) (xy 219.860366 -237.734602)
			(xy 218.174435 -237.734602) (xy 218.154043 -237.739933) (xy 218.098606 -237.746033) (xy 218.042872 -237.743996)
			(xy 217.988029 -237.733866) (xy 217.935245 -237.715859) (xy 217.885645 -237.690358) (xy 217.840287 -237.657907)
			(xy 217.800138 -237.619198) (xy 217.766052 -237.575055) (xy 217.738756 -237.52642) (xy 217.718833 -237.474329)
			(xy 217.706707 -237.419892) (xy 217.702636 -237.36427) (xy 217.047808 -237.36427) (xy 217.050619 -237.383374)
			(xy 217.051128 -237.41126) (xy 217.050619 -237.439146) (xy 217.042499 -237.494322) (xy 217.026431 -237.547729)
			(xy 217.002759 -237.598226) (xy 216.971986 -237.644739) (xy 216.934769 -237.686276) (xy 216.891901 -237.721951)
			(xy 216.844295 -237.751005) (xy 216.792966 -237.772817) (xy 216.739009 -237.786923) (xy 216.683572 -237.793023)
			(xy 216.627838 -237.790986) (xy 216.572995 -237.780856) (xy 216.520211 -237.762849) (xy 216.470611 -237.737348)
			(xy 216.425253 -237.704897) (xy 216.385104 -237.666188) (xy 216.351018 -237.622045) (xy 216.323722 -237.57341)
			(xy 216.303799 -237.521319) (xy 216.291673 -237.466882) (xy 216.287602 -237.41126) (xy 180.995499 -237.41126)
			(xy 180.775881 -238.67237) (xy 209.019138 -238.67237) (xy 209.023209 -238.616748) (xy 209.035335 -238.562311)
			(xy 209.055258 -238.51022) (xy 209.082554 -238.461585) (xy 209.11664 -238.417442) (xy 209.156789 -238.378733)
			(xy 209.202147 -238.346282) (xy 209.251747 -238.320781) (xy 209.304531 -238.302774) (xy 209.359374 -238.292644)
			(xy 209.415108 -238.290607) (xy 209.470545 -238.296707) (xy 209.524502 -238.310813) (xy 209.575831 -238.332625)
			(xy 209.623437 -238.361679) (xy 209.666305 -238.397354) (xy 209.703522 -238.438891) (xy 209.734295 -238.485404)
			(xy 209.757967 -238.535901) (xy 209.774035 -238.589308) (xy 209.782155 -238.644484) (xy 209.78233 -238.654082)
			(xy 210.3407 -238.654082) (xy 210.344771 -238.59846) (xy 210.356897 -238.544023) (xy 210.37682 -238.491932)
			(xy 210.404116 -238.443297) (xy 210.438202 -238.399154) (xy 210.478351 -238.360445) (xy 210.523709 -238.327994)
			(xy 210.573309 -238.302493) (xy 210.626093 -238.284486) (xy 210.680936 -238.274356) (xy 210.73667 -238.272319)
			(xy 210.792107 -238.278419) (xy 210.846064 -238.292525) (xy 210.897393 -238.314337) (xy 210.944999 -238.343391)
			(xy 210.987867 -238.379066) (xy 211.025084 -238.420603) (xy 211.055857 -238.467116) (xy 211.079529 -238.517613)
			(xy 211.095597 -238.57102) (xy 211.103717 -238.626196) (xy 211.104226 -238.654082) (xy 211.103746 -238.680353)
			(xy 211.374444 -238.680353) (xy 211.374444 -238.625847) (xy 211.382201 -238.571896) (xy 211.397556 -238.519598)
			(xy 211.420198 -238.470018) (xy 211.449665 -238.424164) (xy 211.485358 -238.382971) (xy 211.52655 -238.347276)
			(xy 211.572402 -238.317807) (xy 211.621981 -238.295162) (xy 211.674279 -238.279804) (xy 211.728229 -238.272045)
			(xy 211.755482 -238.271558) (xy 211.783662 -238.272089) (xy 211.839409 -238.280384) (xy 211.893331 -238.296781)
			(xy 211.944258 -238.320925) (xy 211.991083 -238.352291) (xy 212.012276 -238.370872) (xy 212.019134 -238.377222)
			(xy 212.036914 -238.38408) (xy 212.12429 -238.38408) (xy 212.14207 -238.377222) (xy 212.148928 -238.370872)
			(xy 212.170123 -238.352291) (xy 212.21694 -238.320907) (xy 212.267865 -238.296751) (xy 212.32179 -238.280351)
			(xy 212.37754 -238.272062) (xy 212.405722 -238.271558) (xy 212.43297 -238.272114) (xy 212.48691 -238.279872)
			(xy 212.539198 -238.295228) (xy 212.588768 -238.317868) (xy 212.634611 -238.347332) (xy 212.675795 -238.383021)
			(xy 212.711481 -238.424207) (xy 212.740943 -238.470052) (xy 212.76358 -238.519623) (xy 212.778933 -238.571911)
			(xy 212.786688 -238.625852) (xy 212.786688 -238.680348) (xy 212.778933 -238.734289) (xy 212.76358 -238.786577)
			(xy 212.740943 -238.836148) (xy 212.711481 -238.881993) (xy 212.675795 -238.923179) (xy 212.634611 -238.958868)
			(xy 212.588768 -238.988332) (xy 212.539198 -239.010972) (xy 212.48691 -239.026328) (xy 212.43297 -239.034086)
			(xy 212.405722 -239.034574) (xy 212.377542 -239.034033) (xy 212.321797 -239.025739) (xy 212.267875 -239.009344)
			(xy 212.216948 -238.985202) (xy 212.170122 -238.953839) (xy 212.148928 -238.93526) (xy 212.14207 -238.92891)
			(xy 212.12429 -238.922052) (xy 212.036914 -238.922052) (xy 212.019134 -238.92891) (xy 212.012276 -238.93526)
			(xy 211.991084 -238.953844) (xy 211.944265 -238.985227) (xy 211.89334 -239.009381) (xy 211.839415 -239.025781)
			(xy 211.783664 -239.03407) (xy 211.755482 -239.034574) (xy 211.728229 -239.034155) (xy 211.674279 -239.026396)
			(xy 211.621981 -239.011038) (xy 211.572402 -238.988393) (xy 211.52655 -238.958924) (xy 211.485358 -238.923229)
			(xy 211.449665 -238.882036) (xy 211.420198 -238.836182) (xy 211.397556 -238.786602) (xy 211.382201 -238.734304)
			(xy 211.374444 -238.680353) (xy 211.103746 -238.680353) (xy 211.103717 -238.681968) (xy 211.095597 -238.737144)
			(xy 211.079529 -238.790551) (xy 211.055857 -238.841048) (xy 211.025084 -238.887561) (xy 210.987867 -238.929098)
			(xy 210.944999 -238.964773) (xy 210.897393 -238.993827) (xy 210.846064 -239.015639) (xy 210.792107 -239.029745)
			(xy 210.73667 -239.035845) (xy 210.680936 -239.033808) (xy 210.626093 -239.023678) (xy 210.573309 -239.005671)
			(xy 210.523709 -238.98017) (xy 210.478351 -238.947719) (xy 210.438202 -238.90901) (xy 210.404116 -238.864867)
			(xy 210.37682 -238.816232) (xy 210.356897 -238.764141) (xy 210.344771 -238.709704) (xy 210.3407 -238.654082)
			(xy 209.78233 -238.654082) (xy 209.782664 -238.67237) (xy 209.782155 -238.700256) (xy 209.774035 -238.755432)
			(xy 209.757967 -238.808839) (xy 209.734295 -238.859336) (xy 209.703522 -238.905849) (xy 209.666305 -238.947386)
			(xy 209.623437 -238.983061) (xy 209.575831 -239.012115) (xy 209.524502 -239.033927) (xy 209.478306 -239.046004)
			(xy 226.0252 -239.046004) (xy 226.029271 -238.990382) (xy 226.041397 -238.935945) (xy 226.06132 -238.883854)
			(xy 226.088616 -238.835219) (xy 226.122702 -238.791076) (xy 226.162851 -238.752367) (xy 226.208209 -238.719916)
			(xy 226.257809 -238.694415) (xy 226.310593 -238.676408) (xy 226.365436 -238.666278) (xy 226.42117 -238.664241)
			(xy 226.476607 -238.670341) (xy 226.530564 -238.684447) (xy 226.581893 -238.706259) (xy 226.629499 -238.735313)
			(xy 226.672367 -238.770988) (xy 226.709584 -238.812525) (xy 226.740357 -238.859038) (xy 226.764029 -238.909535)
			(xy 226.780097 -238.962942) (xy 226.783686 -238.98733) (xy 228.467664 -238.98733) (xy 228.471735 -238.931708)
			(xy 228.483861 -238.877271) (xy 228.503784 -238.82518) (xy 228.53108 -238.776545) (xy 228.565166 -238.732402)
			(xy 228.605315 -238.693693) (xy 228.650673 -238.661242) (xy 228.700273 -238.635741) (xy 228.753057 -238.617734)
			(xy 228.8079 -238.607604) (xy 228.863634 -238.605567) (xy 228.919071 -238.611667) (xy 228.973028 -238.625773)
			(xy 229.024357 -238.647585) (xy 229.071963 -238.676639) (xy 229.114831 -238.712314) (xy 229.152048 -238.753851)
			(xy 229.182821 -238.800364) (xy 229.206493 -238.850861) (xy 229.222561 -238.904268) (xy 229.230681 -238.959444)
			(xy 229.23119 -238.98733) (xy 229.230681 -239.015216) (xy 229.222561 -239.070392) (xy 229.206493 -239.123799)
			(xy 229.182821 -239.174296) (xy 229.152048 -239.220809) (xy 229.114831 -239.262346) (xy 229.071963 -239.298021)
			(xy 229.024357 -239.327075) (xy 228.973028 -239.348887) (xy 228.919071 -239.362993) (xy 228.863634 -239.369093)
			(xy 228.8079 -239.367056) (xy 228.753057 -239.356926) (xy 228.700273 -239.338919) (xy 228.650673 -239.313418)
			(xy 228.605315 -239.280967) (xy 228.565166 -239.242258) (xy 228.53108 -239.198115) (xy 228.503784 -239.14948)
			(xy 228.483861 -239.097389) (xy 228.471735 -239.042952) (xy 228.467664 -238.98733) (xy 226.783686 -238.98733)
			(xy 226.788217 -239.018118) (xy 226.788726 -239.046004) (xy 226.788217 -239.07389) (xy 226.780097 -239.129066)
			(xy 226.764029 -239.182473) (xy 226.740357 -239.23297) (xy 226.709584 -239.279483) (xy 226.672367 -239.32102)
			(xy 226.629499 -239.356695) (xy 226.581893 -239.385749) (xy 226.530564 -239.407561) (xy 226.476607 -239.421667)
			(xy 226.42117 -239.427767) (xy 226.365436 -239.42573) (xy 226.310593 -239.4156) (xy 226.257809 -239.397593)
			(xy 226.208209 -239.372092) (xy 226.162851 -239.339641) (xy 226.122702 -239.300932) (xy 226.088616 -239.256789)
			(xy 226.06132 -239.208154) (xy 226.041397 -239.156063) (xy 226.029271 -239.101626) (xy 226.0252 -239.046004)
			(xy 209.478306 -239.046004) (xy 209.470545 -239.048033) (xy 209.415108 -239.054133) (xy 209.359374 -239.052096)
			(xy 209.304531 -239.041966) (xy 209.251747 -239.023959) (xy 209.202147 -238.998458) (xy 209.156789 -238.966007)
			(xy 209.11664 -238.927298) (xy 209.082554 -238.883155) (xy 209.055258 -238.83452) (xy 209.035335 -238.782429)
			(xy 209.023209 -238.727992) (xy 209.019138 -238.67237) (xy 180.775881 -238.67237) (xy 180.645291 -239.422251)
			(xy 183.108578 -239.422251) (xy 183.108578 -239.367749) (xy 183.116334 -239.313801) (xy 183.131689 -239.261506)
			(xy 183.154331 -239.211929) (xy 183.183797 -239.166079) (xy 183.219488 -239.124888) (xy 183.260679 -239.089197)
			(xy 183.306529 -239.059731) (xy 183.356106 -239.037089) (xy 183.408401 -239.021734) (xy 183.462349 -239.013978)
			(xy 183.4896 -239.013492) (xy 183.515775 -239.013916) (xy 183.567631 -239.021092) (xy 183.618017 -239.035297)
			(xy 183.665986 -239.056263) (xy 183.710635 -239.083595) (xy 183.731154 -239.099852) (xy 183.73979 -239.10671)
			(xy 183.760364 -239.112298) (xy 183.85663 -239.097566) (xy 183.87441 -239.086136) (xy 183.880506 -239.076992)
			(xy 183.895682 -239.054692) (xy 183.93136 -239.014235) (xy 183.972383 -238.97921) (xy 184.017932 -238.950314)
			(xy 184.067098 -238.928125) (xy 184.118901 -238.913085) (xy 184.172305 -238.905495) (xy 184.199276 -238.905034)
			(xy 184.226533 -238.905411) (xy 184.280493 -238.913166) (xy 184.332799 -238.928522) (xy 184.382388 -238.951166)
			(xy 184.428249 -238.980636) (xy 184.469449 -239.016334) (xy 184.505149 -239.057532) (xy 184.534623 -239.103391)
			(xy 184.55727 -239.152978) (xy 184.572629 -239.205284) (xy 184.580387 -239.259243) (xy 184.580387 -239.313757)
			(xy 184.572629 -239.367716) (xy 184.55727 -239.420022) (xy 184.547585 -239.441228) (xy 185.623706 -239.441228)
			(xy 185.627777 -239.385606) (xy 185.639903 -239.331169) (xy 185.659826 -239.279078) (xy 185.687122 -239.230443)
			(xy 185.721208 -239.1863) (xy 185.761357 -239.147591) (xy 185.806715 -239.11514) (xy 185.856315 -239.089639)
			(xy 185.909099 -239.071632) (xy 185.963942 -239.061502) (xy 186.019676 -239.059465) (xy 186.075113 -239.065565)
			(xy 186.12907 -239.079671) (xy 186.180399 -239.101483) (xy 186.228005 -239.130537) (xy 186.270873 -239.166212)
			(xy 186.30809 -239.207749) (xy 186.338863 -239.254262) (xy 186.362535 -239.304759) (xy 186.378603 -239.358166)
			(xy 186.386723 -239.413342) (xy 186.387232 -239.441228) (xy 186.386723 -239.469114) (xy 186.378603 -239.52429)
			(xy 186.362535 -239.577697) (xy 186.338863 -239.628194) (xy 186.30809 -239.674707) (xy 186.270873 -239.716244)
			(xy 186.228005 -239.751919) (xy 186.180399 -239.780973) (xy 186.12907 -239.802785) (xy 186.075113 -239.816891)
			(xy 186.019676 -239.822991) (xy 185.963942 -239.820954) (xy 185.909099 -239.810824) (xy 185.856315 -239.792817)
			(xy 185.806715 -239.767316) (xy 185.761357 -239.734865) (xy 185.721208 -239.696156) (xy 185.687122 -239.652013)
			(xy 185.659826 -239.603378) (xy 185.639903 -239.551287) (xy 185.627777 -239.49685) (xy 185.623706 -239.441228)
			(xy 184.547585 -239.441228) (xy 184.534623 -239.469609) (xy 184.505149 -239.515468) (xy 184.469449 -239.556666)
			(xy 184.428249 -239.592364) (xy 184.382388 -239.621834) (xy 184.332799 -239.644478) (xy 184.280493 -239.659834)
			(xy 184.226533 -239.667589) (xy 184.199276 -239.66805) (xy 184.173102 -239.667596) (xy 184.121247 -239.660429)
			(xy 184.07086 -239.646232) (xy 184.022891 -239.625272) (xy 183.978241 -239.597945) (xy 183.957722 -239.58169)
			(xy 183.949086 -239.574832) (xy 183.928512 -239.569244) (xy 183.832246 -239.583976) (xy 183.814466 -239.595406)
			(xy 183.80837 -239.60455) (xy 183.793158 -239.626824) (xy 183.757485 -239.667279) (xy 183.716467 -239.702305)
			(xy 183.670924 -239.731203) (xy 183.621764 -239.753397) (xy 183.569968 -239.768443) (xy 183.516569 -239.776042)
			(xy 183.4896 -239.776508) (xy 183.462349 -239.776022) (xy 183.408401 -239.768266) (xy 183.356106 -239.752911)
			(xy 183.306529 -239.730269) (xy 183.260679 -239.700803) (xy 183.219488 -239.665112) (xy 183.183797 -239.623921)
			(xy 183.154331 -239.578071) (xy 183.131689 -239.528494) (xy 183.116334 -239.476199) (xy 183.108578 -239.422251)
			(xy 180.645291 -239.422251) (xy 180.392112 -240.876074) (xy 184.744866 -240.876074) (xy 184.748937 -240.820452)
			(xy 184.761063 -240.766015) (xy 184.780986 -240.713924) (xy 184.808282 -240.665289) (xy 184.842368 -240.621146)
			(xy 184.882517 -240.582437) (xy 184.927875 -240.549986) (xy 184.977475 -240.524485) (xy 185.030259 -240.506478)
			(xy 185.085102 -240.496348) (xy 185.140836 -240.494311) (xy 185.196273 -240.500411) (xy 185.25023 -240.514517)
			(xy 185.301559 -240.536329) (xy 185.349165 -240.565383) (xy 185.392033 -240.601058) (xy 185.42925 -240.642595)
			(xy 185.460023 -240.689108) (xy 185.483695 -240.739605) (xy 185.499763 -240.793012) (xy 185.507883 -240.848188)
			(xy 185.508392 -240.876074) (xy 185.507883 -240.90396) (xy 185.499763 -240.959136) (xy 185.483695 -241.012543)
			(xy 185.460023 -241.06304) (xy 185.42925 -241.109553) (xy 185.392033 -241.15109) (xy 185.349165 -241.186765)
			(xy 185.301559 -241.215819) (xy 185.25023 -241.237631) (xy 185.196273 -241.251737) (xy 185.140836 -241.257837)
			(xy 185.085102 -241.2558) (xy 185.030259 -241.24567) (xy 184.977475 -241.227663) (xy 184.927875 -241.202162)
			(xy 184.882517 -241.169711) (xy 184.842368 -241.131002) (xy 184.808282 -241.086859) (xy 184.780986 -241.038224)
			(xy 184.761063 -240.986133) (xy 184.748937 -240.931696) (xy 184.744866 -240.876074) (xy 180.392112 -240.876074)
			(xy 180.310059 -241.347244) (xy 186.002674 -241.347244) (xy 186.006745 -241.291622) (xy 186.018871 -241.237185)
			(xy 186.038794 -241.185094) (xy 186.06609 -241.136459) (xy 186.100176 -241.092316) (xy 186.140325 -241.053607)
			(xy 186.185683 -241.021156) (xy 186.235283 -240.995655) (xy 186.288067 -240.977648) (xy 186.34291 -240.967518)
			(xy 186.398644 -240.965481) (xy 186.454081 -240.971581) (xy 186.508038 -240.985687) (xy 186.559367 -241.007499)
			(xy 186.606973 -241.036553) (xy 186.649841 -241.072228) (xy 186.687058 -241.113765) (xy 186.717831 -241.160278)
			(xy 186.728319 -241.182652) (xy 208.956654 -241.182652) (xy 208.960725 -241.12703) (xy 208.972851 -241.072593)
			(xy 208.992774 -241.020502) (xy 209.02007 -240.971867) (xy 209.054156 -240.927724) (xy 209.094305 -240.889015)
			(xy 209.139663 -240.856564) (xy 209.189263 -240.831063) (xy 209.242047 -240.813056) (xy 209.29689 -240.802926)
			(xy 209.352624 -240.800889) (xy 209.408061 -240.806989) (xy 209.462018 -240.821095) (xy 209.513347 -240.842907)
			(xy 209.560953 -240.871961) (xy 209.603821 -240.907636) (xy 209.641038 -240.949173) (xy 209.671811 -240.995686)
			(xy 209.695483 -241.046183) (xy 209.711551 -241.09959) (xy 209.711604 -241.099953) (xy 211.374448 -241.099953)
			(xy 211.374448 -241.045447) (xy 211.382204 -240.991497) (xy 211.39756 -240.9392) (xy 211.420201 -240.88962)
			(xy 211.449668 -240.843767) (xy 211.485361 -240.802574) (xy 211.526552 -240.766879) (xy 211.572404 -240.73741)
			(xy 211.621983 -240.714766) (xy 211.674279 -240.699408) (xy 211.728229 -240.691649) (xy 211.755482 -240.691162)
			(xy 211.783662 -240.691692) (xy 211.839409 -240.699987) (xy 211.893331 -240.716384) (xy 211.944258 -240.740529)
			(xy 211.991083 -240.771895) (xy 212.012276 -240.790476) (xy 212.019134 -240.796826) (xy 212.036914 -240.803684)
			(xy 212.12429 -240.803684) (xy 212.14207 -240.796826) (xy 212.148928 -240.790476) (xy 212.170123 -240.771895)
			(xy 212.21694 -240.740511) (xy 212.267865 -240.716356) (xy 212.32179 -240.699955) (xy 212.37754 -240.691666)
			(xy 212.405722 -240.691162) (xy 212.43297 -240.69171) (xy 212.486911 -240.699468) (xy 212.539199 -240.714824)
			(xy 212.58877 -240.737465) (xy 212.634614 -240.766929) (xy 212.675798 -240.802618) (xy 212.711484 -240.843804)
			(xy 212.740946 -240.88965) (xy 212.763584 -240.939222) (xy 212.778937 -240.99151) (xy 212.786692 -241.045452)
			(xy 212.786692 -241.083084) (xy 213.703406 -241.083084) (xy 213.707477 -241.027462) (xy 213.719603 -240.973025)
			(xy 213.739526 -240.920934) (xy 213.766822 -240.872299) (xy 213.800908 -240.828156) (xy 213.841057 -240.789447)
			(xy 213.886415 -240.756996) (xy 213.936015 -240.731495) (xy 213.988799 -240.713488) (xy 214.043642 -240.703358)
			(xy 214.099376 -240.701321) (xy 214.154813 -240.707421) (xy 214.20877 -240.721527) (xy 214.260099 -240.743339)
			(xy 214.307705 -240.772393) (xy 214.350573 -240.808068) (xy 214.38779 -240.849605) (xy 214.418563 -240.896118)
			(xy 214.442235 -240.946615) (xy 214.458303 -241.000022) (xy 214.466423 -241.055198) (xy 214.466932 -241.083084)
			(xy 214.466423 -241.11097) (xy 214.46163 -241.143536) (xy 220.651068 -241.143536) (xy 220.655139 -241.087914)
			(xy 220.667265 -241.033477) (xy 220.687188 -240.981386) (xy 220.714484 -240.932751) (xy 220.74857 -240.888608)
			(xy 220.788719 -240.849899) (xy 220.834077 -240.817448) (xy 220.883677 -240.791947) (xy 220.936461 -240.77394)
			(xy 220.991304 -240.76381) (xy 221.047038 -240.761773) (xy 221.102475 -240.767873) (xy 221.156432 -240.781979)
			(xy 221.207761 -240.803791) (xy 221.255367 -240.832845) (xy 221.298235 -240.86852) (xy 221.335452 -240.910057)
			(xy 221.366225 -240.95657) (xy 221.389897 -241.007067) (xy 221.405965 -241.060474) (xy 221.414085 -241.11565)
			(xy 221.414594 -241.143536) (xy 221.414085 -241.171422) (xy 221.405965 -241.226598) (xy 221.389897 -241.280005)
			(xy 221.366225 -241.330502) (xy 221.335452 -241.377015) (xy 221.298235 -241.418552) (xy 221.255367 -241.454227)
			(xy 221.207761 -241.483281) (xy 221.156432 -241.505093) (xy 221.102475 -241.519199) (xy 221.047038 -241.525299)
			(xy 220.991304 -241.523262) (xy 220.936461 -241.513132) (xy 220.883677 -241.495125) (xy 220.834077 -241.469624)
			(xy 220.788719 -241.437173) (xy 220.74857 -241.398464) (xy 220.714484 -241.354321) (xy 220.687188 -241.305686)
			(xy 220.667265 -241.253595) (xy 220.655139 -241.199158) (xy 220.651068 -241.143536) (xy 214.46163 -241.143536)
			(xy 214.458303 -241.166146) (xy 214.442235 -241.219553) (xy 214.418563 -241.27005) (xy 214.38779 -241.316563)
			(xy 214.350573 -241.3581) (xy 214.307705 -241.393775) (xy 214.260099 -241.422829) (xy 214.20877 -241.444641)
			(xy 214.154813 -241.458747) (xy 214.099376 -241.464847) (xy 214.043642 -241.46281) (xy 213.988799 -241.45268)
			(xy 213.936015 -241.434673) (xy 213.886415 -241.409172) (xy 213.841057 -241.376721) (xy 213.800908 -241.338012)
			(xy 213.766822 -241.293869) (xy 213.739526 -241.245234) (xy 213.719603 -241.193143) (xy 213.707477 -241.138706)
			(xy 213.703406 -241.083084) (xy 212.786692 -241.083084) (xy 212.786692 -241.099948) (xy 212.778937 -241.15389)
			(xy 212.763584 -241.206178) (xy 212.740946 -241.25575) (xy 212.711484 -241.301596) (xy 212.675798 -241.342782)
			(xy 212.634614 -241.378471) (xy 212.58877 -241.407935) (xy 212.539199 -241.430576) (xy 212.486911 -241.445932)
			(xy 212.43297 -241.45369) (xy 212.405722 -241.454178) (xy 212.377543 -241.453635) (xy 212.321797 -241.445342)
			(xy 212.267875 -241.428947) (xy 212.216948 -241.404806) (xy 212.170122 -241.373443) (xy 212.148928 -241.354864)
			(xy 212.14207 -241.348514) (xy 212.12429 -241.341656) (xy 212.036914 -241.341656) (xy 212.019134 -241.348514)
			(xy 212.012276 -241.354864) (xy 211.991085 -241.373449) (xy 211.944266 -241.404832) (xy 211.89334 -241.428985)
			(xy 211.839415 -241.445385) (xy 211.783664 -241.453674) (xy 211.755482 -241.454178) (xy 211.728229 -241.453751)
			(xy 211.674279 -241.445992) (xy 211.621983 -241.430634) (xy 211.572404 -241.40799) (xy 211.526552 -241.378521)
			(xy 211.485361 -241.342826) (xy 211.449668 -241.301633) (xy 211.420201 -241.25578) (xy 211.39756 -241.2062)
			(xy 211.382204 -241.153903) (xy 211.374448 -241.099953) (xy 209.711604 -241.099953) (xy 209.719671 -241.154766)
			(xy 209.72018 -241.182652) (xy 209.719671 -241.210538) (xy 209.711551 -241.265714) (xy 209.695483 -241.319121)
			(xy 209.671811 -241.369618) (xy 209.641038 -241.416131) (xy 209.603821 -241.457668) (xy 209.560953 -241.493343)
			(xy 209.513347 -241.522397) (xy 209.462018 -241.544209) (xy 209.408061 -241.558315) (xy 209.352624 -241.564415)
			(xy 209.29689 -241.562378) (xy 209.242047 -241.552248) (xy 209.189263 -241.534241) (xy 209.139663 -241.50874)
			(xy 209.094305 -241.476289) (xy 209.054156 -241.43758) (xy 209.02007 -241.393437) (xy 208.992774 -241.344802)
			(xy 208.972851 -241.292711) (xy 208.960725 -241.238274) (xy 208.956654 -241.182652) (xy 186.728319 -241.182652)
			(xy 186.741503 -241.210775) (xy 186.757571 -241.264182) (xy 186.765691 -241.319358) (xy 186.7662 -241.347244)
			(xy 186.765691 -241.37513) (xy 186.757571 -241.430306) (xy 186.741503 -241.483713) (xy 186.717831 -241.53421)
			(xy 186.687058 -241.580723) (xy 186.649841 -241.62226) (xy 186.625039 -241.6429) (xy 216.006932 -241.6429)
			(xy 216.011003 -241.587278) (xy 216.023129 -241.532841) (xy 216.043052 -241.48075) (xy 216.070348 -241.432115)
			(xy 216.104434 -241.387972) (xy 216.144583 -241.349263) (xy 216.189941 -241.316812) (xy 216.239541 -241.291311)
			(xy 216.292325 -241.273304) (xy 216.347168 -241.263174) (xy 216.402902 -241.261137) (xy 216.458339 -241.267237)
			(xy 216.512296 -241.281343) (xy 216.563625 -241.303155) (xy 216.611231 -241.332209) (xy 216.654099 -241.367884)
			(xy 216.691316 -241.409421) (xy 216.722089 -241.455934) (xy 216.745761 -241.506431) (xy 216.761829 -241.559838)
			(xy 216.769949 -241.615014) (xy 216.770458 -241.6429) (xy 216.770421 -241.644932) (xy 229.172768 -241.644932)
			(xy 229.176839 -241.58931) (xy 229.188965 -241.534873) (xy 229.208888 -241.482782) (xy 229.236184 -241.434147)
			(xy 229.27027 -241.390004) (xy 229.310419 -241.351295) (xy 229.355777 -241.318844) (xy 229.405377 -241.293343)
			(xy 229.458161 -241.275336) (xy 229.513004 -241.265206) (xy 229.568738 -241.263169) (xy 229.624175 -241.269269)
			(xy 229.678132 -241.283375) (xy 229.729461 -241.305187) (xy 229.777067 -241.334241) (xy 229.819935 -241.369916)
			(xy 229.857152 -241.411453) (xy 229.887925 -241.457966) (xy 229.911597 -241.508463) (xy 229.927665 -241.56187)
			(xy 229.935785 -241.617046) (xy 229.936294 -241.644932) (xy 229.935785 -241.672818) (xy 229.927665 -241.727994)
			(xy 229.911597 -241.781401) (xy 229.887925 -241.831898) (xy 229.857152 -241.878411) (xy 229.819935 -241.919948)
			(xy 229.777067 -241.955623) (xy 229.729461 -241.984677) (xy 229.678132 -242.006489) (xy 229.624175 -242.020595)
			(xy 229.568738 -242.026695) (xy 229.513004 -242.024658) (xy 229.458161 -242.014528) (xy 229.405377 -241.996521)
			(xy 229.355777 -241.97102) (xy 229.310419 -241.938569) (xy 229.27027 -241.89986) (xy 229.236184 -241.855717)
			(xy 229.208888 -241.807082) (xy 229.188965 -241.754991) (xy 229.176839 -241.700554) (xy 229.172768 -241.644932)
			(xy 216.770421 -241.644932) (xy 216.769949 -241.670786) (xy 216.761829 -241.725962) (xy 216.745761 -241.779369)
			(xy 216.722089 -241.829866) (xy 216.691316 -241.876379) (xy 216.654099 -241.917916) (xy 216.611231 -241.953591)
			(xy 216.563625 -241.982645) (xy 216.512296 -242.004457) (xy 216.458339 -242.018563) (xy 216.402902 -242.024663)
			(xy 216.347168 -242.022626) (xy 216.292325 -242.012496) (xy 216.239541 -241.994489) (xy 216.189941 -241.968988)
			(xy 216.144583 -241.936537) (xy 216.104434 -241.897828) (xy 216.070348 -241.853685) (xy 216.043052 -241.80505)
			(xy 216.023129 -241.752959) (xy 216.011003 -241.698522) (xy 216.006932 -241.6429) (xy 186.625039 -241.6429)
			(xy 186.606973 -241.657935) (xy 186.559367 -241.686989) (xy 186.508038 -241.708801) (xy 186.454081 -241.722907)
			(xy 186.398644 -241.729007) (xy 186.34291 -241.72697) (xy 186.288067 -241.71684) (xy 186.235283 -241.698833)
			(xy 186.185683 -241.673332) (xy 186.140325 -241.640881) (xy 186.100176 -241.602172) (xy 186.06609 -241.558029)
			(xy 186.038794 -241.509394) (xy 186.018871 -241.457303) (xy 186.006745 -241.402866) (xy 186.002674 -241.347244)
			(xy 180.310059 -241.347244) (xy 179.905765 -243.668804) (xy 184.305446 -243.668804) (xy 184.309517 -243.613182)
			(xy 184.321643 -243.558745) (xy 184.341566 -243.506654) (xy 184.368862 -243.458019) (xy 184.402948 -243.413876)
			(xy 184.443097 -243.375167) (xy 184.488455 -243.342716) (xy 184.538055 -243.317215) (xy 184.590839 -243.299208)
			(xy 184.645682 -243.289078) (xy 184.701416 -243.287041) (xy 184.756853 -243.293141) (xy 184.81081 -243.307247)
			(xy 184.862139 -243.329059) (xy 184.909745 -243.358113) (xy 184.952613 -243.393788) (xy 184.98983 -243.435325)
			(xy 185.020603 -243.481838) (xy 185.044275 -243.532335) (xy 185.060343 -243.585742) (xy 185.068463 -243.640918)
			(xy 185.068972 -243.668804) (xy 185.068463 -243.69669) (xy 185.060343 -243.751866) (xy 185.044275 -243.805273)
			(xy 185.020603 -243.85577) (xy 184.98983 -243.902283) (xy 184.952613 -243.94382) (xy 184.909745 -243.979495)
			(xy 184.862139 -244.008549) (xy 184.81081 -244.030361) (xy 184.756853 -244.044467) (xy 184.701416 -244.050567)
			(xy 184.645682 -244.04853) (xy 184.590839 -244.0384) (xy 184.538055 -244.020393) (xy 184.488455 -243.994892)
			(xy 184.443097 -243.962441) (xy 184.402948 -243.923732) (xy 184.368862 -243.879589) (xy 184.341566 -243.830954)
			(xy 184.321643 -243.778863) (xy 184.309517 -243.724426) (xy 184.305446 -243.668804) (xy 179.905765 -243.668804)
			(xy 179.805178 -244.2464) (xy 219.538802 -244.2464) (xy 219.542873 -244.190778) (xy 219.554999 -244.136341)
			(xy 219.574922 -244.08425) (xy 219.602218 -244.035615) (xy 219.636304 -243.991472) (xy 219.676453 -243.952763)
			(xy 219.721811 -243.920312) (xy 219.771411 -243.894811) (xy 219.824195 -243.876804) (xy 219.879038 -243.866674)
			(xy 219.934772 -243.864637) (xy 219.990209 -243.870737) (xy 220.044166 -243.884843) (xy 220.095495 -243.906655)
			(xy 220.143101 -243.935709) (xy 220.185969 -243.971384) (xy 220.223186 -244.012921) (xy 220.253959 -244.059434)
			(xy 220.277631 -244.109931) (xy 220.293699 -244.163338) (xy 220.301819 -244.218514) (xy 220.302328 -244.2464)
			(xy 220.301819 -244.274286) (xy 220.293699 -244.329462) (xy 220.277631 -244.382869) (xy 220.253959 -244.433366)
			(xy 220.243219 -244.4496) (xy 230.709976 -244.4496) (xy 230.714047 -244.393978) (xy 230.726173 -244.339541)
			(xy 230.746096 -244.28745) (xy 230.773392 -244.238815) (xy 230.807478 -244.194672) (xy 230.847627 -244.155963)
			(xy 230.892985 -244.123512) (xy 230.942585 -244.098011) (xy 230.995369 -244.080004) (xy 231.050212 -244.069874)
			(xy 231.105946 -244.067837) (xy 231.161383 -244.073937) (xy 231.21534 -244.088043) (xy 231.266669 -244.109855)
			(xy 231.314275 -244.138909) (xy 231.357143 -244.174584) (xy 231.39436 -244.216121) (xy 231.425133 -244.262634)
			(xy 231.448805 -244.313131) (xy 231.464873 -244.366538) (xy 231.472993 -244.421714) (xy 231.473502 -244.4496)
			(xy 231.472993 -244.477486) (xy 231.464873 -244.532662) (xy 231.448805 -244.586069) (xy 231.425133 -244.636566)
			(xy 231.39436 -244.683079) (xy 231.357143 -244.724616) (xy 231.314275 -244.760291) (xy 231.266669 -244.789345)
			(xy 231.21534 -244.811157) (xy 231.161383 -244.825263) (xy 231.105946 -244.831363) (xy 231.050212 -244.829326)
			(xy 230.995369 -244.819196) (xy 230.942585 -244.801189) (xy 230.892985 -244.775688) (xy 230.847627 -244.743237)
			(xy 230.807478 -244.704528) (xy 230.773392 -244.660385) (xy 230.746096 -244.61175) (xy 230.726173 -244.559659)
			(xy 230.714047 -244.505222) (xy 230.709976 -244.4496) (xy 220.243219 -244.4496) (xy 220.223186 -244.479879)
			(xy 220.185969 -244.521416) (xy 220.143101 -244.557091) (xy 220.095495 -244.586145) (xy 220.044166 -244.607957)
			(xy 219.990209 -244.622063) (xy 219.934772 -244.628163) (xy 219.879038 -244.626126) (xy 219.824195 -244.615996)
			(xy 219.771411 -244.597989) (xy 219.721811 -244.572488) (xy 219.676453 -244.540037) (xy 219.636304 -244.501328)
			(xy 219.602218 -244.457185) (xy 219.574922 -244.40855) (xy 219.554999 -244.356459) (xy 219.542873 -244.302022)
			(xy 219.538802 -244.2464) (xy 179.805178 -244.2464) (xy 179.669337 -245.026434) (xy 209.338162 -245.026434)
			(xy 209.342233 -244.970812) (xy 209.354359 -244.916375) (xy 209.374282 -244.864284) (xy 209.401578 -244.815649)
			(xy 209.435664 -244.771506) (xy 209.475813 -244.732797) (xy 209.521171 -244.700346) (xy 209.570771 -244.674845)
			(xy 209.623555 -244.656838) (xy 209.678398 -244.646708) (xy 209.734132 -244.644671) (xy 209.789569 -244.650771)
			(xy 209.843526 -244.664877) (xy 209.894855 -244.686689) (xy 209.942461 -244.715743) (xy 209.985329 -244.751418)
			(xy 210.022546 -244.792955) (xy 210.053319 -244.839468) (xy 210.076991 -244.889965) (xy 210.093059 -244.943372)
			(xy 210.101179 -244.998548) (xy 210.101679 -245.025926) (xy 211.053424 -245.025926) (xy 211.057495 -244.970304)
			(xy 211.069621 -244.915867) (xy 211.089544 -244.863776) (xy 211.11684 -244.815141) (xy 211.150926 -244.770998)
			(xy 211.191075 -244.732289) (xy 211.236433 -244.699838) (xy 211.286033 -244.674337) (xy 211.338817 -244.65633)
			(xy 211.39366 -244.6462) (xy 211.449394 -244.644163) (xy 211.504831 -244.650263) (xy 211.558788 -244.664369)
			(xy 211.610117 -244.686181) (xy 211.657723 -244.715235) (xy 211.700591 -244.75091) (xy 211.737808 -244.792447)
			(xy 211.768581 -244.83896) (xy 211.792253 -244.889457) (xy 211.808321 -244.942864) (xy 211.816441 -244.99804)
			(xy 211.81695 -245.025926) (xy 212.069424 -245.025926) (xy 212.073495 -244.970304) (xy 212.085621 -244.915867)
			(xy 212.105544 -244.863776) (xy 212.13284 -244.815141) (xy 212.166926 -244.770998) (xy 212.207075 -244.732289)
			(xy 212.252433 -244.699838) (xy 212.302033 -244.674337) (xy 212.354817 -244.65633) (xy 212.40966 -244.6462)
			(xy 212.465394 -244.644163) (xy 212.520831 -244.650263) (xy 212.574788 -244.664369) (xy 212.626117 -244.686181)
			(xy 212.673723 -244.715235) (xy 212.716591 -244.75091) (xy 212.753808 -244.792447) (xy 212.784581 -244.83896)
			(xy 212.808253 -244.889457) (xy 212.824321 -244.942864) (xy 212.832441 -244.99804) (xy 212.83295 -245.025926)
			(xy 212.832441 -245.053812) (xy 212.824321 -245.108988) (xy 212.808253 -245.162395) (xy 212.784581 -245.212892)
			(xy 212.753808 -245.259405) (xy 212.716591 -245.300942) (xy 212.673723 -245.336617) (xy 212.626117 -245.365671)
			(xy 212.574788 -245.387483) (xy 212.520831 -245.401589) (xy 212.465394 -245.407689) (xy 212.40966 -245.405652)
			(xy 212.354817 -245.395522) (xy 212.302033 -245.377515) (xy 212.252433 -245.352014) (xy 212.207075 -245.319563)
			(xy 212.166926 -245.280854) (xy 212.13284 -245.236711) (xy 212.105544 -245.188076) (xy 212.085621 -245.135985)
			(xy 212.073495 -245.081548) (xy 212.069424 -245.025926) (xy 211.81695 -245.025926) (xy 211.816441 -245.053812)
			(xy 211.808321 -245.108988) (xy 211.792253 -245.162395) (xy 211.768581 -245.212892) (xy 211.737808 -245.259405)
			(xy 211.700591 -245.300942) (xy 211.657723 -245.336617) (xy 211.610117 -245.365671) (xy 211.558788 -245.387483)
			(xy 211.504831 -245.401589) (xy 211.449394 -245.407689) (xy 211.39366 -245.405652) (xy 211.338817 -245.395522)
			(xy 211.286033 -245.377515) (xy 211.236433 -245.352014) (xy 211.191075 -245.319563) (xy 211.150926 -245.280854)
			(xy 211.11684 -245.236711) (xy 211.089544 -245.188076) (xy 211.069621 -245.135985) (xy 211.057495 -245.081548)
			(xy 211.053424 -245.025926) (xy 210.101679 -245.025926) (xy 210.101688 -245.026434) (xy 210.101179 -245.05432)
			(xy 210.093059 -245.109496) (xy 210.076991 -245.162903) (xy 210.053319 -245.2134) (xy 210.022546 -245.259913)
			(xy 209.985329 -245.30145) (xy 209.942461 -245.337125) (xy 209.894855 -245.366179) (xy 209.843526 -245.387991)
			(xy 209.789569 -245.402097) (xy 209.734132 -245.408197) (xy 209.678398 -245.40616) (xy 209.623555 -245.39603)
			(xy 209.570771 -245.378023) (xy 209.521171 -245.352522) (xy 209.475813 -245.320071) (xy 209.435664 -245.281362)
			(xy 209.401578 -245.237219) (xy 209.374282 -245.188584) (xy 209.354359 -245.136493) (xy 209.342233 -245.082056)
			(xy 209.338162 -245.026434) (xy 179.669337 -245.026434) (xy 179.45109 -246.27967) (xy 231.521252 -246.27967)
			(xy 231.525323 -246.224048) (xy 231.537449 -246.169611) (xy 231.557372 -246.11752) (xy 231.584668 -246.068885)
			(xy 231.618754 -246.024742) (xy 231.658903 -245.986033) (xy 231.704261 -245.953582) (xy 231.753861 -245.928081)
			(xy 231.806645 -245.910074) (xy 231.861488 -245.899944) (xy 231.917222 -245.897907) (xy 231.972659 -245.904007)
			(xy 232.026616 -245.918113) (xy 232.077945 -245.939925) (xy 232.125551 -245.968979) (xy 232.168419 -246.004654)
			(xy 232.205636 -246.046191) (xy 232.236409 -246.092704) (xy 232.260081 -246.143201) (xy 232.276149 -246.196608)
			(xy 232.284269 -246.251784) (xy 232.284778 -246.27967) (xy 232.284269 -246.307556) (xy 232.28314 -246.31523)
			(xy 232.857292 -246.31523) (xy 232.861363 -246.259608) (xy 232.873489 -246.205171) (xy 232.893412 -246.15308)
			(xy 232.920708 -246.104445) (xy 232.954794 -246.060302) (xy 232.994943 -246.021593) (xy 233.040301 -245.989142)
			(xy 233.089901 -245.963641) (xy 233.142685 -245.945634) (xy 233.197528 -245.935504) (xy 233.253262 -245.933467)
			(xy 233.308699 -245.939567) (xy 233.362656 -245.953673) (xy 233.413985 -245.975485) (xy 233.461591 -246.004539)
			(xy 233.504459 -246.040214) (xy 233.541676 -246.081751) (xy 233.572449 -246.128264) (xy 233.596121 -246.178761)
			(xy 233.612189 -246.232168) (xy 233.620309 -246.287344) (xy 233.620818 -246.31523) (xy 233.620309 -246.343116)
			(xy 233.612189 -246.398292) (xy 233.596121 -246.451699) (xy 233.572449 -246.502196) (xy 233.541676 -246.548709)
			(xy 233.504459 -246.590246) (xy 233.461591 -246.625921) (xy 233.413985 -246.654975) (xy 233.362656 -246.676787)
			(xy 233.308699 -246.690893) (xy 233.253262 -246.696993) (xy 233.197528 -246.694956) (xy 233.142685 -246.684826)
			(xy 233.089901 -246.666819) (xy 233.040301 -246.641318) (xy 232.994943 -246.608867) (xy 232.954794 -246.570158)
			(xy 232.920708 -246.526015) (xy 232.893412 -246.47738) (xy 232.873489 -246.425289) (xy 232.861363 -246.370852)
			(xy 232.857292 -246.31523) (xy 232.28314 -246.31523) (xy 232.276149 -246.362732) (xy 232.260081 -246.416139)
			(xy 232.236409 -246.466636) (xy 232.205636 -246.513149) (xy 232.168419 -246.554686) (xy 232.125551 -246.590361)
			(xy 232.077945 -246.619415) (xy 232.026616 -246.641227) (xy 231.972659 -246.655333) (xy 231.917222 -246.661433)
			(xy 231.861488 -246.659396) (xy 231.806645 -246.649266) (xy 231.753861 -246.631259) (xy 231.704261 -246.605758)
			(xy 231.658903 -246.573307) (xy 231.618754 -246.534598) (xy 231.584668 -246.490455) (xy 231.557372 -246.44182)
			(xy 231.537449 -246.389729) (xy 231.525323 -246.335292) (xy 231.521252 -246.27967) (xy 179.45109 -246.27967)
			(xy 179.089482 -248.35612) (xy 210.174838 -248.35612) (xy 210.178909 -248.300498) (xy 210.191035 -248.246061)
			(xy 210.210958 -248.19397) (xy 210.238254 -248.145335) (xy 210.27234 -248.101192) (xy 210.312489 -248.062483)
			(xy 210.357847 -248.030032) (xy 210.407447 -248.004531) (xy 210.460231 -247.986524) (xy 210.515074 -247.976394)
			(xy 210.570808 -247.974357) (xy 210.626245 -247.980457) (xy 210.680202 -247.994563) (xy 210.731531 -248.016375)
			(xy 210.779137 -248.045429) (xy 210.822005 -248.081104) (xy 210.859222 -248.122641) (xy 210.889995 -248.169154)
			(xy 210.913667 -248.219651) (xy 210.929735 -248.273058) (xy 210.937855 -248.328234) (xy 210.938341 -248.35485)
			(xy 211.817456 -248.35485) (xy 211.821527 -248.299228) (xy 211.833653 -248.244791) (xy 211.853576 -248.1927)
			(xy 211.880872 -248.144065) (xy 211.914958 -248.099922) (xy 211.955107 -248.061213) (xy 212.000465 -248.028762)
			(xy 212.050065 -248.003261) (xy 212.102849 -247.985254) (xy 212.157692 -247.975124) (xy 212.213426 -247.973087)
			(xy 212.268863 -247.979187) (xy 212.32282 -247.993293) (xy 212.374149 -248.015105) (xy 212.421755 -248.044159)
			(xy 212.464623 -248.079834) (xy 212.50184 -248.121371) (xy 212.532613 -248.167884) (xy 212.556285 -248.218381)
			(xy 212.572353 -248.271788) (xy 212.580473 -248.326964) (xy 212.580982 -248.35485) (xy 212.580473 -248.382736)
			(xy 212.572353 -248.437912) (xy 212.565859 -248.459498) (xy 219.575124 -248.459498) (xy 219.579195 -248.403876)
			(xy 219.591321 -248.349439) (xy 219.611244 -248.297348) (xy 219.63854 -248.248713) (xy 219.672626 -248.20457)
			(xy 219.712775 -248.165861) (xy 219.758133 -248.13341) (xy 219.807733 -248.107909) (xy 219.860517 -248.089902)
			(xy 219.91536 -248.079772) (xy 219.971094 -248.077735) (xy 220.026531 -248.083835) (xy 220.080488 -248.097941)
			(xy 220.131817 -248.119753) (xy 220.179423 -248.148807) (xy 220.222291 -248.184482) (xy 220.259508 -248.226019)
			(xy 220.290281 -248.272532) (xy 220.313953 -248.323029) (xy 220.330021 -248.376436) (xy 220.332563 -248.393712)
			(xy 221.630746 -248.393712) (xy 221.634817 -248.33809) (xy 221.646943 -248.283653) (xy 221.666866 -248.231562)
			(xy 221.694162 -248.182927) (xy 221.728248 -248.138784) (xy 221.768397 -248.100075) (xy 221.813755 -248.067624)
			(xy 221.863355 -248.042123) (xy 221.916139 -248.024116) (xy 221.970982 -248.013986) (xy 222.026716 -248.011949)
			(xy 222.082153 -248.018049) (xy 222.13611 -248.032155) (xy 222.187439 -248.053967) (xy 222.235045 -248.083021)
			(xy 222.277913 -248.118696) (xy 222.31513 -248.160233) (xy 222.345903 -248.206746) (xy 222.369575 -248.257243)
			(xy 222.385643 -248.31065) (xy 222.393763 -248.365826) (xy 222.394272 -248.393712) (xy 222.393763 -248.421598)
			(xy 222.385643 -248.476774) (xy 222.369575 -248.530181) (xy 222.345903 -248.580678) (xy 222.31513 -248.627191)
			(xy 222.277913 -248.668728) (xy 222.235045 -248.704403) (xy 222.187439 -248.733457) (xy 222.13611 -248.755269)
			(xy 222.082153 -248.769375) (xy 222.026716 -248.775475) (xy 221.970982 -248.773438) (xy 221.916139 -248.763308)
			(xy 221.863355 -248.745301) (xy 221.813755 -248.7198) (xy 221.768397 -248.687349) (xy 221.728248 -248.64864)
			(xy 221.694162 -248.604497) (xy 221.666866 -248.555862) (xy 221.646943 -248.503771) (xy 221.634817 -248.449334)
			(xy 221.630746 -248.393712) (xy 220.332563 -248.393712) (xy 220.338141 -248.431612) (xy 220.33865 -248.459498)
			(xy 220.338141 -248.487384) (xy 220.330021 -248.54256) (xy 220.313953 -248.595967) (xy 220.290281 -248.646464)
			(xy 220.259508 -248.692977) (xy 220.222291 -248.734514) (xy 220.179423 -248.770189) (xy 220.131817 -248.799243)
			(xy 220.080488 -248.821055) (xy 220.026531 -248.835161) (xy 219.971094 -248.841261) (xy 219.91536 -248.839224)
			(xy 219.860517 -248.829094) (xy 219.807733 -248.811087) (xy 219.758133 -248.785586) (xy 219.712775 -248.753135)
			(xy 219.672626 -248.714426) (xy 219.63854 -248.670283) (xy 219.611244 -248.621648) (xy 219.591321 -248.569557)
			(xy 219.579195 -248.51512) (xy 219.575124 -248.459498) (xy 212.565859 -248.459498) (xy 212.556285 -248.491319)
			(xy 212.532613 -248.541816) (xy 212.50184 -248.588329) (xy 212.464623 -248.629866) (xy 212.421755 -248.665541)
			(xy 212.374149 -248.694595) (xy 212.32282 -248.716407) (xy 212.268863 -248.730513) (xy 212.213426 -248.736613)
			(xy 212.157692 -248.734576) (xy 212.102849 -248.724446) (xy 212.050065 -248.706439) (xy 212.000465 -248.680938)
			(xy 211.955107 -248.648487) (xy 211.914958 -248.609778) (xy 211.880872 -248.565635) (xy 211.853576 -248.517)
			(xy 211.833653 -248.464909) (xy 211.821527 -248.410472) (xy 211.817456 -248.35485) (xy 210.938341 -248.35485)
			(xy 210.938364 -248.35612) (xy 210.937855 -248.384006) (xy 210.929735 -248.439182) (xy 210.913667 -248.492589)
			(xy 210.889995 -248.543086) (xy 210.859222 -248.589599) (xy 210.822005 -248.631136) (xy 210.779137 -248.666811)
			(xy 210.731531 -248.695865) (xy 210.680202 -248.717677) (xy 210.626245 -248.731783) (xy 210.570808 -248.737883)
			(xy 210.515074 -248.735846) (xy 210.460231 -248.725716) (xy 210.407447 -248.707709) (xy 210.357847 -248.682208)
			(xy 210.312489 -248.649757) (xy 210.27234 -248.611048) (xy 210.238254 -248.566905) (xy 210.210958 -248.51827)
			(xy 210.191035 -248.466179) (xy 210.178909 -248.411742) (xy 210.174838 -248.35612) (xy 179.089482 -248.35612)
			(xy 179.080414 -248.40819) (xy 179.079652 -248.416826) (xy 179.079652 -251.066808) (xy 188.18936 -251.066808)
			(xy 188.193431 -251.011186) (xy 188.205557 -250.956749) (xy 188.22548 -250.904658) (xy 188.252776 -250.856023)
			(xy 188.286862 -250.81188) (xy 188.327011 -250.773171) (xy 188.372369 -250.74072) (xy 188.421969 -250.715219)
			(xy 188.474753 -250.697212) (xy 188.529596 -250.687082) (xy 188.58533 -250.685045) (xy 188.640767 -250.691145)
			(xy 188.694724 -250.705251) (xy 188.746053 -250.727063) (xy 188.793659 -250.756117) (xy 188.836527 -250.791792)
			(xy 188.873744 -250.833329) (xy 188.904517 -250.879842) (xy 188.928189 -250.930339) (xy 188.944257 -250.983746)
			(xy 188.952377 -251.038922) (xy 188.952886 -251.066808) (xy 188.952377 -251.094694) (xy 188.944257 -251.14987)
			(xy 188.928189 -251.203277) (xy 188.904517 -251.253774) (xy 188.873744 -251.300287) (xy 188.836527 -251.341824)
			(xy 188.793659 -251.377499) (xy 188.746053 -251.406553) (xy 188.694724 -251.428365) (xy 188.640767 -251.442471)
			(xy 188.58533 -251.448571) (xy 188.529596 -251.446534) (xy 188.474753 -251.436404) (xy 188.421969 -251.418397)
			(xy 188.372369 -251.392896) (xy 188.327011 -251.360445) (xy 188.286862 -251.321736) (xy 188.252776 -251.277593)
			(xy 188.22548 -251.228958) (xy 188.205557 -251.176867) (xy 188.193431 -251.12243) (xy 188.18936 -251.066808)
			(xy 179.079652 -251.066808) (xy 179.079652 -251.177552) (xy 179.080086 -251.187617) (xy 179.08782 -251.206203)
			(xy 179.094638 -251.21362) (xy 180.379167 -252.498149) (xy 221.153498 -252.498149) (xy 221.153498 -252.443651)
			(xy 221.161254 -252.389708) (xy 221.176607 -252.337417) (xy 221.199246 -252.287844) (xy 221.228709 -252.241997)
			(xy 221.264397 -252.200809) (xy 221.305582 -252.16512) (xy 221.351428 -252.135654) (xy 221.401 -252.113013)
			(xy 221.45329 -252.097658) (xy 221.507233 -252.089899) (xy 221.534482 -252.089412) (xy 221.560355 -252.089843)
			(xy 221.611628 -252.096824) (xy 221.661487 -252.110673) (xy 221.709014 -252.131137) (xy 221.753339 -252.157838)
			(xy 221.793646 -252.190288) (xy 221.829195 -252.22789) (xy 221.844616 -252.24867) (xy 221.853584 -252.260214)
			(xy 221.876666 -252.278124) (xy 221.903874 -252.288768) (xy 221.932982 -252.291274) (xy 221.961609 -252.285438)
			(xy 221.987412 -252.271736) (xy 222.008282 -252.251291) (xy 222.015812 -252.238764) (xy 222.03042 -252.213713)
			(xy 222.065944 -252.167882) (xy 222.107994 -252.127955) (xy 222.155602 -252.094851) (xy 222.207671 -252.069333)
			(xy 222.263002 -252.051988) (xy 222.320321 -252.043215) (xy 222.349314 -252.042676) (xy 222.376563 -252.043195)
			(xy 222.430507 -252.050953) (xy 222.482798 -252.066309) (xy 222.532371 -252.08895) (xy 222.578218 -252.118415)
			(xy 222.619405 -252.154105) (xy 222.655093 -252.195293) (xy 222.684557 -252.241141) (xy 222.707196 -252.290715)
			(xy 222.72255 -252.343006) (xy 222.730306 -252.396951) (xy 222.730306 -252.451449) (xy 222.726046 -252.48108)
			(xy 222.877886 -252.48108) (xy 222.881957 -252.425458) (xy 222.894083 -252.371021) (xy 222.914006 -252.31893)
			(xy 222.941302 -252.270295) (xy 222.975388 -252.226152) (xy 223.015537 -252.187443) (xy 223.060895 -252.154992)
			(xy 223.110495 -252.129491) (xy 223.163279 -252.111484) (xy 223.218122 -252.101354) (xy 223.273856 -252.099317)
			(xy 223.329293 -252.105417) (xy 223.38325 -252.119523) (xy 223.434579 -252.141335) (xy 223.482185 -252.170389)
			(xy 223.525053 -252.206064) (xy 223.56227 -252.247601) (xy 223.593043 -252.294114) (xy 223.616715 -252.344611)
			(xy 223.632783 -252.398018) (xy 223.640903 -252.453194) (xy 223.641412 -252.48108) (xy 223.640903 -252.508966)
			(xy 223.632783 -252.564142) (xy 223.616715 -252.617549) (xy 223.593043 -252.668046) (xy 223.56227 -252.714559)
			(xy 223.525053 -252.756096) (xy 223.482185 -252.791771) (xy 223.434579 -252.820825) (xy 223.38325 -252.842637)
			(xy 223.329293 -252.856743) (xy 223.273856 -252.862843) (xy 223.218122 -252.860806) (xy 223.163279 -252.850676)
			(xy 223.110495 -252.832669) (xy 223.060895 -252.807168) (xy 223.015537 -252.774717) (xy 222.975388 -252.736008)
			(xy 222.941302 -252.691865) (xy 222.914006 -252.64323) (xy 222.894083 -252.591139) (xy 222.881957 -252.536702)
			(xy 222.877886 -252.48108) (xy 222.726046 -252.48108) (xy 222.72255 -252.505394) (xy 222.707196 -252.557685)
			(xy 222.684557 -252.607259) (xy 222.655093 -252.653107) (xy 222.619405 -252.694295) (xy 222.578218 -252.729985)
			(xy 222.532371 -252.75945) (xy 222.482798 -252.782091) (xy 222.430507 -252.797447) (xy 222.376563 -252.805205)
			(xy 222.349314 -252.805692) (xy 222.323441 -252.805262) (xy 222.272168 -252.798281) (xy 222.22231 -252.784432)
			(xy 222.174782 -252.763968) (xy 222.130457 -252.737266) (xy 222.09015 -252.704816) (xy 222.054601 -252.667214)
			(xy 222.03918 -252.646434) (xy 222.030217 -252.634886) (xy 222.007135 -252.616974) (xy 221.979925 -252.60633)
			(xy 221.950816 -252.603824) (xy 221.922188 -252.609662) (xy 221.896383 -252.623365) (xy 221.875514 -252.643812)
			(xy 221.867984 -252.65634) (xy 221.85338 -252.681394) (xy 221.817856 -252.727224) (xy 221.775805 -252.767151)
			(xy 221.728196 -252.800254) (xy 221.676126 -252.825772) (xy 221.620794 -252.843117) (xy 221.563475 -252.851889)
			(xy 221.534482 -252.852428) (xy 221.507233 -252.851901) (xy 221.45329 -252.844142) (xy 221.401 -252.828787)
			(xy 221.351428 -252.806146) (xy 221.305582 -252.77668) (xy 221.264397 -252.740991) (xy 221.228709 -252.699803)
			(xy 221.199246 -252.653956) (xy 221.176607 -252.604383) (xy 221.161254 -252.552092) (xy 221.153498 -252.498149)
			(xy 180.379167 -252.498149) (xy 181.434232 -253.553214) (xy 181.441628 -253.560065) (xy 181.460227 -253.567801)
			(xy 181.4703 -253.5682)
		)
		(stroke
			(width 0)
			(type solid)
		)
		(fill yes)
		(layer "In7.Cu")
		(net "GND")
	)
	(gr_poly
		(pts
			(xy 243.388642 -357.212646) (xy 243.398708 -357.212214) (xy 243.417296 -357.204483) (xy 243.42471 -357.19766)
			(xy 244.261894 -356.360476) (xy 244.269288 -356.35362) (xy 244.287887 -356.345871) (xy 244.297962 -356.34549)
			(xy 255.263904 -356.34549) (xy 255.273974 -356.345066) (xy 255.292576 -356.337349) (xy 255.299972 -356.330504)
			(xy 255.556258 -356.074218) (xy 255.563096 -356.066817) (xy 255.570807 -356.048218) (xy 255.571244 -356.03815)
			(xy 255.571244 -355.415342) (xy 255.546352 -355.386894) (xy 255.527048 -355.384354) (xy 255.499903 -355.380245)
			(xy 255.447091 -355.36525) (xy 255.396973 -355.342842) (xy 255.350583 -355.313484) (xy 255.308878 -355.27778)
			(xy 255.272721 -355.23647) (xy 255.242856 -355.190404) (xy 255.2199 -355.140534) (xy 255.204328 -355.087889)
			(xy 255.19646 -355.033556) (xy 255.196459 -354.978657) (xy 255.204325 -354.924323) (xy 255.219896 -354.871678)
			(xy 255.24285 -354.821807) (xy 255.272713 -354.775741) (xy 255.308869 -354.734429) (xy 255.350573 -354.698724)
			(xy 255.396962 -354.669364) (xy 255.447079 -354.646954) (xy 255.499891 -354.631957) (xy 255.527048 -354.627942)
			(xy 255.546352 -354.625402) (xy 255.571244 -354.596954) (xy 255.571244 -351.55886) (xy 255.571676 -351.548794)
			(xy 255.579405 -351.530204) (xy 255.58623 -351.522792) (xy 255.90373 -351.205292) (xy 255.911131 -351.198451)
			(xy 255.929729 -351.190729) (xy 255.939798 -351.190306) (xy 259.864606 -351.190306) (xy 259.874676 -351.189882)
			(xy 259.893279 -351.182167) (xy 259.900674 -351.17532) (xy 260.421882 -350.654112) (xy 260.428732 -350.646715)
			(xy 260.436474 -350.628117) (xy 260.436868 -350.618044) (xy 260.436868 -345.134692) (xy 260.436443 -345.124623)
			(xy 260.428723 -345.106024) (xy 260.421882 -345.098624) (xy 260.075934 -344.752676) (xy 260.068536 -344.745832)
			(xy 260.049936 -344.73811) (xy 260.039866 -344.73769) (xy 254.659384 -344.73769) (xy 254.649315 -344.737264)
			(xy 254.630716 -344.729544) (xy 254.623316 -344.722704) (xy 254.056134 -344.155522) (xy 254.049296 -344.148121)
			(xy 254.041585 -344.129522) (xy 254.041148 -344.119454) (xy 254.041148 -336.931) (xy 254.040723 -336.920931)
			(xy 254.033003 -336.902331) (xy 254.026162 -336.894932) (xy 252.339094 -335.207864) (xy 252.331698 -335.201011)
			(xy 252.3131 -335.193269) (xy 252.303026 -335.192878) (xy 252.03658 -335.192878) (xy 252.024064 -335.193509)
			(xy 252.001935 -335.205209) (xy 251.994416 -335.21523) (xy 251.94006 -335.294986) (xy 251.93752 -335.320132)
			(xy 251.942092 -335.331816) (xy 251.950557 -335.354209) (xy 251.962438 -335.400586) (xy 251.968412 -335.448087)
			(xy 251.968762 -335.472024) (xy 251.968276 -335.499275) (xy 251.96052 -335.553223) (xy 251.945165 -335.605518)
			(xy 251.922523 -335.655095) (xy 251.893057 -335.700945) (xy 251.857366 -335.742136) (xy 251.816175 -335.777827)
			(xy 251.770325 -335.807293) (xy 251.720748 -335.829935) (xy 251.668453 -335.84529) (xy 251.614505 -335.853046)
			(xy 251.560003 -335.853046) (xy 251.506055 -335.84529) (xy 251.45376 -335.829935) (xy 251.404183 -335.807293)
			(xy 251.358333 -335.777827) (xy 251.317142 -335.742136) (xy 251.281451 -335.700945) (xy 251.251985 -335.655095)
			(xy 251.229343 -335.605518) (xy 251.213988 -335.553223) (xy 251.206232 -335.499275) (xy 251.205746 -335.472024)
			(xy 251.206122 -335.448089) (xy 251.212109 -335.400594) (xy 251.223979 -335.354218) (xy 251.232416 -335.331816)
			(xy 251.236988 -335.320132) (xy 251.234448 -335.294986) (xy 251.180092 -335.21523) (xy 251.172563 -335.205211)
			(xy 251.150446 -335.193487) (xy 251.137928 -335.192878) (xy 240.279428 -335.192878) (xy 240.26711 -335.193677)
			(xy 240.245341 -335.205226) (xy 240.237772 -335.214976) (xy 240.183162 -335.294478) (xy 240.180114 -335.319116)
			(xy 240.184686 -335.3308) (xy 240.192732 -335.352718) (xy 240.20404 -335.398019) (xy 240.209742 -335.444361)
			(xy 240.210086 -335.467706) (xy 240.2096 -335.494957) (xy 240.201844 -335.548905) (xy 240.186489 -335.6012)
			(xy 240.163847 -335.650777) (xy 240.134381 -335.696627) (xy 240.11045 -335.724246) (xy 240.910362 -335.724246)
			(xy 240.914433 -335.668624) (xy 240.926559 -335.614187) (xy 240.946482 -335.562096) (xy 240.973778 -335.513461)
			(xy 241.007864 -335.469318) (xy 241.048013 -335.430609) (xy 241.093371 -335.398158) (xy 241.142971 -335.372657)
			(xy 241.195755 -335.35465) (xy 241.250598 -335.34452) (xy 241.306332 -335.342483) (xy 241.361769 -335.348583)
			(xy 241.415726 -335.362689) (xy 241.467055 -335.384501) (xy 241.514661 -335.413555) (xy 241.557529 -335.44923)
			(xy 241.594746 -335.490767) (xy 241.625519 -335.53728) (xy 241.649191 -335.587777) (xy 241.665259 -335.641184)
			(xy 241.673379 -335.69636) (xy 241.673888 -335.724246) (xy 241.673379 -335.752132) (xy 241.665259 -335.807308)
			(xy 241.649191 -335.860715) (xy 241.625519 -335.911212) (xy 241.594746 -335.957725) (xy 241.557529 -335.999262)
			(xy 241.514661 -336.034937) (xy 241.467055 -336.063991) (xy 241.415726 -336.085803) (xy 241.361769 -336.099909)
			(xy 241.306332 -336.106009) (xy 241.250598 -336.103972) (xy 241.195755 -336.093842) (xy 241.142971 -336.075835)
			(xy 241.093371 -336.050334) (xy 241.048013 -336.017883) (xy 241.007864 -335.979174) (xy 240.973778 -335.935031)
			(xy 240.946482 -335.886396) (xy 240.926559 -335.834305) (xy 240.914433 -335.779868) (xy 240.910362 -335.724246)
			(xy 240.11045 -335.724246) (xy 240.09869 -335.737818) (xy 240.057499 -335.773509) (xy 240.011649 -335.802975)
			(xy 239.962072 -335.825617) (xy 239.909777 -335.840972) (xy 239.855829 -335.848728) (xy 239.801327 -335.848728)
			(xy 239.747379 -335.840972) (xy 239.695084 -335.825617) (xy 239.645507 -335.802975) (xy 239.599657 -335.773509)
			(xy 239.558466 -335.737818) (xy 239.522775 -335.696627) (xy 239.493309 -335.650777) (xy 239.470667 -335.6012)
			(xy 239.455312 -335.548905) (xy 239.447556 -335.494957) (xy 239.44707 -335.467706) (xy 239.447421 -335.444361)
			(xy 239.453118 -335.398019) (xy 239.464428 -335.352719) (xy 239.47247 -335.3308) (xy 239.477042 -335.319116)
			(xy 239.473994 -335.294478) (xy 239.419384 -335.214976) (xy 239.411813 -335.205232) (xy 239.390042 -335.193702)
			(xy 239.377728 -335.192878) (xy 202.831446 -335.192878) (xy 202.82138 -335.19331) (xy 202.802787 -335.201036)
			(xy 202.795378 -335.207864) (xy 200.737216 -337.266026) (xy 234.403392 -337.266026) (xy 234.403392 -336.402426)
			(xy 234.403951 -336.372455) (xy 234.411769 -336.313024) (xy 234.427274 -336.255122) (xy 234.450202 -336.199738)
			(xy 234.48016 -336.147818) (xy 234.516636 -336.100252) (xy 234.559006 -336.057851) (xy 234.606547 -336.021341)
			(xy 234.658445 -335.991346) (xy 234.713813 -335.968379) (xy 234.771704 -335.952833) (xy 234.831129 -335.944973)
			(xy 234.8611 -335.944464) (xy 234.890743 -335.944952) (xy 234.949525 -335.952676) (xy 235.006824 -335.967906)
			(xy 235.061684 -335.990387) (xy 235.087668 -336.004662) (xy 235.096084 -336.008902) (xy 235.114711 -336.01164)
			(xy 235.12399 -336.009996) (xy 235.154216 -336.003138) (xy 235.163199 -336.000682) (xy 235.178708 -335.990408)
			(xy 235.184442 -335.983072) (xy 235.199873 -335.962231) (xy 235.235442 -335.924496) (xy 235.275797 -335.89193)
			(xy 235.320193 -335.865134) (xy 235.367811 -335.844601) (xy 235.417773 -335.830712) (xy 235.469156 -335.823723)
			(xy 235.495084 -335.823306) (xy 235.522339 -335.82374) (xy 235.576293 -335.831495) (xy 235.628595 -335.84685)
			(xy 235.678179 -335.869493) (xy 235.724036 -335.898962) (xy 235.765232 -335.934657) (xy 235.800929 -335.975851)
			(xy 235.830399 -336.021707) (xy 235.853044 -336.07129) (xy 235.868401 -336.123591) (xy 235.876159 -336.177545)
			(xy 235.876159 -336.232055) (xy 235.868401 -336.286009) (xy 235.853044 -336.33831) (xy 235.830399 -336.387893)
			(xy 235.800929 -336.433749) (xy 235.765232 -336.474943) (xy 235.724036 -336.510638) (xy 235.678179 -336.540107)
			(xy 235.637048 -336.55889) (xy 240.234214 -336.55889) (xy 240.238285 -336.503268) (xy 240.250411 -336.448831)
			(xy 240.270334 -336.39674) (xy 240.29763 -336.348105) (xy 240.331716 -336.303962) (xy 240.371865 -336.265253)
			(xy 240.417223 -336.232802) (xy 240.466823 -336.207301) (xy 240.519607 -336.189294) (xy 240.57445 -336.179164)
			(xy 240.630184 -336.177127) (xy 240.685621 -336.183227) (xy 240.739578 -336.197333) (xy 240.790907 -336.219145)
			(xy 240.838513 -336.248199) (xy 240.881381 -336.283874) (xy 240.918598 -336.325411) (xy 240.949371 -336.371924)
			(xy 240.973043 -336.422421) (xy 240.989111 -336.475828) (xy 240.997231 -336.531004) (xy 240.99774 -336.55889)
			(xy 240.997231 -336.586776) (xy 240.989111 -336.641952) (xy 240.973043 -336.695359) (xy 240.949371 -336.745856)
			(xy 240.918598 -336.792369) (xy 240.881381 -336.833906) (xy 240.838513 -336.869581) (xy 240.790907 -336.898635)
			(xy 240.739578 -336.920447) (xy 240.685621 -336.934553) (xy 240.630184 -336.940653) (xy 240.57445 -336.938616)
			(xy 240.519607 -336.928486) (xy 240.466823 -336.910479) (xy 240.417223 -336.884978) (xy 240.371865 -336.852527)
			(xy 240.331716 -336.813818) (xy 240.29763 -336.769675) (xy 240.270334 -336.72104) (xy 240.250411 -336.668949)
			(xy 240.238285 -336.614512) (xy 240.234214 -336.55889) (xy 235.637048 -336.55889) (xy 235.628595 -336.56275)
			(xy 235.576293 -336.578105) (xy 235.522339 -336.58586) (xy 235.495084 -336.586322) (xy 235.480291 -336.58619)
			(xy 235.450793 -336.583899) (xy 235.436156 -336.58175) (xy 235.425234 -336.579972) (xy 235.403898 -336.586068)
			(xy 235.336588 -336.643472) (xy 235.328578 -336.651055) (xy 235.319353 -336.671064) (xy 235.318808 -336.68208)
			(xy 235.318808 -336.986372) (xy 235.319359 -336.997389) (xy 235.328569 -337.017406) (xy 235.336588 -337.02498)
			(xy 235.403898 -337.082384) (xy 235.425234 -337.08848) (xy 235.436156 -337.086702) (xy 235.450794 -337.08456)
			(xy 235.480291 -337.082273) (xy 235.495084 -337.08213) (xy 235.52234 -337.082516) (xy 235.576298 -337.090272)
			(xy 235.628603 -337.105628) (xy 235.678191 -337.128272) (xy 235.72405 -337.157742) (xy 235.765249 -337.19344)
			(xy 235.800948 -337.234637) (xy 235.830421 -337.280495) (xy 235.853066 -337.330082) (xy 235.868425 -337.382386)
			(xy 235.876183 -337.436344) (xy 235.876183 -337.490856) (xy 235.868425 -337.544814) (xy 235.853066 -337.597118)
			(xy 235.830421 -337.646705) (xy 235.800948 -337.692563) (xy 235.765249 -337.73376) (xy 235.72405 -337.769458)
			(xy 235.678191 -337.798928) (xy 235.628603 -337.821572) (xy 235.576298 -337.836928) (xy 235.52234 -337.844684)
			(xy 235.495084 -337.845146) (xy 235.469156 -337.844748) (xy 235.417777 -337.837738) (xy 235.36782 -337.823837)
			(xy 235.320204 -337.8033) (xy 235.275808 -337.776506) (xy 235.235448 -337.743947) (xy 235.199868 -337.706224)
			(xy 235.184442 -337.68538) (xy 235.178684 -337.678065) (xy 235.163194 -337.66777) (xy 235.154216 -337.665314)
			(xy 235.12399 -337.658456) (xy 235.114711 -337.65673) (xy 235.096051 -337.659457) (xy 235.087668 -337.66379)
			(xy 235.061696 -337.678093) (xy 235.006843 -337.700603) (xy 234.949538 -337.715827) (xy 234.890746 -337.72351)
			(xy 234.8611 -337.723988) (xy 234.83112 -337.723538) (xy 234.771672 -337.715709) (xy 234.713756 -337.700184)
			(xy 234.658363 -337.67723) (xy 234.606441 -337.647239) (xy 234.55888 -337.610725) (xy 234.516494 -337.568314)
			(xy 234.480009 -337.520731) (xy 234.450049 -337.468791) (xy 234.427128 -337.413384) (xy 234.411638 -337.355459)
			(xy 234.403844 -337.296007) (xy 234.403392 -337.266026) (xy 200.737216 -337.266026) (xy 200.334118 -337.669124)
			(xy 200.327273 -337.676523) (xy 200.319545 -337.695121) (xy 200.319132 -337.705192) (xy 200.319132 -337.721194)
			(xy 200.319551 -337.731214) (xy 200.327221 -337.749727) (xy 200.341395 -337.763893) (xy 200.359912 -337.771554)
			(xy 200.369932 -337.771994) (xy 200.37806 -337.771994) (xy 200.38568 -337.769454) (xy 200.414297 -337.760754)
			(xy 200.473376 -337.751431) (xy 200.503282 -337.750912) (xy 200.529601 -337.751333) (xy 200.581745 -337.758532)
			(xy 200.632402 -337.772837) (xy 200.680609 -337.793977) (xy 200.725448 -337.821548) (xy 200.766068 -337.855026)
			(xy 200.784206 -337.874102) (xy 200.791701 -337.881543) (xy 200.810996 -337.890069) (xy 200.821544 -337.890612)
			(xy 200.89622 -337.890612) (xy 200.906761 -337.890037) (xy 200.926054 -337.881524) (xy 200.933558 -337.874102)
			(xy 200.951708 -337.855042) (xy 200.99234 -337.821588) (xy 201.037182 -337.794034) (xy 201.085384 -337.7729)
			(xy 201.136032 -337.758588) (xy 201.188166 -337.751369) (xy 201.214482 -337.750912) (xy 201.241735 -337.751374)
			(xy 201.295687 -337.759129) (xy 201.347986 -337.774484) (xy 201.397567 -337.797126) (xy 201.443421 -337.826593)
			(xy 201.484614 -337.862287) (xy 201.520308 -337.903481) (xy 201.549775 -337.949335) (xy 201.572417 -337.998916)
			(xy 201.587771 -338.051215) (xy 201.595526 -338.105167) (xy 201.59599 -338.13242) (xy 201.595566 -338.158738)
			(xy 201.588363 -338.210879) (xy 201.574054 -338.261533) (xy 201.552911 -338.309736) (xy 201.525338 -338.354572)
			(xy 201.491858 -338.395188) (xy 201.4728 -338.413344) (xy 201.465365 -338.420841) (xy 201.456853 -338.440136)
			(xy 201.45629 -338.450682) (xy 201.45629 -338.525358) (xy 201.456873 -338.535895) (xy 201.465395 -338.555178)
			(xy 201.4728 -338.562696) (xy 201.491863 -338.580845) (xy 201.525323 -338.621475) (xy 201.552885 -338.666316)
			(xy 201.574026 -338.714518) (xy 201.588346 -338.765167) (xy 201.595573 -338.817303) (xy 201.59599 -338.84362)
			(xy 201.595502 -338.87087) (xy 201.587743 -338.924814) (xy 201.572386 -338.977106) (xy 201.549744 -339.026679)
			(xy 201.520277 -339.072526) (xy 201.484585 -339.113712) (xy 201.443395 -339.1494) (xy 201.397546 -339.178862)
			(xy 201.34797 -339.2015) (xy 201.295677 -339.216852) (xy 201.241732 -339.224605) (xy 201.214482 -339.225128)
			(xy 201.188164 -339.224704) (xy 201.136024 -339.2175) (xy 201.085372 -339.203189) (xy 201.037171 -339.182045)
			(xy 200.992337 -339.154468) (xy 200.951725 -339.120985) (xy 200.933558 -339.101938) (xy 200.926064 -339.094498)
			(xy 200.906767 -339.085978) (xy 200.89622 -339.085428) (xy 200.821544 -339.085428) (xy 200.811008 -339.086011)
			(xy 200.791729 -339.094538) (xy 200.784206 -339.101938) (xy 200.766056 -339.121) (xy 200.725425 -339.154457)
			(xy 200.680583 -339.182016) (xy 200.632382 -339.203155) (xy 200.581734 -339.217474) (xy 200.529599 -339.2247)
			(xy 200.503282 -339.225128) (xy 200.48688 -339.224968) (xy 200.454195 -339.222169) (xy 200.438004 -339.21954)
			(xy 200.426828 -339.217508) (xy 200.405492 -339.22335) (xy 200.337166 -339.280754) (xy 200.329032 -339.288345)
			(xy 200.319683 -339.308504) (xy 200.319132 -339.319616) (xy 200.319132 -341.799448) (xy 231.047318 -341.799448)
			(xy 231.047318 -341.744952) (xy 231.055074 -341.691011) (xy 231.070427 -341.638723) (xy 231.093065 -341.589151)
			(xy 231.122527 -341.543306) (xy 231.158213 -341.502121) (xy 231.199398 -341.466433) (xy 231.245242 -341.436969)
			(xy 231.294813 -341.41433) (xy 231.347101 -341.398976) (xy 231.401042 -341.391219) (xy 231.42829 -341.390732)
			(xy 231.456426 -341.391179) (xy 231.51209 -341.399433) (xy 231.565936 -341.415778) (xy 231.616795 -341.439859)
			(xy 231.663563 -341.471153) (xy 231.705224 -341.508981) (xy 231.723438 -341.530432) (xy 231.73055 -341.539322)
			(xy 231.750616 -341.548974) (xy 231.850438 -341.550752) (xy 231.870758 -341.541862) (xy 231.878124 -341.53348)
			(xy 231.896316 -341.513539) (xy 231.937357 -341.478478) (xy 231.982928 -341.449551) (xy 232.032122 -341.427334)
			(xy 232.083955 -341.412271) (xy 232.137393 -341.404662) (xy 232.164382 -341.404194) (xy 232.191636 -341.404652)
			(xy 232.245589 -341.412407) (xy 232.297889 -341.427762) (xy 232.347472 -341.450403) (xy 232.393328 -341.479871)
			(xy 232.434523 -341.515565) (xy 232.470218 -341.556758) (xy 232.499688 -341.602612) (xy 232.522332 -341.652194)
			(xy 232.537689 -341.704493) (xy 232.545447 -341.758446) (xy 232.545447 -341.812954) (xy 232.537689 -341.866907)
			(xy 232.522332 -341.919206) (xy 232.499688 -341.968788) (xy 232.470218 -342.014642) (xy 232.434523 -342.055835)
			(xy 232.393328 -342.091529) (xy 232.347472 -342.120997) (xy 232.297889 -342.143638) (xy 232.245589 -342.158993)
			(xy 232.191636 -342.166748) (xy 232.164382 -342.16721) (xy 232.136248 -342.166698) (xy 232.080588 -342.158455)
			(xy 232.026744 -342.142122) (xy 231.975885 -342.118053) (xy 231.929115 -342.086771) (xy 231.887451 -342.048955)
			(xy 231.869234 -342.02751) (xy 231.862122 -342.01862) (xy 231.842056 -342.008968) (xy 231.742234 -342.00719)
			(xy 231.721914 -342.01608) (xy 231.714548 -342.024462) (xy 231.696358 -342.044406) (xy 231.655318 -342.079468)
			(xy 231.609747 -342.108397) (xy 231.560553 -342.130614) (xy 231.508719 -342.145676) (xy 231.455279 -342.153282)
			(xy 231.42829 -342.153748) (xy 231.401042 -342.153181) (xy 231.347101 -342.145424) (xy 231.294813 -342.13007)
			(xy 231.245242 -342.107431) (xy 231.199398 -342.077967) (xy 231.158213 -342.042279) (xy 231.122527 -342.001094)
			(xy 231.093065 -341.955249) (xy 231.070427 -341.905677) (xy 231.055074 -341.853389) (xy 231.047318 -341.799448)
			(xy 200.319132 -341.799448) (xy 200.319132 -341.973154) (xy 200.319566 -341.983219) (xy 200.327297 -342.001806)
			(xy 200.334118 -342.009222) (xy 200.33488 -342.009984) (xy 200.33488 -347.400118) (xy 211.629508 -347.400118)
			(xy 211.633493 -347.218777) (xy 211.645439 -347.037785) (xy 211.665323 -346.857493) (xy 211.693107 -346.678249)
			(xy 211.728738 -346.500397) (xy 211.772146 -346.324283) (xy 211.823248 -346.150245) (xy 211.881946 -345.97862)
			(xy 211.948125 -345.809739) (xy 212.021658 -345.643927) (xy 212.102403 -345.481506) (xy 212.190205 -345.322787)
			(xy 212.284894 -345.168079) (xy 212.386286 -345.017679) (xy 212.494187 -344.871878) (xy 212.608388 -344.730957)
			(xy 212.728669 -344.595188) (xy 212.854797 -344.464834) (xy 212.986529 -344.340145) (xy 213.123611 -344.221363)
			(xy 213.265778 -344.108717) (xy 213.412755 -344.002424) (xy 213.56426 -343.90269) (xy 213.719999 -343.809706)
			(xy 213.879672 -343.723653) (xy 214.042971 -343.644697) (xy 214.20958 -343.572989) (xy 214.379178 -343.508669)
			(xy 214.551438 -343.451861) (xy 214.726026 -343.402673) (xy 214.902607 -343.361202) (xy 215.080839 -343.327527)
			(xy 215.260378 -343.301713) (xy 215.440877 -343.283811) (xy 215.621989 -343.273853) (xy 215.803363 -343.271861)
			(xy 215.98465 -343.277837) (xy 216.165499 -343.291771) (xy 216.345562 -343.313634) (xy 216.52449 -343.343386)
			(xy 216.701939 -343.380968) (xy 216.877566 -343.426308) (xy 217.051032 -343.479319) (xy 217.222002 -343.539898)
			(xy 217.390147 -343.607928) (xy 217.55514 -343.683278) (xy 217.716665 -343.765803) (xy 217.874409 -343.855343)
			(xy 218.028068 -343.951725) (xy 218.177345 -344.054763) (xy 218.321952 -344.164259) (xy 218.46161 -344.280001)
			(xy 218.59605 -344.401766) (xy 218.725011 -344.529318) (xy 218.848245 -344.662412) (xy 218.965514 -344.80079)
			(xy 219.076592 -344.944186) (xy 219.181264 -345.092322) (xy 219.279328 -345.244913) (xy 219.370595 -345.401664)
			(xy 219.384716 -345.42857) (xy 229.27894 -345.42857) (xy 229.283011 -345.372948) (xy 229.295137 -345.318511)
			(xy 229.31506 -345.26642) (xy 229.342356 -345.217785) (xy 229.376442 -345.173642) (xy 229.416591 -345.134933)
			(xy 229.461949 -345.102482) (xy 229.511549 -345.076981) (xy 229.564333 -345.058974) (xy 229.619176 -345.048844)
			(xy 229.67491 -345.046807) (xy 229.730347 -345.052907) (xy 229.784304 -345.067013) (xy 229.835633 -345.088825)
			(xy 229.883239 -345.117879) (xy 229.926107 -345.153554) (xy 229.963324 -345.195091) (xy 229.994097 -345.241604)
			(xy 230.017769 -345.292101) (xy 230.033837 -345.345508) (xy 230.041957 -345.400684) (xy 230.042466 -345.42857)
			(xy 230.041957 -345.456456) (xy 230.033837 -345.511632) (xy 230.017769 -345.565039) (xy 229.994097 -345.615536)
			(xy 229.963324 -345.662049) (xy 229.926107 -345.703586) (xy 229.883239 -345.739261) (xy 229.835633 -345.768315)
			(xy 229.784304 -345.790127) (xy 229.730347 -345.804233) (xy 229.67491 -345.810333) (xy 229.619176 -345.808296)
			(xy 229.564333 -345.798166) (xy 229.511549 -345.780159) (xy 229.461949 -345.754658) (xy 229.416591 -345.722207)
			(xy 229.376442 -345.683498) (xy 229.342356 -345.639355) (xy 229.31506 -345.59072) (xy 229.295137 -345.538629)
			(xy 229.283011 -345.484192) (xy 229.27894 -345.42857) (xy 219.384716 -345.42857) (xy 219.454889 -345.562273)
			(xy 219.532047 -345.726429) (xy 219.576507 -345.832938) (xy 235.125004 -345.832938) (xy 235.129075 -345.777316)
			(xy 235.141201 -345.722879) (xy 235.161124 -345.670788) (xy 235.18842 -345.622153) (xy 235.222506 -345.57801)
			(xy 235.262655 -345.539301) (xy 235.308013 -345.50685) (xy 235.357613 -345.481349) (xy 235.410397 -345.463342)
			(xy 235.46524 -345.453212) (xy 235.520974 -345.451175) (xy 235.576411 -345.457275) (xy 235.630368 -345.471381)
			(xy 235.681697 -345.493193) (xy 235.729303 -345.522247) (xy 235.772171 -345.557922) (xy 235.809388 -345.599459)
			(xy 235.840161 -345.645972) (xy 235.863833 -345.696469) (xy 235.867076 -345.707248) (xy 248.248708 -345.707248)
			(xy 248.248708 -345.652752) (xy 248.256463 -345.59881) (xy 248.271816 -345.546522) (xy 248.294454 -345.49695)
			(xy 248.323916 -345.451104) (xy 248.359602 -345.409918) (xy 248.400786 -345.374229) (xy 248.44663 -345.344765)
			(xy 248.496201 -345.322124) (xy 248.548489 -345.306768) (xy 248.60243 -345.29901) (xy 248.629678 -345.298522)
			(xy 248.658595 -345.299048) (xy 248.715766 -345.307774) (xy 248.770965 -345.32503) (xy 248.822927 -345.35042)
			(xy 248.870461 -345.383363) (xy 248.912478 -345.423103) (xy 248.930668 -345.445588) (xy 248.93825 -345.454329)
			(xy 248.958993 -345.464525) (xy 248.970546 -345.465146) (xy 249.05081 -345.465146) (xy 249.062382 -345.4646)
			(xy 249.083153 -345.45439) (xy 249.090688 -345.445588) (xy 249.108883 -345.423108) (xy 249.150902 -345.383373)
			(xy 249.198436 -345.350434) (xy 249.250397 -345.325045) (xy 249.305594 -345.307788) (xy 249.362762 -345.299058)
			(xy 249.391678 -345.298522) (xy 249.418934 -345.298923) (xy 249.472892 -345.306678) (xy 249.525196 -345.322034)
			(xy 249.574783 -345.344677) (xy 249.620643 -345.374147) (xy 249.661841 -345.409843) (xy 249.69754 -345.45104)
			(xy 249.727013 -345.496897) (xy 249.749658 -345.546483) (xy 249.765017 -345.598787) (xy 249.772775 -345.652744)
			(xy 249.772775 -345.707256) (xy 249.765017 -345.761213) (xy 249.749658 -345.813517) (xy 249.727013 -345.863103)
			(xy 249.69754 -345.90896) (xy 249.669433 -345.941396) (xy 250.769118 -345.941396) (xy 250.773189 -345.885774)
			(xy 250.785315 -345.831337) (xy 250.805238 -345.779246) (xy 250.832534 -345.730611) (xy 250.86662 -345.686468)
			(xy 250.906769 -345.647759) (xy 250.952127 -345.615308) (xy 251.001727 -345.589807) (xy 251.054511 -345.5718)
			(xy 251.109354 -345.56167) (xy 251.165088 -345.559633) (xy 251.220525 -345.565733) (xy 251.274482 -345.579839)
			(xy 251.325811 -345.601651) (xy 251.373417 -345.630705) (xy 251.416285 -345.66638) (xy 251.453502 -345.707917)
			(xy 251.484275 -345.75443) (xy 251.507947 -345.804927) (xy 251.524015 -345.858334) (xy 251.532135 -345.91351)
			(xy 251.532644 -345.941396) (xy 251.532135 -345.969282) (xy 251.524015 -346.024458) (xy 251.507947 -346.077865)
			(xy 251.484275 -346.128362) (xy 251.453502 -346.174875) (xy 251.416285 -346.216412) (xy 251.373417 -346.252087)
			(xy 251.325811 -346.281141) (xy 251.274482 -346.302953) (xy 251.220525 -346.317059) (xy 251.165088 -346.323159)
			(xy 251.109354 -346.321122) (xy 251.054511 -346.310992) (xy 251.001727 -346.292985) (xy 250.952127 -346.267484)
			(xy 250.906769 -346.235033) (xy 250.86662 -346.196324) (xy 250.832534 -346.152181) (xy 250.805238 -346.103546)
			(xy 250.785315 -346.051455) (xy 250.773189 -345.997018) (xy 250.769118 -345.941396) (xy 249.669433 -345.941396)
			(xy 249.661841 -345.950157) (xy 249.620643 -345.985853) (xy 249.574783 -346.015323) (xy 249.525196 -346.037966)
			(xy 249.472892 -346.053322) (xy 249.418934 -346.061077) (xy 249.391678 -346.061538) (xy 249.362762 -346.060987)
			(xy 249.305591 -346.052268) (xy 249.250392 -346.035018) (xy 249.19843 -346.009633) (xy 249.150895 -345.976694)
			(xy 249.108878 -345.936956) (xy 249.090688 -345.914472) (xy 249.083132 -345.905704) (xy 249.062369 -345.895525)
			(xy 249.05081 -345.894914) (xy 248.970546 -345.894914) (xy 248.958981 -345.895506) (xy 248.938209 -345.905685)
			(xy 248.930668 -345.914472) (xy 248.912488 -345.936965) (xy 248.870467 -345.976701) (xy 248.82293 -346.00964)
			(xy 248.770966 -346.035027) (xy 248.715766 -346.05228) (xy 248.658595 -346.061005) (xy 248.629678 -346.061538)
			(xy 248.60243 -346.06099) (xy 248.548489 -346.053232) (xy 248.496201 -346.037876) (xy 248.44663 -346.015235)
			(xy 248.400786 -345.985771) (xy 248.359602 -345.950082) (xy 248.323916 -345.908896) (xy 248.294454 -345.86305)
			(xy 248.271816 -345.813478) (xy 248.256463 -345.76119) (xy 248.248708 -345.707248) (xy 235.867076 -345.707248)
			(xy 235.879901 -345.749876) (xy 235.888021 -345.805052) (xy 235.88853 -345.832938) (xy 235.888021 -345.860824)
			(xy 235.879901 -345.916) (xy 235.863833 -345.969407) (xy 235.840161 -346.019904) (xy 235.809388 -346.066417)
			(xy 235.772171 -346.107954) (xy 235.729303 -346.143629) (xy 235.681697 -346.172683) (xy 235.630368 -346.194495)
			(xy 235.576411 -346.208601) (xy 235.520974 -346.214701) (xy 235.46524 -346.212664) (xy 235.410397 -346.202534)
			(xy 235.357613 -346.184527) (xy 235.308013 -346.159026) (xy 235.262655 -346.126575) (xy 235.222506 -346.087866)
			(xy 235.18842 -346.043723) (xy 235.161124 -345.995088) (xy 235.141201 -345.942997) (xy 235.129075 -345.88856)
			(xy 235.125004 -345.832938) (xy 219.576507 -345.832938) (xy 219.60192 -345.893816) (xy 219.664374 -346.06411)
			(xy 219.719286 -346.236983) (xy 219.766553 -346.412102) (xy 219.806082 -346.589127) (xy 219.837797 -346.767718)
			(xy 219.857717 -346.917956) (xy 245.50903 -346.917956) (xy 245.50903 -346.83326) (xy 245.517081 -346.748946)
			(xy 245.53311 -346.66578) (xy 245.556971 -346.584513) (xy 245.58845 -346.505883) (xy 245.627261 -346.430602)
			(xy 245.673051 -346.35935) (xy 245.725407 -346.292774) (xy 245.783855 -346.231476) (xy 245.847865 -346.176011)
			(xy 245.916857 -346.126882) (xy 245.990207 -346.084533) (xy 246.06725 -346.049349) (xy 246.147289 -346.021647)
			(xy 246.229598 -346.001679) (xy 246.313433 -345.989626) (xy 246.398034 -345.985596) (xy 246.482635 -345.989626)
			(xy 246.56647 -346.001679) (xy 246.648779 -346.021647) (xy 246.728818 -346.049349) (xy 246.805861 -346.084533)
			(xy 246.879211 -346.126882) (xy 246.948203 -346.176011) (xy 247.012213 -346.231476) (xy 247.070661 -346.292774)
			(xy 247.105741 -346.337382) (xy 255.72923 -346.337382) (xy 255.733301 -346.28176) (xy 255.745427 -346.227323)
			(xy 255.76535 -346.175232) (xy 255.792646 -346.126597) (xy 255.826732 -346.082454) (xy 255.866881 -346.043745)
			(xy 255.912239 -346.011294) (xy 255.961839 -345.985793) (xy 256.014623 -345.967786) (xy 256.069466 -345.957656)
			(xy 256.1252 -345.955619) (xy 256.180637 -345.961719) (xy 256.234594 -345.975825) (xy 256.285923 -345.997637)
			(xy 256.333529 -346.026691) (xy 256.376397 -346.062366) (xy 256.413614 -346.103903) (xy 256.444387 -346.150416)
			(xy 256.468059 -346.200913) (xy 256.484127 -346.25432) (xy 256.492247 -346.309496) (xy 256.492756 -346.337382)
			(xy 256.492247 -346.365268) (xy 256.484127 -346.420444) (xy 256.468059 -346.473851) (xy 256.444387 -346.524348)
			(xy 256.413614 -346.570861) (xy 256.376397 -346.612398) (xy 256.333529 -346.648073) (xy 256.285923 -346.677127)
			(xy 256.234594 -346.698939) (xy 256.180637 -346.713045) (xy 256.1252 -346.719145) (xy 256.069466 -346.717108)
			(xy 256.014623 -346.706978) (xy 255.961839 -346.688971) (xy 255.912239 -346.66347) (xy 255.866881 -346.631019)
			(xy 255.826732 -346.59231) (xy 255.792646 -346.548167) (xy 255.76535 -346.499532) (xy 255.745427 -346.447441)
			(xy 255.733301 -346.393004) (xy 255.72923 -346.337382) (xy 247.105741 -346.337382) (xy 247.123017 -346.35935)
			(xy 247.168807 -346.430602) (xy 247.207618 -346.505883) (xy 247.239097 -346.584513) (xy 247.262958 -346.66578)
			(xy 247.278987 -346.748946) (xy 247.287038 -346.83326) (xy 247.287542 -346.875608) (xy 247.287038 -346.917956)
			(xy 247.278987 -347.00227) (xy 247.262958 -347.085436) (xy 247.239097 -347.166703) (xy 247.207618 -347.245333)
			(xy 247.168807 -347.320614) (xy 247.123017 -347.391866) (xy 247.070661 -347.458442) (xy 247.012213 -347.51974)
			(xy 246.948203 -347.575205) (xy 246.879211 -347.624334) (xy 246.805861 -347.666683) (xy 246.728818 -347.701867)
			(xy 246.648779 -347.729569) (xy 246.56647 -347.749537) (xy 246.482635 -347.76159) (xy 246.398034 -347.765621)
			(xy 246.313433 -347.76159) (xy 246.229598 -347.749537) (xy 246.147289 -347.729569) (xy 246.06725 -347.701867)
			(xy 245.990207 -347.666683) (xy 245.916857 -347.624334) (xy 245.847865 -347.575205) (xy 245.783855 -347.51974)
			(xy 245.725407 -347.458442) (xy 245.673051 -347.391866) (xy 245.627261 -347.320614) (xy 245.58845 -347.245333)
			(xy 245.556971 -347.166703) (xy 245.53311 -347.085436) (xy 245.517081 -347.00227) (xy 245.50903 -346.917956)
			(xy 219.857717 -346.917956) (xy 219.861638 -346.94753) (xy 219.877557 -347.128215) (xy 219.885524 -347.309425)
			(xy 219.886022 -347.400118) (xy 219.885872 -347.427349) (xy 240.682796 -347.427349) (xy 240.682796 -347.372851)
			(xy 240.690552 -347.318908) (xy 240.705905 -347.266617) (xy 240.728544 -347.217044) (xy 240.758007 -347.171196)
			(xy 240.793694 -347.130009) (xy 240.83488 -347.094319) (xy 240.880726 -347.064853) (xy 240.930298 -347.042212)
			(xy 240.982588 -347.026856) (xy 241.036531 -347.019098) (xy 241.06378 -347.01861) (xy 241.092697 -347.019139)
			(xy 241.149867 -347.027865) (xy 241.205066 -347.045121) (xy 241.257028 -347.070511) (xy 241.304562 -347.103452)
			(xy 241.34658 -347.143191) (xy 241.36477 -347.165676) (xy 241.372336 -347.174433) (xy 241.393092 -347.184616)
			(xy 241.404648 -347.185234) (xy 241.484912 -347.185234) (xy 241.496484 -347.184693) (xy 241.517256 -347.17448)
			(xy 241.52479 -347.165676) (xy 241.542981 -347.143192) (xy 241.585001 -347.103458) (xy 241.632536 -347.07052)
			(xy 241.684498 -347.045132) (xy 241.739695 -347.027875) (xy 241.796864 -347.019146) (xy 241.82578 -347.01861)
			(xy 241.853035 -347.019036) (xy 241.906991 -347.026791) (xy 241.959294 -347.042146) (xy 242.008879 -347.064788)
			(xy 242.054736 -347.094257) (xy 242.095934 -347.129952) (xy 242.131631 -347.171147) (xy 242.161102 -347.217004)
			(xy 242.183747 -347.266588) (xy 242.199105 -347.31889) (xy 242.206863 -347.372845) (xy 242.206863 -347.427355)
			(xy 242.199105 -347.48131) (xy 242.183747 -347.533612) (xy 242.161102 -347.583196) (xy 242.131631 -347.629053)
			(xy 242.095934 -347.670248) (xy 242.054736 -347.705943) (xy 242.008879 -347.735412) (xy 241.959294 -347.758054)
			(xy 241.906991 -347.773409) (xy 241.853035 -347.781164) (xy 241.82578 -347.781626) (xy 241.796864 -347.781078)
			(xy 241.739693 -347.772359) (xy 241.684493 -347.755109) (xy 241.632531 -347.729723) (xy 241.584996 -347.696783)
			(xy 241.54298 -347.657044) (xy 241.52479 -347.63456) (xy 241.517235 -347.625791) (xy 241.496471 -347.615613)
			(xy 241.484912 -347.615002) (xy 241.404648 -347.615002) (xy 241.393084 -347.615599) (xy 241.372312 -347.625775)
			(xy 241.36477 -347.63456) (xy 241.346586 -347.65705) (xy 241.304566 -347.696786) (xy 241.25703 -347.729726)
			(xy 241.205067 -347.755113) (xy 241.149868 -347.772368) (xy 241.092697 -347.781093) (xy 241.06378 -347.781626)
			(xy 241.036531 -347.781102) (xy 240.982588 -347.773344) (xy 240.930298 -347.757988) (xy 240.880726 -347.735347)
			(xy 240.83488 -347.705881) (xy 240.793694 -347.670191) (xy 240.758007 -347.629004) (xy 240.728544 -347.583156)
			(xy 240.705905 -347.533583) (xy 240.690552 -347.481292) (xy 240.682796 -347.427349) (xy 219.885872 -347.427349)
			(xy 219.885524 -347.490811) (xy 219.877557 -347.672021) (xy 219.861638 -347.852706) (xy 219.851754 -347.92725)
			(xy 248.666268 -347.92725) (xy 248.666268 -347.87275) (xy 248.674023 -347.818805) (xy 248.689376 -347.766513)
			(xy 248.712015 -347.716937) (xy 248.741478 -347.671088) (xy 248.777165 -347.629898) (xy 248.818351 -347.594205)
			(xy 248.864197 -347.564737) (xy 248.913769 -347.542092) (xy 248.96606 -347.526733) (xy 249.020004 -347.518971)
			(xy 249.047254 -347.518482) (xy 249.076171 -347.519003) (xy 249.133344 -347.527727) (xy 249.188544 -347.544982)
			(xy 249.240506 -347.570373) (xy 249.28804 -347.603318) (xy 249.330055 -347.643061) (xy 249.348244 -347.665548)
			(xy 249.355783 -347.674333) (xy 249.376559 -347.684502) (xy 249.388122 -347.685106) (xy 249.468386 -347.685106)
			(xy 249.479952 -347.684526) (xy 249.500724 -347.674338) (xy 249.508264 -347.665548) (xy 249.526462 -347.643071)
			(xy 249.568482 -347.603338) (xy 249.616016 -347.570399) (xy 249.667976 -347.54501) (xy 249.723171 -347.527752)
			(xy 249.780339 -347.519019) (xy 249.809254 -347.518482) (xy 249.836508 -347.518962) (xy 249.890463 -347.526714)
			(xy 249.942765 -347.542065) (xy 249.992349 -347.564705) (xy 250.038207 -347.594171) (xy 250.079404 -347.629863)
			(xy 250.115102 -347.671056) (xy 250.144573 -347.71691) (xy 250.167219 -347.766492) (xy 250.170246 -347.7768)
			(xy 253.262382 -347.7768) (xy 253.266453 -347.721178) (xy 253.278579 -347.666741) (xy 253.298502 -347.61465)
			(xy 253.325798 -347.566015) (xy 253.359884 -347.521872) (xy 253.400033 -347.483163) (xy 253.445391 -347.450712)
			(xy 253.494991 -347.425211) (xy 253.547775 -347.407204) (xy 253.602618 -347.397074) (xy 253.658352 -347.395037)
			(xy 253.713789 -347.401137) (xy 253.767746 -347.415243) (xy 253.819075 -347.437055) (xy 253.866681 -347.466109)
			(xy 253.909549 -347.501784) (xy 253.946766 -347.543321) (xy 253.977539 -347.589834) (xy 254.001211 -347.640331)
			(xy 254.014376 -347.68409) (xy 255.611882 -347.68409) (xy 255.615953 -347.628468) (xy 255.628079 -347.574031)
			(xy 255.648002 -347.52194) (xy 255.675298 -347.473305) (xy 255.709384 -347.429162) (xy 255.749533 -347.390453)
			(xy 255.794891 -347.358002) (xy 255.844491 -347.332501) (xy 255.897275 -347.314494) (xy 255.952118 -347.304364)
			(xy 256.007852 -347.302327) (xy 256.063289 -347.308427) (xy 256.117246 -347.322533) (xy 256.168575 -347.344345)
			(xy 256.216181 -347.373399) (xy 256.259049 -347.409074) (xy 256.296266 -347.450611) (xy 256.327039 -347.497124)
			(xy 256.350711 -347.547621) (xy 256.366779 -347.601028) (xy 256.374899 -347.656204) (xy 256.375408 -347.68409)
			(xy 256.374899 -347.711976) (xy 256.366779 -347.767152) (xy 256.350711 -347.820559) (xy 256.327039 -347.871056)
			(xy 256.296266 -347.917569) (xy 256.259049 -347.959106) (xy 256.216181 -347.994781) (xy 256.168575 -348.023835)
			(xy 256.117246 -348.045647) (xy 256.063289 -348.059753) (xy 256.007852 -348.065853) (xy 255.952118 -348.063816)
			(xy 255.897275 -348.053686) (xy 255.844491 -348.035679) (xy 255.794891 -348.010178) (xy 255.749533 -347.977727)
			(xy 255.709384 -347.939018) (xy 255.675298 -347.894875) (xy 255.648002 -347.84624) (xy 255.628079 -347.794149)
			(xy 255.615953 -347.739712) (xy 255.611882 -347.68409) (xy 254.014376 -347.68409) (xy 254.017279 -347.693738)
			(xy 254.025399 -347.748914) (xy 254.025908 -347.7768) (xy 254.025399 -347.804686) (xy 254.017279 -347.859862)
			(xy 254.001211 -347.913269) (xy 253.977539 -347.963766) (xy 253.946766 -348.010279) (xy 253.909549 -348.051816)
			(xy 253.866681 -348.087491) (xy 253.819075 -348.116545) (xy 253.767746 -348.138357) (xy 253.713789 -348.152463)
			(xy 253.658352 -348.158563) (xy 253.602618 -348.156526) (xy 253.547775 -348.146396) (xy 253.494991 -348.128389)
			(xy 253.445391 -348.102888) (xy 253.400033 -348.070437) (xy 253.359884 -348.031728) (xy 253.325798 -347.987585)
			(xy 253.298502 -347.93895) (xy 253.278579 -347.886859) (xy 253.266453 -347.832422) (xy 253.262382 -347.7768)
			(xy 250.170246 -347.7768) (xy 250.182577 -347.818792) (xy 250.190335 -347.872746) (xy 250.190335 -347.927254)
			(xy 250.182577 -347.981208) (xy 250.167219 -348.033508) (xy 250.144573 -348.08309) (xy 250.115102 -348.128944)
			(xy 250.079404 -348.170137) (xy 250.038207 -348.205829) (xy 249.992349 -348.235295) (xy 249.942765 -348.257935)
			(xy 249.890463 -348.273286) (xy 249.836508 -348.281038) (xy 249.809254 -348.281498) (xy 249.780339 -348.280942)
			(xy 249.723169 -348.272221) (xy 249.667971 -348.25497) (xy 249.616009 -348.229586) (xy 249.568474 -348.196649)
			(xy 249.526455 -348.156914) (xy 249.508264 -348.134432) (xy 249.500725 -348.125647) (xy 249.479948 -348.115479)
			(xy 249.468386 -348.114874) (xy 249.388122 -348.114874) (xy 249.376552 -348.115431) (xy 249.355779 -348.125633)
			(xy 249.348244 -348.134432) (xy 249.330036 -348.156901) (xy 249.288019 -348.196636) (xy 249.240487 -348.229575)
			(xy 249.188529 -348.254966) (xy 249.133335 -348.272226) (xy 249.076169 -348.28096) (xy 249.047254 -348.281498)
			(xy 249.020004 -348.281029) (xy 248.96606 -348.273267) (xy 248.913769 -348.257908) (xy 248.864197 -348.235263)
			(xy 248.818351 -348.205795) (xy 248.777165 -348.170102) (xy 248.741478 -348.128912) (xy 248.712015 -348.083063)
			(xy 248.689376 -348.033487) (xy 248.674023 -347.981195) (xy 248.666268 -347.92725) (xy 219.851754 -347.92725)
			(xy 219.837797 -348.032518) (xy 219.806082 -348.211109) (xy 219.766553 -348.388134) (xy 219.742957 -348.475554)
			(xy 236.142528 -348.475554) (xy 236.146599 -348.419932) (xy 236.158725 -348.365495) (xy 236.178648 -348.313404)
			(xy 236.205944 -348.264769) (xy 236.24003 -348.220626) (xy 236.280179 -348.181917) (xy 236.325537 -348.149466)
			(xy 236.375137 -348.123965) (xy 236.427921 -348.105958) (xy 236.482764 -348.095828) (xy 236.538498 -348.093791)
			(xy 236.593935 -348.099891) (xy 236.647892 -348.113997) (xy 236.699221 -348.135809) (xy 236.746827 -348.164863)
			(xy 236.789695 -348.200538) (xy 236.826912 -348.242075) (xy 236.857685 -348.288588) (xy 236.881357 -348.339085)
			(xy 236.897425 -348.392492) (xy 236.902555 -348.427353) (xy 240.622271 -348.427353) (xy 240.622271 -348.372847)
			(xy 240.630029 -348.318896) (xy 240.645386 -348.266598) (xy 240.668029 -348.217018) (xy 240.697499 -348.171166)
			(xy 240.733194 -348.129974) (xy 240.774388 -348.094282) (xy 240.820243 -348.064816) (xy 240.869824 -348.042176)
			(xy 240.922123 -348.026823) (xy 240.976075 -348.019069) (xy 241.003328 -348.018608) (xy 241.032243 -348.019175)
			(xy 241.089412 -348.027893) (xy 241.14461 -348.045141) (xy 241.196572 -348.070524) (xy 241.244107 -348.103459)
			(xy 241.286126 -348.143192) (xy 241.304318 -348.165674) (xy 241.311864 -348.174452) (xy 241.332635 -348.184623)
			(xy 241.344196 -348.185232) (xy 241.42446 -348.185232) (xy 241.436029 -348.184662) (xy 241.456801 -348.17447)
			(xy 241.464338 -348.165674) (xy 241.482501 -348.143167) (xy 241.524527 -348.103434) (xy 241.572068 -348.070499)
			(xy 241.624035 -348.045115) (xy 241.679237 -348.027863) (xy 241.73641 -348.01914) (xy 241.765328 -348.018608)
			(xy 241.792579 -348.019064) (xy 241.846526 -348.026824) (xy 241.89882 -348.042182) (xy 241.948395 -348.064826)
			(xy 241.994244 -348.094294) (xy 242.035433 -348.129987) (xy 242.071123 -348.171178) (xy 242.100588 -348.217029)
			(xy 242.123228 -348.266607) (xy 242.138582 -348.318901) (xy 242.146338 -348.372849) (xy 242.146338 -348.427351)
			(xy 242.138582 -348.481299) (xy 242.123228 -348.533593) (xy 242.100588 -348.583171) (xy 242.071123 -348.629022)
			(xy 242.035433 -348.670213) (xy 241.994244 -348.705906) (xy 241.948395 -348.735374) (xy 241.89882 -348.758018)
			(xy 241.846526 -348.773376) (xy 241.792579 -348.781136) (xy 241.765328 -348.781624) (xy 241.73641 -348.781115)
			(xy 241.679237 -348.772388) (xy 241.624037 -348.75513) (xy 241.572075 -348.729737) (xy 241.524541 -348.69679)
			(xy 241.482527 -348.657046) (xy 241.464338 -348.634558) (xy 241.456762 -348.625811) (xy 241.436014 -348.615621)
			(xy 241.42446 -348.615) (xy 241.344196 -348.615) (xy 241.332628 -348.615568) (xy 241.311857 -348.625764)
			(xy 241.304318 -348.634558) (xy 241.286106 -348.657024) (xy 241.244092 -348.696762) (xy 241.196562 -348.729705)
			(xy 241.144604 -348.755096) (xy 241.08941 -348.772356) (xy 241.032243 -348.781088) (xy 241.003328 -348.781624)
			(xy 240.976075 -348.781131) (xy 240.922123 -348.773377) (xy 240.869824 -348.758024) (xy 240.820243 -348.735384)
			(xy 240.774388 -348.705918) (xy 240.733194 -348.670226) (xy 240.697499 -348.629034) (xy 240.668029 -348.583182)
			(xy 240.645386 -348.533602) (xy 240.630029 -348.481304) (xy 240.622271 -348.427353) (xy 236.902555 -348.427353)
			(xy 236.905545 -348.447668) (xy 236.906054 -348.475554) (xy 236.905545 -348.50344) (xy 236.897425 -348.558616)
			(xy 236.881357 -348.612023) (xy 236.857685 -348.66252) (xy 236.826912 -348.709033) (xy 236.789695 -348.75057)
			(xy 236.746827 -348.786245) (xy 236.699221 -348.815299) (xy 236.647892 -348.837111) (xy 236.593935 -348.851217)
			(xy 236.538498 -348.857317) (xy 236.482764 -348.85528) (xy 236.427921 -348.84515) (xy 236.375137 -348.827143)
			(xy 236.325537 -348.801642) (xy 236.280179 -348.769191) (xy 236.24003 -348.730482) (xy 236.205944 -348.686339)
			(xy 236.178648 -348.637704) (xy 236.158725 -348.585613) (xy 236.146599 -348.531176) (xy 236.142528 -348.475554)
			(xy 219.742957 -348.475554) (xy 219.719286 -348.563253) (xy 219.664374 -348.736126) (xy 219.604279 -348.899988)
			(xy 248.580146 -348.899988) (xy 248.584217 -348.844366) (xy 248.596343 -348.789929) (xy 248.616266 -348.737838)
			(xy 248.643562 -348.689203) (xy 248.677648 -348.64506) (xy 248.717797 -348.606351) (xy 248.763155 -348.5739)
			(xy 248.812755 -348.548399) (xy 248.865539 -348.530392) (xy 248.920382 -348.520262) (xy 248.976116 -348.518225)
			(xy 249.031553 -348.524325) (xy 249.08551 -348.538431) (xy 249.136839 -348.560243) (xy 249.184445 -348.589297)
			(xy 249.227313 -348.624972) (xy 249.26453 -348.666509) (xy 249.295303 -348.713022) (xy 249.318975 -348.763519)
			(xy 249.335043 -348.816926) (xy 249.338968 -348.8436) (xy 253.262382 -348.8436) (xy 253.266453 -348.787978)
			(xy 253.278579 -348.733541) (xy 253.298502 -348.68145) (xy 253.325798 -348.632815) (xy 253.359884 -348.588672)
			(xy 253.400033 -348.549963) (xy 253.445391 -348.517512) (xy 253.494991 -348.492011) (xy 253.547775 -348.474004)
			(xy 253.602618 -348.463874) (xy 253.658352 -348.461837) (xy 253.713789 -348.467937) (xy 253.767746 -348.482043)
			(xy 253.819075 -348.503855) (xy 253.866681 -348.532909) (xy 253.909549 -348.568584) (xy 253.946766 -348.610121)
			(xy 253.977539 -348.656634) (xy 253.985884 -348.674436) (xy 255.772664 -348.674436) (xy 255.776735 -348.618814)
			(xy 255.788861 -348.564377) (xy 255.808784 -348.512286) (xy 255.83608 -348.463651) (xy 255.870166 -348.419508)
			(xy 255.910315 -348.380799) (xy 255.955673 -348.348348) (xy 256.005273 -348.322847) (xy 256.058057 -348.30484)
			(xy 256.1129 -348.29471) (xy 256.168634 -348.292673) (xy 256.224071 -348.298773) (xy 256.278028 -348.312879)
			(xy 256.329357 -348.334691) (xy 256.376963 -348.363745) (xy 256.419831 -348.39942) (xy 256.457048 -348.440957)
			(xy 256.487821 -348.48747) (xy 256.511493 -348.537967) (xy 256.527561 -348.591374) (xy 256.535681 -348.64655)
			(xy 256.53619 -348.674436) (xy 256.535681 -348.702322) (xy 256.527561 -348.757498) (xy 256.515717 -348.796864)
			(xy 259.110224 -348.796864) (xy 259.114295 -348.741242) (xy 259.126421 -348.686805) (xy 259.146344 -348.634714)
			(xy 259.17364 -348.586079) (xy 259.207726 -348.541936) (xy 259.247875 -348.503227) (xy 259.293233 -348.470776)
			(xy 259.342833 -348.445275) (xy 259.395617 -348.427268) (xy 259.45046 -348.417138) (xy 259.506194 -348.415101)
			(xy 259.561631 -348.421201) (xy 259.615588 -348.435307) (xy 259.666917 -348.457119) (xy 259.714523 -348.486173)
			(xy 259.757391 -348.521848) (xy 259.794608 -348.563385) (xy 259.825381 -348.609898) (xy 259.849053 -348.660395)
			(xy 259.865121 -348.713802) (xy 259.873241 -348.768978) (xy 259.87375 -348.796864) (xy 259.873241 -348.82475)
			(xy 259.865121 -348.879926) (xy 259.849053 -348.933333) (xy 259.825381 -348.98383) (xy 259.794608 -349.030343)
			(xy 259.757391 -349.07188) (xy 259.714523 -349.107555) (xy 259.666917 -349.136609) (xy 259.615588 -349.158421)
			(xy 259.561631 -349.172527) (xy 259.506194 -349.178627) (xy 259.45046 -349.17659) (xy 259.395617 -349.16646)
			(xy 259.342833 -349.148453) (xy 259.293233 -349.122952) (xy 259.247875 -349.090501) (xy 259.207726 -349.051792)
			(xy 259.17364 -349.007649) (xy 259.146344 -348.959014) (xy 259.126421 -348.906923) (xy 259.114295 -348.852486)
			(xy 259.110224 -348.796864) (xy 256.515717 -348.796864) (xy 256.511493 -348.810905) (xy 256.487821 -348.861402)
			(xy 256.457048 -348.907915) (xy 256.419831 -348.949452) (xy 256.376963 -348.985127) (xy 256.329357 -349.014181)
			(xy 256.278028 -349.035993) (xy 256.224071 -349.050099) (xy 256.168634 -349.056199) (xy 256.1129 -349.054162)
			(xy 256.058057 -349.044032) (xy 256.005273 -349.026025) (xy 255.955673 -349.000524) (xy 255.910315 -348.968073)
			(xy 255.870166 -348.929364) (xy 255.83608 -348.885221) (xy 255.808784 -348.836586) (xy 255.788861 -348.784495)
			(xy 255.776735 -348.730058) (xy 255.772664 -348.674436) (xy 253.985884 -348.674436) (xy 254.001211 -348.707131)
			(xy 254.017279 -348.760538) (xy 254.025399 -348.815714) (xy 254.025908 -348.8436) (xy 254.025399 -348.871486)
			(xy 254.017279 -348.926662) (xy 254.001211 -348.980069) (xy 253.977539 -349.030566) (xy 253.946766 -349.077079)
			(xy 253.909549 -349.118616) (xy 253.866681 -349.154291) (xy 253.819075 -349.183345) (xy 253.767746 -349.205157)
			(xy 253.713789 -349.219263) (xy 253.658352 -349.225363) (xy 253.602618 -349.223326) (xy 253.547775 -349.213196)
			(xy 253.494991 -349.195189) (xy 253.445391 -349.169688) (xy 253.400033 -349.137237) (xy 253.359884 -349.098528)
			(xy 253.325798 -349.054385) (xy 253.298502 -349.00575) (xy 253.278579 -348.953659) (xy 253.266453 -348.899222)
			(xy 253.262382 -348.8436) (xy 249.338968 -348.8436) (xy 249.343163 -348.872102) (xy 249.343672 -348.899988)
			(xy 249.343163 -348.927874) (xy 249.335043 -348.98305) (xy 249.318975 -349.036457) (xy 249.295303 -349.086954)
			(xy 249.26453 -349.133467) (xy 249.227313 -349.175004) (xy 249.184445 -349.210679) (xy 249.136839 -349.239733)
			(xy 249.08551 -349.261545) (xy 249.031553 -349.275651) (xy 248.976116 -349.281751) (xy 248.920382 -349.279714)
			(xy 248.865539 -349.269584) (xy 248.812755 -349.251577) (xy 248.763155 -349.226076) (xy 248.717797 -349.193625)
			(xy 248.677648 -349.154916) (xy 248.643562 -349.110773) (xy 248.616266 -349.062138) (xy 248.596343 -349.010047)
			(xy 248.584217 -348.95561) (xy 248.580146 -348.899988) (xy 219.604279 -348.899988) (xy 219.60192 -348.90642)
			(xy 219.532047 -349.073807) (xy 219.454889 -349.237963) (xy 219.370595 -349.398572) (xy 219.327253 -349.473012)
			(xy 236.12678 -349.473012) (xy 236.130851 -349.41739) (xy 236.142977 -349.362953) (xy 236.1629 -349.310862)
			(xy 236.190196 -349.262227) (xy 236.224282 -349.218084) (xy 236.264431 -349.179375) (xy 236.309789 -349.146924)
			(xy 236.359389 -349.121423) (xy 236.412173 -349.103416) (xy 236.467016 -349.093286) (xy 236.52275 -349.091249)
			(xy 236.578187 -349.097349) (xy 236.632144 -349.111455) (xy 236.683473 -349.133267) (xy 236.731079 -349.162321)
			(xy 236.773947 -349.197996) (xy 236.811164 -349.239533) (xy 236.841937 -349.286046) (xy 236.865609 -349.336543)
			(xy 236.881677 -349.38995) (xy 236.887181 -349.42735) (xy 240.762792 -349.42735) (xy 240.762792 -349.37285)
			(xy 240.770548 -349.318905) (xy 240.785902 -349.266613) (xy 240.808542 -349.217039) (xy 240.838006 -349.171191)
			(xy 240.873695 -349.130002) (xy 240.914883 -349.094312) (xy 240.96073 -349.064847) (xy 241.010304 -349.042206)
			(xy 241.062596 -349.02685) (xy 241.11654 -349.019093) (xy 241.14379 -349.018606) (xy 241.172707 -349.019129)
			(xy 241.229878 -349.027857) (xy 241.285077 -349.045114) (xy 241.337038 -349.070505) (xy 241.384572 -349.103447)
			(xy 241.42659 -349.143187) (xy 241.44478 -349.165672) (xy 241.452343 -349.174432) (xy 241.473101 -349.184614)
			(xy 241.484658 -349.18523) (xy 241.564922 -349.18523) (xy 241.576488 -349.184639) (xy 241.597261 -349.174462)
			(xy 241.6048 -349.165672) (xy 241.622984 -349.143183) (xy 241.665006 -349.103449) (xy 241.712543 -349.070512)
			(xy 241.764505 -349.045125) (xy 241.819704 -349.027869) (xy 241.876874 -349.019141) (xy 241.90579 -349.018606)
			(xy 241.933044 -349.01904) (xy 241.986998 -349.026796) (xy 242.039299 -349.042152) (xy 242.088883 -349.064795)
			(xy 242.134739 -349.094264) (xy 242.175934 -349.129959) (xy 242.21163 -349.171153) (xy 242.2411 -349.217009)
			(xy 242.263744 -349.266591) (xy 242.279102 -349.318892) (xy 242.286859 -349.372846) (xy 242.286859 -349.427354)
			(xy 242.279102 -349.481308) (xy 242.263744 -349.533609) (xy 242.2411 -349.583191) (xy 242.21163 -349.629047)
			(xy 242.175934 -349.670241) (xy 242.134739 -349.705936) (xy 242.088883 -349.735405) (xy 242.039299 -349.758048)
			(xy 241.986998 -349.773404) (xy 241.933044 -349.78116) (xy 241.90579 -349.781622) (xy 241.876874 -349.781069)
			(xy 241.819703 -349.772351) (xy 241.764504 -349.755102) (xy 241.712541 -349.729717) (xy 241.665007 -349.696778)
			(xy 241.62299 -349.65704) (xy 241.6048 -349.634556) (xy 241.597241 -349.625791) (xy 241.57648 -349.615611)
			(xy 241.564922 -349.614998) (xy 241.484658 -349.614998) (xy 241.473095 -349.615603) (xy 241.452323 -349.625773)
			(xy 241.44478 -349.634556) (xy 241.426589 -349.65704) (xy 241.384571 -349.696777) (xy 241.337036 -349.729717)
			(xy 241.285075 -349.755106) (xy 241.229876 -349.772362) (xy 241.172706 -349.781088) (xy 241.14379 -349.781622)
			(xy 241.11654 -349.781107) (xy 241.062596 -349.77335) (xy 241.010304 -349.757994) (xy 240.96073 -349.735353)
			(xy 240.914883 -349.705888) (xy 240.873695 -349.670198) (xy 240.838006 -349.629009) (xy 240.808542 -349.583161)
			(xy 240.785902 -349.533587) (xy 240.770548 -349.481295) (xy 240.762792 -349.42735) (xy 236.887181 -349.42735)
			(xy 236.889797 -349.445126) (xy 236.890306 -349.473012) (xy 236.889797 -349.500898) (xy 236.881677 -349.556074)
			(xy 236.865609 -349.609481) (xy 236.841937 -349.659978) (xy 236.811164 -349.706491) (xy 236.773947 -349.748028)
			(xy 236.731079 -349.783703) (xy 236.683473 -349.812757) (xy 236.632144 -349.834569) (xy 236.578187 -349.848675)
			(xy 236.52275 -349.854775) (xy 236.467016 -349.852738) (xy 236.412173 -349.842608) (xy 236.359389 -349.824601)
			(xy 236.309789 -349.7991) (xy 236.264431 -349.766649) (xy 236.224282 -349.72794) (xy 236.190196 -349.683797)
			(xy 236.1629 -349.635162) (xy 236.142977 -349.583071) (xy 236.130851 -349.528634) (xy 236.12678 -349.473012)
			(xy 219.327253 -349.473012) (xy 219.279328 -349.555323) (xy 219.181264 -349.707914) (xy 219.076592 -349.85605)
			(xy 219.042558 -349.899986) (xy 248.589544 -349.899986) (xy 248.593615 -349.844364) (xy 248.605741 -349.789927)
			(xy 248.625664 -349.737836) (xy 248.65296 -349.689201) (xy 248.687046 -349.645058) (xy 248.727195 -349.606349)
			(xy 248.772553 -349.573898) (xy 248.822153 -349.548397) (xy 248.874937 -349.53039) (xy 248.92978 -349.52026)
			(xy 248.985514 -349.518223) (xy 249.040951 -349.524323) (xy 249.094908 -349.538429) (xy 249.146237 -349.560241)
			(xy 249.193843 -349.589295) (xy 249.236711 -349.62497) (xy 249.273928 -349.666507) (xy 249.304701 -349.71302)
			(xy 249.328373 -349.763517) (xy 249.344441 -349.816924) (xy 249.350721 -349.8596) (xy 253.435864 -349.8596)
			(xy 253.439935 -349.803978) (xy 253.452061 -349.749541) (xy 253.471984 -349.69745) (xy 253.49928 -349.648815)
			(xy 253.533366 -349.604672) (xy 253.573515 -349.565963) (xy 253.618873 -349.533512) (xy 253.668473 -349.508011)
			(xy 253.721257 -349.490004) (xy 253.7761 -349.479874) (xy 253.831834 -349.477837) (xy 253.887271 -349.483937)
			(xy 253.941228 -349.498043) (xy 253.992557 -349.519855) (xy 254.040163 -349.548909) (xy 254.083031 -349.584584)
			(xy 254.120248 -349.626121) (xy 254.151021 -349.672634) (xy 254.161509 -349.695008) (xy 255.76479 -349.695008)
			(xy 255.768861 -349.639386) (xy 255.780987 -349.584949) (xy 255.80091 -349.532858) (xy 255.828206 -349.484223)
			(xy 255.862292 -349.44008) (xy 255.902441 -349.401371) (xy 255.947799 -349.36892) (xy 255.997399 -349.343419)
			(xy 256.050183 -349.325412) (xy 256.105026 -349.315282) (xy 256.16076 -349.313245) (xy 256.216197 -349.319345)
			(xy 256.270154 -349.333451) (xy 256.321483 -349.355263) (xy 256.369089 -349.384317) (xy 256.411957 -349.419992)
			(xy 256.449174 -349.461529) (xy 256.479947 -349.508042) (xy 256.503619 -349.558539) (xy 256.519687 -349.611946)
			(xy 256.527807 -349.667122) (xy 256.528316 -349.695008) (xy 256.527807 -349.722894) (xy 256.52036 -349.773494)
			(xy 258.543296 -349.773494) (xy 258.547367 -349.717872) (xy 258.559493 -349.663435) (xy 258.579416 -349.611344)
			(xy 258.606712 -349.562709) (xy 258.640798 -349.518566) (xy 258.680947 -349.479857) (xy 258.726305 -349.447406)
			(xy 258.775905 -349.421905) (xy 258.828689 -349.403898) (xy 258.883532 -349.393768) (xy 258.939266 -349.391731)
			(xy 258.994703 -349.397831) (xy 259.04866 -349.411937) (xy 259.099989 -349.433749) (xy 259.147595 -349.462803)
			(xy 259.190463 -349.498478) (xy 259.22768 -349.540015) (xy 259.258453 -349.586528) (xy 259.282125 -349.637025)
			(xy 259.298193 -349.690432) (xy 259.306313 -349.745608) (xy 259.306822 -349.773494) (xy 259.306313 -349.80138)
			(xy 259.298193 -349.856556) (xy 259.282125 -349.909963) (xy 259.258453 -349.96046) (xy 259.22768 -350.006973)
			(xy 259.190463 -350.04851) (xy 259.147595 -350.084185) (xy 259.099989 -350.113239) (xy 259.04866 -350.135051)
			(xy 258.994703 -350.149157) (xy 258.939266 -350.155257) (xy 258.883532 -350.15322) (xy 258.828689 -350.14309)
			(xy 258.775905 -350.125083) (xy 258.726305 -350.099582) (xy 258.680947 -350.067131) (xy 258.640798 -350.028422)
			(xy 258.606712 -349.984279) (xy 258.579416 -349.935644) (xy 258.559493 -349.883553) (xy 258.547367 -349.829116)
			(xy 258.543296 -349.773494) (xy 256.52036 -349.773494) (xy 256.519687 -349.77807) (xy 256.503619 -349.831477)
			(xy 256.479947 -349.881974) (xy 256.449174 -349.928487) (xy 256.411957 -349.970024) (xy 256.369089 -350.005699)
			(xy 256.321483 -350.034753) (xy 256.270154 -350.056565) (xy 256.216197 -350.070671) (xy 256.16076 -350.076771)
			(xy 256.105026 -350.074734) (xy 256.050183 -350.064604) (xy 255.997399 -350.046597) (xy 255.947799 -350.021096)
			(xy 255.902441 -349.988645) (xy 255.862292 -349.949936) (xy 255.828206 -349.905793) (xy 255.80091 -349.857158)
			(xy 255.780987 -349.805067) (xy 255.768861 -349.75063) (xy 255.76479 -349.695008) (xy 254.161509 -349.695008)
			(xy 254.174693 -349.723131) (xy 254.190761 -349.776538) (xy 254.198881 -349.831714) (xy 254.19939 -349.8596)
			(xy 254.198881 -349.887486) (xy 254.190761 -349.942662) (xy 254.174693 -349.996069) (xy 254.151021 -350.046566)
			(xy 254.120248 -350.093079) (xy 254.083031 -350.134616) (xy 254.040163 -350.170291) (xy 253.992557 -350.199345)
			(xy 253.941228 -350.221157) (xy 253.887271 -350.235263) (xy 253.831834 -350.241363) (xy 253.7761 -350.239326)
			(xy 253.721257 -350.229196) (xy 253.668473 -350.211189) (xy 253.618873 -350.185688) (xy 253.573515 -350.153237)
			(xy 253.533366 -350.114528) (xy 253.49928 -350.070385) (xy 253.471984 -350.02175) (xy 253.452061 -349.969659)
			(xy 253.439935 -349.915222) (xy 253.435864 -349.8596) (xy 249.350721 -349.8596) (xy 249.352561 -349.8721)
			(xy 249.35307 -349.899986) (xy 249.352561 -349.927872) (xy 249.344441 -349.983048) (xy 249.328373 -350.036455)
			(xy 249.304701 -350.086952) (xy 249.273928 -350.133465) (xy 249.236711 -350.175002) (xy 249.193843 -350.210677)
			(xy 249.146237 -350.239731) (xy 249.094908 -350.261543) (xy 249.040951 -350.275649) (xy 248.985514 -350.281749)
			(xy 248.92978 -350.279712) (xy 248.874937 -350.269582) (xy 248.822153 -350.251575) (xy 248.772553 -350.226074)
			(xy 248.727195 -350.193623) (xy 248.687046 -350.154914) (xy 248.65296 -350.110771) (xy 248.625664 -350.062136)
			(xy 248.605741 -350.010045) (xy 248.593615 -349.955608) (xy 248.589544 -349.899986) (xy 219.042558 -349.899986)
			(xy 218.965514 -349.999446) (xy 218.848245 -350.137824) (xy 218.725011 -350.270918) (xy 218.620327 -350.374458)
			(xy 236.132368 -350.374458) (xy 236.136439 -350.318836) (xy 236.148565 -350.264399) (xy 236.168488 -350.212308)
			(xy 236.195784 -350.163673) (xy 236.22987 -350.11953) (xy 236.270019 -350.080821) (xy 236.315377 -350.04837)
			(xy 236.364977 -350.022869) (xy 236.417761 -350.004862) (xy 236.472604 -349.994732) (xy 236.528338 -349.992695)
			(xy 236.583775 -349.998795) (xy 236.637732 -350.012901) (xy 236.689061 -350.034713) (xy 236.736667 -350.063767)
			(xy 236.779535 -350.099442) (xy 236.816752 -350.140979) (xy 236.847525 -350.187492) (xy 236.871197 -350.237989)
			(xy 236.887265 -350.291396) (xy 236.895385 -350.346572) (xy 236.895894 -350.374458) (xy 236.895385 -350.402344)
			(xy 236.891705 -350.427353) (xy 240.784067 -350.427353) (xy 240.784067 -350.372847) (xy 240.791825 -350.318895)
			(xy 240.807182 -350.266597) (xy 240.829825 -350.217017) (xy 240.859295 -350.171164) (xy 240.89499 -350.129972)
			(xy 240.936185 -350.094279) (xy 240.98204 -350.064813) (xy 241.031621 -350.042173) (xy 241.083921 -350.026819)
			(xy 241.137873 -350.019066) (xy 241.165126 -350.018604) (xy 241.19333 -350.019135) (xy 241.249121 -350.027455)
			(xy 241.30308 -350.043897) (xy 241.354032 -350.0681) (xy 241.400866 -350.09954) (xy 241.442563 -350.13753)
			(xy 241.460782 -350.159066) (xy 241.468402 -350.167434) (xy 241.488848 -350.177065) (xy 241.500152 -350.177608)
			(xy 241.578892 -350.177608) (xy 241.590183 -350.177023) (xy 241.610611 -350.167391) (xy 241.618262 -350.159066)
			(xy 241.636487 -350.137533) (xy 241.678171 -350.099523) (xy 241.725 -350.06807) (xy 241.775952 -350.043859)
			(xy 241.829916 -350.02742) (xy 241.885712 -350.019111) (xy 241.913918 -350.018604) (xy 241.941169 -350.019067)
			(xy 241.995117 -350.026826) (xy 242.047411 -350.042183) (xy 242.096987 -350.064826) (xy 242.142837 -350.094294)
			(xy 242.184026 -350.129986) (xy 242.219717 -350.171177) (xy 242.249183 -350.217028) (xy 242.271823 -350.266606)
			(xy 242.287178 -350.318901) (xy 242.294934 -350.372849) (xy 242.294934 -350.427351) (xy 242.287178 -350.481299)
			(xy 242.271823 -350.533594) (xy 242.249183 -350.583172) (xy 242.219717 -350.629023) (xy 242.184026 -350.670214)
			(xy 242.142837 -350.705906) (xy 242.096987 -350.735374) (xy 242.047411 -350.758017) (xy 241.995117 -350.773374)
			(xy 241.941169 -350.781133) (xy 241.913918 -350.78162) (xy 241.885713 -350.78112) (xy 241.829921 -350.772792)
			(xy 241.775962 -350.756344) (xy 241.72501 -350.732134) (xy 241.678177 -350.70069) (xy 241.63648 -350.662696)
			(xy 241.618262 -350.641158) (xy 241.610662 -350.632769) (xy 241.590201 -350.623148) (xy 241.578892 -350.622616)
			(xy 241.500152 -350.622616) (xy 241.488863 -350.623218) (xy 241.468434 -350.632837) (xy 241.460782 -350.641158)
			(xy 241.442593 -350.662723) (xy 241.400901 -350.70073) (xy 241.354064 -350.732178) (xy 241.303105 -350.756383)
			(xy 241.249135 -350.772815) (xy 241.193334 -350.781117) (xy 241.165126 -350.78162) (xy 241.137873 -350.781134)
			(xy 241.083921 -350.773381) (xy 241.031621 -350.758027) (xy 240.98204 -350.735387) (xy 240.936185 -350.705921)
			(xy 240.89499 -350.670228) (xy 240.859295 -350.629036) (xy 240.829825 -350.583183) (xy 240.807182 -350.533603)
			(xy 240.791825 -350.481305) (xy 240.784067 -350.427353) (xy 236.891705 -350.427353) (xy 236.887265 -350.45752)
			(xy 236.871197 -350.510927) (xy 236.847525 -350.561424) (xy 236.816752 -350.607937) (xy 236.779535 -350.649474)
			(xy 236.736667 -350.685149) (xy 236.689061 -350.714203) (xy 236.637732 -350.736015) (xy 236.583775 -350.750121)
			(xy 236.528338 -350.756221) (xy 236.472604 -350.754184) (xy 236.417761 -350.744054) (xy 236.364977 -350.726047)
			(xy 236.315377 -350.700546) (xy 236.270019 -350.668095) (xy 236.22987 -350.629386) (xy 236.195784 -350.585243)
			(xy 236.168488 -350.536608) (xy 236.148565 -350.484517) (xy 236.136439 -350.43008) (xy 236.132368 -350.374458)
			(xy 218.620327 -350.374458) (xy 218.59605 -350.39847) (xy 218.46161 -350.520235) (xy 218.321952 -350.635977)
			(xy 218.177345 -350.745473) (xy 218.028068 -350.848511) (xy 217.946006 -350.899984) (xy 248.573288 -350.899984)
			(xy 248.577359 -350.844362) (xy 248.589485 -350.789925) (xy 248.609408 -350.737834) (xy 248.636704 -350.689199)
			(xy 248.67079 -350.645056) (xy 248.710939 -350.606347) (xy 248.756297 -350.573896) (xy 248.805897 -350.548395)
			(xy 248.858681 -350.530388) (xy 248.913524 -350.520258) (xy 248.969258 -350.518221) (xy 249.024695 -350.524321)
			(xy 249.078652 -350.538427) (xy 249.129981 -350.560239) (xy 249.177587 -350.589293) (xy 249.220455 -350.624968)
			(xy 249.257672 -350.666505) (xy 249.288445 -350.713018) (xy 249.312117 -350.763515) (xy 249.328185 -350.816922)
			(xy 249.329344 -350.8248) (xy 252.957836 -350.8248) (xy 252.961907 -350.769178) (xy 252.974033 -350.714741)
			(xy 252.993956 -350.66265) (xy 253.021252 -350.614015) (xy 253.055338 -350.569872) (xy 253.095487 -350.531163)
			(xy 253.140845 -350.498712) (xy 253.190445 -350.473211) (xy 253.243229 -350.455204) (xy 253.298072 -350.445074)
			(xy 253.353806 -350.443037) (xy 253.409243 -350.449137) (xy 253.4632 -350.463243) (xy 253.514529 -350.485055)
			(xy 253.562135 -350.514109) (xy 253.605003 -350.549784) (xy 253.64222 -350.591321) (xy 253.672993 -350.637834)
			(xy 253.696665 -350.688331) (xy 253.712733 -350.741738) (xy 253.720853 -350.796914) (xy 253.721362 -350.8248)
			(xy 253.720853 -350.852686) (xy 253.712733 -350.907862) (xy 253.696665 -350.961269) (xy 253.672993 -351.011766)
			(xy 253.64222 -351.058279) (xy 253.605003 -351.099816) (xy 253.562135 -351.135491) (xy 253.514529 -351.164545)
			(xy 253.4632 -351.186357) (xy 253.409243 -351.200463) (xy 253.353806 -351.206563) (xy 253.298072 -351.204526)
			(xy 253.243229 -351.194396) (xy 253.190445 -351.176389) (xy 253.140845 -351.150888) (xy 253.095487 -351.118437)
			(xy 253.055338 -351.079728) (xy 253.021252 -351.035585) (xy 252.993956 -350.98695) (xy 252.974033 -350.934859)
			(xy 252.961907 -350.880422) (xy 252.957836 -350.8248) (xy 249.329344 -350.8248) (xy 249.336305 -350.872098)
			(xy 249.336814 -350.899984) (xy 249.336305 -350.92787) (xy 249.328185 -350.983046) (xy 249.312117 -351.036453)
			(xy 249.288445 -351.08695) (xy 249.257672 -351.133463) (xy 249.220455 -351.175) (xy 249.177587 -351.210675)
			(xy 249.129981 -351.239729) (xy 249.078652 -351.261541) (xy 249.024695 -351.275647) (xy 248.969258 -351.281747)
			(xy 248.913524 -351.27971) (xy 248.858681 -351.26958) (xy 248.805897 -351.251573) (xy 248.756297 -351.226072)
			(xy 248.710939 -351.193621) (xy 248.67079 -351.154912) (xy 248.636704 -351.110769) (xy 248.609408 -351.062134)
			(xy 248.589485 -351.010043) (xy 248.577359 -350.955606) (xy 248.573288 -350.899984) (xy 217.946006 -350.899984)
			(xy 217.874409 -350.944893) (xy 217.716665 -351.034433) (xy 217.55514 -351.116958) (xy 217.390147 -351.192308)
			(xy 217.222002 -351.260338) (xy 217.051032 -351.320917) (xy 216.958954 -351.349056) (xy 233.362752 -351.349056)
			(xy 233.366823 -351.293434) (xy 233.378949 -351.238997) (xy 233.398872 -351.186906) (xy 233.426168 -351.138271)
			(xy 233.460254 -351.094128) (xy 233.500403 -351.055419) (xy 233.545761 -351.022968) (xy 233.595361 -350.997467)
			(xy 233.648145 -350.97946) (xy 233.702988 -350.96933) (xy 233.758722 -350.967293) (xy 233.814159 -350.973393)
			(xy 233.868116 -350.987499) (xy 233.919445 -351.009311) (xy 233.967051 -351.038365) (xy 234.009919 -351.07404)
			(xy 234.047136 -351.115577) (xy 234.077909 -351.16209) (xy 234.101581 -351.212587) (xy 234.117649 -351.265994)
			(xy 234.125769 -351.32117) (xy 234.126106 -351.339658) (xy 236.132368 -351.339658) (xy 236.136439 -351.284036)
			(xy 236.148565 -351.229599) (xy 236.168488 -351.177508) (xy 236.195784 -351.128873) (xy 236.22987 -351.08473)
			(xy 236.270019 -351.046021) (xy 236.315377 -351.01357) (xy 236.364977 -350.988069) (xy 236.417761 -350.970062)
			(xy 236.472604 -350.959932) (xy 236.528338 -350.957895) (xy 236.583775 -350.963995) (xy 236.637732 -350.978101)
			(xy 236.689061 -350.999913) (xy 236.736667 -351.028967) (xy 236.779535 -351.064642) (xy 236.816752 -351.106179)
			(xy 236.847525 -351.152692) (xy 236.871197 -351.203189) (xy 236.887265 -351.256596) (xy 236.895385 -351.311772)
			(xy 236.895894 -351.339658) (xy 236.895385 -351.367544) (xy 236.887265 -351.42272) (xy 236.871197 -351.476127)
			(xy 236.847525 -351.526624) (xy 236.816752 -351.573137) (xy 236.779535 -351.614674) (xy 236.736667 -351.650349)
			(xy 236.689061 -351.679403) (xy 236.637732 -351.701215) (xy 236.583775 -351.715321) (xy 236.528338 -351.721421)
			(xy 236.472604 -351.719384) (xy 236.417761 -351.709254) (xy 236.364977 -351.691247) (xy 236.315377 -351.665746)
			(xy 236.270019 -351.633295) (xy 236.22987 -351.594586) (xy 236.195784 -351.550443) (xy 236.168488 -351.501808)
			(xy 236.148565 -351.449717) (xy 236.136439 -351.39528) (xy 236.132368 -351.339658) (xy 234.126106 -351.339658)
			(xy 234.126278 -351.349056) (xy 234.125769 -351.376942) (xy 234.117649 -351.432118) (xy 234.101581 -351.485525)
			(xy 234.077909 -351.536022) (xy 234.047136 -351.582535) (xy 234.009919 -351.624072) (xy 233.967051 -351.659747)
			(xy 233.919445 -351.688801) (xy 233.868116 -351.710613) (xy 233.814159 -351.724719) (xy 233.758722 -351.730819)
			(xy 233.702988 -351.728782) (xy 233.648145 -351.718652) (xy 233.595361 -351.700645) (xy 233.545761 -351.675144)
			(xy 233.500403 -351.642693) (xy 233.460254 -351.603984) (xy 233.426168 -351.559841) (xy 233.398872 -351.511206)
			(xy 233.378949 -351.459115) (xy 233.366823 -351.404678) (xy 233.362752 -351.349056) (xy 216.958954 -351.349056)
			(xy 216.877566 -351.373928) (xy 216.701939 -351.419268) (xy 216.52449 -351.45685) (xy 216.345562 -351.486602)
			(xy 216.165499 -351.508465) (xy 215.98465 -351.522399) (xy 215.803363 -351.528375) (xy 215.621989 -351.526383)
			(xy 215.440877 -351.516425) (xy 215.260378 -351.498523) (xy 215.080839 -351.472709) (xy 214.902607 -351.439034)
			(xy 214.726026 -351.397563) (xy 214.551438 -351.348375) (xy 214.379178 -351.291567) (xy 214.20958 -351.227247)
			(xy 214.042971 -351.155539) (xy 213.879672 -351.076583) (xy 213.719999 -350.99053) (xy 213.56426 -350.897546)
			(xy 213.412755 -350.797812) (xy 213.265778 -350.691519) (xy 213.123611 -350.578873) (xy 212.986529 -350.460091)
			(xy 212.854797 -350.335402) (xy 212.728669 -350.205048) (xy 212.608388 -350.069279) (xy 212.494187 -349.928358)
			(xy 212.386286 -349.782557) (xy 212.284894 -349.632157) (xy 212.190205 -349.477449) (xy 212.102403 -349.31873)
			(xy 212.021658 -349.156309) (xy 211.948125 -348.990497) (xy 211.881946 -348.821616) (xy 211.823248 -348.649991)
			(xy 211.772146 -348.475953) (xy 211.728738 -348.299839) (xy 211.693107 -348.121987) (xy 211.665323 -347.942743)
			(xy 211.645439 -347.762451) (xy 211.633493 -347.581459) (xy 211.629508 -347.400118) (xy 200.33488 -347.400118)
			(xy 200.33488 -349.302832) (xy 204.379574 -349.302832) (xy 204.383645 -349.24721) (xy 204.395771 -349.192773)
			(xy 204.415694 -349.140682) (xy 204.44299 -349.092047) (xy 204.477076 -349.047904) (xy 204.517225 -349.009195)
			(xy 204.562583 -348.976744) (xy 204.612183 -348.951243) (xy 204.664967 -348.933236) (xy 204.71981 -348.923106)
			(xy 204.775544 -348.921069) (xy 204.830981 -348.927169) (xy 204.884938 -348.941275) (xy 204.936267 -348.963087)
			(xy 204.983873 -348.992141) (xy 205.026741 -349.027816) (xy 205.063958 -349.069353) (xy 205.094731 -349.115866)
			(xy 205.118403 -349.166363) (xy 205.134471 -349.21977) (xy 205.142591 -349.274946) (xy 205.1431 -349.302832)
			(xy 205.142591 -349.330718) (xy 205.134471 -349.385894) (xy 205.118403 -349.439301) (xy 205.094731 -349.489798)
			(xy 205.063958 -349.536311) (xy 205.026741 -349.577848) (xy 204.983873 -349.613523) (xy 204.936267 -349.642577)
			(xy 204.884938 -349.664389) (xy 204.830981 -349.678495) (xy 204.775544 -349.684595) (xy 204.71981 -349.682558)
			(xy 204.664967 -349.672428) (xy 204.612183 -349.654421) (xy 204.562583 -349.62892) (xy 204.517225 -349.596469)
			(xy 204.477076 -349.55776) (xy 204.44299 -349.513617) (xy 204.415694 -349.464982) (xy 204.395771 -349.412891)
			(xy 204.383645 -349.358454) (xy 204.379574 -349.302832) (xy 200.33488 -349.302832) (xy 200.33488 -349.912432)
			(xy 207.046574 -349.912432) (xy 207.050645 -349.85681) (xy 207.062771 -349.802373) (xy 207.082694 -349.750282)
			(xy 207.10999 -349.701647) (xy 207.144076 -349.657504) (xy 207.184225 -349.618795) (xy 207.229583 -349.586344)
			(xy 207.279183 -349.560843) (xy 207.331967 -349.542836) (xy 207.38681 -349.532706) (xy 207.442544 -349.530669)
			(xy 207.497981 -349.536769) (xy 207.551938 -349.550875) (xy 207.603267 -349.572687) (xy 207.650873 -349.601741)
			(xy 207.693741 -349.637416) (xy 207.730958 -349.678953) (xy 207.761731 -349.725466) (xy 207.785403 -349.775963)
			(xy 207.801471 -349.82937) (xy 207.809591 -349.884546) (xy 207.8101 -349.912432) (xy 207.809591 -349.940318)
			(xy 207.801471 -349.995494) (xy 207.785403 -350.048901) (xy 207.761731 -350.099398) (xy 207.730958 -350.145911)
			(xy 207.693741 -350.187448) (xy 207.650873 -350.223123) (xy 207.603267 -350.252177) (xy 207.551938 -350.273989)
			(xy 207.497981 -350.288095) (xy 207.442544 -350.294195) (xy 207.38681 -350.292158) (xy 207.331967 -350.282028)
			(xy 207.279183 -350.264021) (xy 207.229583 -350.23852) (xy 207.184225 -350.206069) (xy 207.144076 -350.16736)
			(xy 207.10999 -350.123217) (xy 207.082694 -350.074582) (xy 207.062771 -350.022491) (xy 207.050645 -349.968054)
			(xy 207.046574 -349.912432) (xy 200.33488 -349.912432) (xy 200.33488 -350.859344) (xy 200.335311 -350.869411)
			(xy 200.343034 -350.888006) (xy 200.349866 -350.895412) (xy 200.918064 -351.46361) (xy 204.379574 -351.46361)
			(xy 204.383645 -351.407988) (xy 204.395771 -351.353551) (xy 204.415694 -351.30146) (xy 204.44299 -351.252825)
			(xy 204.477076 -351.208682) (xy 204.517225 -351.169973) (xy 204.562583 -351.137522) (xy 204.612183 -351.112021)
			(xy 204.664967 -351.094014) (xy 204.71981 -351.083884) (xy 204.775544 -351.081847) (xy 204.830981 -351.087947)
			(xy 204.884938 -351.102053) (xy 204.936267 -351.123865) (xy 204.983873 -351.152919) (xy 205.026741 -351.188594)
			(xy 205.063958 -351.230131) (xy 205.094731 -351.276644) (xy 205.118403 -351.327141) (xy 205.134471 -351.380548)
			(xy 205.142591 -351.435724) (xy 205.1431 -351.46361) (xy 205.142591 -351.491496) (xy 205.134471 -351.546672)
			(xy 205.118403 -351.600079) (xy 205.094731 -351.650576) (xy 205.063958 -351.697089) (xy 205.026741 -351.738626)
			(xy 204.983873 -351.774301) (xy 204.936267 -351.803355) (xy 204.884938 -351.825167) (xy 204.830981 -351.839273)
			(xy 204.775544 -351.845373) (xy 204.71981 -351.843336) (xy 204.664967 -351.833206) (xy 204.612183 -351.815199)
			(xy 204.562583 -351.789698) (xy 204.517225 -351.757247) (xy 204.477076 -351.718538) (xy 204.44299 -351.674395)
			(xy 204.415694 -351.62576) (xy 204.395771 -351.573669) (xy 204.383645 -351.519232) (xy 204.379574 -351.46361)
			(xy 200.918064 -351.46361) (xy 201.46391 -352.009456) (xy 201.471307 -352.016306) (xy 201.489905 -352.024043)
			(xy 201.499978 -352.024442) (xy 208.855056 -352.024442) (xy 208.86512 -352.024007) (xy 208.883705 -352.016272)
			(xy 208.891124 -352.009456) (xy 233.516678 -352.009456) (xy 233.524707 -352.009216) (xy 233.539989 -352.004294)
			(xy 233.54665 -351.999804) (xy 233.571266 -351.982522) (xy 233.6248 -351.955112) (xy 233.681973 -351.936448)
			(xy 233.741369 -351.926994) (xy 233.77144 -351.926398) (xy 233.801509 -351.926988) (xy 233.860897 -351.936469)
			(xy 233.918064 -351.955143) (xy 233.971597 -351.982549) (xy 233.99623 -351.999804) (xy 234.002915 -352.004249)
			(xy 234.01818 -352.009184) (xy 234.026202 -352.009456) (xy 236.25556 -352.009456) (xy 236.263688 -352.009115)
			(xy 236.279098 -352.003929) (xy 236.285786 -351.999296) (xy 236.310705 -351.981438) (xy 236.365045 -351.953063)
			(xy 236.42322 -351.93373) (xy 236.483735 -351.923937) (xy 236.514386 -351.92335) (xy 236.545039 -351.923938)
			(xy 236.605562 -351.933703) (xy 236.66374 -351.953032) (xy 236.718073 -351.981427) (xy 236.742986 -351.999296)
			(xy 236.749667 -352.003943) (xy 236.765081 -352.009138) (xy 236.773212 -352.009456) (xy 239.870234 -352.009456)
			(xy 239.8803 -352.009887) (xy 239.89889 -352.017616) (xy 239.906302 -352.024442) (xy 241.384582 -353.502722)
			(xy 241.392177 -353.50971) (xy 241.411291 -353.517444) (xy 241.431905 -353.516991) (xy 241.441478 -353.513136)
			(xy 241.542824 -353.467416) (xy 241.558826 -353.440492) (xy 241.55781 -353.42449) (xy 241.557048 -353.400106)
			(xy 241.557511 -353.372849) (xy 241.565268 -353.31889) (xy 241.580626 -353.266585) (xy 241.603271 -353.216998)
			(xy 241.632744 -353.171138) (xy 241.668443 -353.129939) (xy 241.709642 -353.094241) (xy 241.755502 -353.064769)
			(xy 241.805089 -353.042124) (xy 241.857395 -353.026767) (xy 241.911354 -353.01901) (xy 241.965867 -353.019012)
			(xy 242.019826 -353.026772) (xy 242.072131 -353.042132) (xy 242.121717 -353.064779) (xy 242.167576 -353.094254)
			(xy 242.208772 -353.129954) (xy 242.244469 -353.171155) (xy 242.273939 -353.217016) (xy 242.296582 -353.266605)
			(xy 242.311937 -353.318911) (xy 242.319691 -353.372871) (xy 242.319687 -353.427384) (xy 242.311925 -353.481342)
			(xy 242.296562 -353.533646) (xy 242.273913 -353.583232) (xy 242.244436 -353.629089) (xy 242.208734 -353.670284)
			(xy 242.167532 -353.705979) (xy 242.121669 -353.735447) (xy 242.072079 -353.758087) (xy 242.019772 -353.77344)
			(xy 241.965813 -353.781192) (xy 241.938556 -353.781614) (xy 241.907428 -353.780991) (xy 241.845997 -353.770886)
			(xy 241.787013 -353.750966) (xy 241.759232 -353.73691) (xy 241.7445 -353.729036) (xy 241.711226 -353.733862)
			(xy 241.699542 -353.7458) (xy 241.692715 -353.753168) (xy 241.684996 -353.771694) (xy 241.685007 -353.791764)
			(xy 241.692748 -353.810281) (xy 241.699542 -353.817682) (xy 241.72545 -353.84359) (xy 241.732303 -353.850986)
			(xy 241.740049 -353.869584) (xy 241.740436 -353.879658) (xy 241.740436 -353.921568) (xy 241.740955 -353.932497)
			(xy 241.750038 -353.952377) (xy 241.757962 -353.959922) (xy 241.824002 -354.01758) (xy 241.84483 -354.023676)
			(xy 241.856006 -354.022152) (xy 241.869021 -354.020468) (xy 241.895207 -354.018687) (xy 241.90833 -354.018596)
			(xy 241.93558 -354.019084) (xy 241.989523 -354.026844) (xy 242.041814 -354.042201) (xy 242.091387 -354.064844)
			(xy 242.137233 -354.094311) (xy 242.178419 -354.130002) (xy 242.214107 -354.171191) (xy 242.24357 -354.217039)
			(xy 242.266209 -354.266614) (xy 242.281563 -354.318906) (xy 242.289318 -354.37285) (xy 242.289318 -354.42735)
			(xy 242.281563 -354.481294) (xy 242.266209 -354.533586) (xy 242.24357 -354.583161) (xy 242.214107 -354.629009)
			(xy 242.178419 -354.670198) (xy 242.137233 -354.705889) (xy 242.091387 -354.735356) (xy 242.041814 -354.757999)
			(xy 241.989523 -354.773356) (xy 241.93558 -354.781116) (xy 241.90833 -354.781612) (xy 241.895207 -354.781505)
			(xy 241.869023 -354.779724) (xy 241.856006 -354.778056) (xy 241.84483 -354.776532) (xy 241.824002 -354.782628)
			(xy 241.757962 -354.840286) (xy 241.75005 -354.847839) (xy 241.740968 -354.867714) (xy 241.740436 -354.87864)
			(xy 241.740436 -355.060504) (xy 241.740857 -355.070522) (xy 241.748529 -355.089031) (xy 241.762702 -355.103194)
			(xy 241.781218 -355.110851) (xy 241.791236 -355.111304) (xy 242.085114 -355.111304) (xy 242.095183 -355.110878)
			(xy 242.113784 -355.103161) (xy 242.121182 -355.096318) (xy 242.708176 -354.509324) (xy 242.71496 -354.501902)
			(xy 242.722566 -354.483305) (xy 242.722908 -354.473256) (xy 242.722908 -352.700844) (xy 242.722469 -352.690812)
			(xy 242.714895 -352.672237) (xy 242.708176 -352.664776) (xy 242.514882 -352.471482) (xy 242.507242 -352.464563)
			(xy 242.488104 -352.456958) (xy 242.477798 -352.45675) (xy 242.467638 -352.45675) (xy 242.449096 -352.465386)
			(xy 242.270026 -352.658934) (xy 242.25191 -352.677918) (xy 242.211369 -352.711235) (xy 242.166644 -352.738678)
			(xy 242.118577 -352.75973) (xy 242.068078 -352.773992) (xy 242.016101 -352.781196) (xy 241.989864 -352.781616)
			(xy 241.962614 -352.781128) (xy 241.90867 -352.773367) (xy 241.856379 -352.758009) (xy 241.806806 -352.735366)
			(xy 241.760959 -352.705899) (xy 241.719773 -352.670207) (xy 241.684084 -352.629018) (xy 241.654621 -352.58317)
			(xy 241.631981 -352.533595) (xy 241.616627 -352.481303) (xy 241.60887 -352.427358) (xy 241.608356 -352.400108)
			(xy 241.608884 -352.371643) (xy 241.617351 -352.315345) (xy 241.634097 -352.260933) (xy 241.658751 -352.209617)
			(xy 241.690763 -352.16254) (xy 241.709702 -352.141282) (xy 241.896646 -351.939098) (xy 241.90302 -351.931418)
			(xy 241.90987 -351.912692) (xy 241.909092 -351.892767) (xy 241.900804 -351.874632) (xy 241.893852 -351.86747)
			(xy 241.691414 -351.680018) (xy 241.672493 -351.661894) (xy 241.639297 -351.621359) (xy 241.611961 -351.576662)
			(xy 241.590998 -351.528644) (xy 241.576805 -351.47821) (xy 241.569647 -351.426307) (xy 241.56924 -351.40011)
			(xy 241.569702 -351.372875) (xy 241.577453 -351.318958) (xy 241.592798 -351.266694) (xy 241.615424 -351.217145)
			(xy 241.644872 -351.17132) (xy 241.680542 -351.130154) (xy 241.721708 -351.094482) (xy 241.767531 -351.065032)
			(xy 241.817079 -351.042403) (xy 241.869343 -351.027056) (xy 241.923259 -351.019303) (xy 241.950494 -351.018856)
			(xy 241.978986 -351.019364) (xy 242.035342 -351.027802) (xy 242.089813 -351.044537) (xy 242.141185 -351.069195)
			(xy 242.188314 -351.101227) (xy 242.209574 -351.120202) (xy 242.399058 -351.295716) (xy 242.406721 -351.302226)
			(xy 242.425579 -351.309159) (xy 242.435634 -351.309178) (xy 242.783106 -351.295462) (xy 242.798092 -351.295208)
			(xy 242.82806 -351.295778) (xy 242.887264 -351.305117) (xy 242.94428 -351.323596) (xy 242.997705 -351.350762)
			(xy 243.046227 -351.385947) (xy 243.06784 -351.406714) (xy 243.730526 -352.0694) (xy 248.537476 -352.0694)
			(xy 248.537962 -352.042149) (xy 248.545718 -351.988201) (xy 248.561073 -351.935906) (xy 248.583715 -351.886329)
			(xy 248.613181 -351.840479) (xy 248.648872 -351.799288) (xy 248.690063 -351.763597) (xy 248.735913 -351.734131)
			(xy 248.78549 -351.711489) (xy 248.837785 -351.696134) (xy 248.891733 -351.688378) (xy 248.946235 -351.688378)
			(xy 249.000183 -351.696134) (xy 249.052478 -351.711489) (xy 249.102055 -351.734131) (xy 249.147905 -351.763597)
			(xy 249.189096 -351.799288) (xy 249.224787 -351.840479) (xy 249.254253 -351.886329) (xy 249.276895 -351.935906)
			(xy 249.29225 -351.988201) (xy 249.300006 -352.042149) (xy 249.300492 -352.0694) (xy 249.30006 -352.09683)
			(xy 249.292182 -352.151123) (xy 249.276617 -352.20373) (xy 249.253686 -352.253569) (xy 249.223861 -352.299614)
			(xy 249.187754 -352.340918) (xy 249.146109 -352.376632) (xy 249.1232 -352.391726) (xy 249.11084 -352.400294)
			(xy 249.091263 -352.423097) (xy 249.079171 -352.45061) (xy 249.07561 -352.480453) (xy 249.080889 -352.510039)
			(xy 249.094552 -352.536808) (xy 249.115414 -352.558442) (xy 249.12828 -352.566224) (xy 249.153419 -352.580761)
			(xy 249.199351 -352.616288) (xy 249.239371 -352.658364) (xy 249.272556 -352.706016) (xy 249.29814 -352.758145)
			(xy 249.315532 -352.813548) (xy 249.324332 -352.870946) (xy 249.324876 -352.89998) (xy 249.32439 -352.927231)
			(xy 249.316634 -352.981179) (xy 249.301279 -353.033474) (xy 249.278637 -353.083051) (xy 249.249171 -353.128901)
			(xy 249.21348 -353.170092) (xy 249.172289 -353.205783) (xy 249.126439 -353.235249) (xy 249.076862 -353.257891)
			(xy 249.024567 -353.273246) (xy 248.970619 -353.281002) (xy 248.916117 -353.281002) (xy 248.862169 -353.273246)
			(xy 248.809874 -353.257891) (xy 248.760297 -353.235249) (xy 248.714447 -353.205783) (xy 248.673256 -353.170092)
			(xy 248.637565 -353.128901) (xy 248.608099 -353.083051) (xy 248.585457 -353.033474) (xy 248.570102 -352.981179)
			(xy 248.562346 -352.927231) (xy 248.56186 -352.89998) (xy 248.562376 -352.872553) (xy 248.570242 -352.818265)
			(xy 248.585793 -352.765661) (xy 248.608711 -352.715823) (xy 248.638523 -352.669777) (xy 248.674617 -352.62847)
			(xy 248.716249 -352.592751) (xy 248.739152 -352.577654) (xy 248.751525 -352.569107) (xy 248.771093 -352.546296)
			(xy 248.783177 -352.518779) (xy 248.786733 -352.488937) (xy 248.781453 -352.45935) (xy 248.767793 -352.43258)
			(xy 248.746936 -352.410942) (xy 248.734072 -352.403156) (xy 248.708914 -352.388652) (xy 248.662984 -352.353117)
			(xy 248.622966 -352.311035) (xy 248.589784 -352.263378) (xy 248.564204 -352.211244) (xy 248.546815 -352.155837)
			(xy 248.538019 -352.098436) (xy 248.537476 -352.0694) (xy 243.730526 -352.0694) (xy 243.755164 -352.094038)
			(xy 243.775946 -352.115651) (xy 243.811191 -352.164155) (xy 243.838417 -352.217573) (xy 243.856954 -352.274592)
			(xy 243.866348 -352.333808) (xy 243.866924 -352.363786) (xy 243.866924 -353.900232) (xy 248.573288 -353.900232)
			(xy 248.577359 -353.84461) (xy 248.589485 -353.790173) (xy 248.609408 -353.738082) (xy 248.636704 -353.689447)
			(xy 248.67079 -353.645304) (xy 248.710939 -353.606595) (xy 248.756297 -353.574144) (xy 248.805897 -353.548643)
			(xy 248.858681 -353.530636) (xy 248.913524 -353.520506) (xy 248.969258 -353.518469) (xy 249.024695 -353.524569)
			(xy 249.078652 -353.538675) (xy 249.129981 -353.560487) (xy 249.177587 -353.589541) (xy 249.220455 -353.625216)
			(xy 249.257672 -353.666753) (xy 249.288445 -353.713266) (xy 249.312117 -353.763763) (xy 249.328185 -353.81717)
			(xy 249.336305 -353.872346) (xy 249.336814 -353.900232) (xy 249.336305 -353.928118) (xy 249.328185 -353.983294)
			(xy 249.312117 -354.036701) (xy 249.288445 -354.087198) (xy 249.257672 -354.133711) (xy 249.220455 -354.175248)
			(xy 249.177587 -354.210923) (xy 249.129981 -354.239977) (xy 249.078652 -354.261789) (xy 249.024695 -354.275895)
			(xy 248.969258 -354.281995) (xy 248.913524 -354.279958) (xy 248.858681 -354.269828) (xy 248.805897 -354.251821)
			(xy 248.756297 -354.22632) (xy 248.710939 -354.193869) (xy 248.67079 -354.15516) (xy 248.636704 -354.111017)
			(xy 248.609408 -354.062382) (xy 248.589485 -354.010291) (xy 248.577359 -353.955854) (xy 248.573288 -353.900232)
			(xy 243.866924 -353.900232) (xy 243.866924 -354.810314) (xy 243.866365 -354.840294) (xy 243.856979 -354.899514)
			(xy 243.856746 -354.90023) (xy 248.54992 -354.90023) (xy 248.553991 -354.844608) (xy 248.566117 -354.790171)
			(xy 248.58604 -354.73808) (xy 248.613336 -354.689445) (xy 248.647422 -354.645302) (xy 248.687571 -354.606593)
			(xy 248.732929 -354.574142) (xy 248.782529 -354.548641) (xy 248.835313 -354.530634) (xy 248.890156 -354.520504)
			(xy 248.94589 -354.518467) (xy 249.001327 -354.524567) (xy 249.055284 -354.538673) (xy 249.106613 -354.560485)
			(xy 249.154219 -354.589539) (xy 249.197087 -354.625214) (xy 249.234304 -354.666751) (xy 249.265077 -354.713264)
			(xy 249.288749 -354.763761) (xy 249.304817 -354.817168) (xy 249.312937 -354.872344) (xy 249.313446 -354.90023)
			(xy 249.312937 -354.928116) (xy 249.304817 -354.983292) (xy 249.288749 -355.036699) (xy 249.265077 -355.087196)
			(xy 249.234304 -355.133709) (xy 249.21 -355.160834) (xy 249.921774 -355.160834) (xy 249.925845 -355.105212)
			(xy 249.937971 -355.050775) (xy 249.957894 -354.998684) (xy 249.98519 -354.950049) (xy 250.019276 -354.905906)
			(xy 250.059425 -354.867197) (xy 250.104783 -354.834746) (xy 250.154383 -354.809245) (xy 250.207167 -354.791238)
			(xy 250.26201 -354.781108) (xy 250.317744 -354.779071) (xy 250.373181 -354.785171) (xy 250.427138 -354.799277)
			(xy 250.478467 -354.821089) (xy 250.526073 -354.850143) (xy 250.568941 -354.885818) (xy 250.606158 -354.927355)
			(xy 250.636931 -354.973868) (xy 250.660603 -355.024365) (xy 250.676671 -355.077772) (xy 250.684791 -355.132948)
			(xy 250.6853 -355.160834) (xy 253.273304 -355.160834) (xy 253.277375 -355.105212) (xy 253.289501 -355.050775)
			(xy 253.309424 -354.998684) (xy 253.33672 -354.950049) (xy 253.370806 -354.905906) (xy 253.410955 -354.867197)
			(xy 253.456313 -354.834746) (xy 253.505913 -354.809245) (xy 253.558697 -354.791238) (xy 253.61354 -354.781108)
			(xy 253.669274 -354.779071) (xy 253.724711 -354.785171) (xy 253.778668 -354.799277) (xy 253.829997 -354.821089)
			(xy 253.877603 -354.850143) (xy 253.920471 -354.885818) (xy 253.957688 -354.927355) (xy 253.988461 -354.973868)
			(xy 254.012133 -355.024365) (xy 254.028201 -355.077772) (xy 254.036321 -355.132948) (xy 254.03683 -355.160834)
			(xy 254.036321 -355.18872) (xy 254.028201 -355.243896) (xy 254.012133 -355.297303) (xy 253.988461 -355.3478)
			(xy 253.957688 -355.394313) (xy 253.920471 -355.43585) (xy 253.877603 -355.471525) (xy 253.829997 -355.500579)
			(xy 253.778668 -355.522391) (xy 253.724711 -355.536497) (xy 253.669274 -355.542597) (xy 253.61354 -355.54056)
			(xy 253.558697 -355.53043) (xy 253.505913 -355.512423) (xy 253.456313 -355.486922) (xy 253.410955 -355.454471)
			(xy 253.370806 -355.415762) (xy 253.33672 -355.371619) (xy 253.309424 -355.322984) (xy 253.289501 -355.270893)
			(xy 253.277375 -355.216456) (xy 253.273304 -355.160834) (xy 250.6853 -355.160834) (xy 250.684791 -355.18872)
			(xy 250.676671 -355.243896) (xy 250.660603 -355.297303) (xy 250.636931 -355.3478) (xy 250.606158 -355.394313)
			(xy 250.568941 -355.43585) (xy 250.526073 -355.471525) (xy 250.478467 -355.500579) (xy 250.427138 -355.522391)
			(xy 250.373181 -355.536497) (xy 250.317744 -355.542597) (xy 250.26201 -355.54056) (xy 250.207167 -355.53043)
			(xy 250.154383 -355.512423) (xy 250.104783 -355.486922) (xy 250.059425 -355.454471) (xy 250.019276 -355.415762)
			(xy 249.98519 -355.371619) (xy 249.957894 -355.322984) (xy 249.937971 -355.270893) (xy 249.925845 -355.216456)
			(xy 249.921774 -355.160834) (xy 249.21 -355.160834) (xy 249.197087 -355.175246) (xy 249.154219 -355.210921)
			(xy 249.106613 -355.239975) (xy 249.055284 -355.261787) (xy 249.001327 -355.275893) (xy 248.94589 -355.281993)
			(xy 248.890156 -355.279956) (xy 248.835313 -355.269826) (xy 248.782529 -355.251819) (xy 248.732929 -355.226318)
			(xy 248.687571 -355.193867) (xy 248.647422 -355.155158) (xy 248.613336 -355.111015) (xy 248.58604 -355.06238)
			(xy 248.566117 -355.010289) (xy 248.553991 -354.955852) (xy 248.54992 -354.90023) (xy 243.856746 -354.90023)
			(xy 243.838441 -354.956535) (xy 243.811208 -355.009953) (xy 243.77595 -355.05845) (xy 243.755164 -355.080062)
			(xy 242.69192 -356.143306) (xy 242.670324 -356.164097) (xy 242.621812 -356.199306) (xy 242.568384 -356.226485)
			(xy 242.511359 -356.244962) (xy 242.452144 -356.254282) (xy 242.422172 -356.254812) (xy 241.791236 -356.254812)
			(xy 241.781211 -356.255225) (xy 241.762684 -356.262889) (xy 241.748503 -356.277063) (xy 241.74083 -356.295587)
			(xy 241.740436 -356.305612) (xy 241.740436 -356.917244) (xy 241.740886 -356.927399) (xy 241.74875 -356.946125)
			(xy 241.755676 -356.953566) (xy 241.815366 -357.011478) (xy 241.833908 -357.018844) (xy 241.844576 -357.01859)
			(xy 241.85372 -357.01859) (xy 241.880626 -357.019046) (xy 241.933905 -357.026599) (xy 241.985594 -357.041565)
			(xy 242.034666 -357.063648) (xy 242.080147 -357.092409) (xy 242.121134 -357.127277) (xy 242.156813 -357.16756)
			(xy 242.171982 -357.189786) (xy 242.179503 -357.199966) (xy 242.201761 -357.211947) (xy 242.2144 -357.212646)
		)
		(stroke
			(width 0)
			(type solid)
		)
		(fill yes)
		(layer "In7.Cu")
		(net "P3V3_AUX")
	)
	(gr_poly
		(pts
			(xy 313.023504 -417.177474) (xy 313.032722 -417.177056) (xy 313.049947 -417.170479) (xy 313.063717 -417.158218)
			(xy 313.072241 -417.141869) (xy 313.073796 -417.13277) (xy 313.073796 -368.14379) (xy 313.073371 -368.133721)
			(xy 313.065653 -368.115119) (xy 313.05881 -368.107722) (xy 311.545986 -366.594898) (xy 311.538874 -366.587532)
			(xy 311.520078 -366.579912) (xy 307.20157 -366.579912) (xy 307.191502 -366.580341) (xy 307.172907 -366.588064)
			(xy 307.165502 -366.594898) (xy 306.602384 -367.158016) (xy 306.595531 -367.165411) (xy 306.587789 -367.18401)
			(xy 306.587398 -367.194084) (xy 306.587398 -368.990118) (xy 306.803814 -368.990118) (xy 306.807805 -368.927951)
			(xy 306.819714 -368.866804) (xy 306.839343 -368.807683) (xy 306.866372 -368.751557) (xy 306.900356 -368.699348)
			(xy 306.940738 -368.651913) (xy 306.986854 -368.610032) (xy 307.037946 -368.574392) (xy 307.093177 -368.545578)
			(xy 307.151639 -368.524064) (xy 307.212373 -368.510202) (xy 307.27438 -368.50422) (xy 307.336643 -368.506216)
			(xy 307.39814 -368.516159) (xy 307.457861 -368.533883) (xy 307.514824 -368.5591) (xy 307.568095 -368.591393)
			(xy 307.6168 -368.630233) (xy 307.660137 -368.674983) (xy 307.697397 -368.724907) (xy 307.727966 -368.779186)
			(xy 307.751344 -368.836929) (xy 307.767145 -368.897187) (xy 307.775111 -368.95897) (xy 307.77561 -368.990118)
			(xy 307.775111 -369.021266) (xy 307.767145 -369.083049) (xy 307.751344 -369.143307) (xy 307.727966 -369.20105)
			(xy 307.697397 -369.255329) (xy 307.660137 -369.305253) (xy 307.6168 -369.350003) (xy 307.568095 -369.388843)
			(xy 307.514824 -369.421136) (xy 307.457861 -369.446353) (xy 307.39814 -369.464077) (xy 307.336643 -369.47402)
			(xy 307.27438 -369.476016) (xy 307.212373 -369.470034) (xy 307.151639 -369.456172) (xy 307.093177 -369.434658)
			(xy 307.037946 -369.405844) (xy 306.986854 -369.370204) (xy 306.940738 -369.328323) (xy 306.900356 -369.280888)
			(xy 306.866372 -369.228679) (xy 306.839343 -369.172553) (xy 306.819714 -369.113432) (xy 306.807805 -369.052285)
			(xy 306.803814 -368.990118) (xy 306.587398 -368.990118) (xy 306.587398 -371.590062) (xy 306.803814 -371.590062)
			(xy 306.807805 -371.527895) (xy 306.819714 -371.466748) (xy 306.839343 -371.407627) (xy 306.866372 -371.351501)
			(xy 306.900356 -371.299292) (xy 306.940738 -371.251857) (xy 306.986854 -371.209976) (xy 307.037946 -371.174336)
			(xy 307.093177 -371.145522) (xy 307.151639 -371.124008) (xy 307.212373 -371.110146) (xy 307.27438 -371.104164)
			(xy 307.336643 -371.10616) (xy 307.39814 -371.116103) (xy 307.457861 -371.133827) (xy 307.514824 -371.159044)
			(xy 307.568095 -371.191337) (xy 307.6168 -371.230177) (xy 307.660137 -371.274927) (xy 307.697397 -371.324851)
			(xy 307.727966 -371.37913) (xy 307.751344 -371.436873) (xy 307.767145 -371.497131) (xy 307.775111 -371.558914)
			(xy 307.77561 -371.590062) (xy 307.775111 -371.62121) (xy 307.767145 -371.682993) (xy 307.751344 -371.743251)
			(xy 307.727966 -371.800994) (xy 307.697397 -371.855273) (xy 307.660137 -371.905197) (xy 307.6168 -371.949947)
			(xy 307.568095 -371.988787) (xy 307.514824 -372.02108) (xy 307.457861 -372.046297) (xy 307.39814 -372.064021)
			(xy 307.336643 -372.073964) (xy 307.27438 -372.07596) (xy 307.212373 -372.069978) (xy 307.151639 -372.056116)
			(xy 307.093177 -372.034602) (xy 307.037946 -372.005788) (xy 306.986854 -371.970148) (xy 306.940738 -371.928267)
			(xy 306.900356 -371.880832) (xy 306.866372 -371.828623) (xy 306.839343 -371.772497) (xy 306.819714 -371.713376)
			(xy 306.807805 -371.652229) (xy 306.803814 -371.590062) (xy 306.587398 -371.590062) (xy 306.587398 -372.890034)
			(xy 306.803814 -372.890034) (xy 306.807805 -372.827867) (xy 306.819714 -372.76672) (xy 306.839343 -372.707599)
			(xy 306.866372 -372.651473) (xy 306.900356 -372.599264) (xy 306.940738 -372.551829) (xy 306.986854 -372.509948)
			(xy 307.037946 -372.474308) (xy 307.093177 -372.445494) (xy 307.151639 -372.42398) (xy 307.212373 -372.410118)
			(xy 307.27438 -372.404136) (xy 307.336643 -372.406132) (xy 307.39814 -372.416075) (xy 307.457861 -372.433799)
			(xy 307.514824 -372.459016) (xy 307.568095 -372.491309) (xy 307.6168 -372.530149) (xy 307.660137 -372.574899)
			(xy 307.697397 -372.624823) (xy 307.727966 -372.679102) (xy 307.751344 -372.736845) (xy 307.767145 -372.797103)
			(xy 307.775111 -372.858886) (xy 307.77561 -372.890034) (xy 307.775111 -372.921182) (xy 307.767145 -372.982965)
			(xy 307.751344 -373.043223) (xy 307.727966 -373.100966) (xy 307.697397 -373.155245) (xy 307.660137 -373.205169)
			(xy 307.6168 -373.249919) (xy 307.568095 -373.288759) (xy 307.514824 -373.321052) (xy 307.457861 -373.346269)
			(xy 307.39814 -373.363993) (xy 307.336643 -373.373936) (xy 307.27438 -373.375932) (xy 307.212373 -373.36995)
			(xy 307.151639 -373.356088) (xy 307.093177 -373.334574) (xy 307.037946 -373.30576) (xy 306.986854 -373.27012)
			(xy 306.940738 -373.228239) (xy 306.900356 -373.180804) (xy 306.866372 -373.128595) (xy 306.839343 -373.072469)
			(xy 306.819714 -373.013348) (xy 306.807805 -372.952201) (xy 306.803814 -372.890034) (xy 306.587398 -372.890034)
			(xy 306.587398 -375.490232) (xy 306.803814 -375.490232) (xy 306.807805 -375.428065) (xy 306.819714 -375.366918)
			(xy 306.839343 -375.307797) (xy 306.866372 -375.251671) (xy 306.900356 -375.199462) (xy 306.940738 -375.152027)
			(xy 306.986854 -375.110146) (xy 307.037946 -375.074506) (xy 307.093177 -375.045692) (xy 307.151639 -375.024178)
			(xy 307.212373 -375.010316) (xy 307.27438 -375.004334) (xy 307.336643 -375.00633) (xy 307.39814 -375.016273)
			(xy 307.457861 -375.033997) (xy 307.514824 -375.059214) (xy 307.568095 -375.091507) (xy 307.6168 -375.130347)
			(xy 307.660137 -375.175097) (xy 307.697397 -375.225021) (xy 307.727966 -375.2793) (xy 307.751344 -375.337043)
			(xy 307.767145 -375.397301) (xy 307.775111 -375.459084) (xy 307.77561 -375.490232) (xy 307.775111 -375.52138)
			(xy 307.767145 -375.583163) (xy 307.751344 -375.643421) (xy 307.727966 -375.701164) (xy 307.697397 -375.755443)
			(xy 307.660137 -375.805367) (xy 307.6168 -375.850117) (xy 307.568095 -375.888957) (xy 307.514824 -375.92125)
			(xy 307.457861 -375.946467) (xy 307.39814 -375.964191) (xy 307.336643 -375.974134) (xy 307.27438 -375.97613)
			(xy 307.212373 -375.970148) (xy 307.151639 -375.956286) (xy 307.093177 -375.934772) (xy 307.037946 -375.905958)
			(xy 306.986854 -375.870318) (xy 306.940738 -375.828437) (xy 306.900356 -375.781002) (xy 306.866372 -375.728793)
			(xy 306.839343 -375.672667) (xy 306.819714 -375.613546) (xy 306.807805 -375.552399) (xy 306.803814 -375.490232)
			(xy 306.587398 -375.490232) (xy 306.587398 -376.790204) (xy 306.803814 -376.790204) (xy 306.807805 -376.728037)
			(xy 306.819714 -376.66689) (xy 306.839343 -376.607769) (xy 306.866372 -376.551643) (xy 306.900356 -376.499434)
			(xy 306.940738 -376.451999) (xy 306.986854 -376.410118) (xy 307.037946 -376.374478) (xy 307.093177 -376.345664)
			(xy 307.151639 -376.32415) (xy 307.212373 -376.310288) (xy 307.27438 -376.304306) (xy 307.336643 -376.306302)
			(xy 307.39814 -376.316245) (xy 307.457861 -376.333969) (xy 307.514824 -376.359186) (xy 307.568095 -376.391479)
			(xy 307.6168 -376.430319) (xy 307.660137 -376.475069) (xy 307.697397 -376.524993) (xy 307.727966 -376.579272)
			(xy 307.751344 -376.637015) (xy 307.767145 -376.697273) (xy 307.775111 -376.759056) (xy 307.77561 -376.790204)
			(xy 307.775111 -376.821352) (xy 307.767145 -376.883135) (xy 307.751344 -376.943393) (xy 307.727966 -377.001136)
			(xy 307.697397 -377.055415) (xy 307.660137 -377.105339) (xy 307.6168 -377.150089) (xy 307.568095 -377.188929)
			(xy 307.514824 -377.221222) (xy 307.457861 -377.246439) (xy 307.39814 -377.264163) (xy 307.336643 -377.274106)
			(xy 307.27438 -377.276102) (xy 307.212373 -377.27012) (xy 307.151639 -377.256258) (xy 307.093177 -377.234744)
			(xy 307.037946 -377.20593) (xy 306.986854 -377.17029) (xy 306.940738 -377.128409) (xy 306.900356 -377.080974)
			(xy 306.866372 -377.028765) (xy 306.839343 -376.972639) (xy 306.819714 -376.913518) (xy 306.807805 -376.852371)
			(xy 306.803814 -376.790204) (xy 306.587398 -376.790204) (xy 306.587398 -379.390148) (xy 306.803814 -379.390148)
			(xy 306.807805 -379.327981) (xy 306.819714 -379.266834) (xy 306.839343 -379.207713) (xy 306.866372 -379.151587)
			(xy 306.900356 -379.099378) (xy 306.940738 -379.051943) (xy 306.986854 -379.010062) (xy 307.037946 -378.974422)
			(xy 307.093177 -378.945608) (xy 307.151639 -378.924094) (xy 307.212373 -378.910232) (xy 307.27438 -378.90425)
			(xy 307.336643 -378.906246) (xy 307.39814 -378.916189) (xy 307.457861 -378.933913) (xy 307.514824 -378.95913)
			(xy 307.568095 -378.991423) (xy 307.6168 -379.030263) (xy 307.660137 -379.075013) (xy 307.697397 -379.124937)
			(xy 307.727966 -379.179216) (xy 307.751344 -379.236959) (xy 307.767145 -379.297217) (xy 307.775111 -379.359)
			(xy 307.77561 -379.390148) (xy 307.775111 -379.421296) (xy 307.767145 -379.483079) (xy 307.751344 -379.543337)
			(xy 307.727966 -379.60108) (xy 307.697397 -379.655359) (xy 307.660137 -379.705283) (xy 307.6168 -379.750033)
			(xy 307.568095 -379.788873) (xy 307.514824 -379.821166) (xy 307.457861 -379.846383) (xy 307.39814 -379.864107)
			(xy 307.336643 -379.87405) (xy 307.27438 -379.876046) (xy 307.212373 -379.870064) (xy 307.151639 -379.856202)
			(xy 307.093177 -379.834688) (xy 307.037946 -379.805874) (xy 306.986854 -379.770234) (xy 306.940738 -379.728353)
			(xy 306.900356 -379.680918) (xy 306.866372 -379.628709) (xy 306.839343 -379.572583) (xy 306.819714 -379.513462)
			(xy 306.807805 -379.452315) (xy 306.803814 -379.390148) (xy 306.587398 -379.390148) (xy 306.587398 -380.69012)
			(xy 306.803814 -380.69012) (xy 306.807805 -380.627953) (xy 306.819714 -380.566806) (xy 306.839343 -380.507685)
			(xy 306.866372 -380.451559) (xy 306.900356 -380.39935) (xy 306.940738 -380.351915) (xy 306.986854 -380.310034)
			(xy 307.037946 -380.274394) (xy 307.093177 -380.24558) (xy 307.151639 -380.224066) (xy 307.212373 -380.210204)
			(xy 307.27438 -380.204222) (xy 307.336643 -380.206218) (xy 307.39814 -380.216161) (xy 307.457861 -380.233885)
			(xy 307.514824 -380.259102) (xy 307.568095 -380.291395) (xy 307.6168 -380.330235) (xy 307.660137 -380.374985)
			(xy 307.697397 -380.424909) (xy 307.727966 -380.479188) (xy 307.751344 -380.536931) (xy 307.767145 -380.597189)
			(xy 307.775111 -380.658972) (xy 307.77561 -380.69012) (xy 307.775111 -380.721268) (xy 307.767145 -380.783051)
			(xy 307.751344 -380.843309) (xy 307.727966 -380.901052) (xy 307.697397 -380.955331) (xy 307.660137 -381.005255)
			(xy 307.6168 -381.050005) (xy 307.568095 -381.088845) (xy 307.514824 -381.121138) (xy 307.457861 -381.146355)
			(xy 307.39814 -381.164079) (xy 307.336643 -381.174022) (xy 307.27438 -381.176018) (xy 307.212373 -381.170036)
			(xy 307.151639 -381.156174) (xy 307.093177 -381.13466) (xy 307.037946 -381.105846) (xy 306.986854 -381.070206)
			(xy 306.940738 -381.028325) (xy 306.900356 -380.98089) (xy 306.866372 -380.928681) (xy 306.839343 -380.872555)
			(xy 306.819714 -380.813434) (xy 306.807805 -380.752287) (xy 306.803814 -380.69012) (xy 306.587398 -380.69012)
			(xy 306.587398 -383.290064) (xy 306.803814 -383.290064) (xy 306.807805 -383.227897) (xy 306.819714 -383.16675)
			(xy 306.839343 -383.107629) (xy 306.866372 -383.051503) (xy 306.900356 -382.999294) (xy 306.940738 -382.951859)
			(xy 306.986854 -382.909978) (xy 307.037946 -382.874338) (xy 307.093177 -382.845524) (xy 307.151639 -382.82401)
			(xy 307.212373 -382.810148) (xy 307.27438 -382.804166) (xy 307.336643 -382.806162) (xy 307.39814 -382.816105)
			(xy 307.457861 -382.833829) (xy 307.514824 -382.859046) (xy 307.568095 -382.891339) (xy 307.6168 -382.930179)
			(xy 307.660137 -382.974929) (xy 307.697397 -383.024853) (xy 307.727966 -383.079132) (xy 307.751344 -383.136875)
			(xy 307.767145 -383.197133) (xy 307.775111 -383.258916) (xy 307.77561 -383.290064) (xy 307.775111 -383.321212)
			(xy 307.767145 -383.382995) (xy 307.751344 -383.443253) (xy 307.727966 -383.500996) (xy 307.697397 -383.555275)
			(xy 307.660137 -383.605199) (xy 307.6168 -383.649949) (xy 307.568095 -383.688789) (xy 307.514824 -383.721082)
			(xy 307.457861 -383.746299) (xy 307.39814 -383.764023) (xy 307.336643 -383.773966) (xy 307.27438 -383.775962)
			(xy 307.212373 -383.76998) (xy 307.151639 -383.756118) (xy 307.093177 -383.734604) (xy 307.037946 -383.70579)
			(xy 306.986854 -383.67015) (xy 306.940738 -383.628269) (xy 306.900356 -383.580834) (xy 306.866372 -383.528625)
			(xy 306.839343 -383.472499) (xy 306.819714 -383.413378) (xy 306.807805 -383.352231) (xy 306.803814 -383.290064)
			(xy 306.587398 -383.290064) (xy 306.587398 -384.590036) (xy 306.803814 -384.590036) (xy 306.807805 -384.527869)
			(xy 306.819714 -384.466722) (xy 306.839343 -384.407601) (xy 306.866372 -384.351475) (xy 306.900356 -384.299266)
			(xy 306.940738 -384.251831) (xy 306.986854 -384.20995) (xy 307.037946 -384.17431) (xy 307.093177 -384.145496)
			(xy 307.151639 -384.123982) (xy 307.212373 -384.11012) (xy 307.27438 -384.104138) (xy 307.336643 -384.106134)
			(xy 307.39814 -384.116077) (xy 307.457861 -384.133801) (xy 307.514824 -384.159018) (xy 307.568095 -384.191311)
			(xy 307.6168 -384.230151) (xy 307.660137 -384.274901) (xy 307.697397 -384.324825) (xy 307.727966 -384.379104)
			(xy 307.751344 -384.436847) (xy 307.767145 -384.497105) (xy 307.775111 -384.558888) (xy 307.77561 -384.590036)
			(xy 307.775111 -384.621184) (xy 307.767145 -384.682967) (xy 307.751344 -384.743225) (xy 307.727966 -384.800968)
			(xy 307.697397 -384.855247) (xy 307.660137 -384.905171) (xy 307.6168 -384.949921) (xy 307.568095 -384.988761)
			(xy 307.514824 -385.021054) (xy 307.457861 -385.046271) (xy 307.39814 -385.063995) (xy 307.336643 -385.073938)
			(xy 307.27438 -385.075934) (xy 307.212373 -385.069952) (xy 307.151639 -385.05609) (xy 307.093177 -385.034576)
			(xy 307.037946 -385.005762) (xy 306.986854 -384.970122) (xy 306.940738 -384.928241) (xy 306.900356 -384.880806)
			(xy 306.866372 -384.828597) (xy 306.839343 -384.772471) (xy 306.819714 -384.71335) (xy 306.807805 -384.652203)
			(xy 306.803814 -384.590036) (xy 306.587398 -384.590036) (xy 306.587398 -397.59001) (xy 306.803814 -397.59001)
			(xy 306.807805 -397.527843) (xy 306.819714 -397.466696) (xy 306.839343 -397.407575) (xy 306.866372 -397.351449)
			(xy 306.900356 -397.29924) (xy 306.940738 -397.251805) (xy 306.986854 -397.209924) (xy 307.037946 -397.174284)
			(xy 307.093177 -397.14547) (xy 307.151639 -397.123956) (xy 307.212373 -397.110094) (xy 307.27438 -397.104112)
			(xy 307.336643 -397.106108) (xy 307.39814 -397.116051) (xy 307.457861 -397.133775) (xy 307.514824 -397.158992)
			(xy 307.568095 -397.191285) (xy 307.6168 -397.230125) (xy 307.660137 -397.274875) (xy 307.697397 -397.324799)
			(xy 307.727966 -397.379078) (xy 307.751344 -397.436821) (xy 307.767145 -397.497079) (xy 307.775111 -397.558862)
			(xy 307.77561 -397.59001) (xy 307.775111 -397.621158) (xy 307.767145 -397.682941) (xy 307.751344 -397.743199)
			(xy 307.727966 -397.800942) (xy 307.697397 -397.855221) (xy 307.660137 -397.905145) (xy 307.6168 -397.949895)
			(xy 307.568095 -397.988735) (xy 307.514824 -398.021028) (xy 307.457861 -398.046245) (xy 307.39814 -398.063969)
			(xy 307.336643 -398.073912) (xy 307.27438 -398.075908) (xy 307.212373 -398.069926) (xy 307.151639 -398.056064)
			(xy 307.093177 -398.03455) (xy 307.037946 -398.005736) (xy 306.986854 -397.970096) (xy 306.940738 -397.928215)
			(xy 306.900356 -397.88078) (xy 306.866372 -397.828571) (xy 306.839343 -397.772445) (xy 306.819714 -397.713324)
			(xy 306.807805 -397.652177) (xy 306.803814 -397.59001) (xy 306.587398 -397.59001) (xy 306.587398 -398.890236)
			(xy 306.803814 -398.890236) (xy 306.807805 -398.828069) (xy 306.819714 -398.766922) (xy 306.839343 -398.707801)
			(xy 306.866372 -398.651675) (xy 306.900356 -398.599466) (xy 306.940738 -398.552031) (xy 306.986854 -398.51015)
			(xy 307.037946 -398.47451) (xy 307.093177 -398.445696) (xy 307.151639 -398.424182) (xy 307.212373 -398.41032)
			(xy 307.27438 -398.404338) (xy 307.336643 -398.406334) (xy 307.39814 -398.416277) (xy 307.457861 -398.434001)
			(xy 307.514824 -398.459218) (xy 307.568095 -398.491511) (xy 307.6168 -398.530351) (xy 307.660137 -398.575101)
			(xy 307.697397 -398.625025) (xy 307.727966 -398.679304) (xy 307.751344 -398.737047) (xy 307.767145 -398.797305)
			(xy 307.775111 -398.859088) (xy 307.77561 -398.890236) (xy 307.775111 -398.921384) (xy 307.767145 -398.983167)
			(xy 307.751344 -399.043425) (xy 307.727966 -399.101168) (xy 307.697397 -399.155447) (xy 307.660137 -399.205371)
			(xy 307.6168 -399.250121) (xy 307.568095 -399.288961) (xy 307.514824 -399.321254) (xy 307.457861 -399.346471)
			(xy 307.39814 -399.364195) (xy 307.336643 -399.374138) (xy 307.27438 -399.376134) (xy 307.212373 -399.370152)
			(xy 307.151639 -399.35629) (xy 307.093177 -399.334776) (xy 307.037946 -399.305962) (xy 306.986854 -399.270322)
			(xy 306.940738 -399.228441) (xy 306.900356 -399.181006) (xy 306.866372 -399.128797) (xy 306.839343 -399.072671)
			(xy 306.819714 -399.01355) (xy 306.807805 -398.952403) (xy 306.803814 -398.890236) (xy 306.587398 -398.890236)
			(xy 306.587398 -400.724116) (xy 306.586972 -400.734185) (xy 306.579253 -400.752785) (xy 306.572412 -400.760184)
			(xy 305.842416 -401.49018) (xy 306.803814 -401.49018) (xy 306.807805 -401.428013) (xy 306.819714 -401.366866)
			(xy 306.839343 -401.307745) (xy 306.866372 -401.251619) (xy 306.900356 -401.19941) (xy 306.940738 -401.151975)
			(xy 306.986854 -401.110094) (xy 307.037946 -401.074454) (xy 307.093177 -401.04564) (xy 307.151639 -401.024126)
			(xy 307.212373 -401.010264) (xy 307.27438 -401.004282) (xy 307.336643 -401.006278) (xy 307.39814 -401.016221)
			(xy 307.457861 -401.033945) (xy 307.514824 -401.059162) (xy 307.568095 -401.091455) (xy 307.6168 -401.130295)
			(xy 307.660137 -401.175045) (xy 307.697397 -401.224969) (xy 307.727966 -401.279248) (xy 307.751344 -401.336991)
			(xy 307.767145 -401.397249) (xy 307.775111 -401.459032) (xy 307.77561 -401.49018) (xy 307.775111 -401.521328)
			(xy 307.767145 -401.583111) (xy 307.751344 -401.643369) (xy 307.727966 -401.701112) (xy 307.697397 -401.755391)
			(xy 307.660137 -401.805315) (xy 307.6168 -401.850065) (xy 307.568095 -401.888905) (xy 307.514824 -401.921198)
			(xy 307.457861 -401.946415) (xy 307.39814 -401.964139) (xy 307.336643 -401.974082) (xy 307.27438 -401.976078)
			(xy 307.212373 -401.970096) (xy 307.151639 -401.956234) (xy 307.093177 -401.93472) (xy 307.037946 -401.905906)
			(xy 306.986854 -401.870266) (xy 306.940738 -401.828385) (xy 306.900356 -401.78095) (xy 306.866372 -401.728741)
			(xy 306.839343 -401.672615) (xy 306.819714 -401.613494) (xy 306.807805 -401.552347) (xy 306.803814 -401.49018)
			(xy 305.842416 -401.49018) (xy 305.586892 -401.745704) (xy 305.578764 -401.756118) (xy 305.56835 -401.773898)
			(xy 305.566826 -401.782534) (xy 305.560156 -401.814192) (xy 305.539536 -401.875515) (xy 305.510954 -401.933556)
			(xy 305.474916 -401.987286) (xy 305.432061 -402.035754) (xy 305.383148 -402.0781) (xy 305.329044 -402.113574)
			(xy 305.270707 -402.141548) (xy 305.209172 -402.161525) (xy 305.177444 -402.167852) (xy 305.16957 -402.169376)
			(xy 305.156362 -402.176234) (xy 304.542444 -402.790152) (xy 306.803814 -402.790152) (xy 306.807805 -402.727985)
			(xy 306.819714 -402.666838) (xy 306.839343 -402.607717) (xy 306.866372 -402.551591) (xy 306.900356 -402.499382)
			(xy 306.940738 -402.451947) (xy 306.986854 -402.410066) (xy 307.037946 -402.374426) (xy 307.093177 -402.345612)
			(xy 307.151639 -402.324098) (xy 307.212373 -402.310236) (xy 307.27438 -402.304254) (xy 307.336643 -402.30625)
			(xy 307.39814 -402.316193) (xy 307.457861 -402.333917) (xy 307.514824 -402.359134) (xy 307.568095 -402.391427)
			(xy 307.6168 -402.430267) (xy 307.660137 -402.475017) (xy 307.697397 -402.524941) (xy 307.727966 -402.57922)
			(xy 307.751344 -402.636963) (xy 307.767145 -402.697221) (xy 307.775111 -402.759004) (xy 307.77561 -402.790152)
			(xy 307.775111 -402.8213) (xy 307.767145 -402.883083) (xy 307.751344 -402.943341) (xy 307.727966 -403.001084)
			(xy 307.697397 -403.055363) (xy 307.660137 -403.105287) (xy 307.6168 -403.150037) (xy 307.568095 -403.188877)
			(xy 307.514824 -403.22117) (xy 307.457861 -403.246387) (xy 307.39814 -403.264111) (xy 307.336643 -403.274054)
			(xy 307.27438 -403.27605) (xy 307.212373 -403.270068) (xy 307.151639 -403.256206) (xy 307.093177 -403.234692)
			(xy 307.037946 -403.205878) (xy 306.986854 -403.170238) (xy 306.940738 -403.128357) (xy 306.900356 -403.080922)
			(xy 306.866372 -403.028713) (xy 306.839343 -402.972587) (xy 306.819714 -402.913466) (xy 306.807805 -402.852319)
			(xy 306.803814 -402.790152) (xy 304.542444 -402.790152) (xy 304.371502 -402.961094) (xy 304.364104 -402.967942)
			(xy 304.345506 -402.975678) (xy 304.335434 -402.97608) (xy 304.30216 -402.97608) (xy 304.297842 -402.976842)
			(xy 304.282856 -402.979382) (xy 304.275236 -402.983446) (xy 304.26914 -402.986748) (xy 304.263806 -402.991828)
			(xy 304.263552 -402.992082) (xy 304.231517 -403.02291) (xy 304.162836 -403.079376) (xy 304.089404 -403.129509)
			(xy 304.011804 -403.172912) (xy 303.930652 -403.209241) (xy 303.84659 -403.238207) (xy 303.803558 -403.249384)
			(xy 303.793144 -403.251924) (xy 303.760632 -403.276816) (xy 303.755298 -403.285706) (xy 303.733206 -403.323382)
			(xy 303.683367 -403.395113) (xy 303.627443 -403.462209) (xy 303.565863 -403.524154) (xy 303.4991 -403.580474)
			(xy 303.427665 -403.630737) (xy 303.352106 -403.674557) (xy 303.273003 -403.711599) (xy 303.190963 -403.741577)
			(xy 303.106614 -403.764263) (xy 303.020605 -403.779481) (xy 302.933593 -403.787116) (xy 302.88992 -403.78761)
			(xy 302.889666 -403.78761) (xy 302.87595 -403.787356) (xy 302.828873 -403.786135) (xy 302.73525 -403.77592)
			(xy 302.643005 -403.756934) (xy 302.59782 -403.743668) (xy 302.571338 -403.735484) (xy 302.519238 -403.716548)
			(xy 302.49368 -403.705822) (xy 302.489108 -403.70379) (xy 302.47844 -403.701504) (xy 302.47372 -403.70065)
			(xy 302.46413 -403.700514) (xy 302.45939 -403.70125) (xy 302.45304 -403.702266) (xy 302.44923 -403.703536)
			(xy 302.420409 -403.712607) (xy 302.360817 -403.722565) (xy 302.330612 -403.723348) (xy 302.325786 -403.723348)
			(xy 302.298628 -403.722725) (xy 302.244896 -403.714737) (xy 302.19284 -403.699209) (xy 302.143513 -403.676454)
			(xy 302.097912 -403.646934) (xy 302.056958 -403.611244) (xy 302.021481 -403.570107) (xy 301.992197 -403.524353)
			(xy 301.969698 -403.474909) (xy 301.954439 -403.422774) (xy 301.946729 -403.369001) (xy 301.94631 -403.34184)
			(xy 301.94631 -403.341332) (xy 301.947029 -403.309005) (xy 301.958004 -403.245287) (xy 301.968154 -403.214586)
			(xy 301.970948 -403.206458) (xy 301.970948 -403.18309) (xy 301.968916 -403.173184) (xy 301.965614 -403.164294)
			(xy 301.96536 -403.163278) (xy 301.951098 -403.127167) (xy 301.927574 -403.053169) (xy 301.91837 -403.01545)
			(xy 301.914306 -402.998178) (xy 301.88662 -402.97608) (xy 299.910246 -402.97608) (xy 299.905148 -402.976189)
			(xy 299.895159 -402.978229) (xy 299.890434 -402.980144) (xy 299.864526 -402.991066) (xy 299.857668 -402.99767)
			(xy 299.825888 -403.027787) (xy 299.757888 -403.082952) (xy 299.685315 -403.131946) (xy 299.608729 -403.174391)
			(xy 299.528717 -403.209962) (xy 299.445895 -403.238384) (xy 299.403516 -403.249384) (xy 299.393102 -403.251924)
			(xy 299.36059 -403.276816) (xy 299.355256 -403.285706) (xy 299.333164 -403.323383) (xy 299.283326 -403.395118)
			(xy 299.227403 -403.462217) (xy 299.165824 -403.524166) (xy 299.099062 -403.58049) (xy 299.027627 -403.630757)
			(xy 298.952069 -403.674581) (xy 298.872966 -403.711627) (xy 298.790925 -403.74161) (xy 298.706576 -403.7643)
			(xy 298.620565 -403.779524) (xy 298.533552 -403.787164) (xy 298.489878 -403.78761) (xy 298.489624 -403.78761)
			(xy 298.475908 -403.787356) (xy 298.428831 -403.786138) (xy 298.335207 -403.775928) (xy 298.24296 -403.756947)
			(xy 298.197778 -403.743668) (xy 298.171296 -403.735485) (xy 298.119195 -403.716552) (xy 298.093638 -403.705822)
			(xy 298.089066 -403.70379) (xy 298.078398 -403.701504) (xy 298.073678 -403.700654) (xy 298.064089 -403.700525)
			(xy 298.059348 -403.70125) (xy 298.052998 -403.702266) (xy 298.049188 -403.703536) (xy 298.020366 -403.712604)
			(xy 297.960774 -403.722556) (xy 297.93057 -403.723348) (xy 297.925744 -403.723348) (xy 297.898588 -403.722723)
			(xy 297.84486 -403.714729) (xy 297.79281 -403.699197) (xy 297.743488 -403.676441) (xy 297.697892 -403.646919)
			(xy 297.656943 -403.611229) (xy 297.621471 -403.570093) (xy 297.59219 -403.524342) (xy 297.569694 -403.4749)
			(xy 297.554438 -403.422768) (xy 297.546728 -403.368999) (xy 297.546268 -403.34184) (xy 297.546268 -403.341332)
			(xy 297.546987 -403.309005) (xy 297.55796 -403.245286) (xy 297.568112 -403.214586) (xy 297.570906 -403.206458)
			(xy 297.570906 -403.18309) (xy 297.568874 -403.173184) (xy 297.565572 -403.164294) (xy 297.565318 -403.163278)
			(xy 297.551055 -403.127167) (xy 297.52753 -403.053169) (xy 297.518328 -403.01545) (xy 297.514264 -402.998178)
			(xy 297.486578 -402.97608) (xy 295.510204 -402.97608) (xy 295.505107 -402.976193) (xy 295.495122 -402.978241)
			(xy 295.490392 -402.980144) (xy 295.464484 -402.991066) (xy 295.457626 -402.99767) (xy 295.425847 -403.027789)
			(xy 295.357848 -403.082957) (xy 295.285277 -403.131955) (xy 295.208691 -403.174405) (xy 295.12868 -403.20998)
			(xy 295.04586 -403.238407) (xy 295.003474 -403.249384) (xy 294.99306 -403.251924) (xy 294.960548 -403.276816)
			(xy 294.955214 -403.285706) (xy 294.933122 -403.323382) (xy 294.883283 -403.395114) (xy 294.827359 -403.462211)
			(xy 294.76578 -403.524157) (xy 294.699017 -403.580479) (xy 294.627582 -403.630743) (xy 294.552023 -403.674564)
			(xy 294.472921 -403.711606) (xy 294.39088 -403.741586) (xy 294.306531 -403.764273) (xy 294.220521 -403.779493)
			(xy 294.133509 -403.787129) (xy 294.089836 -403.78761) (xy 294.089582 -403.78761) (xy 294.075866 -403.787356)
			(xy 294.028789 -403.786136) (xy 293.935166 -403.775922) (xy 293.84292 -403.756938) (xy 293.797736 -403.743668)
			(xy 293.771254 -403.735484) (xy 293.719154 -403.716549) (xy 293.693596 -403.705822) (xy 293.689024 -403.70379)
			(xy 293.678356 -403.701504) (xy 293.673636 -403.700658) (xy 293.664048 -403.700537) (xy 293.659306 -403.70125)
			(xy 293.652956 -403.702266) (xy 293.649146 -403.703536) (xy 293.620325 -403.712608) (xy 293.560733 -403.722569)
			(xy 293.530528 -403.723348) (xy 293.525702 -403.723348) (xy 293.498543 -403.722726) (xy 293.444809 -403.71474)
			(xy 293.392752 -403.699213) (xy 293.343423 -403.676459) (xy 293.297819 -403.646939) (xy 293.256864 -403.61125)
			(xy 293.221385 -403.570112) (xy 293.192099 -403.524358) (xy 293.169599 -403.474912) (xy 293.15434 -403.422776)
			(xy 293.146629 -403.369002) (xy 293.146226 -403.34184) (xy 293.146226 -403.341332) (xy 293.146945 -403.309005)
			(xy 293.15792 -403.245287) (xy 293.16807 -403.214586) (xy 293.170864 -403.206458) (xy 293.170864 -403.18309)
			(xy 293.168832 -403.173184) (xy 293.16553 -403.164294) (xy 293.165276 -403.163278) (xy 293.151014 -403.127167)
			(xy 293.12749 -403.053169) (xy 293.118286 -403.01545) (xy 293.114222 -402.998178) (xy 293.086536 -402.97608)
			(xy 291.110162 -402.97608) (xy 291.105066 -402.976197) (xy 291.095084 -402.978253) (xy 291.09035 -402.980144)
			(xy 291.064442 -402.991066) (xy 291.057584 -402.99767) (xy 291.025804 -403.027788) (xy 290.957805 -403.082954)
			(xy 290.885232 -403.131948) (xy 290.808646 -403.174395) (xy 290.728634 -403.209967) (xy 290.645813 -403.23839)
			(xy 290.603432 -403.249384) (xy 290.593018 -403.251924) (xy 290.560506 -403.276816) (xy 290.555172 -403.285706)
			(xy 290.53308 -403.323384) (xy 290.483243 -403.395119) (xy 290.42732 -403.462219) (xy 290.365741 -403.524169)
			(xy 290.298979 -403.580494) (xy 290.227545 -403.630762) (xy 290.151986 -403.674588) (xy 290.072883 -403.711635)
			(xy 289.990843 -403.741619) (xy 289.906493 -403.764311) (xy 289.820482 -403.779536) (xy 289.733468 -403.787177)
			(xy 289.689794 -403.78761) (xy 289.68954 -403.78761) (xy 289.675824 -403.787356) (xy 289.628747 -403.786138)
			(xy 289.535122 -403.77593) (xy 289.442875 -403.756951) (xy 289.397694 -403.743668) (xy 289.371211 -403.735486)
			(xy 289.31911 -403.716553) (xy 289.293554 -403.705822) (xy 289.288982 -403.70379) (xy 289.278314 -403.701504)
			(xy 289.273594 -403.700652) (xy 289.264004 -403.700521) (xy 289.259264 -403.70125) (xy 289.252914 -403.702266)
			(xy 289.249104 -403.703536) (xy 289.220283 -403.712605) (xy 289.16069 -403.722559) (xy 289.130486 -403.723348)
			(xy 289.12566 -403.723348) (xy 289.098503 -403.722724) (xy 289.044774 -403.714732) (xy 288.992721 -403.699202)
			(xy 288.943397 -403.676446) (xy 288.897799 -403.646925) (xy 288.856849 -403.611235) (xy 288.821375 -403.570098)
			(xy 288.792093 -403.524346) (xy 288.769596 -403.474904) (xy 288.754338 -403.42277) (xy 288.746629 -403.369)
			(xy 288.746184 -403.34184) (xy 288.746184 -403.341332) (xy 288.746903 -403.309005) (xy 288.757877 -403.245286)
			(xy 288.768028 -403.214586) (xy 288.770822 -403.206458) (xy 288.770822 -403.18309) (xy 288.76879 -403.173184)
			(xy 288.765488 -403.164294) (xy 288.765234 -403.163278) (xy 288.750971 -403.127167) (xy 288.727446 -403.053169)
			(xy 288.718244 -403.01545) (xy 288.71418 -402.998178) (xy 288.686494 -402.97608) (xy 285.266638 -402.97608)
			(xy 285.247842 -402.9837) (xy 285.24073 -402.991066) (xy 283.319474 -404.912322) (xy 283.312108 -404.919434)
			(xy 283.304488 -404.93823) (xy 283.304488 -405.622717) (xy 287.004775 -405.622717) (xy 287.004776 -405.557273)
			(xy 287.013571 -405.492423) (xy 287.031 -405.429342) (xy 287.056747 -405.369176) (xy 287.073086 -405.34082)
			(xy 287.076438 -405.334799) (xy 287.080182 -405.321543) (xy 287.080452 -405.314658) (xy 287.080452 -404.565358)
			(xy 287.080225 -404.558465) (xy 287.076492 -404.545193) (xy 287.073086 -404.539196) (xy 287.056766 -404.51083)
			(xy 287.031018 -404.450666) (xy 287.013587 -404.387588) (xy 287.004791 -404.32274) (xy 287.004789 -404.257298)
			(xy 287.01358 -404.192449) (xy 287.031005 -404.12937) (xy 287.056749 -404.069204) (xy 287.073086 -404.040848)
			(xy 287.076464 -404.034839) (xy 287.080192 -404.021574) (xy 287.080452 -404.014686) (xy 287.080452 -403.728682)
			(xy 287.080912 -403.718553) (xy 287.088648 -403.699829) (xy 287.102942 -403.685473) (xy 287.121633 -403.677656)
			(xy 287.13176 -403.67712) (xy 287.84804 -403.67712) (xy 287.858199 -403.677489) (xy 287.876956 -403.685302)
			(xy 287.891279 -403.699715) (xy 287.898974 -403.71852) (xy 287.899348 -403.728682) (xy 287.899348 -404.014686)
			(xy 287.899558 -404.021581) (xy 287.903302 -404.034853) (xy 287.906714 -404.040848) (xy 287.923071 -404.069193)
			(xy 287.948816 -404.129362) (xy 287.966242 -404.192444) (xy 287.975034 -404.257296) (xy 287.975031 -404.322741)
			(xy 287.966235 -404.387593) (xy 287.948804 -404.450674) (xy 287.923054 -404.51084) (xy 287.906714 -404.539196)
			(xy 287.903356 -404.545214) (xy 287.899616 -404.558472) (xy 287.899348 -404.565358) (xy 287.899348 -405.314658)
			(xy 287.899569 -405.321552) (xy 287.903306 -405.334824) (xy 287.906714 -405.34082) (xy 287.923048 -405.369178)
			(xy 287.948795 -405.429344) (xy 287.966223 -405.492424) (xy 287.975018 -405.557273) (xy 287.975018 -405.622716)
			(xy 287.966225 -405.687566) (xy 287.948798 -405.750646) (xy 287.923052 -405.810812) (xy 287.906714 -405.839168)
			(xy 287.903366 -405.845191) (xy 287.899619 -405.858445) (xy 287.899348 -405.86533) (xy 287.899348 -406.151334)
			(xy 287.898901 -406.161464) (xy 287.89116 -406.180189) (xy 287.876861 -406.194544) (xy 287.858168 -406.20236)
			(xy 287.84804 -406.202896) (xy 287.13176 -406.202896) (xy 287.121603 -406.202511) (xy 287.102849 -406.194701)
			(xy 287.088527 -406.180294) (xy 287.080829 -406.161494) (xy 287.080452 -406.151334) (xy 287.080452 -405.86533)
			(xy 287.080235 -405.858436) (xy 287.076496 -405.845164) (xy 287.073086 -405.839168) (xy 287.056742 -405.810815)
			(xy 287.030996 -405.750648) (xy 287.013569 -405.687567) (xy 287.004775 -405.622717) (xy 283.304488 -405.622717)
			(xy 283.304488 -406.722795) (xy 289.204655 -406.722795) (xy 289.204659 -406.65735) (xy 289.213457 -406.592498)
			(xy 289.230889 -406.529417) (xy 289.256639 -406.46925) (xy 289.27298 -406.440894) (xy 289.276295 -406.43487)
			(xy 289.279901 -406.421606) (xy 289.280092 -406.414732) (xy 289.280092 -405.665432) (xy 289.279889 -405.65856)
			(xy 289.276288 -405.645297) (xy 289.27298 -405.63927) (xy 289.256638 -405.610916) (xy 289.230892 -405.550749)
			(xy 289.213465 -405.487669) (xy 289.204671 -405.422818) (xy 289.204672 -405.357375) (xy 289.213466 -405.292525)
			(xy 289.230894 -405.229444) (xy 289.256641 -405.169278) (xy 289.27298 -405.140922) (xy 289.276286 -405.134893)
			(xy 289.279897 -405.121633) (xy 289.280092 -405.11476) (xy 289.280092 -404.828756) (xy 289.280486 -404.8186)
			(xy 289.288294 -404.799848) (xy 289.302699 -404.785527) (xy 289.321496 -404.777827) (xy 289.331654 -404.777448)
			(xy 290.047934 -404.777448) (xy 290.058064 -404.777899) (xy 290.076787 -404.785639) (xy 290.091143 -404.799936)
			(xy 290.098959 -404.818628) (xy 290.099496 -404.828756) (xy 290.099496 -405.11476) (xy 290.099704 -405.121632)
			(xy 290.103301 -405.134895) (xy 290.106608 -405.140922) (xy 290.122944 -405.169279) (xy 290.148691 -405.229445)
			(xy 290.166119 -405.292525) (xy 290.174914 -405.357375) (xy 290.174914 -405.422818) (xy 290.166121 -405.487668)
			(xy 290.148693 -405.550748) (xy 290.122947 -405.610914) (xy 290.116147 -405.622716) (xy 291.404825 -405.622716)
			(xy 291.404826 -405.557273) (xy 291.41362 -405.492423) (xy 291.431046 -405.429343) (xy 291.456791 -405.369176)
			(xy 291.473128 -405.34082) (xy 291.476438 -405.334793) (xy 291.480046 -405.321531) (xy 291.48024 -405.314658)
			(xy 291.48024 -404.565358) (xy 291.480021 -404.558487) (xy 291.476431 -404.545224) (xy 291.473128 -404.539196)
			(xy 291.45681 -404.510829) (xy 291.431065 -404.450665) (xy 291.413636 -404.387587) (xy 291.404841 -404.32274)
			(xy 291.404839 -404.257298) (xy 291.413629 -404.19245) (xy 291.431052 -404.129371) (xy 291.456792 -404.069204)
			(xy 291.473128 -404.040848) (xy 291.476463 -404.034833) (xy 291.480055 -404.021562) (xy 291.48024 -404.014686)
			(xy 291.48024 -403.728682) (xy 291.480718 -403.718523) (xy 291.488499 -403.699753) (xy 291.50287 -403.685388)
			(xy 291.521643 -403.677615) (xy 291.531802 -403.67712) (xy 292.248082 -403.67712) (xy 292.258236 -403.677648)
			(xy 292.277002 -403.685413) (xy 292.291367 -403.699768) (xy 292.299145 -403.718528) (xy 292.299644 -403.728682)
			(xy 292.299644 -404.014686) (xy 292.299836 -404.021559) (xy 292.303444 -404.034822) (xy 292.306756 -404.040848)
			(xy 292.323112 -404.069194) (xy 292.348855 -404.129363) (xy 292.366279 -404.192445) (xy 292.37507 -404.257297)
			(xy 292.375067 -404.322741) (xy 292.366272 -404.387592) (xy 292.348842 -404.450673) (xy 292.323095 -404.51084)
			(xy 292.306756 -404.539196) (xy 292.303447 -404.545224) (xy 292.299837 -404.558485) (xy 292.299644 -404.565358)
			(xy 292.299644 -405.314658) (xy 292.299846 -405.321531) (xy 292.303447 -405.334794) (xy 292.306756 -405.34082)
			(xy 292.323088 -405.369179) (xy 292.348833 -405.429345) (xy 292.36626 -405.492424) (xy 292.375054 -405.557274)
			(xy 292.375055 -405.622716) (xy 292.366262 -405.687565) (xy 292.348836 -405.750645) (xy 292.323093 -405.810812)
			(xy 292.306756 -405.839168) (xy 292.303457 -405.8452) (xy 292.299841 -405.858458) (xy 292.299644 -405.86533)
			(xy 292.299644 -406.151334) (xy 292.299194 -406.161496) (xy 292.291405 -406.18027) (xy 292.277026 -406.194634)
			(xy 292.258245 -406.202404) (xy 292.248082 -406.202896) (xy 291.531802 -406.202896) (xy 291.521649 -406.202366)
			(xy 291.502886 -406.194598) (xy 291.488522 -406.180244) (xy 291.480741 -406.161487) (xy 291.48024 -406.151334)
			(xy 291.48024 -405.86533) (xy 291.480032 -405.858458) (xy 291.476434 -405.845195) (xy 291.473128 -405.839168)
			(xy 291.456786 -405.810815) (xy 291.431043 -405.750647) (xy 291.413618 -405.687566) (xy 291.404825 -405.622716)
			(xy 290.116147 -405.622716) (xy 290.106608 -405.63927) (xy 290.103304 -405.6453) (xy 290.099692 -405.65856)
			(xy 290.099496 -405.665432) (xy 290.099496 -406.414732) (xy 290.099676 -406.421606) (xy 290.103292 -406.434869)
			(xy 290.106608 -406.440894) (xy 290.12292 -406.469265) (xy 290.148669 -406.529427) (xy 290.1661 -406.592504)
			(xy 290.174898 -406.657352) (xy 290.174901 -406.722793) (xy 290.174901 -406.722795) (xy 293.604705 -406.722795)
			(xy 293.604709 -406.65735) (xy 293.613506 -406.592499) (xy 293.630936 -406.529418) (xy 293.656683 -406.46925)
			(xy 293.673022 -406.440894) (xy 293.676386 -406.434879) (xy 293.680122 -406.421619) (xy 293.680388 -406.414732)
			(xy 293.680388 -405.665432) (xy 293.680144 -405.658541) (xy 293.676409 -405.645275) (xy 293.673022 -405.63927)
			(xy 293.656682 -405.610916) (xy 293.630939 -405.550748) (xy 293.613514 -405.487668) (xy 293.604721 -405.422818)
			(xy 293.604722 -405.357375) (xy 293.613515 -405.292525) (xy 293.630941 -405.229445) (xy 293.656685 -405.169278)
			(xy 293.673022 -405.140922) (xy 293.676376 -405.134902) (xy 293.680118 -405.121646) (xy 293.680388 -405.11476)
			(xy 293.680388 -404.828756) (xy 293.680849 -404.818646) (xy 293.688599 -404.799969) (xy 293.702903 -404.785676)
			(xy 293.721586 -404.777941) (xy 293.731696 -404.777448) (xy 294.447976 -404.777448) (xy 294.458077 -404.778003)
			(xy 294.476745 -404.785723) (xy 294.491038 -404.799998) (xy 294.498783 -404.818656) (xy 294.499284 -404.828756)
			(xy 294.499284 -405.11476) (xy 294.4995 -405.121654) (xy 294.50324 -405.134926) (xy 294.50665 -405.140922)
			(xy 294.522984 -405.16928) (xy 294.548729 -405.229446) (xy 294.566156 -405.292526) (xy 294.57495 -405.357375)
			(xy 294.57495 -405.422818) (xy 294.566158 -405.487667) (xy 294.548731 -405.550747) (xy 294.522987 -405.610914)
			(xy 294.516187 -405.622717) (xy 295.804862 -405.622717) (xy 295.804862 -405.557273) (xy 295.813657 -405.492423)
			(xy 295.831085 -405.429342) (xy 295.856831 -405.369176) (xy 295.87317 -405.34082) (xy 295.876529 -405.334802)
			(xy 295.880268 -405.321544) (xy 295.880536 -405.314658) (xy 295.880536 -404.565358) (xy 295.880311 -404.558465)
			(xy 295.876577 -404.545192) (xy 295.87317 -404.539196) (xy 295.85685 -404.51083) (xy 295.831103 -404.450666)
			(xy 295.813673 -404.387588) (xy 295.804878 -404.32274) (xy 295.804875 -404.257298) (xy 295.813666 -404.192449)
			(xy 295.831091 -404.12937) (xy 295.856833 -404.069204) (xy 295.87317 -404.040848) (xy 295.876554 -404.034843)
			(xy 295.880277 -404.021575) (xy 295.880536 -404.014686) (xy 295.880536 -403.728682) (xy 295.881011 -403.718555)
			(xy 295.888744 -403.699834) (xy 295.903034 -403.685478) (xy 295.921719 -403.677659) (xy 295.931844 -403.67712)
			(xy 296.648124 -403.67712) (xy 296.658282 -403.677502) (xy 296.677039 -403.685309) (xy 296.691362 -403.699718)
			(xy 296.699058 -403.718521) (xy 296.699432 -403.728682) (xy 296.699432 -404.014686) (xy 296.699666 -404.021577)
			(xy 296.703407 -404.034843) (xy 296.706798 -404.040848) (xy 296.723153 -404.069194) (xy 296.748893 -404.129364)
			(xy 296.766316 -404.192446) (xy 296.775106 -404.257297) (xy 296.775103 -404.322741) (xy 296.766309 -404.387591)
			(xy 296.748881 -404.450672) (xy 296.723136 -404.510839) (xy 296.706798 -404.539196) (xy 296.703439 -404.545214)
			(xy 296.6997 -404.558472) (xy 296.699432 -404.565358) (xy 296.699432 -405.314658) (xy 296.699655 -405.321552)
			(xy 296.703391 -405.334823) (xy 296.706798 -405.34082) (xy 296.723129 -405.369179) (xy 296.748872 -405.429346)
			(xy 296.766297 -405.492425) (xy 296.77509 -405.557274) (xy 296.775091 -405.622716) (xy 296.766299 -405.687565)
			(xy 296.748875 -405.750645) (xy 296.723134 -405.810811) (xy 296.706798 -405.839168) (xy 296.703449 -405.845191)
			(xy 296.699703 -405.858445) (xy 296.699432 -405.86533) (xy 296.699432 -406.151334) (xy 296.699001 -406.161466)
			(xy 296.691256 -406.180194) (xy 296.676953 -406.19455) (xy 296.658254 -406.202363) (xy 296.648124 -406.202896)
			(xy 295.931844 -406.202896) (xy 295.921692 -406.202442) (xy 295.90294 -406.19466) (xy 295.888615 -406.180273)
			(xy 295.880915 -406.161487) (xy 295.880536 -406.151334) (xy 295.880536 -405.86533) (xy 295.880322 -405.858436)
			(xy 295.876581 -405.845164) (xy 295.87317 -405.839168) (xy 295.856827 -405.810815) (xy 295.831082 -405.750648)
			(xy 295.813655 -405.687567) (xy 295.804862 -405.622717) (xy 294.516187 -405.622717) (xy 294.50665 -405.63927)
			(xy 294.503297 -405.64529) (xy 294.499554 -405.658547) (xy 294.499284 -405.665432) (xy 294.499284 -406.414732)
			(xy 294.499511 -406.421625) (xy 294.503243 -406.434897) (xy 294.50665 -406.440894) (xy 294.522961 -406.469265)
			(xy 294.548708 -406.529428) (xy 294.566137 -406.592505) (xy 294.574934 -406.657352) (xy 294.574938 -406.722793)
			(xy 294.574938 -406.722795) (xy 298.004742 -406.722795) (xy 298.004745 -406.65735) (xy 298.013543 -406.592498)
			(xy 298.030974 -406.529417) (xy 298.056724 -406.46925) (xy 298.073064 -406.440894) (xy 298.076378 -406.434869)
			(xy 298.079984 -406.421606) (xy 298.080176 -406.414732) (xy 298.080176 -405.665432) (xy 298.079975 -405.658559)
			(xy 298.076373 -405.645297) (xy 298.073064 -405.63927) (xy 298.056722 -405.610916) (xy 298.030978 -405.550749)
			(xy 298.013551 -405.487668) (xy 298.004758 -405.422818) (xy 298.004758 -405.357375) (xy 298.013552 -405.292525)
			(xy 298.03098 -405.229444) (xy 298.056726 -405.169278) (xy 298.073064 -405.140922) (xy 298.076368 -405.134892)
			(xy 298.079981 -405.121632) (xy 298.080176 -405.11476) (xy 298.080176 -404.828756) (xy 298.080585 -404.818602)
			(xy 298.088391 -404.799853) (xy 298.102791 -404.785532) (xy 298.121582 -404.77783) (xy 298.131738 -404.777448)
			(xy 298.848018 -404.777448) (xy 298.858147 -404.777912) (xy 298.87687 -404.785647) (xy 298.891226 -404.79994)
			(xy 298.899043 -404.818629) (xy 298.89958 -404.828756) (xy 298.89958 -405.11476) (xy 298.89979 -405.121632)
			(xy 298.903386 -405.134895) (xy 298.906692 -405.140922) (xy 298.923025 -405.16928) (xy 298.948768 -405.229447)
			(xy 298.966193 -405.292527) (xy 298.974986 -405.357375) (xy 298.974987 -405.422818) (xy 298.966195 -405.487667)
			(xy 298.94877 -405.550747) (xy 298.923028 -405.610914) (xy 298.916228 -405.622717) (xy 300.204651 -405.622717)
			(xy 300.204652 -405.557273) (xy 300.213446 -405.492423) (xy 300.230874 -405.429343) (xy 300.25662 -405.369176)
			(xy 300.272958 -405.34082) (xy 300.276316 -405.334802) (xy 300.280055 -405.321544) (xy 300.280324 -405.314658)
			(xy 300.280324 -404.565358) (xy 300.2801 -404.558464) (xy 300.276366 -404.545192) (xy 300.272958 -404.539196)
			(xy 300.256639 -404.51083) (xy 300.230892 -404.450666) (xy 300.213463 -404.387588) (xy 300.204667 -404.32274)
			(xy 300.204665 -404.257298) (xy 300.213455 -404.192449) (xy 300.23088 -404.12937) (xy 300.256622 -404.069204)
			(xy 300.272958 -404.040848) (xy 300.276341 -404.034842) (xy 300.280065 -404.021575) (xy 300.280324 -404.014686)
			(xy 300.280324 -403.728682) (xy 300.280811 -403.718556) (xy 300.288542 -403.699837) (xy 300.302828 -403.685482)
			(xy 300.321509 -403.677661) (xy 300.331632 -403.67712) (xy 301.047912 -403.67712) (xy 301.058069 -403.677512)
			(xy 301.076826 -403.685315) (xy 301.09115 -403.699721) (xy 301.098846 -403.718522) (xy 301.09922 -403.728682)
			(xy 301.09922 -404.014686) (xy 301.099456 -404.021577) (xy 301.103196 -404.034843) (xy 301.106586 -404.040848)
			(xy 301.122941 -404.069194) (xy 301.148682 -404.129363) (xy 301.166106 -404.192446) (xy 301.174896 -404.257297)
			(xy 301.174894 -404.290022) (xy 304.603666 -404.290022) (xy 304.607657 -404.227855) (xy 304.619566 -404.166708)
			(xy 304.639195 -404.107587) (xy 304.666224 -404.051461) (xy 304.700208 -403.999252) (xy 304.74059 -403.951817)
			(xy 304.786706 -403.909936) (xy 304.837798 -403.874296) (xy 304.893029 -403.845482) (xy 304.951491 -403.823968)
			(xy 305.012225 -403.810106) (xy 305.074232 -403.804124) (xy 305.136495 -403.80612) (xy 305.197992 -403.816063)
			(xy 305.257713 -403.833787) (xy 305.314676 -403.859004) (xy 305.367947 -403.891297) (xy 305.416652 -403.930137)
			(xy 305.459989 -403.974887) (xy 305.497249 -404.024811) (xy 305.527818 -404.07909) (xy 305.551196 -404.136833)
			(xy 305.566997 -404.197091) (xy 305.574963 -404.258874) (xy 305.575462 -404.290022) (xy 305.574963 -404.32117)
			(xy 305.566997 -404.382953) (xy 305.551196 -404.443211) (xy 305.527818 -404.500954) (xy 305.497249 -404.555233)
			(xy 305.459989 -404.605157) (xy 305.416652 -404.649907) (xy 305.367947 -404.688747) (xy 305.314676 -404.72104)
			(xy 305.257713 -404.746257) (xy 305.197992 -404.763981) (xy 305.136495 -404.773924) (xy 305.074232 -404.77592)
			(xy 305.012225 -404.769938) (xy 304.951491 -404.756076) (xy 304.893029 -404.734562) (xy 304.837798 -404.705748)
			(xy 304.786706 -404.670108) (xy 304.74059 -404.628227) (xy 304.700208 -404.580792) (xy 304.666224 -404.528583)
			(xy 304.639195 -404.472457) (xy 304.619566 -404.413336) (xy 304.607657 -404.352189) (xy 304.603666 -404.290022)
			(xy 301.174894 -404.290022) (xy 301.174893 -404.322741) (xy 301.166098 -404.387591) (xy 301.14867 -404.450672)
			(xy 301.122924 -404.51084) (xy 301.106586 -404.539196) (xy 301.103226 -404.545213) (xy 301.099487 -404.558472)
			(xy 301.09922 -404.565358) (xy 301.09922 -405.314658) (xy 301.099467 -405.321548) (xy 301.1032 -405.334814)
			(xy 301.106586 -405.34082) (xy 301.122918 -405.369179) (xy 301.148661 -405.429346) (xy 301.166087 -405.492425)
			(xy 301.17488 -405.557274) (xy 301.17488 -405.622716) (xy 301.166089 -405.687565) (xy 301.148664 -405.750645)
			(xy 301.122922 -405.810812) (xy 301.106586 -405.839168) (xy 301.103236 -405.84519) (xy 301.099491 -405.858445)
			(xy 301.09922 -405.86533) (xy 301.09922 -406.151334) (xy 301.0988 -406.161468) (xy 301.091054 -406.180197)
			(xy 301.076747 -406.194554) (xy 301.058044 -406.202365) (xy 301.047912 -406.202896) (xy 300.331632 -406.202896)
			(xy 300.321479 -406.202452) (xy 300.302727 -406.194667) (xy 300.288402 -406.180276) (xy 300.280702 -406.161488)
			(xy 300.280324 -406.151334) (xy 300.280324 -405.86533) (xy 300.280111 -405.858436) (xy 300.276369 -405.845163)
			(xy 300.272958 -405.839168) (xy 300.256615 -405.810815) (xy 300.230871 -405.750648) (xy 300.213444 -405.687567)
			(xy 300.204651 -405.622717) (xy 298.916228 -405.622717) (xy 298.906692 -405.63927) (xy 298.903387 -405.6453)
			(xy 298.899775 -405.65856) (xy 298.89958 -405.665432) (xy 298.89958 -406.414732) (xy 298.899762 -406.421606)
			(xy 298.903377 -406.434869) (xy 298.906692 -406.440894) (xy 298.923001 -406.469265) (xy 298.948746 -406.529429)
			(xy 298.966174 -406.592506) (xy 298.97497 -406.657352) (xy 298.974974 -406.722793) (xy 298.974974 -406.722795)
			(xy 302.404792 -406.722795) (xy 302.404795 -406.65735) (xy 302.413592 -406.592499) (xy 302.431021 -406.529418)
			(xy 302.456768 -406.469251) (xy 302.473106 -406.440894) (xy 302.476469 -406.434878) (xy 302.480206 -406.421619)
			(xy 302.480472 -406.414732) (xy 302.480472 -405.665432) (xy 302.48023 -405.658541) (xy 302.476494 -405.645275)
			(xy 302.473106 -405.63927) (xy 302.456766 -405.610915) (xy 302.431024 -405.550748) (xy 302.4136 -405.487668)
			(xy 302.404808 -405.422818) (xy 302.404808 -405.357375) (xy 302.413601 -405.292526) (xy 302.431027 -405.229446)
			(xy 302.456769 -405.169279) (xy 302.473106 -405.140922) (xy 302.476459 -405.134901) (xy 302.480202 -405.121645)
			(xy 302.480472 -405.11476) (xy 302.480472 -404.828756) (xy 302.480948 -404.818648) (xy 302.488695 -404.799974)
			(xy 302.502994 -404.785682) (xy 302.521672 -404.777944) (xy 302.53178 -404.777448) (xy 303.24806 -404.777448)
			(xy 303.25816 -404.778017) (xy 303.276827 -404.785732) (xy 303.291121 -404.800002) (xy 303.298867 -404.818657)
			(xy 303.299368 -404.828756) (xy 303.299368 -405.11476) (xy 303.299586 -405.121654) (xy 303.303324 -405.134926)
			(xy 303.306734 -405.140922) (xy 303.323069 -405.16928) (xy 303.348814 -405.229446) (xy 303.366242 -405.292526)
			(xy 303.375036 -405.357375) (xy 303.375037 -405.422818) (xy 303.366244 -405.487668) (xy 303.348817 -405.550748)
			(xy 303.332024 -405.589994) (xy 304.603666 -405.589994) (xy 304.607657 -405.527827) (xy 304.619566 -405.46668)
			(xy 304.639195 -405.407559) (xy 304.666224 -405.351433) (xy 304.700208 -405.299224) (xy 304.74059 -405.251789)
			(xy 304.786706 -405.209908) (xy 304.837798 -405.174268) (xy 304.893029 -405.145454) (xy 304.951491 -405.12394)
			(xy 305.012225 -405.110078) (xy 305.074232 -405.104096) (xy 305.136495 -405.106092) (xy 305.197992 -405.116035)
			(xy 305.257713 -405.133759) (xy 305.314676 -405.158976) (xy 305.367947 -405.191269) (xy 305.416652 -405.230109)
			(xy 305.459989 -405.274859) (xy 305.497249 -405.324783) (xy 305.527818 -405.379062) (xy 305.532285 -405.390096)
			(xy 306.803814 -405.390096) (xy 306.807805 -405.327929) (xy 306.819714 -405.266782) (xy 306.839343 -405.207661)
			(xy 306.866372 -405.151535) (xy 306.900356 -405.099326) (xy 306.940738 -405.051891) (xy 306.986854 -405.01001)
			(xy 307.037946 -404.97437) (xy 307.093177 -404.945556) (xy 307.151639 -404.924042) (xy 307.212373 -404.91018)
			(xy 307.27438 -404.904198) (xy 307.336643 -404.906194) (xy 307.39814 -404.916137) (xy 307.457861 -404.933861)
			(xy 307.514824 -404.959078) (xy 307.568095 -404.991371) (xy 307.6168 -405.030211) (xy 307.660137 -405.074961)
			(xy 307.697397 -405.124885) (xy 307.727966 -405.179164) (xy 307.751344 -405.236907) (xy 307.767145 -405.297165)
			(xy 307.775111 -405.358948) (xy 307.77561 -405.390096) (xy 307.775111 -405.421244) (xy 307.767145 -405.483027)
			(xy 307.751344 -405.543285) (xy 307.727966 -405.601028) (xy 307.697397 -405.655307) (xy 307.660137 -405.705231)
			(xy 307.6168 -405.749981) (xy 307.568095 -405.788821) (xy 307.514824 -405.821114) (xy 307.457861 -405.846331)
			(xy 307.39814 -405.864055) (xy 307.336643 -405.873998) (xy 307.27438 -405.875994) (xy 307.212373 -405.870012)
			(xy 307.151639 -405.85615) (xy 307.093177 -405.834636) (xy 307.037946 -405.805822) (xy 306.986854 -405.770182)
			(xy 306.940738 -405.728301) (xy 306.900356 -405.680866) (xy 306.866372 -405.628657) (xy 306.839343 -405.572531)
			(xy 306.819714 -405.51341) (xy 306.807805 -405.452263) (xy 306.803814 -405.390096) (xy 305.532285 -405.390096)
			(xy 305.551196 -405.436805) (xy 305.566997 -405.497063) (xy 305.574963 -405.558846) (xy 305.575462 -405.589994)
			(xy 305.574963 -405.621142) (xy 305.566997 -405.682925) (xy 305.551196 -405.743183) (xy 305.527818 -405.800926)
			(xy 305.497249 -405.855205) (xy 305.459989 -405.905129) (xy 305.416652 -405.949879) (xy 305.367947 -405.988719)
			(xy 305.314676 -406.021012) (xy 305.257713 -406.046229) (xy 305.197992 -406.063953) (xy 305.136495 -406.073896)
			(xy 305.074232 -406.075892) (xy 305.012225 -406.06991) (xy 304.951491 -406.056048) (xy 304.893029 -406.034534)
			(xy 304.837798 -406.00572) (xy 304.786706 -405.97008) (xy 304.74059 -405.928199) (xy 304.700208 -405.880764)
			(xy 304.666224 -405.828555) (xy 304.639195 -405.772429) (xy 304.619566 -405.713308) (xy 304.607657 -405.652161)
			(xy 304.603666 -405.589994) (xy 303.332024 -405.589994) (xy 303.323072 -405.610914) (xy 303.306734 -405.63927)
			(xy 303.303379 -405.64529) (xy 303.299638 -405.658546) (xy 303.299368 -405.665432) (xy 303.299368 -406.414732)
			(xy 303.299597 -406.421625) (xy 303.303328 -406.434897) (xy 303.306734 -406.440894) (xy 303.323045 -406.469265)
			(xy 303.348793 -406.529428) (xy 303.366223 -406.592505) (xy 303.37502 -406.657352) (xy 303.375022 -406.690068)
			(xy 306.803814 -406.690068) (xy 306.807805 -406.627901) (xy 306.819714 -406.566754) (xy 306.839343 -406.507633)
			(xy 306.866372 -406.451507) (xy 306.900356 -406.399298) (xy 306.940738 -406.351863) (xy 306.986854 -406.309982)
			(xy 307.037946 -406.274342) (xy 307.093177 -406.245528) (xy 307.151639 -406.224014) (xy 307.212373 -406.210152)
			(xy 307.27438 -406.20417) (xy 307.336643 -406.206166) (xy 307.39814 -406.216109) (xy 307.457861 -406.233833)
			(xy 307.514824 -406.25905) (xy 307.568095 -406.291343) (xy 307.6168 -406.330183) (xy 307.660137 -406.374933)
			(xy 307.697397 -406.424857) (xy 307.727966 -406.479136) (xy 307.751344 -406.536879) (xy 307.767145 -406.597137)
			(xy 307.775111 -406.65892) (xy 307.77561 -406.690068) (xy 307.775111 -406.721216) (xy 307.767145 -406.782999)
			(xy 307.751344 -406.843257) (xy 307.727966 -406.901) (xy 307.697397 -406.955279) (xy 307.660137 -407.005203)
			(xy 307.6168 -407.049953) (xy 307.568095 -407.088793) (xy 307.514824 -407.121086) (xy 307.457861 -407.146303)
			(xy 307.39814 -407.164027) (xy 307.336643 -407.17397) (xy 307.27438 -407.175966) (xy 307.212373 -407.169984)
			(xy 307.151639 -407.156122) (xy 307.093177 -407.134608) (xy 307.037946 -407.105794) (xy 306.986854 -407.070154)
			(xy 306.940738 -407.028273) (xy 306.900356 -406.980838) (xy 306.866372 -406.928629) (xy 306.839343 -406.872503)
			(xy 306.819714 -406.813382) (xy 306.807805 -406.752235) (xy 306.803814 -406.690068) (xy 303.375022 -406.690068)
			(xy 303.375024 -406.722793) (xy 303.366234 -406.787641) (xy 303.348811 -406.85072) (xy 303.32307 -406.910886)
			(xy 303.306734 -406.939242) (xy 303.303354 -406.945249) (xy 303.299629 -406.958516) (xy 303.299368 -406.965404)
			(xy 303.299368 -407.251408) (xy 303.29899 -407.261535) (xy 303.291233 -407.280245) (xy 303.276904 -407.29456)
			(xy 303.258187 -407.302299) (xy 303.24806 -407.302716) (xy 302.53178 -407.302716) (xy 302.521672 -407.302232)
			(xy 302.502996 -407.294491) (xy 302.488703 -407.280194) (xy 302.480966 -407.261516) (xy 302.480472 -407.251408)
			(xy 302.480472 -406.965404) (xy 302.480241 -406.958512) (xy 302.476498 -406.945246) (xy 302.473106 -406.939242)
			(xy 302.456743 -406.9109) (xy 302.431003 -406.85073) (xy 302.413581 -406.787647) (xy 302.404792 -406.722795)
			(xy 298.974974 -406.722795) (xy 298.966185 -406.78764) (xy 298.948764 -406.850719) (xy 298.923026 -406.910886)
			(xy 298.906692 -406.939242) (xy 298.903362 -406.945259) (xy 298.899766 -406.958529) (xy 298.89958 -406.965404)
			(xy 298.89958 -407.251408) (xy 298.899184 -407.261565) (xy 298.891382 -407.280321) (xy 298.876978 -407.294645)
			(xy 298.858177 -407.302341) (xy 298.848018 -407.302716) (xy 298.131738 -407.302716) (xy 298.121608 -407.302241)
			(xy 298.10288 -407.294517) (xy 298.088521 -407.280227) (xy 298.080708 -407.261535) (xy 298.080176 -407.251408)
			(xy 298.080176 -406.965404) (xy 298.079985 -406.958531) (xy 298.076376 -406.945268) (xy 298.073064 -406.939242)
			(xy 298.056699 -406.910901) (xy 298.030956 -406.850731) (xy 298.013532 -406.787648) (xy 298.004742 -406.722795)
			(xy 294.574938 -406.722795) (xy 294.566148 -406.787641) (xy 294.548726 -406.85072) (xy 294.522986 -406.910886)
			(xy 294.50665 -406.939242) (xy 294.503271 -406.94525) (xy 294.499545 -406.958516) (xy 294.499284 -406.965404)
			(xy 294.499284 -407.251408) (xy 294.49889 -407.261533) (xy 294.491136 -407.28024) (xy 294.476813 -407.294554)
			(xy 294.458101 -407.302296) (xy 294.447976 -407.302716) (xy 293.731696 -407.302716) (xy 293.721589 -407.302218)
			(xy 293.702914 -407.294482) (xy 293.68862 -407.28019) (xy 293.680882 -407.261515) (xy 293.680388 -407.251408)
			(xy 293.680388 -406.965404) (xy 293.680155 -406.958513) (xy 293.676413 -406.945247) (xy 293.673022 -406.939242)
			(xy 293.656658 -406.910901) (xy 293.630918 -406.85073) (xy 293.613495 -406.787647) (xy 293.604705 -406.722795)
			(xy 290.174901 -406.722795) (xy 290.166112 -406.787642) (xy 290.148687 -406.850721) (xy 290.122945 -406.910886)
			(xy 290.106608 -406.939242) (xy 290.103279 -406.94526) (xy 290.099682 -406.958529) (xy 290.099496 -406.965404)
			(xy 290.099496 -407.251408) (xy 290.099085 -407.261563) (xy 290.091286 -407.280316) (xy 290.076886 -407.29464)
			(xy 290.058091 -407.302338) (xy 290.047934 -407.302716) (xy 289.331654 -407.302716) (xy 289.321519 -407.30231)
			(xy 289.302788 -407.294559) (xy 289.288432 -407.280248) (xy 289.280622 -407.261541) (xy 289.280092 -407.251408)
			(xy 289.280092 -406.965404) (xy 289.2799 -406.958531) (xy 289.276292 -406.945268) (xy 289.27298 -406.939242)
			(xy 289.256614 -406.910901) (xy 289.230871 -406.850731) (xy 289.213446 -406.787648) (xy 289.204655 -406.722795)
			(xy 283.304488 -406.722795) (xy 283.304488 -409.522892) (xy 287.004758 -409.522892) (xy 287.004762 -409.457446)
			(xy 287.013561 -409.392594) (xy 287.030994 -409.329513) (xy 287.056745 -409.269346) (xy 287.073086 -409.24099)
			(xy 287.076449 -409.234974) (xy 287.080186 -409.221715) (xy 287.080452 -409.214828) (xy 287.080452 -408.465528)
			(xy 287.080236 -408.458634) (xy 287.076496 -408.445362) (xy 287.073086 -408.439366) (xy 287.05674 -408.411014)
			(xy 287.030995 -408.350847) (xy 287.013567 -408.287766) (xy 287.004774 -408.222915) (xy 287.004775 -408.157471)
			(xy 287.01357 -408.092621) (xy 287.030999 -408.02954) (xy 287.056747 -407.969374) (xy 287.073086 -407.941018)
			(xy 287.076439 -407.934997) (xy 287.080183 -407.921741) (xy 287.080452 -407.914856) (xy 287.080452 -407.628852)
			(xy 287.080945 -407.618746) (xy 287.088689 -407.600076) (xy 287.102983 -407.585785) (xy 287.121654 -407.578043)
			(xy 287.13176 -407.577544) (xy 287.84804 -407.577544) (xy 287.858144 -407.578051) (xy 287.876813 -407.585791)
			(xy 287.891104 -407.600081) (xy 287.898847 -407.618748) (xy 287.899348 -407.628852) (xy 287.899348 -407.914856)
			(xy 287.89957 -407.92175) (xy 287.903306 -407.935022) (xy 287.906714 -407.941018) (xy 287.923046 -407.969377)
			(xy 287.948793 -408.029543) (xy 287.966222 -408.092622) (xy 287.975017 -408.157472) (xy 287.975018 -408.222915)
			(xy 287.966225 -408.287764) (xy 287.948798 -408.350844) (xy 287.923052 -408.41101) (xy 287.906714 -408.439366)
			(xy 287.903367 -408.44539) (xy 287.89962 -408.458643) (xy 287.899348 -408.465528) (xy 287.899348 -409.214828)
			(xy 287.899581 -409.221721) (xy 287.903309 -409.234993) (xy 287.906714 -409.24099) (xy 287.923022 -409.269363)
			(xy 287.948772 -409.329525) (xy 287.966203 -409.392602) (xy 287.975001 -409.457449) (xy 287.975005 -409.52289)
			(xy 287.966215 -409.587738) (xy 287.948792 -409.650817) (xy 287.92305 -409.710982) (xy 287.906714 -409.739338)
			(xy 287.903341 -409.745349) (xy 287.89961 -409.758612) (xy 287.899348 -409.7655) (xy 287.899348 -410.051504)
			(xy 287.898819 -410.061607) (xy 287.891089 -410.080276) (xy 287.876806 -410.094569) (xy 287.858143 -410.102312)
			(xy 287.84804 -410.102812) (xy 287.13176 -410.102812) (xy 287.12165 -410.102348) (xy 287.102973 -410.094599)
			(xy 287.08868 -410.080296) (xy 287.080945 -410.061614) (xy 287.080452 -410.051504) (xy 287.080452 -409.7655)
			(xy 287.080247 -409.758605) (xy 287.076499 -409.745333) (xy 287.073086 -409.739338) (xy 287.056717 -409.710999)
			(xy 287.030973 -409.650829) (xy 287.013548 -409.587745) (xy 287.004758 -409.522892) (xy 283.304488 -409.522892)
			(xy 283.304488 -410.622709) (xy 289.204665 -410.622709) (xy 289.204666 -410.557264) (xy 289.213462 -410.492413)
			(xy 289.230892 -410.429332) (xy 289.25664 -410.369166) (xy 289.27298 -410.34081) (xy 289.27629 -410.334783)
			(xy 289.279899 -410.321521) (xy 289.280092 -410.314648) (xy 289.280092 -409.565348) (xy 289.279883 -409.558476)
			(xy 289.276286 -409.545213) (xy 289.27298 -409.539186) (xy 289.256652 -409.510825) (xy 289.230905 -409.45066)
			(xy 289.213475 -409.387581) (xy 289.20468 -409.322732) (xy 289.204679 -409.257289) (xy 289.213471 -409.19244)
			(xy 289.230898 -409.12936) (xy 289.256642 -409.069194) (xy 289.27298 -409.040838) (xy 289.27628 -409.034806)
			(xy 289.279895 -409.021548) (xy 289.280092 -409.014676) (xy 289.280092 -408.728672) (xy 289.280498 -408.718517)
			(xy 289.288302 -408.699766) (xy 289.302703 -408.685443) (xy 289.321497 -408.677743) (xy 289.331654 -408.677364)
			(xy 290.047934 -408.677364) (xy 290.058066 -408.677799) (xy 290.076792 -408.685543) (xy 290.091148 -408.699845)
			(xy 290.098962 -408.718542) (xy 290.099496 -408.728672) (xy 290.099496 -409.014676) (xy 290.099697 -409.021549)
			(xy 290.103299 -409.034811) (xy 290.106608 -409.040838) (xy 290.122957 -409.069188) (xy 290.148703 -409.129356)
			(xy 290.16613 -409.192437) (xy 290.174923 -409.257288) (xy 290.174921 -409.322733) (xy 290.166126 -409.387583)
			(xy 290.148696 -409.450664) (xy 290.122948 -409.51083) (xy 290.115997 -409.522892) (xy 291.404808 -409.522892)
			(xy 291.404813 -409.457446) (xy 291.41361 -409.392595) (xy 291.43104 -409.329514) (xy 291.456789 -409.269346)
			(xy 291.473128 -409.24099) (xy 291.476448 -409.234968) (xy 291.48005 -409.221702) (xy 291.48024 -409.214828)
			(xy 291.48024 -408.465528) (xy 291.480032 -408.458656) (xy 291.476434 -408.445393) (xy 291.473128 -408.439366)
			(xy 291.456784 -408.411013) (xy 291.431042 -408.350846) (xy 291.413616 -408.287765) (xy 291.404824 -408.222915)
			(xy 291.404825 -408.157471) (xy 291.413619 -408.092622) (xy 291.431046 -408.029541) (xy 291.45679 -407.969374)
			(xy 291.473128 -407.941018) (xy 291.476438 -407.934991) (xy 291.480046 -407.921729) (xy 291.48024 -407.914856)
			(xy 291.48024 -407.628852) (xy 291.480583 -407.61869) (xy 291.488402 -407.599929) (xy 291.502823 -407.585606)
			(xy 291.521637 -407.577915) (xy 291.531802 -407.577544) (xy 292.248082 -407.577544) (xy 292.258208 -407.578041)
			(xy 292.27693 -407.585764) (xy 292.291287 -407.600047) (xy 292.299106 -407.618729) (xy 292.299644 -407.628852)
			(xy 292.299644 -407.914856) (xy 292.299847 -407.921728) (xy 292.303447 -407.934991) (xy 292.306756 -407.941018)
			(xy 292.323087 -407.969378) (xy 292.348832 -408.029544) (xy 292.366259 -408.092623) (xy 292.375053 -408.157472)
			(xy 292.375054 -408.222914) (xy 292.366262 -408.287764) (xy 292.348836 -408.350843) (xy 292.323093 -408.41101)
			(xy 292.306756 -408.439366) (xy 292.303458 -408.445399) (xy 292.299841 -408.458656) (xy 292.299644 -408.465528)
			(xy 292.299644 -409.214828) (xy 292.29982 -409.221703) (xy 292.303439 -409.234965) (xy 292.306756 -409.24099)
			(xy 292.323063 -409.269363) (xy 292.34881 -409.329526) (xy 292.36624 -409.392602) (xy 292.375037 -409.457449)
			(xy 292.375041 -409.522889) (xy 292.366252 -409.587737) (xy 292.34883 -409.650816) (xy 292.323091 -409.710982)
			(xy 292.306756 -409.739338) (xy 292.303432 -409.745358) (xy 292.299832 -409.758625) (xy 292.299644 -409.7655)
			(xy 292.299644 -410.051504) (xy 292.299182 -410.061653) (xy 292.291394 -410.080397) (xy 292.27701 -410.094718)
			(xy 292.258233 -410.102426) (xy 292.248082 -410.102812) (xy 291.531802 -410.102812) (xy 291.521682 -410.102273)
			(xy 291.502971 -410.094556) (xy 291.488616 -410.080286) (xy 291.480788 -410.061621) (xy 291.48024 -410.051504)
			(xy 291.48024 -409.7655) (xy 291.480043 -409.758627) (xy 291.476438 -409.745365) (xy 291.473128 -409.739338)
			(xy 291.45676 -409.710999) (xy 291.43102 -409.650828) (xy 291.413597 -409.587744) (xy 291.404808 -409.522892)
			(xy 290.115997 -409.522892) (xy 290.106608 -409.539186) (xy 290.103299 -409.545213) (xy 290.09969 -409.558475)
			(xy 290.099496 -409.565348) (xy 290.099496 -410.314648) (xy 290.099709 -410.32152) (xy 290.103303 -410.334782)
			(xy 290.106608 -410.34081) (xy 290.122933 -410.369173) (xy 290.148681 -410.429338) (xy 290.166111 -410.492416)
			(xy 290.174907 -410.557265) (xy 290.174909 -410.622708) (xy 293.604715 -410.622708) (xy 293.604716 -410.557264)
			(xy 293.613511 -410.492414) (xy 293.630939 -410.429334) (xy 293.656684 -410.369166) (xy 293.673022 -410.34081)
			(xy 293.67638 -410.334792) (xy 293.68012 -410.321534) (xy 293.680388 -410.314648) (xy 293.680388 -409.565348)
			(xy 293.680138 -409.558458) (xy 293.676407 -409.545192) (xy 293.673022 -409.539186) (xy 293.656695 -409.510824)
			(xy 293.630951 -409.450658) (xy 293.613524 -409.38758) (xy 293.604731 -409.322731) (xy 293.604729 -409.257289)
			(xy 293.61352 -409.192441) (xy 293.630945 -409.129361) (xy 293.656686 -409.069194) (xy 293.673022 -409.040838)
			(xy 293.676406 -409.034833) (xy 293.680129 -409.021565) (xy 293.680388 -409.014676) (xy 293.680388 -408.728672)
			(xy 293.680862 -408.718563) (xy 293.688606 -408.699886) (xy 293.702907 -408.685593) (xy 293.721587 -408.677857)
			(xy 293.731696 -408.677364) (xy 294.447976 -408.677364) (xy 294.458079 -408.677904) (xy 294.47675 -408.685627)
			(xy 294.491044 -408.699907) (xy 294.498786 -408.71857) (xy 294.499284 -408.728672) (xy 294.499284 -409.014676)
			(xy 294.499493 -409.021571) (xy 294.503237 -409.034843) (xy 294.50665 -409.040838) (xy 294.522998 -409.069188)
			(xy 294.548741 -409.129356) (xy 294.566167 -409.192438) (xy 294.574959 -409.257288) (xy 294.574958 -409.322732)
			(xy 294.566163 -409.387583) (xy 294.548735 -409.450663) (xy 294.522989 -409.51083) (xy 294.516039 -409.522892)
			(xy 295.804845 -409.522892) (xy 295.804849 -409.457446) (xy 295.813647 -409.392594) (xy 295.831079 -409.329513)
			(xy 295.856829 -409.269346) (xy 295.87317 -409.24099) (xy 295.876539 -409.234978) (xy 295.880271 -409.221715)
			(xy 295.880536 -409.214828) (xy 295.880536 -408.465528) (xy 295.880322 -408.458634) (xy 295.876581 -408.445362)
			(xy 295.87317 -408.439366) (xy 295.856825 -408.411014) (xy 295.83108 -408.350847) (xy 295.813653 -408.287766)
			(xy 295.80486 -408.222915) (xy 295.804861 -408.157471) (xy 295.813656 -408.092621) (xy 295.831085 -408.02954)
			(xy 295.856831 -407.969374) (xy 295.87317 -407.941018) (xy 295.87653 -407.935001) (xy 295.880268 -407.921742)
			(xy 295.880536 -407.914856) (xy 295.880536 -407.628852) (xy 295.880947 -407.618736) (xy 295.888707 -407.60005)
			(xy 295.903027 -407.585755) (xy 295.921727 -407.578029) (xy 295.931844 -407.577544) (xy 296.648124 -407.577544)
			(xy 296.658227 -407.578064) (xy 296.676895 -407.585799) (xy 296.691187 -407.600084) (xy 296.698931 -407.618749)
			(xy 296.699432 -407.628852) (xy 296.699432 -407.914856) (xy 296.699656 -407.921749) (xy 296.703391 -407.935021)
			(xy 296.706798 -407.941018) (xy 296.723127 -407.969378) (xy 296.74887 -408.029544) (xy 296.766296 -408.092624)
			(xy 296.775089 -408.157472) (xy 296.77509 -408.222914) (xy 296.766299 -408.287763) (xy 296.748875 -408.350843)
			(xy 296.723134 -408.411009) (xy 296.706798 -408.439366) (xy 296.703449 -408.445389) (xy 296.699703 -408.458643)
			(xy 296.699432 -408.465528) (xy 296.699432 -409.214828) (xy 296.699667 -409.221721) (xy 296.703394 -409.234993)
			(xy 296.706798 -409.24099) (xy 296.723104 -409.269363) (xy 296.748848 -409.329527) (xy 296.766277 -409.392603)
			(xy 296.775073 -409.457449) (xy 296.775077 -409.522889) (xy 296.766289 -409.587736) (xy 296.748869 -409.650815)
			(xy 296.723132 -409.710981) (xy 296.706798 -409.739338) (xy 296.703424 -409.745348) (xy 296.699694 -409.758612)
			(xy 296.699432 -409.7655) (xy 296.699432 -410.051504) (xy 296.698919 -410.061609) (xy 296.691186 -410.080281)
			(xy 296.676898 -410.094575) (xy 296.658229 -410.102315) (xy 296.648124 -410.102812) (xy 295.931844 -410.102812)
			(xy 295.921726 -410.102348) (xy 295.903026 -410.094617) (xy 295.88871 -410.080315) (xy 295.880961 -410.061622)
			(xy 295.880536 -410.051504) (xy 295.880536 -409.7655) (xy 295.880333 -409.758605) (xy 295.876584 -409.745333)
			(xy 295.87317 -409.739338) (xy 295.856801 -409.710999) (xy 295.831058 -409.650829) (xy 295.813634 -409.587745)
			(xy 295.804845 -409.522892) (xy 294.516039 -409.522892) (xy 294.50665 -409.539186) (xy 294.503291 -409.545204)
			(xy 294.499552 -409.558462) (xy 294.499284 -409.565348) (xy 294.499284 -410.314648) (xy 294.499505 -410.321542)
			(xy 294.503241 -410.334814) (xy 294.50665 -410.34081) (xy 294.522974 -410.369174) (xy 294.54872 -410.429338)
			(xy 294.566148 -410.492417) (xy 294.574943 -410.557265) (xy 294.574945 -410.622707) (xy 294.574945 -410.622708)
			(xy 298.004751 -410.622708) (xy 298.004753 -410.557264) (xy 298.013548 -410.492413) (xy 298.030977 -410.429333)
			(xy 298.056725 -410.369166) (xy 298.073064 -410.34081) (xy 298.076372 -410.334782) (xy 298.079982 -410.321521)
			(xy 298.080176 -410.314648) (xy 298.080176 -409.565348) (xy 298.079969 -409.558476) (xy 298.076371 -409.545213)
			(xy 298.073064 -409.539186) (xy 298.056736 -409.510824) (xy 298.03099 -409.450659) (xy 298.013561 -409.38758)
			(xy 298.004767 -409.322732) (xy 298.004765 -409.257289) (xy 298.013557 -409.19244) (xy 298.030983 -409.12936)
			(xy 298.056727 -409.069194) (xy 298.073064 -409.040838) (xy 298.076362 -409.034805) (xy 298.079979 -409.021548)
			(xy 298.080176 -409.014676) (xy 298.080176 -408.728672) (xy 298.080598 -408.718519) (xy 298.088398 -408.699771)
			(xy 298.102794 -408.685449) (xy 298.121583 -408.677746) (xy 298.131738 -408.677364) (xy 298.848018 -408.677364)
			(xy 298.858149 -408.677812) (xy 298.876875 -408.68555) (xy 298.891232 -408.699849) (xy 298.899046 -408.718543)
			(xy 298.89958 -408.728672) (xy 298.89958 -409.014676) (xy 298.899783 -409.021548) (xy 298.903384 -409.034811)
			(xy 298.906692 -409.040838) (xy 298.923039 -409.069189) (xy 298.94878 -409.129357) (xy 298.966204 -409.192438)
			(xy 298.974995 -409.257289) (xy 298.974994 -409.322732) (xy 298.9662 -409.387582) (xy 298.948773 -409.450662)
			(xy 298.923029 -409.510829) (xy 298.916079 -409.522892) (xy 300.204634 -409.522892) (xy 300.204638 -409.457446)
			(xy 300.213436 -409.392595) (xy 300.230868 -409.329513) (xy 300.256618 -409.269346) (xy 300.272958 -409.24099)
			(xy 300.276326 -409.234977) (xy 300.280059 -409.221715) (xy 300.280324 -409.214828) (xy 300.280324 -408.465528)
			(xy 300.280112 -408.458633) (xy 300.27637 -408.445361) (xy 300.272958 -408.439366) (xy 300.256613 -408.411014)
			(xy 300.230869 -408.350846) (xy 300.213443 -408.287765) (xy 300.20465 -408.222915) (xy 300.204651 -408.157471)
			(xy 300.213445 -408.092621) (xy 300.230874 -408.029541) (xy 300.25662 -407.969374) (xy 300.272958 -407.941018)
			(xy 300.276317 -407.935) (xy 300.280056 -407.921742) (xy 300.280324 -407.914856) (xy 300.280324 -407.628852)
			(xy 300.280747 -407.618737) (xy 300.288504 -407.600053) (xy 300.302821 -407.585759) (xy 300.321516 -407.578031)
			(xy 300.331632 -407.577544) (xy 301.047912 -407.577544) (xy 301.058015 -407.578074) (xy 301.076682 -407.585805)
			(xy 301.090975 -407.600088) (xy 301.098719 -407.61875) (xy 301.09922 -407.628852) (xy 301.09922 -407.914856)
			(xy 301.099467 -407.921746) (xy 301.1032 -407.935012) (xy 301.106586 -407.941018) (xy 301.122916 -407.969378)
			(xy 301.148659 -408.029544) (xy 301.166085 -408.092623) (xy 301.174879 -408.157472) (xy 301.174879 -408.190192)
			(xy 304.603666 -408.190192) (xy 304.607657 -408.128025) (xy 304.619566 -408.066878) (xy 304.639195 -408.007757)
			(xy 304.666224 -407.951631) (xy 304.700208 -407.899422) (xy 304.74059 -407.851987) (xy 304.786706 -407.810106)
			(xy 304.837798 -407.774466) (xy 304.893029 -407.745652) (xy 304.951491 -407.724138) (xy 305.012225 -407.710276)
			(xy 305.074232 -407.704294) (xy 305.136495 -407.70629) (xy 305.197992 -407.716233) (xy 305.257713 -407.733957)
			(xy 305.314676 -407.759174) (xy 305.367947 -407.791467) (xy 305.416652 -407.830307) (xy 305.459989 -407.875057)
			(xy 305.497249 -407.924981) (xy 305.527818 -407.97926) (xy 305.551196 -408.037003) (xy 305.566997 -408.097261)
			(xy 305.574963 -408.159044) (xy 305.575462 -408.190192) (xy 305.574963 -408.22134) (xy 305.566997 -408.283123)
			(xy 305.551196 -408.343381) (xy 305.527818 -408.401124) (xy 305.497249 -408.455403) (xy 305.459989 -408.505327)
			(xy 305.416652 -408.550077) (xy 305.367947 -408.588917) (xy 305.314676 -408.62121) (xy 305.257713 -408.646427)
			(xy 305.197992 -408.664151) (xy 305.136495 -408.674094) (xy 305.074232 -408.67609) (xy 305.012225 -408.670108)
			(xy 304.951491 -408.656246) (xy 304.893029 -408.634732) (xy 304.837798 -408.605918) (xy 304.786706 -408.570278)
			(xy 304.74059 -408.528397) (xy 304.700208 -408.480962) (xy 304.666224 -408.428753) (xy 304.639195 -408.372627)
			(xy 304.619566 -408.313506) (xy 304.607657 -408.252359) (xy 304.603666 -408.190192) (xy 301.174879 -408.190192)
			(xy 301.17488 -408.222914) (xy 301.166088 -408.287763) (xy 301.148664 -408.350843) (xy 301.122922 -408.41101)
			(xy 301.106586 -408.439366) (xy 301.103237 -408.445388) (xy 301.099491 -408.458643) (xy 301.09922 -408.465528)
			(xy 301.09922 -409.214828) (xy 301.099479 -409.221717) (xy 301.103204 -409.234983) (xy 301.106586 -409.24099)
			(xy 301.122892 -409.269363) (xy 301.148638 -409.329526) (xy 301.166066 -409.392603) (xy 301.174863 -409.457449)
			(xy 301.174867 -409.522889) (xy 301.166079 -409.587737) (xy 301.148658 -409.650815) (xy 301.12292 -409.710982)
			(xy 301.106586 -409.739338) (xy 301.103211 -409.745348) (xy 301.099482 -409.758612) (xy 301.09922 -409.7655)
			(xy 301.09922 -410.051504) (xy 301.098719 -410.06161) (xy 301.090983 -410.080285) (xy 301.076692 -410.094579)
			(xy 301.058018 -410.102317) (xy 301.047912 -410.102812) (xy 300.331632 -410.102812) (xy 300.321513 -410.102358)
			(xy 300.302812 -410.094623) (xy 300.288497 -410.080318) (xy 300.280749 -410.061623) (xy 300.280324 -410.051504)
			(xy 300.280324 -409.7655) (xy 300.280123 -409.758605) (xy 300.276373 -409.745333) (xy 300.272958 -409.739338)
			(xy 300.25659 -409.710999) (xy 300.230847 -409.650828) (xy 300.213424 -409.587745) (xy 300.204634 -409.522892)
			(xy 298.916079 -409.522892) (xy 298.906692 -409.539186) (xy 298.903382 -409.545213) (xy 298.899773 -409.558475)
			(xy 298.89958 -409.565348) (xy 298.89958 -410.314648) (xy 298.899794 -410.32152) (xy 298.903387 -410.334782)
			(xy 298.906692 -410.34081) (xy 298.923015 -410.369174) (xy 298.948758 -410.429339) (xy 298.966185 -410.492418)
			(xy 298.974979 -410.557266) (xy 298.974981 -410.622707) (xy 298.974981 -410.622708) (xy 302.404801 -410.622708)
			(xy 302.404803 -410.557264) (xy 302.413597 -410.492414) (xy 302.431024 -410.429334) (xy 302.456769 -410.369167)
			(xy 302.473106 -410.34081) (xy 302.476463 -410.334791) (xy 302.480204 -410.321534) (xy 302.480472 -410.314648)
			(xy 302.480472 -409.565348) (xy 302.480246 -409.558455) (xy 302.476512 -409.545183) (xy 302.473106 -409.539186)
			(xy 302.45678 -409.510824) (xy 302.431037 -409.450658) (xy 302.41361 -409.387579) (xy 302.404817 -409.322731)
			(xy 302.404815 -409.257289) (xy 302.413606 -409.192441) (xy 302.43103 -409.129361) (xy 302.45677 -409.069195)
			(xy 302.473106 -409.040838) (xy 302.476488 -409.034832) (xy 302.480213 -409.021565) (xy 302.480472 -409.014676)
			(xy 302.480472 -408.728672) (xy 302.480961 -408.718565) (xy 302.488703 -408.699891) (xy 302.502998 -408.685599)
			(xy 302.521673 -408.67786) (xy 302.53178 -408.677364) (xy 303.24806 -408.677364) (xy 303.258175 -408.677848)
			(xy 303.276871 -408.685576) (xy 303.291186 -408.699872) (xy 303.298939 -408.718557) (xy 303.299368 -408.728672)
			(xy 303.299368 -409.014676) (xy 303.299579 -409.021571) (xy 303.303322 -409.034843) (xy 303.306734 -409.040838)
			(xy 303.323082 -409.069188) (xy 303.348827 -409.129356) (xy 303.366253 -409.192437) (xy 303.375045 -409.257288)
			(xy 303.375044 -409.322732) (xy 303.366249 -409.387583) (xy 303.34882 -409.450663) (xy 303.331917 -409.490164)
			(xy 304.603666 -409.490164) (xy 304.607657 -409.427997) (xy 304.619566 -409.36685) (xy 304.639195 -409.307729)
			(xy 304.666224 -409.251603) (xy 304.700208 -409.199394) (xy 304.74059 -409.151959) (xy 304.786706 -409.110078)
			(xy 304.837798 -409.074438) (xy 304.893029 -409.045624) (xy 304.951491 -409.02411) (xy 305.012225 -409.010248)
			(xy 305.074232 -409.004266) (xy 305.136495 -409.006262) (xy 305.197992 -409.016205) (xy 305.257713 -409.033929)
			(xy 305.314676 -409.059146) (xy 305.367947 -409.091439) (xy 305.416652 -409.130279) (xy 305.459989 -409.175029)
			(xy 305.497249 -409.224953) (xy 305.527818 -409.279232) (xy 305.532182 -409.290012) (xy 306.803814 -409.290012)
			(xy 306.807805 -409.227845) (xy 306.819714 -409.166698) (xy 306.839343 -409.107577) (xy 306.866372 -409.051451)
			(xy 306.900356 -408.999242) (xy 306.940738 -408.951807) (xy 306.986854 -408.909926) (xy 307.037946 -408.874286)
			(xy 307.093177 -408.845472) (xy 307.151639 -408.823958) (xy 307.212373 -408.810096) (xy 307.27438 -408.804114)
			(xy 307.336643 -408.80611) (xy 307.39814 -408.816053) (xy 307.457861 -408.833777) (xy 307.514824 -408.858994)
			(xy 307.568095 -408.891287) (xy 307.6168 -408.930127) (xy 307.660137 -408.974877) (xy 307.697397 -409.024801)
			(xy 307.727966 -409.07908) (xy 307.751344 -409.136823) (xy 307.767145 -409.197081) (xy 307.775111 -409.258864)
			(xy 307.77561 -409.290012) (xy 307.775111 -409.32116) (xy 307.767145 -409.382943) (xy 307.751344 -409.443201)
			(xy 307.727966 -409.500944) (xy 307.697397 -409.555223) (xy 307.660137 -409.605147) (xy 307.6168 -409.649897)
			(xy 307.568095 -409.688737) (xy 307.514824 -409.72103) (xy 307.457861 -409.746247) (xy 307.39814 -409.763971)
			(xy 307.336643 -409.773914) (xy 307.27438 -409.77591) (xy 307.212373 -409.769928) (xy 307.151639 -409.756066)
			(xy 307.093177 -409.734552) (xy 307.037946 -409.705738) (xy 306.986854 -409.670098) (xy 306.940738 -409.628217)
			(xy 306.900356 -409.580782) (xy 306.866372 -409.528573) (xy 306.839343 -409.472447) (xy 306.819714 -409.413326)
			(xy 306.807805 -409.352179) (xy 306.803814 -409.290012) (xy 305.532182 -409.290012) (xy 305.551196 -409.336975)
			(xy 305.566997 -409.397233) (xy 305.574963 -409.459016) (xy 305.575462 -409.490164) (xy 305.574963 -409.521312)
			(xy 305.566997 -409.583095) (xy 305.551196 -409.643353) (xy 305.527818 -409.701096) (xy 305.497249 -409.755375)
			(xy 305.459989 -409.805299) (xy 305.416652 -409.850049) (xy 305.367947 -409.888889) (xy 305.314676 -409.921182)
			(xy 305.257713 -409.946399) (xy 305.197992 -409.964123) (xy 305.136495 -409.974066) (xy 305.074232 -409.976062)
			(xy 305.012225 -409.97008) (xy 304.951491 -409.956218) (xy 304.893029 -409.934704) (xy 304.837798 -409.90589)
			(xy 304.786706 -409.87025) (xy 304.74059 -409.828369) (xy 304.700208 -409.780934) (xy 304.666224 -409.728725)
			(xy 304.639195 -409.672599) (xy 304.619566 -409.613478) (xy 304.607657 -409.552331) (xy 304.603666 -409.490164)
			(xy 303.331917 -409.490164) (xy 303.323073 -409.51083) (xy 303.306734 -409.539186) (xy 303.303373 -409.545203)
			(xy 303.299636 -409.558462) (xy 303.299368 -409.565348) (xy 303.299368 -410.314648) (xy 303.29959 -410.321542)
			(xy 303.303326 -410.334814) (xy 303.306734 -410.34081) (xy 303.323059 -410.369173) (xy 303.348805 -410.429338)
			(xy 303.366234 -410.492417) (xy 303.375029 -410.557265) (xy 303.37503 -410.589984) (xy 306.803814 -410.589984)
			(xy 306.807805 -410.527817) (xy 306.819714 -410.46667) (xy 306.839343 -410.407549) (xy 306.866372 -410.351423)
			(xy 306.900356 -410.299214) (xy 306.940738 -410.251779) (xy 306.986854 -410.209898) (xy 307.037946 -410.174258)
			(xy 307.093177 -410.145444) (xy 307.151639 -410.12393) (xy 307.212373 -410.110068) (xy 307.27438 -410.104086)
			(xy 307.336643 -410.106082) (xy 307.39814 -410.116025) (xy 307.457861 -410.133749) (xy 307.514824 -410.158966)
			(xy 307.568095 -410.191259) (xy 307.6168 -410.230099) (xy 307.660137 -410.274849) (xy 307.697397 -410.324773)
			(xy 307.727966 -410.379052) (xy 307.751344 -410.436795) (xy 307.767145 -410.497053) (xy 307.775111 -410.558836)
			(xy 307.77561 -410.589984) (xy 307.775111 -410.621132) (xy 307.767145 -410.682915) (xy 307.751344 -410.743173)
			(xy 307.727966 -410.800916) (xy 307.697397 -410.855195) (xy 307.660137 -410.905119) (xy 307.6168 -410.949869)
			(xy 307.568095 -410.988709) (xy 307.514824 -411.021002) (xy 307.457861 -411.046219) (xy 307.39814 -411.063943)
			(xy 307.336643 -411.073886) (xy 307.27438 -411.075882) (xy 307.212373 -411.0699) (xy 307.151639 -411.056038)
			(xy 307.093177 -411.034524) (xy 307.037946 -411.00571) (xy 306.986854 -410.97007) (xy 306.940738 -410.928189)
			(xy 306.900356 -410.880754) (xy 306.866372 -410.828545) (xy 306.839343 -410.772419) (xy 306.819714 -410.713298)
			(xy 306.807805 -410.652151) (xy 306.803814 -410.589984) (xy 303.37503 -410.589984) (xy 303.375031 -410.622707)
			(xy 303.36624 -410.687556) (xy 303.348814 -410.750636) (xy 303.323071 -410.810802) (xy 303.306734 -410.839158)
			(xy 303.303348 -410.845162) (xy 303.299626 -410.858431) (xy 303.299368 -410.86532) (xy 303.299368 -411.151324)
			(xy 303.299003 -411.161452) (xy 303.291241 -411.180162) (xy 303.276909 -411.194477) (xy 303.258189 -411.202216)
			(xy 303.24806 -411.202632) (xy 302.53178 -411.202632) (xy 302.521674 -411.202132) (xy 302.503001 -411.194394)
			(xy 302.488708 -411.180102) (xy 302.480969 -411.16143) (xy 302.480472 -411.151324) (xy 302.480472 -410.86532)
			(xy 302.480235 -410.858429) (xy 302.476496 -410.845163) (xy 302.473106 -410.839158) (xy 302.456756 -410.810809)
			(xy 302.431015 -410.75064) (xy 302.413591 -410.687559) (xy 302.404801 -410.622708) (xy 298.974981 -410.622708)
			(xy 298.966191 -410.687555) (xy 298.948767 -410.750635) (xy 298.923027 -410.810802) (xy 298.906692 -410.839158)
			(xy 298.903392 -410.84519) (xy 298.899777 -410.858448) (xy 298.89958 -410.86532) (xy 298.89958 -411.151324)
			(xy 298.899198 -411.161482) (xy 298.891391 -411.180239) (xy 298.876982 -411.194562) (xy 298.858179 -411.202258)
			(xy 298.848018 -411.202632) (xy 298.131738 -411.202632) (xy 298.12161 -411.202141) (xy 298.102885 -411.194421)
			(xy 298.088526 -411.180135) (xy 298.080711 -411.161449) (xy 298.080176 -411.151324) (xy 298.080176 -410.86532)
			(xy 298.079979 -410.858447) (xy 298.076375 -410.845184) (xy 298.073064 -410.839158) (xy 298.056712 -410.81081)
			(xy 298.030968 -410.750641) (xy 298.013542 -410.68756) (xy 298.004751 -410.622708) (xy 294.574945 -410.622708)
			(xy 294.566154 -410.687556) (xy 294.548729 -410.750636) (xy 294.522987 -410.810802) (xy 294.50665 -410.839158)
			(xy 294.503266 -410.845163) (xy 294.499543 -410.858431) (xy 294.499284 -410.86532) (xy 294.499284 -411.151324)
			(xy 294.498834 -411.161436) (xy 294.491086 -411.180118) (xy 294.476778 -411.194413) (xy 294.458089 -411.202144)
			(xy 294.447976 -411.202632) (xy 293.731696 -411.202632) (xy 293.721591 -411.202119) (xy 293.702919 -411.194386)
			(xy 293.688625 -411.180098) (xy 293.680885 -411.161429) (xy 293.680388 -411.151324) (xy 293.680388 -410.86532)
			(xy 293.680149 -410.858429) (xy 293.676411 -410.845163) (xy 293.673022 -410.839158) (xy 293.656672 -410.810809)
			(xy 293.63093 -410.750641) (xy 293.613506 -410.687559) (xy 293.604715 -410.622708) (xy 290.174909 -410.622708)
			(xy 290.166117 -410.687557) (xy 290.148691 -410.750636) (xy 290.122946 -410.810802) (xy 290.106608 -410.839158)
			(xy 290.103309 -410.84519) (xy 290.099693 -410.858448) (xy 290.099496 -410.86532) (xy 290.099496 -411.151324)
			(xy 290.099098 -411.16148) (xy 290.091294 -411.180234) (xy 290.07689 -411.194557) (xy 290.058092 -411.202255)
			(xy 290.047934 -411.202632) (xy 289.331654 -411.202632) (xy 289.321521 -411.20221) (xy 289.302793 -411.194462)
			(xy 289.288438 -411.180156) (xy 289.280625 -411.161455) (xy 289.280092 -411.151324) (xy 289.280092 -410.86532)
			(xy 289.279893 -410.858447) (xy 289.27629 -410.845185) (xy 289.27298 -410.839158) (xy 289.256628 -410.81081)
			(xy 289.230883 -410.750642) (xy 289.213457 -410.68756) (xy 289.204665 -410.622709) (xy 283.304488 -410.622709)
			(xy 283.304488 -412.090108) (xy 287.003752 -412.090108) (xy 287.007743 -412.027941) (xy 287.019652 -411.966794)
			(xy 287.039281 -411.907673) (xy 287.06631 -411.851547) (xy 287.100294 -411.799338) (xy 287.140676 -411.751903)
			(xy 287.186792 -411.710022) (xy 287.237884 -411.674382) (xy 287.293115 -411.645568) (xy 287.351577 -411.624054)
			(xy 287.412311 -411.610192) (xy 287.474318 -411.60421) (xy 287.536581 -411.606206) (xy 287.598078 -411.616149)
			(xy 287.657799 -411.633873) (xy 287.714762 -411.65909) (xy 287.768033 -411.691383) (xy 287.816738 -411.730223)
			(xy 287.860075 -411.774973) (xy 287.897335 -411.824897) (xy 287.927904 -411.879176) (xy 287.951282 -411.936919)
			(xy 287.967083 -411.997177) (xy 287.975049 -412.05896) (xy 287.975548 -412.090108) (xy 291.403794 -412.090108)
			(xy 291.407785 -412.027941) (xy 291.419694 -411.966794) (xy 291.439323 -411.907673) (xy 291.466352 -411.851547)
			(xy 291.500336 -411.799338) (xy 291.540718 -411.751903) (xy 291.586834 -411.710022) (xy 291.637926 -411.674382)
			(xy 291.693157 -411.645568) (xy 291.751619 -411.624054) (xy 291.812353 -411.610192) (xy 291.87436 -411.60421)
			(xy 291.936623 -411.606206) (xy 291.99812 -411.616149) (xy 292.057841 -411.633873) (xy 292.114804 -411.65909)
			(xy 292.168075 -411.691383) (xy 292.21678 -411.730223) (xy 292.260117 -411.774973) (xy 292.297377 -411.824897)
			(xy 292.327946 -411.879176) (xy 292.351324 -411.936919) (xy 292.367125 -411.997177) (xy 292.375091 -412.05896)
			(xy 292.37559 -412.090108) (xy 295.803836 -412.090108) (xy 295.807827 -412.027941) (xy 295.819736 -411.966794)
			(xy 295.839365 -411.907673) (xy 295.866394 -411.851547) (xy 295.900378 -411.799338) (xy 295.94076 -411.751903)
			(xy 295.986876 -411.710022) (xy 296.037968 -411.674382) (xy 296.093199 -411.645568) (xy 296.151661 -411.624054)
			(xy 296.212395 -411.610192) (xy 296.274402 -411.60421) (xy 296.336665 -411.606206) (xy 296.398162 -411.616149)
			(xy 296.457883 -411.633873) (xy 296.514846 -411.65909) (xy 296.568117 -411.691383) (xy 296.616822 -411.730223)
			(xy 296.660159 -411.774973) (xy 296.697419 -411.824897) (xy 296.727988 -411.879176) (xy 296.751366 -411.936919)
			(xy 296.767167 -411.997177) (xy 296.775133 -412.05896) (xy 296.775632 -412.090108) (xy 300.203624 -412.090108)
			(xy 300.207615 -412.027941) (xy 300.219524 -411.966794) (xy 300.239153 -411.907673) (xy 300.266182 -411.851547)
			(xy 300.300166 -411.799338) (xy 300.340548 -411.751903) (xy 300.386664 -411.710022) (xy 300.437756 -411.674382)
			(xy 300.492987 -411.645568) (xy 300.551449 -411.624054) (xy 300.612183 -411.610192) (xy 300.67419 -411.60421)
			(xy 300.736453 -411.606206) (xy 300.79795 -411.616149) (xy 300.857671 -411.633873) (xy 300.914634 -411.65909)
			(xy 300.967905 -411.691383) (xy 301.01661 -411.730223) (xy 301.059947 -411.774973) (xy 301.097207 -411.824897)
			(xy 301.127776 -411.879176) (xy 301.151154 -411.936919) (xy 301.166955 -411.997177) (xy 301.174921 -412.05896)
			(xy 301.17542 -412.090108) (xy 304.603666 -412.090108) (xy 304.607657 -412.027941) (xy 304.619566 -411.966794)
			(xy 304.639195 -411.907673) (xy 304.666224 -411.851547) (xy 304.700208 -411.799338) (xy 304.74059 -411.751903)
			(xy 304.786706 -411.710022) (xy 304.837798 -411.674382) (xy 304.893029 -411.645568) (xy 304.951491 -411.624054)
			(xy 305.012225 -411.610192) (xy 305.074232 -411.60421) (xy 305.136495 -411.606206) (xy 305.197992 -411.616149)
			(xy 305.257713 -411.633873) (xy 305.314676 -411.65909) (xy 305.367947 -411.691383) (xy 305.416652 -411.730223)
			(xy 305.459989 -411.774973) (xy 305.497249 -411.824897) (xy 305.527818 -411.879176) (xy 305.551196 -411.936919)
			(xy 305.566997 -411.997177) (xy 305.574963 -412.05896) (xy 305.575462 -412.090108) (xy 305.574963 -412.121256)
			(xy 305.566997 -412.183039) (xy 305.551196 -412.243297) (xy 305.527818 -412.30104) (xy 305.497249 -412.355319)
			(xy 305.459989 -412.405243) (xy 305.416652 -412.449993) (xy 305.367947 -412.488833) (xy 305.314676 -412.521126)
			(xy 305.257713 -412.546343) (xy 305.197992 -412.564067) (xy 305.136495 -412.57401) (xy 305.074232 -412.576006)
			(xy 305.012225 -412.570024) (xy 304.951491 -412.556162) (xy 304.893029 -412.534648) (xy 304.837798 -412.505834)
			(xy 304.786706 -412.470194) (xy 304.74059 -412.428313) (xy 304.700208 -412.380878) (xy 304.666224 -412.328669)
			(xy 304.639195 -412.272543) (xy 304.619566 -412.213422) (xy 304.607657 -412.152275) (xy 304.603666 -412.090108)
			(xy 301.17542 -412.090108) (xy 301.174921 -412.121256) (xy 301.166955 -412.183039) (xy 301.151154 -412.243297)
			(xy 301.127776 -412.30104) (xy 301.097207 -412.355319) (xy 301.059947 -412.405243) (xy 301.01661 -412.449993)
			(xy 300.967905 -412.488833) (xy 300.914634 -412.521126) (xy 300.857671 -412.546343) (xy 300.79795 -412.564067)
			(xy 300.736453 -412.57401) (xy 300.67419 -412.576006) (xy 300.612183 -412.570024) (xy 300.551449 -412.556162)
			(xy 300.492987 -412.534648) (xy 300.437756 -412.505834) (xy 300.386664 -412.470194) (xy 300.340548 -412.428313)
			(xy 300.300166 -412.380878) (xy 300.266182 -412.328669) (xy 300.239153 -412.272543) (xy 300.219524 -412.213422)
			(xy 300.207615 -412.152275) (xy 300.203624 -412.090108) (xy 296.775632 -412.090108) (xy 296.775133 -412.121256)
			(xy 296.767167 -412.183039) (xy 296.751366 -412.243297) (xy 296.727988 -412.30104) (xy 296.697419 -412.355319)
			(xy 296.660159 -412.405243) (xy 296.616822 -412.449993) (xy 296.568117 -412.488833) (xy 296.514846 -412.521126)
			(xy 296.457883 -412.546343) (xy 296.398162 -412.564067) (xy 296.336665 -412.57401) (xy 296.274402 -412.576006)
			(xy 296.212395 -412.570024) (xy 296.151661 -412.556162) (xy 296.093199 -412.534648) (xy 296.037968 -412.505834)
			(xy 295.986876 -412.470194) (xy 295.94076 -412.428313) (xy 295.900378 -412.380878) (xy 295.866394 -412.328669)
			(xy 295.839365 -412.272543) (xy 295.819736 -412.213422) (xy 295.807827 -412.152275) (xy 295.803836 -412.090108)
			(xy 292.37559 -412.090108) (xy 292.375091 -412.121256) (xy 292.367125 -412.183039) (xy 292.351324 -412.243297)
			(xy 292.327946 -412.30104) (xy 292.297377 -412.355319) (xy 292.260117 -412.405243) (xy 292.21678 -412.449993)
			(xy 292.168075 -412.488833) (xy 292.114804 -412.521126) (xy 292.057841 -412.546343) (xy 291.99812 -412.564067)
			(xy 291.936623 -412.57401) (xy 291.87436 -412.576006) (xy 291.812353 -412.570024) (xy 291.751619 -412.556162)
			(xy 291.693157 -412.534648) (xy 291.637926 -412.505834) (xy 291.586834 -412.470194) (xy 291.540718 -412.428313)
			(xy 291.500336 -412.380878) (xy 291.466352 -412.328669) (xy 291.439323 -412.272543) (xy 291.419694 -412.213422)
			(xy 291.407785 -412.152275) (xy 291.403794 -412.090108) (xy 287.975548 -412.090108) (xy 287.975049 -412.121256)
			(xy 287.967083 -412.183039) (xy 287.951282 -412.243297) (xy 287.927904 -412.30104) (xy 287.897335 -412.355319)
			(xy 287.860075 -412.405243) (xy 287.816738 -412.449993) (xy 287.768033 -412.488833) (xy 287.714762 -412.521126)
			(xy 287.657799 -412.546343) (xy 287.598078 -412.564067) (xy 287.536581 -412.57401) (xy 287.474318 -412.576006)
			(xy 287.412311 -412.570024) (xy 287.351577 -412.556162) (xy 287.293115 -412.534648) (xy 287.237884 -412.505834)
			(xy 287.186792 -412.470194) (xy 287.140676 -412.428313) (xy 287.100294 -412.380878) (xy 287.06631 -412.328669)
			(xy 287.039281 -412.272543) (xy 287.019652 -412.213422) (xy 287.007743 -412.152275) (xy 287.003752 -412.090108)
			(xy 283.304488 -412.090108) (xy 283.304488 -415.805112) (xy 283.304947 -415.81499) (xy 283.312387 -415.833291)
			(xy 283.318966 -415.840672) (xy 283.31922 -415.840926) (xy 284.640782 -417.162488) (xy 284.64129 -417.162996)
			(xy 284.648675 -417.169568) (xy 284.666974 -417.176999) (xy 284.67685 -417.177474)
		)
		(stroke
			(width 0)
			(type solid)
		)
		(fill yes)
		(layer "In7.Cu")
		(net "GND")
	)
	(gr_poly
		(pts
			(xy 315.292486 -270.31823) (xy 315.299727 -270.316597) (xy 315.312886 -270.309745) (xy 315.318394 -270.304768)
			(xy 319.763648 -265.859514) (xy 319.771048 -265.852673) (xy 319.789647 -265.844954) (xy 319.799716 -265.844528)
			(xy 323.80809 -265.844528) (xy 323.819266 -265.843258) (xy 323.826067 -265.841463) (xy 323.838429 -265.834764)
			(xy 323.84365 -265.83005) (xy 327.17105 -262.502904) (xy 327.176441 -262.496713) (xy 327.183313 -262.481815)
			(xy 327.184512 -262.473694) (xy 327.184766 -262.468106) (xy 327.184766 -259.51053) (xy 327.184258 -259.503418)
			(xy 326.244204 -258.56311) (xy 326.236806 -258.556262) (xy 326.218208 -258.548524) (xy 326.208136 -258.548124)
			(xy 316.940692 -258.548124) (xy 316.91467 -258.547592) (xy 316.863272 -258.539417) (xy 316.813781 -258.523315)
			(xy 316.767412 -258.499682) (xy 316.725303 -258.469098) (xy 316.706504 -258.451096) (xy 316.695074 -258.439666)
			(xy 316.687677 -258.432817) (xy 316.669078 -258.425081) (xy 316.659006 -258.42468) (xy 316.559438 -258.42468)
			(xy 316.534149 -258.42418) (xy 316.484195 -258.416265) (xy 316.436091 -258.400638) (xy 316.391022 -258.377685)
			(xy 316.350095 -258.347969) (xy 316.331854 -258.330446) (xy 316.221364 -258.219702) (xy 316.210696 -258.211574)
			(xy 316.205108 -258.208272) (xy 316.19825 -258.206494) (xy 316.171321 -258.199024) (xy 316.11984 -258.177288)
			(xy 316.072079 -258.148275) (xy 316.029061 -258.112606) (xy 315.991707 -258.071044) (xy 315.960814 -258.024477)
			(xy 315.937043 -257.973903) (xy 315.920904 -257.920402) (xy 315.912742 -257.865119) (xy 315.912246 -257.837178)
			(xy 315.912718 -257.810037) (xy 315.920398 -257.756303) (xy 315.935614 -257.704198) (xy 315.958058 -257.654775)
			(xy 315.987279 -257.60903) (xy 316.022687 -257.567887) (xy 316.063566 -257.532176) (xy 316.109093 -257.502618)
			(xy 316.158348 -257.479808) (xy 316.210339 -257.464206) (xy 316.237112 -257.459734) (xy 316.243132 -257.458685)
			(xy 316.254442 -257.454069) (xy 316.259464 -257.45059) (xy 316.284078 -257.433396) (xy 316.337574 -257.406142)
			(xy 316.394678 -257.387602) (xy 316.453981 -257.378231) (xy 316.484 -257.377692) (xy 316.509579 -257.378104)
			(xy 316.560278 -257.384941) (xy 316.609609 -257.398491) (xy 316.656686 -257.418513) (xy 316.700666 -257.444646)
			(xy 316.740758 -257.476422) (xy 316.758828 -257.494532) (xy 316.768226 -257.504438) (xy 316.794388 -257.512058)
			(xy 316.893194 -257.487166) (xy 316.901764 -257.484703) (xy 316.916552 -257.47476) (xy 316.927024 -257.460342)
			(xy 316.92977 -257.45186) (xy 316.937721 -257.425586) (xy 316.960118 -257.375469) (xy 316.989468 -257.32908)
			(xy 317.025162 -257.287376) (xy 317.066465 -257.251218) (xy 317.112524 -257.221353) (xy 317.162387 -257.198398)
			(xy 317.215026 -257.182826) (xy 317.269353 -257.174959) (xy 317.2968 -257.174492) (xy 317.330582 -257.176016)
			(xy 317.339794 -257.176359) (xy 317.357505 -257.171294) (xy 317.365126 -257.16611) (xy 317.394925 -257.14482)
			(xy 317.458888 -257.109145) (xy 317.52686 -257.081876) (xy 317.597743 -257.063453) (xy 317.670391 -257.054173)
			(xy 317.70701 -257.053588) (xy 318.025526 -257.053588) (xy 318.030098 -257.052826) (xy 318.055911 -257.048447)
			(xy 318.108058 -257.043742) (xy 318.134238 -257.043428) (xy 326.666606 -257.043428) (xy 326.699459 -257.043889)
			(xy 326.764753 -257.051246) (xy 326.828812 -257.065868) (xy 326.890831 -257.08757) (xy 326.950031 -257.116079)
			(xy 327.005666 -257.151038) (xy 327.057037 -257.192005) (xy 327.080626 -257.214878) (xy 327.098152 -257.232404)
			(xy 327.105554 -257.239078) (xy 327.123964 -257.246661) (xy 327.143874 -257.246653) (xy 327.15327 -257.243326)
			(xy 327.18121 -257.231896) (xy 327.184766 -257.226562) (xy 327.184766 -251.544836) (xy 327.184597 -251.538827)
			(xy 327.181768 -251.527147) (xy 327.179178 -251.521722) (xy 327.17734 -251.518247) (xy 327.172749 -251.511866)
			(xy 327.170034 -251.509022) (xy 321.247008 -245.585996) (xy 321.240162 -245.578597) (xy 321.232427 -245.56)
			(xy 321.232022 -245.549928) (xy 321.232022 -225.530156) (xy 321.231514 -225.523044) (xy 320.132964 -224.424494)
			(xy 320.114931 -224.405724) (xy 320.08435 -224.363607) (xy 320.060724 -224.317231) (xy 320.044632 -224.267733)
			(xy 320.03647 -224.21633) (xy 320.035936 -224.190306) (xy 320.035936 -190.929514) (xy 320.036377 -190.905615)
			(xy 320.043269 -190.858315) (xy 320.049652 -190.83528) (xy 320.051684 -190.828168) (xy 320.051684 -190.822834)
			(xy 320.059304 -190.804292) (xy 320.061082 -190.802514) (xy 320.064892 -190.794132) (xy 320.077833 -190.766795)
			(xy 320.112078 -190.716948) (xy 320.132964 -190.695072) (xy 324.037198 -186.790838) (xy 324.044035 -186.783436)
			(xy 324.051747 -186.764838) (xy 324.052184 -186.75477) (xy 324.052184 -177.490882) (xy 324.051757 -177.480814)
			(xy 324.044036 -177.462215) (xy 324.037198 -177.454814) (xy 321.909694 -175.32731) (xy 321.891578 -175.308531)
			(xy 321.860887 -175.266335) (xy 321.837181 -175.219854) (xy 321.821043 -175.170236) (xy 321.812872 -175.118702)
			(xy 321.812412 -175.092614) (xy 321.812412 -138.079226) (xy 321.811976 -138.069161) (xy 321.804244 -138.050575)
			(xy 321.797426 -138.043158) (xy 317.408814 -133.654546) (xy 317.390701 -133.635766) (xy 317.360016 -133.593569)
			(xy 317.336317 -133.547088) (xy 317.320188 -133.497469) (xy 317.312027 -133.445937) (xy 317.311532 -133.41985)
			(xy 317.311532 -120.274588) (xy 317.311108 -120.264518) (xy 317.303394 -120.245914) (xy 317.296546 -120.23852)
			(xy 317.05042 -119.992394) (xy 317.032389 -119.973623) (xy 317.001813 -119.931505) (xy 316.978189 -119.885129)
			(xy 316.9621 -119.835632) (xy 316.953939 -119.784229) (xy 316.953392 -119.758206) (xy 316.953392 -109.837474)
			(xy 316.952964 -109.827406) (xy 316.945242 -109.808809) (xy 316.938406 -109.801406) (xy 316.64402 -109.50702)
			(xy 316.636618 -109.500184) (xy 316.61802 -109.492476) (xy 316.607952 -109.492034) (xy 314.648596 -109.492034)
			(xy 314.636898 -109.492625) (xy 314.615925 -109.502991) (xy 314.601715 -109.521577) (xy 314.598812 -109.532928)
			(xy 313.165744 -116.755926) (xy 313.164728 -116.76507) (xy 313.149488 -118.077234) (xy 313.149838 -118.088726)
			(xy 313.159509 -118.109558) (xy 313.177304 -118.124079) (xy 313.18835 -118.127272) (xy 313.21652 -118.134679)
			(xy 313.270369 -118.156877) (xy 313.320211 -118.187014) (xy 313.364883 -118.224389) (xy 313.403344 -118.268129)
			(xy 313.41949 -118.292372) (xy 313.423808 -118.298214) (xy 313.430015 -118.30481) (xy 313.445887 -118.313506)
			(xy 313.463793 -118.316146) (xy 313.4815 -118.3124) (xy 313.48934 -118.307866) (xy 313.51675 -118.291315)
			(xy 313.575213 -118.265202) (xy 313.636747 -118.247498) (xy 313.700149 -118.238549) (xy 313.732164 -118.238016)
			(xy 313.762134 -118.238483) (xy 313.821562 -118.246303) (xy 313.87946 -118.261813) (xy 313.934838 -118.284748)
			(xy 313.986749 -118.314716) (xy 314.034303 -118.351204) (xy 314.076688 -118.393588) (xy 314.113177 -118.441141)
			(xy 314.143146 -118.493051) (xy 314.166083 -118.548429) (xy 314.181595 -118.606327) (xy 314.189416 -118.665754)
			(xy 314.189872 -118.695724) (xy 314.189872 -119.559324) (xy 314.189401 -119.589291) (xy 314.181575 -119.648712)
			(xy 314.16606 -119.706604) (xy 314.143121 -119.761974) (xy 314.11315 -119.813877) (xy 314.076661 -119.861424)
			(xy 314.034279 -119.903801) (xy 313.986727 -119.940284) (xy 313.93482 -119.970247) (xy 313.879447 -119.993179)
			(xy 313.821553 -120.008687) (xy 313.762131 -120.016505) (xy 313.732164 -120.017032) (xy 313.700152 -120.016475)
			(xy 313.636757 -120.007512) (xy 313.575228 -119.989807) (xy 313.516764 -119.963707) (xy 313.48934 -119.947182)
			(xy 313.479055 -119.941367) (xy 313.455583 -119.938947) (xy 313.433512 -119.947293) (xy 313.425078 -119.955564)
			(xy 313.41949 -119.962676) (xy 313.405021 -119.984389) (xy 313.37112 -120.024052) (xy 313.332138 -120.058734)
			(xy 313.2888 -120.087789) (xy 313.241911 -120.110678) (xy 313.192345 -120.126975) (xy 313.16676 -120.132094)
			(xy 313.155286 -120.134787) (xy 313.136412 -120.148857) (xy 313.125775 -120.169858) (xy 313.125104 -120.181624)
			(xy 313.111558 -121.365772) (xy 315.916564 -121.365772) (xy 315.916564 -120.502172) (xy 315.917054 -120.472204)
			(xy 315.924877 -120.412782) (xy 315.94039 -120.354889) (xy 315.963326 -120.299516) (xy 315.993293 -120.24761)
			(xy 316.02978 -120.20006) (xy 316.07216 -120.15768) (xy 316.11971 -120.121193) (xy 316.171616 -120.091226)
			(xy 316.226989 -120.06829) (xy 316.284882 -120.052777) (xy 316.344304 -120.044954) (xy 316.40424 -120.044954)
			(xy 316.463662 -120.052777) (xy 316.521555 -120.06829) (xy 316.576928 -120.091226) (xy 316.628834 -120.121193)
			(xy 316.676384 -120.15768) (xy 316.718764 -120.20006) (xy 316.755251 -120.24761) (xy 316.785218 -120.299516)
			(xy 316.808154 -120.354889) (xy 316.823667 -120.412782) (xy 316.83149 -120.472204) (xy 316.83198 -120.502172)
			(xy 316.83198 -121.365772) (xy 316.83149 -121.39574) (xy 316.823667 -121.455162) (xy 316.808154 -121.513055)
			(xy 316.785218 -121.568428) (xy 316.755251 -121.620334) (xy 316.718764 -121.667884) (xy 316.676384 -121.710264)
			(xy 316.628834 -121.746751) (xy 316.576928 -121.776718) (xy 316.521555 -121.799654) (xy 316.463662 -121.815167)
			(xy 316.40424 -121.82299) (xy 316.344304 -121.82299) (xy 316.284882 -121.815167) (xy 316.226989 -121.799654)
			(xy 316.171616 -121.776718) (xy 316.11971 -121.746751) (xy 316.07216 -121.710264) (xy 316.02978 -121.667884)
			(xy 315.993293 -121.620334) (xy 315.963326 -121.568428) (xy 315.94039 -121.513055) (xy 315.924877 -121.455162)
			(xy 315.917054 -121.39574) (xy 315.916564 -121.365772) (xy 313.111558 -121.365772) (xy 313.108086 -121.669302)
			(xy 313.108384 -121.678481) (xy 313.114679 -121.695718) (xy 313.126643 -121.709634) (xy 313.142742 -121.718443)
			(xy 313.151774 -121.720102) (xy 313.178805 -121.724441) (xy 313.231339 -121.739846) (xy 313.281137 -121.762593)
			(xy 313.327178 -121.792214) (xy 313.368519 -121.828104) (xy 313.404313 -121.869528) (xy 313.41949 -121.892314)
			(xy 313.423808 -121.898156) (xy 313.430017 -121.904747) (xy 313.445889 -121.913437) (xy 313.463792 -121.916074)
			(xy 313.481496 -121.912331) (xy 313.48934 -121.907808) (xy 313.516751 -121.891259) (xy 313.575215 -121.865149)
			(xy 313.636748 -121.847447) (xy 313.700149 -121.838499) (xy 313.732164 -121.837958) (xy 313.762135 -121.838425)
			(xy 313.821566 -121.846244) (xy 313.879467 -121.861754) (xy 313.934849 -121.884689) (xy 313.986763 -121.914656)
			(xy 314.034321 -121.951143) (xy 314.076711 -121.993526) (xy 314.113205 -122.041079) (xy 314.14318 -122.092988)
			(xy 314.166123 -122.148366) (xy 314.181642 -122.206265) (xy 314.189471 -122.265695) (xy 314.189872 -122.295666)
			(xy 314.189872 -123.159266) (xy 314.189382 -123.189234) (xy 314.181559 -123.248656) (xy 314.166046 -123.306549)
			(xy 314.14311 -123.361922) (xy 314.113143 -123.413828) (xy 314.076656 -123.461378) (xy 314.034276 -123.503758)
			(xy 313.986726 -123.540245) (xy 313.93482 -123.570212) (xy 313.879447 -123.593148) (xy 313.821554 -123.608661)
			(xy 313.762132 -123.616484) (xy 313.702196 -123.616484) (xy 313.642774 -123.608661) (xy 313.584881 -123.593148)
			(xy 313.529508 -123.570212) (xy 313.477602 -123.540245) (xy 313.430052 -123.503758) (xy 313.387672 -123.461378)
			(xy 313.351185 -123.413828) (xy 313.321218 -123.361922) (xy 313.298282 -123.306549) (xy 313.282769 -123.248656)
			(xy 313.274946 -123.189234) (xy 313.274456 -123.159266) (xy 313.274456 -122.51182) (xy 313.274202 -122.506232)
			(xy 313.272596 -122.495558) (xy 313.26176 -122.476911) (xy 313.244231 -122.464347) (xy 313.223092 -122.460075)
			(xy 313.21248 -122.462036) (xy 313.208924 -122.463052) (xy 313.192711 -122.467828) (xy 313.159641 -122.47482)
			(xy 313.142884 -122.477022) (xy 313.133841 -122.478517) (xy 313.117601 -122.486983) (xy 313.105359 -122.500605)
			(xy 313.098671 -122.517655) (xy 313.09818 -122.526806) (xy 313.070009 -124.965714) (xy 315.916564 -124.965714)
			(xy 315.916564 -124.102114) (xy 315.917054 -124.072146) (xy 315.924877 -124.012724) (xy 315.94039 -123.954831)
			(xy 315.963326 -123.899458) (xy 315.993293 -123.847552) (xy 316.02978 -123.800002) (xy 316.07216 -123.757622)
			(xy 316.11971 -123.721135) (xy 316.171616 -123.691168) (xy 316.226989 -123.668232) (xy 316.284882 -123.652719)
			(xy 316.344304 -123.644896) (xy 316.40424 -123.644896) (xy 316.463662 -123.652719) (xy 316.521555 -123.668232)
			(xy 316.576928 -123.691168) (xy 316.628834 -123.721135) (xy 316.676384 -123.757622) (xy 316.718764 -123.800002)
			(xy 316.755251 -123.847552) (xy 316.785218 -123.899458) (xy 316.808154 -123.954831) (xy 316.823667 -124.012724)
			(xy 316.83149 -124.072146) (xy 316.83198 -124.102114) (xy 316.83198 -124.965714) (xy 316.83149 -124.995682)
			(xy 316.823667 -125.055104) (xy 316.808154 -125.112997) (xy 316.785218 -125.16837) (xy 316.755251 -125.220276)
			(xy 316.718764 -125.267826) (xy 316.676384 -125.310206) (xy 316.628834 -125.346693) (xy 316.576928 -125.37666)
			(xy 316.521555 -125.399596) (xy 316.463662 -125.415109) (xy 316.40424 -125.422932) (xy 316.344304 -125.422932)
			(xy 316.284882 -125.415109) (xy 316.226989 -125.399596) (xy 316.171616 -125.37666) (xy 316.11971 -125.346693)
			(xy 316.07216 -125.310206) (xy 316.02978 -125.267826) (xy 315.993293 -125.220276) (xy 315.963326 -125.16837)
			(xy 315.94039 -125.112997) (xy 315.924877 -125.055104) (xy 315.917054 -124.995682) (xy 315.916564 -124.965714)
			(xy 313.070009 -124.965714) (xy 313.002976 -130.769106) (xy 313.274456 -130.769106) (xy 313.274456 -129.905506)
			(xy 313.274946 -129.875538) (xy 313.282769 -129.816116) (xy 313.298282 -129.758223) (xy 313.321218 -129.70285)
			(xy 313.351185 -129.650944) (xy 313.387672 -129.603394) (xy 313.430052 -129.561014) (xy 313.477602 -129.524527)
			(xy 313.529508 -129.49456) (xy 313.584881 -129.471624) (xy 313.642774 -129.456111) (xy 313.702196 -129.448288)
			(xy 313.762132 -129.448288) (xy 313.821554 -129.456111) (xy 313.879447 -129.471624) (xy 313.93482 -129.49456)
			(xy 313.986726 -129.524527) (xy 314.034276 -129.561014) (xy 314.076656 -129.603394) (xy 314.113143 -129.650944)
			(xy 314.14311 -129.70285) (xy 314.166046 -129.758223) (xy 314.181559 -129.816116) (xy 314.189382 -129.875538)
			(xy 314.189872 -129.905506) (xy 314.189872 -130.769106) (xy 314.189382 -130.799074) (xy 314.181559 -130.858496)
			(xy 314.166046 -130.916389) (xy 314.14311 -130.971762) (xy 314.113143 -131.023668) (xy 314.076656 -131.071218)
			(xy 314.034276 -131.113598) (xy 313.986726 -131.150085) (xy 313.93482 -131.180052) (xy 313.879447 -131.202988)
			(xy 313.821554 -131.218501) (xy 313.762132 -131.226324) (xy 313.702196 -131.226324) (xy 313.642774 -131.218501)
			(xy 313.584881 -131.202988) (xy 313.529508 -131.180052) (xy 313.477602 -131.150085) (xy 313.430052 -131.113598)
			(xy 313.387672 -131.071218) (xy 313.351185 -131.023668) (xy 313.321218 -130.971762) (xy 313.298282 -130.916389)
			(xy 313.282769 -130.858496) (xy 313.274946 -130.799074) (xy 313.274456 -130.769106) (xy 313.002976 -130.769106)
			(xy 312.982108 -132.575808) (xy 315.916564 -132.575808) (xy 315.916564 -131.712208) (xy 315.917054 -131.68224)
			(xy 315.924877 -131.622818) (xy 315.94039 -131.564925) (xy 315.963326 -131.509552) (xy 315.993293 -131.457646)
			(xy 316.02978 -131.410096) (xy 316.07216 -131.367716) (xy 316.11971 -131.331229) (xy 316.171616 -131.301262)
			(xy 316.226989 -131.278326) (xy 316.284882 -131.262813) (xy 316.344304 -131.25499) (xy 316.40424 -131.25499)
			(xy 316.463662 -131.262813) (xy 316.521555 -131.278326) (xy 316.576928 -131.301262) (xy 316.628834 -131.331229)
			(xy 316.676384 -131.367716) (xy 316.718764 -131.410096) (xy 316.755251 -131.457646) (xy 316.785218 -131.509552)
			(xy 316.808154 -131.564925) (xy 316.823667 -131.622818) (xy 316.83149 -131.68224) (xy 316.83198 -131.712208)
			(xy 316.83198 -132.575808) (xy 316.83149 -132.605776) (xy 316.823667 -132.665198) (xy 316.808154 -132.723091)
			(xy 316.785218 -132.778464) (xy 316.755251 -132.83037) (xy 316.718764 -132.87792) (xy 316.676384 -132.9203)
			(xy 316.628834 -132.956787) (xy 316.576928 -132.986754) (xy 316.521555 -133.00969) (xy 316.463662 -133.025203)
			(xy 316.40424 -133.033026) (xy 316.344304 -133.033026) (xy 316.284882 -133.025203) (xy 316.226989 -133.00969)
			(xy 316.171616 -132.986754) (xy 316.11971 -132.956787) (xy 316.07216 -132.9203) (xy 316.02978 -132.87792)
			(xy 315.993293 -132.83037) (xy 315.963326 -132.778464) (xy 315.94039 -132.723091) (xy 315.924877 -132.665198)
			(xy 315.917054 -132.605776) (xy 315.916564 -132.575808) (xy 312.982108 -132.575808) (xy 312.961392 -134.369302)
			(xy 313.274456 -134.369302) (xy 313.274456 -133.505702) (xy 313.274946 -133.475734) (xy 313.282769 -133.416312)
			(xy 313.298282 -133.358419) (xy 313.321218 -133.303046) (xy 313.351185 -133.25114) (xy 313.387672 -133.20359)
			(xy 313.430052 -133.16121) (xy 313.477602 -133.124723) (xy 313.529508 -133.094756) (xy 313.584881 -133.07182)
			(xy 313.642774 -133.056307) (xy 313.702196 -133.048484) (xy 313.762132 -133.048484) (xy 313.821554 -133.056307)
			(xy 313.879447 -133.07182) (xy 313.93482 -133.094756) (xy 313.986726 -133.124723) (xy 314.034276 -133.16121)
			(xy 314.076656 -133.20359) (xy 314.113143 -133.25114) (xy 314.14311 -133.303046) (xy 314.166046 -133.358419)
			(xy 314.181559 -133.416312) (xy 314.189382 -133.475734) (xy 314.189872 -133.505702) (xy 314.189872 -134.369302)
			(xy 314.189382 -134.39927) (xy 314.181559 -134.458692) (xy 314.166046 -134.516585) (xy 314.14311 -134.571958)
			(xy 314.113143 -134.623864) (xy 314.076656 -134.671414) (xy 314.034276 -134.713794) (xy 313.986726 -134.750281)
			(xy 313.93482 -134.780248) (xy 313.879447 -134.803184) (xy 313.821554 -134.818697) (xy 313.762132 -134.82652)
			(xy 313.702196 -134.82652) (xy 313.642774 -134.818697) (xy 313.584881 -134.803184) (xy 313.529508 -134.780248)
			(xy 313.477602 -134.750281) (xy 313.430052 -134.713794) (xy 313.387672 -134.671414) (xy 313.351185 -134.623864)
			(xy 313.321218 -134.571958) (xy 313.298282 -134.516585) (xy 313.282769 -134.458692) (xy 313.274946 -134.39927)
			(xy 313.274456 -134.369302) (xy 312.961392 -134.369302) (xy 312.940526 -136.17575) (xy 315.916564 -136.17575)
			(xy 315.916564 -135.31215) (xy 315.917054 -135.282182) (xy 315.924877 -135.22276) (xy 315.94039 -135.164867)
			(xy 315.963326 -135.109494) (xy 315.993293 -135.057588) (xy 316.02978 -135.010038) (xy 316.07216 -134.967658)
			(xy 316.11971 -134.931171) (xy 316.171616 -134.901204) (xy 316.226989 -134.878268) (xy 316.284882 -134.862755)
			(xy 316.344304 -134.854932) (xy 316.40424 -134.854932) (xy 316.463662 -134.862755) (xy 316.521555 -134.878268)
			(xy 316.576928 -134.901204) (xy 316.628834 -134.931171) (xy 316.676384 -134.967658) (xy 316.718764 -135.010038)
			(xy 316.755251 -135.057588) (xy 316.785218 -135.109494) (xy 316.808154 -135.164867) (xy 316.823667 -135.22276)
			(xy 316.83149 -135.282182) (xy 316.83198 -135.31215) (xy 316.83198 -136.17575) (xy 316.83149 -136.205718)
			(xy 316.823667 -136.26514) (xy 316.808154 -136.323033) (xy 316.785218 -136.378406) (xy 316.755251 -136.430312)
			(xy 316.718764 -136.477862) (xy 316.676384 -136.520242) (xy 316.628834 -136.556729) (xy 316.576928 -136.586696)
			(xy 316.521555 -136.609632) (xy 316.463662 -136.625145) (xy 316.40424 -136.632968) (xy 316.344304 -136.632968)
			(xy 316.284882 -136.625145) (xy 316.226989 -136.609632) (xy 316.171616 -136.586696) (xy 316.11971 -136.556729)
			(xy 316.07216 -136.520242) (xy 316.02978 -136.477862) (xy 315.993293 -136.430312) (xy 315.963326 -136.378406)
			(xy 315.94039 -136.323033) (xy 315.924877 -136.26514) (xy 315.917054 -136.205718) (xy 315.916564 -136.17575)
			(xy 312.940526 -136.17575) (xy 312.936636 -136.512554) (xy 312.937059 -136.524034) (xy 312.946856 -136.544787)
			(xy 312.955432 -136.552432) (xy 313.0169 -136.60247) (xy 313.026116 -136.609228) (xy 313.048283 -136.614652)
			(xy 313.059572 -136.612884) (xy 313.079026 -136.608998) (xy 313.118476 -136.604795) (xy 313.138312 -136.604502)
			(xy 313.145678 -136.604502) (xy 313.172643 -136.605399) (xy 313.225929 -136.613851) (xy 313.277491 -136.629727)
			(xy 313.326303 -136.652711) (xy 313.371389 -136.682343) (xy 313.411849 -136.718032) (xy 313.446878 -136.759066)
			(xy 313.475774 -136.804627) (xy 313.497963 -136.853805) (xy 313.513001 -136.905618) (xy 313.520587 -136.959034)
			(xy 313.52109 -136.98601) (xy 313.520626 -137.013262) (xy 313.512868 -137.067211) (xy 313.497511 -137.119506)
			(xy 313.474867 -137.169084) (xy 313.445399 -137.214935) (xy 313.409705 -137.256125) (xy 313.368512 -137.291816)
			(xy 313.32266 -137.321281) (xy 313.27308 -137.34392) (xy 313.220783 -137.359274) (xy 313.166834 -137.367028)
			(xy 313.139582 -137.367518) (xy 313.139328 -137.367518) (xy 313.117021 -137.367173) (xy 313.072712 -137.361953)
			(xy 313.050936 -137.357104) (xy 313.050682 -137.357104) (xy 313.039497 -137.355162) (xy 313.017358 -137.360056)
			(xy 313.00801 -137.366502) (xy 312.945272 -137.41527) (xy 312.936567 -137.422712) (xy 312.926396 -137.443207)
			(xy 312.925714 -137.45464) (xy 312.904886 -139.252198) (xy 312.905196 -139.261761) (xy 312.911977 -139.279639)
			(xy 312.918094 -139.286996) (xy 312.970926 -139.345416) (xy 312.988452 -139.353798) (xy 312.998104 -139.35456)
			(xy 313.026322 -139.357498) (xy 313.081507 -139.370652) (xy 313.134138 -139.391827) (xy 313.183057 -139.420555)
			(xy 313.227188 -139.456205) (xy 313.24677 -139.476734) (xy 313.252051 -139.481794) (xy 313.264829 -139.488897)
			(xy 313.271916 -139.490704) (xy 313.283092 -139.491974) (xy 313.358022 -139.491974) (xy 313.358276 -139.491974)
			(xy 313.35853 -139.491974) (xy 313.368908 -139.491365) (xy 313.387903 -139.482964) (xy 313.39536 -139.475718)
			(xy 313.413456 -139.456788) (xy 313.45394 -139.423568) (xy 313.498588 -139.3962) (xy 313.546563 -139.3752)
			(xy 313.596959 -139.360964) (xy 313.64883 -139.353758) (xy 313.675014 -139.35329) (xy 313.702265 -139.353777)
			(xy 313.756211 -139.361535) (xy 313.808505 -139.376891) (xy 313.85808 -139.399533) (xy 313.903929 -139.429)
			(xy 313.945118 -139.464692) (xy 313.980808 -139.505882) (xy 314.010273 -139.551732) (xy 314.032914 -139.601309)
			(xy 314.048268 -139.653602) (xy 314.056024 -139.707549) (xy 314.056024 -139.71651) (xy 314.991748 -139.71651)
			(xy 314.995819 -139.660888) (xy 315.007945 -139.606451) (xy 315.027868 -139.55436) (xy 315.055164 -139.505725)
			(xy 315.08925 -139.461582) (xy 315.129399 -139.422873) (xy 315.174757 -139.390422) (xy 315.224357 -139.364921)
			(xy 315.277141 -139.346914) (xy 315.331984 -139.336784) (xy 315.387718 -139.334747) (xy 315.443155 -139.340847)
			(xy 315.497112 -139.354953) (xy 315.548441 -139.376765) (xy 315.596047 -139.405819) (xy 315.638915 -139.441494)
			(xy 315.676132 -139.483031) (xy 315.706905 -139.529544) (xy 315.730577 -139.580041) (xy 315.746645 -139.633448)
			(xy 315.754765 -139.688624) (xy 315.755274 -139.71651) (xy 315.754765 -139.744396) (xy 315.746645 -139.799572)
			(xy 315.730577 -139.852979) (xy 315.706905 -139.903476) (xy 315.676132 -139.949989) (xy 315.638915 -139.991526)
			(xy 315.596047 -140.027201) (xy 315.548441 -140.056255) (xy 315.497112 -140.078067) (xy 315.443155 -140.092173)
			(xy 315.387718 -140.098273) (xy 315.331984 -140.096236) (xy 315.277141 -140.086106) (xy 315.224357 -140.068099)
			(xy 315.174757 -140.042598) (xy 315.129399 -140.010147) (xy 315.08925 -139.971438) (xy 315.055164 -139.927295)
			(xy 315.027868 -139.87866) (xy 315.007945 -139.826569) (xy 314.995819 -139.772132) (xy 314.991748 -139.71651)
			(xy 314.056024 -139.71651) (xy 314.056024 -139.762051) (xy 314.048268 -139.815998) (xy 314.032914 -139.868291)
			(xy 314.010273 -139.917868) (xy 313.980808 -139.963718) (xy 313.945118 -140.004908) (xy 313.903929 -140.0406)
			(xy 313.85808 -140.070067) (xy 313.808505 -140.092709) (xy 313.756211 -140.108065) (xy 313.702265 -140.115823)
			(xy 313.675014 -140.116306) (xy 313.648828 -140.115859) (xy 313.596951 -140.108662) (xy 313.546549 -140.094429)
			(xy 313.498571 -140.073429) (xy 313.45392 -140.046057) (xy 313.413438 -140.012828) (xy 313.39536 -139.993878)
			(xy 313.387938 -139.986587) (xy 313.368919 -139.97821) (xy 313.35853 -139.977622) (xy 313.282838 -139.977622)
			(xy 313.28233 -139.977622) (xy 313.277504 -139.977876) (xy 313.268408 -139.979286) (xy 313.252019 -139.987632)
			(xy 313.2455 -139.994132) (xy 313.229498 -140.010388) (xy 313.209498 -140.028896) (xy 313.165173 -140.060594)
			(xy 313.116785 -140.085656) (xy 313.065322 -140.103572) (xy 313.011832 -140.113975) (xy 312.984642 -140.115798)
			(xy 312.983626 -140.115798) (xy 312.979308 -140.116052) (xy 312.962036 -140.12418) (xy 312.90768 -140.18133)
			(xy 312.901375 -140.188546) (xy 312.894207 -140.206303) (xy 312.89371 -140.215874) (xy 312.856066 -143.479266)
			(xy 313.274456 -143.479266) (xy 313.274456 -142.615666) (xy 313.274946 -142.585698) (xy 313.282769 -142.526276)
			(xy 313.298282 -142.468383) (xy 313.321218 -142.41301) (xy 313.351185 -142.361104) (xy 313.387672 -142.313554)
			(xy 313.430052 -142.271174) (xy 313.477602 -142.234687) (xy 313.529508 -142.20472) (xy 313.584881 -142.181784)
			(xy 313.642774 -142.166271) (xy 313.702196 -142.158448) (xy 313.762132 -142.158448) (xy 313.821554 -142.166271)
			(xy 313.879447 -142.181784) (xy 313.93482 -142.20472) (xy 313.986726 -142.234687) (xy 314.034276 -142.271174)
			(xy 314.076656 -142.313554) (xy 314.113143 -142.361104) (xy 314.14311 -142.41301) (xy 314.166046 -142.468383)
			(xy 314.181559 -142.526276) (xy 314.189382 -142.585698) (xy 314.189872 -142.615666) (xy 314.189872 -143.479266)
			(xy 314.189382 -143.509234) (xy 314.181559 -143.568656) (xy 314.166046 -143.626549) (xy 314.14311 -143.681922)
			(xy 314.113143 -143.733828) (xy 314.076656 -143.781378) (xy 314.034276 -143.823758) (xy 313.986726 -143.860245)
			(xy 313.93482 -143.890212) (xy 313.879447 -143.913148) (xy 313.821554 -143.928661) (xy 313.762132 -143.936484)
			(xy 313.702196 -143.936484) (xy 313.642774 -143.928661) (xy 313.584881 -143.913148) (xy 313.529508 -143.890212)
			(xy 313.477602 -143.860245) (xy 313.430052 -143.823758) (xy 313.387672 -143.781378) (xy 313.351185 -143.733828)
			(xy 313.321218 -143.681922) (xy 313.298282 -143.626549) (xy 313.282769 -143.568656) (xy 313.274946 -143.509234)
			(xy 313.274456 -143.479266) (xy 312.856066 -143.479266) (xy 312.84926 -144.069308) (xy 312.848718 -144.098413)
			(xy 312.844652 -144.156489) (xy 312.841132 -144.185386) (xy 312.699389 -145.285714) (xy 315.916564 -145.285714)
			(xy 315.916564 -144.422114) (xy 315.917054 -144.392146) (xy 315.924877 -144.332724) (xy 315.94039 -144.274831)
			(xy 315.963326 -144.219458) (xy 315.993293 -144.167552) (xy 316.02978 -144.120002) (xy 316.07216 -144.077622)
			(xy 316.11971 -144.041135) (xy 316.171616 -144.011168) (xy 316.226989 -143.988232) (xy 316.284882 -143.972719)
			(xy 316.344304 -143.964896) (xy 316.40424 -143.964896) (xy 316.463662 -143.972719) (xy 316.521555 -143.988232)
			(xy 316.576928 -144.011168) (xy 316.628834 -144.041135) (xy 316.676384 -144.077622) (xy 316.718764 -144.120002)
			(xy 316.755251 -144.167552) (xy 316.785218 -144.219458) (xy 316.808154 -144.274831) (xy 316.823667 -144.332724)
			(xy 316.83149 -144.392146) (xy 316.83198 -144.422114) (xy 316.83198 -145.285714) (xy 316.83149 -145.315682)
			(xy 316.823667 -145.375104) (xy 316.808154 -145.432997) (xy 316.785218 -145.48837) (xy 316.755251 -145.540276)
			(xy 316.718764 -145.587826) (xy 316.676384 -145.630206) (xy 316.628834 -145.666693) (xy 316.576928 -145.69666)
			(xy 316.521555 -145.719596) (xy 316.463662 -145.735109) (xy 316.40424 -145.742932) (xy 316.344304 -145.742932)
			(xy 316.284882 -145.735109) (xy 316.226989 -145.719596) (xy 316.171616 -145.69666) (xy 316.11971 -145.666693)
			(xy 316.07216 -145.630206) (xy 316.02978 -145.587826) (xy 315.993293 -145.540276) (xy 315.963326 -145.48837)
			(xy 315.94039 -145.432997) (xy 315.924877 -145.375104) (xy 315.917054 -145.315682) (xy 315.916564 -145.285714)
			(xy 312.699389 -145.285714) (xy 312.468354 -147.079208) (xy 313.274456 -147.079208) (xy 313.274456 -146.215608)
			(xy 313.274946 -146.18564) (xy 313.282769 -146.126218) (xy 313.298282 -146.068325) (xy 313.321218 -146.012952)
			(xy 313.351185 -145.961046) (xy 313.387672 -145.913496) (xy 313.430052 -145.871116) (xy 313.477602 -145.834629)
			(xy 313.529508 -145.804662) (xy 313.584881 -145.781726) (xy 313.642774 -145.766213) (xy 313.702196 -145.75839)
			(xy 313.762132 -145.75839) (xy 313.821554 -145.766213) (xy 313.879447 -145.781726) (xy 313.93482 -145.804662)
			(xy 313.986726 -145.834629) (xy 314.034276 -145.871116) (xy 314.076656 -145.913496) (xy 314.113143 -145.961046)
			(xy 314.14311 -146.012952) (xy 314.166046 -146.068325) (xy 314.181559 -146.126218) (xy 314.189382 -146.18564)
			(xy 314.189872 -146.215608) (xy 314.189872 -147.079208) (xy 314.189382 -147.109176) (xy 314.181559 -147.168598)
			(xy 314.166046 -147.226491) (xy 314.14311 -147.281864) (xy 314.113143 -147.33377) (xy 314.076656 -147.38132)
			(xy 314.034276 -147.4237) (xy 313.986726 -147.460187) (xy 313.93482 -147.490154) (xy 313.879447 -147.51309)
			(xy 313.821554 -147.528603) (xy 313.762132 -147.536426) (xy 313.702196 -147.536426) (xy 313.642774 -147.528603)
			(xy 313.584881 -147.51309) (xy 313.529508 -147.490154) (xy 313.477602 -147.460187) (xy 313.430052 -147.4237)
			(xy 313.387672 -147.38132) (xy 313.351185 -147.33377) (xy 313.321218 -147.281864) (xy 313.298282 -147.226491)
			(xy 313.282769 -147.168598) (xy 313.274946 -147.109176) (xy 313.274456 -147.079208) (xy 312.468354 -147.079208)
			(xy 312.235617 -148.88591) (xy 315.916564 -148.88591) (xy 315.916564 -148.02231) (xy 315.917054 -147.992342)
			(xy 315.924877 -147.93292) (xy 315.94039 -147.875027) (xy 315.963326 -147.819654) (xy 315.993293 -147.767748)
			(xy 316.02978 -147.720198) (xy 316.07216 -147.677818) (xy 316.11971 -147.641331) (xy 316.171616 -147.611364)
			(xy 316.226989 -147.588428) (xy 316.284882 -147.572915) (xy 316.344304 -147.565092) (xy 316.40424 -147.565092)
			(xy 316.463662 -147.572915) (xy 316.521555 -147.588428) (xy 316.576928 -147.611364) (xy 316.628834 -147.641331)
			(xy 316.676384 -147.677818) (xy 316.718764 -147.720198) (xy 316.755251 -147.767748) (xy 316.785218 -147.819654)
			(xy 316.808154 -147.875027) (xy 316.823667 -147.93292) (xy 316.83149 -147.992342) (xy 316.83198 -148.02231)
			(xy 316.83198 -148.88591) (xy 316.83149 -148.915878) (xy 316.823667 -148.9753) (xy 316.808154 -149.033193)
			(xy 316.785218 -149.088566) (xy 316.755251 -149.140472) (xy 316.718764 -149.188022) (xy 316.676384 -149.230402)
			(xy 316.628834 -149.266889) (xy 316.576928 -149.296856) (xy 316.521555 -149.319792) (xy 316.463662 -149.335305)
			(xy 316.40424 -149.343128) (xy 316.344304 -149.343128) (xy 316.284882 -149.335305) (xy 316.226989 -149.319792)
			(xy 316.171616 -149.296856) (xy 316.11971 -149.266889) (xy 316.07216 -149.230402) (xy 316.02978 -149.188022)
			(xy 315.993293 -149.140472) (xy 315.963326 -149.088566) (xy 315.94039 -149.033193) (xy 315.924877 -148.9753)
			(xy 315.917054 -148.915878) (xy 315.916564 -148.88591) (xy 312.235617 -148.88591) (xy 312.004614 -150.67915)
			(xy 313.274456 -150.67915) (xy 313.274456 -149.81555) (xy 313.274946 -149.785582) (xy 313.282769 -149.72616)
			(xy 313.298282 -149.668267) (xy 313.321218 -149.612894) (xy 313.351185 -149.560988) (xy 313.387672 -149.513438)
			(xy 313.430052 -149.471058) (xy 313.477602 -149.434571) (xy 313.529508 -149.404604) (xy 313.584881 -149.381668)
			(xy 313.642774 -149.366155) (xy 313.702196 -149.358332) (xy 313.762132 -149.358332) (xy 313.821554 -149.366155)
			(xy 313.879447 -149.381668) (xy 313.93482 -149.404604) (xy 313.986726 -149.434571) (xy 314.034276 -149.471058)
			(xy 314.076656 -149.513438) (xy 314.113143 -149.560988) (xy 314.14311 -149.612894) (xy 314.166046 -149.668267)
			(xy 314.181559 -149.72616) (xy 314.189382 -149.785582) (xy 314.189872 -149.81555) (xy 314.189872 -150.67915)
			(xy 314.189382 -150.709118) (xy 314.181559 -150.76854) (xy 314.166046 -150.826433) (xy 314.14311 -150.881806)
			(xy 314.113143 -150.933712) (xy 314.076656 -150.981262) (xy 314.034276 -151.023642) (xy 313.986726 -151.060129)
			(xy 313.93482 -151.090096) (xy 313.879447 -151.113032) (xy 313.821554 -151.128545) (xy 313.762132 -151.136368)
			(xy 313.702196 -151.136368) (xy 313.642774 -151.128545) (xy 313.584881 -151.113032) (xy 313.529508 -151.090096)
			(xy 313.477602 -151.060129) (xy 313.430052 -151.023642) (xy 313.387672 -150.981262) (xy 313.351185 -150.933712)
			(xy 313.321218 -150.881806) (xy 313.298282 -150.826433) (xy 313.282769 -150.76854) (xy 313.274946 -150.709118)
			(xy 313.274456 -150.67915) (xy 312.004614 -150.67915) (xy 311.771877 -152.485852) (xy 315.916564 -152.485852)
			(xy 315.916564 -151.622252) (xy 315.917054 -151.592284) (xy 315.924877 -151.532862) (xy 315.94039 -151.474969)
			(xy 315.963326 -151.419596) (xy 315.993293 -151.36769) (xy 316.02978 -151.32014) (xy 316.07216 -151.27776)
			(xy 316.11971 -151.241273) (xy 316.171616 -151.211306) (xy 316.226989 -151.18837) (xy 316.284882 -151.172857)
			(xy 316.344304 -151.165034) (xy 316.40424 -151.165034) (xy 316.463662 -151.172857) (xy 316.521555 -151.18837)
			(xy 316.576928 -151.211306) (xy 316.628834 -151.241273) (xy 316.676384 -151.27776) (xy 316.718764 -151.32014)
			(xy 316.755251 -151.36769) (xy 316.785218 -151.419596) (xy 316.808154 -151.474969) (xy 316.823667 -151.532862)
			(xy 316.83149 -151.592284) (xy 316.83198 -151.622252) (xy 316.83198 -152.485852) (xy 316.83149 -152.51582)
			(xy 316.823667 -152.575242) (xy 316.808154 -152.633135) (xy 316.785218 -152.688508) (xy 316.755251 -152.740414)
			(xy 316.718764 -152.787964) (xy 316.676384 -152.830344) (xy 316.628834 -152.866831) (xy 316.576928 -152.896798)
			(xy 316.521555 -152.919734) (xy 316.463662 -152.935247) (xy 316.40424 -152.94307) (xy 316.344304 -152.94307)
			(xy 316.284882 -152.935247) (xy 316.226989 -152.919734) (xy 316.171616 -152.896798) (xy 316.11971 -152.866831)
			(xy 316.07216 -152.830344) (xy 316.02978 -152.787964) (xy 315.993293 -152.740414) (xy 315.963326 -152.688508)
			(xy 315.94039 -152.633135) (xy 315.924877 -152.575242) (xy 315.917054 -152.51582) (xy 315.916564 -152.485852)
			(xy 311.771877 -152.485852) (xy 311.540841 -154.279346) (xy 313.274456 -154.279346) (xy 313.274456 -153.415746)
			(xy 313.274946 -153.385778) (xy 313.282769 -153.326356) (xy 313.298282 -153.268463) (xy 313.321218 -153.21309)
			(xy 313.351185 -153.161184) (xy 313.387672 -153.113634) (xy 313.430052 -153.071254) (xy 313.477602 -153.034767)
			(xy 313.529508 -153.0048) (xy 313.584881 -152.981864) (xy 313.642774 -152.966351) (xy 313.702196 -152.958528)
			(xy 313.762132 -152.958528) (xy 313.821554 -152.966351) (xy 313.879447 -152.981864) (xy 313.93482 -153.0048)
			(xy 313.986726 -153.034767) (xy 314.034276 -153.071254) (xy 314.076656 -153.113634) (xy 314.113143 -153.161184)
			(xy 314.14311 -153.21309) (xy 314.166046 -153.268463) (xy 314.181559 -153.326356) (xy 314.189382 -153.385778)
			(xy 314.189872 -153.415746) (xy 314.189872 -154.279346) (xy 314.189382 -154.309314) (xy 314.181559 -154.368736)
			(xy 314.166046 -154.426629) (xy 314.14311 -154.482002) (xy 314.113143 -154.533908) (xy 314.076656 -154.581458)
			(xy 314.034276 -154.623838) (xy 313.986726 -154.660325) (xy 313.93482 -154.690292) (xy 313.879447 -154.713228)
			(xy 313.821554 -154.728741) (xy 313.762132 -154.736564) (xy 313.702196 -154.736564) (xy 313.642774 -154.728741)
			(xy 313.584881 -154.713228) (xy 313.529508 -154.690292) (xy 313.477602 -154.660325) (xy 313.430052 -154.623838)
			(xy 313.387672 -154.581458) (xy 313.351185 -154.533908) (xy 313.321218 -154.482002) (xy 313.298282 -154.426629)
			(xy 313.282769 -154.368736) (xy 313.274946 -154.309314) (xy 313.274456 -154.279346) (xy 311.540841 -154.279346)
			(xy 311.452006 -154.968956) (xy 311.445402 -155.012644) (xy 311.258509 -156.085794) (xy 315.916564 -156.085794)
			(xy 315.916564 -155.222194) (xy 315.917054 -155.192226) (xy 315.924877 -155.132804) (xy 315.94039 -155.074911)
			(xy 315.963326 -155.019538) (xy 315.993293 -154.967632) (xy 316.02978 -154.920082) (xy 316.07216 -154.877702)
			(xy 316.11971 -154.841215) (xy 316.171616 -154.811248) (xy 316.226989 -154.788312) (xy 316.284882 -154.772799)
			(xy 316.344304 -154.764976) (xy 316.40424 -154.764976) (xy 316.463662 -154.772799) (xy 316.521555 -154.788312)
			(xy 316.576928 -154.811248) (xy 316.628834 -154.841215) (xy 316.676384 -154.877702) (xy 316.718764 -154.920082)
			(xy 316.755251 -154.967632) (xy 316.785218 -155.019538) (xy 316.808154 -155.074911) (xy 316.823667 -155.132804)
			(xy 316.83149 -155.192226) (xy 316.83198 -155.222194) (xy 316.83198 -156.085794) (xy 316.83149 -156.115762)
			(xy 316.823667 -156.175184) (xy 316.808154 -156.233077) (xy 316.785218 -156.28845) (xy 316.755251 -156.340356)
			(xy 316.718764 -156.387906) (xy 316.676384 -156.430286) (xy 316.628834 -156.466773) (xy 316.576928 -156.49674)
			(xy 316.521555 -156.519676) (xy 316.463662 -156.535189) (xy 316.40424 -156.543012) (xy 316.344304 -156.543012)
			(xy 316.284882 -156.535189) (xy 316.226989 -156.519676) (xy 316.171616 -156.49674) (xy 316.11971 -156.466773)
			(xy 316.07216 -156.430286) (xy 316.02978 -156.387906) (xy 315.993293 -156.340356) (xy 315.963326 -156.28845)
			(xy 315.94039 -156.233077) (xy 315.924877 -156.175184) (xy 315.917054 -156.115762) (xy 315.916564 -156.085794)
			(xy 311.258509 -156.085794) (xy 310.88689 -158.219648) (xy 313.38266 -158.219648) (xy 313.3832 -158.192398)
			(xy 313.390949 -158.138451) (xy 313.406298 -158.086157) (xy 313.428932 -158.036579) (xy 313.458392 -157.990727)
			(xy 313.494078 -157.949535) (xy 313.535263 -157.91384) (xy 313.581109 -157.884371) (xy 313.630682 -157.861726)
			(xy 313.682973 -157.846366) (xy 313.736918 -157.838606) (xy 313.764168 -157.83814) (xy 313.790799 -157.838586)
			(xy 313.843545 -157.845992) (xy 313.894747 -157.860662) (xy 313.943411 -157.882313) (xy 313.98859 -157.910524)
			(xy 314.029404 -157.944745) (xy 314.065062 -157.984311) (xy 314.094868 -158.028453) (xy 314.118244 -158.076312)
			(xy 314.134735 -158.126957) (xy 314.139834 -158.1531) (xy 314.141834 -158.162162) (xy 314.151347 -158.17808)
			(xy 314.165906 -158.189564) (xy 314.174632 -158.192724) (xy 314.260484 -158.219902) (xy 314.269476 -158.22227)
			(xy 314.288021 -158.221148) (xy 314.304953 -158.213501) (xy 314.311792 -158.207202) (xy 314.855352 -157.663642)
			(xy 314.874157 -157.645556) (xy 314.916349 -157.614868) (xy 314.962823 -157.591163) (xy 315.012436 -157.575024)
			(xy 315.063962 -157.56685) (xy 315.090048 -157.56636) (xy 316.621414 -157.56636) (xy 316.631485 -157.565952)
			(xy 316.650084 -157.55822) (xy 316.657482 -157.551374) (xy 317.937134 -156.271722) (xy 317.943962 -156.264312)
			(xy 317.951688 -156.24572) (xy 317.95212 -156.235654) (xy 317.95212 -140.682218) (xy 317.94958 -140.671042)
			(xy 317.946786 -140.665708) (xy 317.946278 -140.664692) (xy 317.932554 -140.637218) (xy 317.9131 -140.57897)
			(xy 317.903225 -140.518359) (xy 317.90259 -140.487654) (xy 317.903076 -140.460403) (xy 317.910832 -140.406455)
			(xy 317.926187 -140.35416) (xy 317.948829 -140.304583) (xy 317.978295 -140.258733) (xy 318.013986 -140.217542)
			(xy 318.055177 -140.181851) (xy 318.101027 -140.152385) (xy 318.150604 -140.129743) (xy 318.202899 -140.114388)
			(xy 318.256847 -140.106632) (xy 318.311349 -140.106632) (xy 318.365297 -140.114388) (xy 318.417592 -140.129743)
			(xy 318.467169 -140.152385) (xy 318.513019 -140.181851) (xy 318.55421 -140.217542) (xy 318.589901 -140.258733)
			(xy 318.619367 -140.304583) (xy 318.642009 -140.35416) (xy 318.657364 -140.406455) (xy 318.66512 -140.460403)
			(xy 318.665606 -140.487654) (xy 318.665011 -140.518457) (xy 318.655079 -140.579259) (xy 318.6355 -140.637672)
			(xy 318.621664 -140.6652) (xy 318.62141 -140.665708) (xy 318.618935 -140.67103) (xy 318.616231 -140.682447)
			(xy 318.616076 -140.688314) (xy 318.616076 -156.39415) (xy 318.615579 -156.420237) (xy 318.607418 -156.471769)
			(xy 318.591289 -156.521387) (xy 318.56759 -156.567868) (xy 318.536906 -156.610066) (xy 318.518794 -156.628846)
			(xy 317.014606 -158.133034) (xy 316.995815 -158.151136) (xy 316.953621 -158.181822) (xy 316.907142 -158.205525)
			(xy 316.857527 -158.22166) (xy 316.805997 -158.229829) (xy 316.77991 -158.230316) (xy 315.248544 -158.230316)
			(xy 315.238477 -158.23076) (xy 315.219879 -158.238467) (xy 315.212476 -158.245302) (xy 314.663328 -158.79445)
			(xy 314.657178 -158.801118) (xy 314.649621 -158.817596) (xy 314.648239 -158.835671) (xy 314.650374 -158.844488)
			(xy 314.678822 -158.943294) (xy 314.698888 -158.962344) (xy 314.712604 -158.965392) (xy 314.740379 -158.972221)
			(xy 314.793664 -158.993004) (xy 314.843248 -159.02151) (xy 314.88802 -159.057099) (xy 314.926977 -159.098974)
			(xy 314.959246 -159.146197) (xy 314.984102 -159.197707) (xy 315.000989 -159.252352) (xy 315.009528 -159.308905)
			(xy 315.010038 -159.337502) (xy 315.009489 -159.365988) (xy 315.001017 -159.422326) (xy 314.984261 -159.476778)
			(xy 314.959594 -159.528132) (xy 314.927565 -159.575248) (xy 314.888886 -159.617077) (xy 314.844416 -159.652689)
			(xy 314.820046 -159.667448) (xy 314.811156 -159.672528) (xy 314.79871 -159.689038) (xy 314.778644 -159.770064)
			(xy 314.776653 -159.779956) (xy 314.779804 -159.79987) (xy 314.78474 -159.808672) (xy 314.78474 -159.80918)
			(xy 314.798318 -159.831905) (xy 314.819762 -159.880304) (xy 314.834306 -159.931204) (xy 314.84167 -159.983626)
			(xy 314.842144 -160.010094) (xy 314.842144 -160.010348) (xy 314.841588 -160.040003) (xy 314.83239 -160.098597)
			(xy 314.814239 -160.155063) (xy 314.787571 -160.208041) (xy 314.753029 -160.256255) (xy 314.711444 -160.298546)
			(xy 314.687966 -160.316672) (xy 314.6806 -160.322006) (xy 314.67044 -160.3375) (xy 314.654184 -160.411922)
			(xy 314.652637 -160.420873) (xy 314.65523 -160.438836) (xy 314.659264 -160.446974) (xy 314.659264 -160.447228)
			(xy 314.674107 -160.475538) (xy 314.69515 -160.535893) (xy 314.70584 -160.598911) (xy 314.706508 -160.63087)
			(xy 314.706022 -160.658121) (xy 314.698266 -160.712069) (xy 314.682911 -160.764364) (xy 314.660269 -160.813941)
			(xy 314.630803 -160.859791) (xy 314.595112 -160.900982) (xy 314.553921 -160.936673) (xy 314.508071 -160.966139)
			(xy 314.458494 -160.988781) (xy 314.406199 -161.004136) (xy 314.352251 -161.011892) (xy 314.297749 -161.011892)
			(xy 314.243801 -161.004136) (xy 314.191506 -160.988781) (xy 314.141929 -160.966139) (xy 314.096079 -160.936673)
			(xy 314.054888 -160.900982) (xy 314.019197 -160.859791) (xy 313.989731 -160.813941) (xy 313.967089 -160.764364)
			(xy 313.951734 -160.712069) (xy 313.943978 -160.658121) (xy 313.943492 -160.63087) (xy 313.943492 -160.630616)
			(xy 313.944047 -160.600961) (xy 313.953249 -160.542368) (xy 313.971402 -160.485904) (xy 313.99807 -160.432927)
			(xy 314.032611 -160.384712) (xy 314.074193 -160.342419) (xy 314.09767 -160.324292) (xy 314.105036 -160.318958)
			(xy 314.115196 -160.303464) (xy 314.131452 -160.229042) (xy 314.133025 -160.220094) (xy 314.130416 -160.202126)
			(xy 314.126372 -160.19399) (xy 314.126372 -160.193736) (xy 314.111547 -160.165417) (xy 314.090499 -160.105066)
			(xy 314.079801 -160.042052) (xy 314.079128 -160.010094) (xy 314.079691 -159.981609) (xy 314.088163 -159.925272)
			(xy 314.104917 -159.870822) (xy 314.129582 -159.819467) (xy 314.161609 -159.772352) (xy 314.200285 -159.730522)
			(xy 314.244752 -159.694908) (xy 314.26912 -159.680148) (xy 314.27801 -159.675068) (xy 314.290456 -159.658558)
			(xy 314.310522 -159.577532) (xy 314.31252 -159.567641) (xy 314.309365 -159.547725) (xy 314.304426 -159.538924)
			(xy 314.304426 -159.538416) (xy 314.291982 -159.517694) (xy 314.271861 -159.473743) (xy 314.264294 -159.450786)
			(xy 314.264294 -159.450532) (xy 314.260245 -159.43988) (xy 314.244685 -159.423269) (xy 314.234322 -159.418528)
			(xy 314.149486 -159.385254) (xy 314.126626 -159.387032) (xy 314.116466 -159.392874) (xy 314.094684 -159.404956)
			(xy 314.04864 -159.423957) (xy 314.000514 -159.436803) (xy 313.951125 -159.443276) (xy 313.92622 -159.443674)
			(xy 313.898966 -159.443226) (xy 313.845013 -159.435471) (xy 313.792713 -159.420116) (xy 313.74313 -159.397473)
			(xy 313.697275 -159.368004) (xy 313.656082 -159.332308) (xy 313.620388 -159.291113) (xy 313.59092 -159.245257)
			(xy 313.568279 -159.195674) (xy 313.552926 -159.143373) (xy 313.545173 -159.08942) (xy 313.544712 -159.062166)
			(xy 313.545248 -159.033447) (xy 313.553856 -158.976659) (xy 313.570887 -158.921805) (xy 313.595955 -158.870128)
			(xy 313.628493 -158.822796) (xy 313.667765 -158.780883) (xy 313.69 -158.7627) (xy 313.690254 -158.762446)
			(xy 313.697175 -158.756347) (xy 313.706517 -158.740458) (xy 313.709646 -158.722294) (xy 313.708288 -158.71317)
			(xy 313.688476 -158.610554) (xy 313.66968 -158.589472) (xy 313.656218 -158.585408) (xy 313.655964 -158.585408)
			(xy 313.630006 -158.577244) (xy 313.580542 -158.554566) (xy 313.534805 -158.525087) (xy 313.493722 -158.489406)
			(xy 313.458128 -158.448248) (xy 313.428746 -158.402448) (xy 313.406173 -158.352936) (xy 313.390867 -158.300718)
			(xy 313.38314 -158.246855) (xy 313.38266 -158.219648) (xy 310.88689 -158.219648) (xy 301.163482 -214.051896)
			(xy 301.1678 -214.057992) (xy 301.207678 -214.06739) (xy 301.235271 -214.074361) (xy 301.288163 -214.095369)
			(xy 301.337347 -214.124001) (xy 301.381731 -214.159623) (xy 301.42033 -214.201444) (xy 301.452288 -214.248536)
			(xy 301.476894 -214.299852) (xy 301.493604 -214.354255) (xy 301.502045 -214.410536) (xy 301.502572 -214.438992)
			(xy 301.502109 -214.466244) (xy 301.494353 -214.520194) (xy 301.478997 -214.572491) (xy 301.456355 -214.62207)
			(xy 301.426886 -214.667921) (xy 301.391192 -214.709112) (xy 301.349999 -214.744803) (xy 301.304145 -214.774268)
			(xy 301.254565 -214.796907) (xy 301.202267 -214.812259) (xy 301.148316 -214.820011) (xy 301.121064 -214.8205)
			(xy 301.110374 -214.820455) (xy 301.089025 -214.819312) (xy 301.078392 -214.818214) (xy 301.03699 -214.813642)
			(xy 301.029878 -214.818722) (xy 300.899062 -215.570562) (xy 302.123854 -215.570562) (xy 302.127925 -215.51494)
			(xy 302.140051 -215.460503) (xy 302.159974 -215.408412) (xy 302.18727 -215.359777) (xy 302.221356 -215.315634)
			(xy 302.261505 -215.276925) (xy 302.306863 -215.244474) (xy 302.356463 -215.218973) (xy 302.409247 -215.200966)
			(xy 302.46409 -215.190836) (xy 302.519824 -215.188799) (xy 302.575261 -215.194899) (xy 302.629218 -215.209005)
			(xy 302.680547 -215.230817) (xy 302.728153 -215.259871) (xy 302.771021 -215.295546) (xy 302.808238 -215.337083)
			(xy 302.839011 -215.383596) (xy 302.862683 -215.434093) (xy 302.878751 -215.4875) (xy 302.886871 -215.542676)
			(xy 302.88738 -215.570562) (xy 302.886871 -215.598448) (xy 302.878751 -215.653624) (xy 302.862683 -215.707031)
			(xy 302.839011 -215.757528) (xy 302.808238 -215.804041) (xy 302.771021 -215.845578) (xy 302.728153 -215.881253)
			(xy 302.680547 -215.910307) (xy 302.629218 -215.932119) (xy 302.575261 -215.946225) (xy 302.519824 -215.952325)
			(xy 302.46409 -215.950288) (xy 302.409247 -215.940158) (xy 302.356463 -215.922151) (xy 302.306863 -215.89665)
			(xy 302.261505 -215.864199) (xy 302.221356 -215.82549) (xy 302.18727 -215.781347) (xy 302.159974 -215.732712)
			(xy 302.140051 -215.680621) (xy 302.127925 -215.626184) (xy 302.123854 -215.570562) (xy 300.899062 -215.570562)
			(xy 300.864016 -215.771984) (xy 300.868334 -215.791034) (xy 300.868588 -215.791542) (xy 300.907704 -215.800432)
			(xy 300.935391 -215.807328) (xy 300.988482 -215.828225) (xy 301.037869 -215.856794) (xy 301.082451 -215.892399)
			(xy 301.121234 -215.934247) (xy 301.153353 -215.981403) (xy 301.17809 -216.032817) (xy 301.194896 -216.087341)
			(xy 301.203394 -216.14376) (xy 301.203868 -216.172288) (xy 301.203405 -216.19954) (xy 301.19565 -216.25349)
			(xy 301.180294 -216.305787) (xy 301.157652 -216.355367) (xy 301.128184 -216.401218) (xy 301.092489 -216.442409)
			(xy 301.051296 -216.4781) (xy 301.005442 -216.507565) (xy 300.955861 -216.530204) (xy 300.903563 -216.545556)
			(xy 300.849612 -216.553307) (xy 300.82236 -216.553796) (xy 300.822106 -216.553796) (xy 300.808661 -216.553669)
			(xy 300.781839 -216.551765) (xy 300.768512 -216.549986) (xy 300.767496 -216.549986) (xy 300.747938 -216.5477)
			(xy 300.729904 -216.552018) (xy 300.727872 -216.553542) (xy 300.614842 -217.20175) (xy 300.616366 -217.20429)
			(xy 300.641004 -217.216482) (xy 300.642528 -217.21699) (xy 300.667218 -217.228695) (xy 300.713257 -217.258123)
			(xy 300.754627 -217.293816) (xy 300.790482 -217.335047) (xy 300.820089 -217.38097) (xy 300.842843 -217.430647)
			(xy 300.858277 -217.483062) (xy 300.866077 -217.537142) (xy 300.866556 -217.564462) (xy 300.866062 -217.592504)
			(xy 300.860328 -217.631264) (xy 301.932084 -217.631264) (xy 301.936155 -217.575642) (xy 301.948281 -217.521205)
			(xy 301.968204 -217.469114) (xy 301.9955 -217.420479) (xy 302.029586 -217.376336) (xy 302.069735 -217.337627)
			(xy 302.115093 -217.305176) (xy 302.164693 -217.279675) (xy 302.217477 -217.261668) (xy 302.27232 -217.251538)
			(xy 302.328054 -217.249501) (xy 302.383491 -217.255601) (xy 302.437448 -217.269707) (xy 302.488777 -217.291519)
			(xy 302.536383 -217.320573) (xy 302.579251 -217.356248) (xy 302.616468 -217.397785) (xy 302.647241 -217.444298)
			(xy 302.670913 -217.494795) (xy 302.686981 -217.548202) (xy 302.695101 -217.603378) (xy 302.69561 -217.631264)
			(xy 302.695101 -217.65915) (xy 302.686981 -217.714326) (xy 302.670913 -217.767733) (xy 302.647241 -217.81823)
			(xy 302.616468 -217.864743) (xy 302.579251 -217.90628) (xy 302.536383 -217.941955) (xy 302.488777 -217.971009)
			(xy 302.437448 -217.992821) (xy 302.383491 -218.006927) (xy 302.328054 -218.013027) (xy 302.27232 -218.01099)
			(xy 302.217477 -218.00086) (xy 302.164693 -217.982853) (xy 302.115093 -217.957352) (xy 302.069735 -217.924901)
			(xy 302.029586 -217.886192) (xy 301.9955 -217.842049) (xy 301.968204 -217.793414) (xy 301.948281 -217.741323)
			(xy 301.936155 -217.686886) (xy 301.932084 -217.631264) (xy 300.860328 -217.631264) (xy 300.857854 -217.647983)
			(xy 300.841608 -217.701662) (xy 300.817676 -217.752382) (xy 300.786574 -217.799051) (xy 300.748972 -217.840661)
			(xy 300.705681 -217.876315) (xy 300.657634 -217.905244) (xy 300.605869 -217.926825) (xy 300.551502 -217.940591)
			(xy 300.523656 -217.943938) (xy 300.523148 -217.943938) (xy 300.488096 -217.947748) (xy 300.48454 -217.950796)
			(xy 300.072044 -220.320362) (xy 300.07687 -220.340682) (xy 300.083474 -220.349064) (xy 300.098357 -220.369114)
			(xy 300.123312 -220.412366) (xy 300.142408 -220.458506) (xy 300.155317 -220.506743) (xy 300.16182 -220.556252)
			(xy 300.161853 -220.55836) (xy 301.225456 -220.55836) (xy 301.229527 -220.502738) (xy 301.241653 -220.448301)
			(xy 301.261576 -220.39621) (xy 301.288872 -220.347575) (xy 301.322958 -220.303432) (xy 301.363107 -220.264723)
			(xy 301.408465 -220.232272) (xy 301.458065 -220.206771) (xy 301.510849 -220.188764) (xy 301.565692 -220.178634)
			(xy 301.621426 -220.176597) (xy 301.676863 -220.182697) (xy 301.73082 -220.196803) (xy 301.782149 -220.218615)
			(xy 301.829755 -220.247669) (xy 301.872623 -220.283344) (xy 301.90984 -220.324881) (xy 301.940613 -220.371394)
			(xy 301.964285 -220.421891) (xy 301.980353 -220.475298) (xy 301.988473 -220.530474) (xy 301.988982 -220.55836)
			(xy 301.988473 -220.586246) (xy 301.98211 -220.62948) (xy 302.495456 -220.62948) (xy 302.499527 -220.573858)
			(xy 302.511653 -220.519421) (xy 302.531576 -220.46733) (xy 302.558872 -220.418695) (xy 302.592958 -220.374552)
			(xy 302.633107 -220.335843) (xy 302.678465 -220.303392) (xy 302.728065 -220.277891) (xy 302.780849 -220.259884)
			(xy 302.835692 -220.249754) (xy 302.891426 -220.247717) (xy 302.946863 -220.253817) (xy 303.00082 -220.267923)
			(xy 303.052149 -220.289735) (xy 303.099755 -220.318789) (xy 303.142623 -220.354464) (xy 303.17984 -220.396001)
			(xy 303.210613 -220.442514) (xy 303.234285 -220.493011) (xy 303.250353 -220.546418) (xy 303.258473 -220.601594)
			(xy 303.258982 -220.62948) (xy 303.258473 -220.657366) (xy 303.250353 -220.712542) (xy 303.234285 -220.765949)
			(xy 303.210613 -220.816446) (xy 303.17984 -220.862959) (xy 303.142623 -220.904496) (xy 303.099755 -220.940171)
			(xy 303.052149 -220.969225) (xy 303.00082 -220.991037) (xy 302.946863 -221.005143) (xy 302.891426 -221.011243)
			(xy 302.835692 -221.009206) (xy 302.780849 -220.999076) (xy 302.728065 -220.981069) (xy 302.678465 -220.955568)
			(xy 302.633107 -220.923117) (xy 302.592958 -220.884408) (xy 302.558872 -220.840265) (xy 302.531576 -220.79163)
			(xy 302.511653 -220.739539) (xy 302.499527 -220.685102) (xy 302.495456 -220.62948) (xy 301.98211 -220.62948)
			(xy 301.980353 -220.641422) (xy 301.964285 -220.694829) (xy 301.940613 -220.745326) (xy 301.90984 -220.791839)
			(xy 301.872623 -220.833376) (xy 301.829755 -220.869051) (xy 301.782149 -220.898105) (xy 301.73082 -220.919917)
			(xy 301.676863 -220.934023) (xy 301.621426 -220.940123) (xy 301.565692 -220.938086) (xy 301.510849 -220.927956)
			(xy 301.458065 -220.909949) (xy 301.408465 -220.884448) (xy 301.363107 -220.851997) (xy 301.322958 -220.813288)
			(xy 301.288872 -220.769145) (xy 301.261576 -220.72051) (xy 301.241653 -220.668419) (xy 301.229527 -220.613982)
			(xy 301.225456 -220.55836) (xy 300.161853 -220.55836) (xy 300.162214 -220.58122) (xy 300.162135 -220.593958)
			(xy 300.16048 -220.619379) (xy 300.158912 -220.63202) (xy 300.154536 -220.660596) (xy 300.138288 -220.716073)
			(xy 300.113861 -220.768466) (xy 300.081813 -220.816577) (xy 300.042877 -220.859305) (xy 300.020736 -220.877892)
			(xy 300.012231 -220.884618) (xy 299.994567 -220.897199) (xy 299.98543 -220.903038) (xy 299.984922 -220.903546)
			(xy 299.978064 -220.907864) (xy 299.96638 -220.92539) (xy 299.439076 -223.953578) (xy 299.441319 -223.957644)
			(xy 299.447071 -223.964931) (xy 299.450506 -223.968056) (xy 299.5168 -224.025206) (xy 299.521796 -224.029322)
			(xy 299.533369 -224.035111) (xy 299.53966 -224.036636) (xy 299.545756 -224.037906) (xy 299.558964 -224.03689)
			(xy 299.565314 -224.034858) (xy 299.593985 -224.026087) (xy 299.653193 -224.016647) (xy 299.68317 -224.016062)
			(xy 299.683932 -224.016062) (xy 299.711183 -224.01655) (xy 299.765128 -224.02431) (xy 299.817421 -224.039668)
			(xy 299.866996 -224.06231) (xy 299.912845 -224.091777) (xy 299.954034 -224.127468) (xy 299.989724 -224.168657)
			(xy 300.019191 -224.214506) (xy 300.041833 -224.264081) (xy 300.05719 -224.316374) (xy 300.06495 -224.370319)
			(xy 300.06544 -224.39757) (xy 300.06535 -224.40265) (xy 300.622714 -224.40265) (xy 300.626785 -224.347028)
			(xy 300.638911 -224.292591) (xy 300.658834 -224.2405) (xy 300.68613 -224.191865) (xy 300.720216 -224.147722)
			(xy 300.760365 -224.109013) (xy 300.805723 -224.076562) (xy 300.855323 -224.051061) (xy 300.908107 -224.033054)
			(xy 300.96295 -224.022924) (xy 301.018684 -224.020887) (xy 301.074121 -224.026987) (xy 301.128078 -224.041093)
			(xy 301.179407 -224.062905) (xy 301.227013 -224.091959) (xy 301.269881 -224.127634) (xy 301.307098 -224.169171)
			(xy 301.337871 -224.215684) (xy 301.361543 -224.266181) (xy 301.377611 -224.319588) (xy 301.385731 -224.374764)
			(xy 301.38624 -224.40265) (xy 301.385731 -224.430536) (xy 301.377611 -224.485712) (xy 301.361543 -224.539119)
			(xy 301.337871 -224.589616) (xy 301.307098 -224.636129) (xy 301.306008 -224.637346) (xy 302.42459 -224.637346)
			(xy 302.428661 -224.581724) (xy 302.440787 -224.527287) (xy 302.46071 -224.475196) (xy 302.488006 -224.426561)
			(xy 302.522092 -224.382418) (xy 302.562241 -224.343709) (xy 302.607599 -224.311258) (xy 302.657199 -224.285757)
			(xy 302.709983 -224.26775) (xy 302.764826 -224.25762) (xy 302.82056 -224.255583) (xy 302.875997 -224.261683)
			(xy 302.929954 -224.275789) (xy 302.981283 -224.297601) (xy 303.028889 -224.326655) (xy 303.071757 -224.36233)
			(xy 303.108974 -224.403867) (xy 303.139747 -224.45038) (xy 303.163419 -224.500877) (xy 303.179487 -224.554284)
			(xy 303.187607 -224.60946) (xy 303.188116 -224.637346) (xy 303.187607 -224.665232) (xy 303.179487 -224.720408)
			(xy 303.163419 -224.773815) (xy 303.139747 -224.824312) (xy 303.108974 -224.870825) (xy 303.071757 -224.912362)
			(xy 303.028889 -224.948037) (xy 302.981283 -224.977091) (xy 302.929954 -224.998903) (xy 302.875997 -225.013009)
			(xy 302.82056 -225.019109) (xy 302.764826 -225.017072) (xy 302.709983 -225.006942) (xy 302.657199 -224.988935)
			(xy 302.607599 -224.963434) (xy 302.562241 -224.930983) (xy 302.522092 -224.892274) (xy 302.488006 -224.848131)
			(xy 302.46071 -224.799496) (xy 302.440787 -224.747405) (xy 302.428661 -224.692968) (xy 302.42459 -224.637346)
			(xy 301.306008 -224.637346) (xy 301.269881 -224.677666) (xy 301.227013 -224.713341) (xy 301.179407 -224.742395)
			(xy 301.128078 -224.764207) (xy 301.074121 -224.778313) (xy 301.018684 -224.784413) (xy 300.96295 -224.782376)
			(xy 300.908107 -224.772246) (xy 300.855323 -224.754239) (xy 300.805723 -224.728738) (xy 300.760365 -224.696287)
			(xy 300.720216 -224.657578) (xy 300.68613 -224.613435) (xy 300.658834 -224.5648) (xy 300.638911 -224.512709)
			(xy 300.626785 -224.458272) (xy 300.622714 -224.40265) (xy 300.06535 -224.40265) (xy 300.064961 -224.424754)
			(xy 300.057245 -224.478571) (xy 300.041967 -224.530747) (xy 300.019435 -224.580225) (xy 299.990105 -224.626003)
			(xy 299.954573 -224.667152) (xy 299.934376 -224.685352) (xy 299.926756 -224.691956) (xy 299.922438 -224.700846)
			(xy 299.920171 -224.705635) (xy 299.917483 -224.715881) (xy 299.917104 -224.721166) (xy 299.913802 -224.794572)
			(xy 299.913699 -224.79962) (xy 299.915241 -224.809598) (xy 299.91685 -224.814384) (xy 299.920406 -224.824036)
			(xy 299.927518 -224.831656) (xy 299.94705 -224.853033) (xy 299.980084 -224.900588) (xy 300.005546 -224.952592)
			(xy 300.022851 -225.007849) (xy 300.031602 -225.065087) (xy 300.032166 -225.094038) (xy 300.0317 -225.121288)
			(xy 300.023938 -225.175233) (xy 300.008579 -225.227523) (xy 299.985933 -225.277096) (xy 299.956464 -225.322941)
			(xy 299.92077 -225.364126) (xy 299.879577 -225.399812) (xy 299.833726 -225.429272) (xy 299.784148 -225.451907)
			(xy 299.731854 -225.467255) (xy 299.677908 -225.475006) (xy 299.650658 -225.475546) (xy 299.622859 -225.475041)
			(xy 299.567849 -225.466967) (xy 299.514593 -225.450997) (xy 299.464218 -225.427469) (xy 299.41779 -225.39688)
			(xy 299.376292 -225.359877) (xy 299.35805 -225.338894) (xy 299.357796 -225.33864) (xy 299.352991 -225.33339)
			(xy 299.341133 -225.325531) (xy 299.334428 -225.323146) (xy 299.327824 -225.32086) (xy 299.313092 -225.320606)
			(xy 299.21708 -225.346514) (xy 299.210684 -225.348469) (xy 299.199108 -225.355157) (xy 299.19422 -225.359722)
			(xy 298.865642 -227.246434) (xy 299.758098 -227.246434) (xy 299.762169 -227.190812) (xy 299.774295 -227.136375)
			(xy 299.794218 -227.084284) (xy 299.821514 -227.035649) (xy 299.8556 -226.991506) (xy 299.895749 -226.952797)
			(xy 299.941107 -226.920346) (xy 299.990707 -226.894845) (xy 300.043491 -226.876838) (xy 300.098334 -226.866708)
			(xy 300.154068 -226.864671) (xy 300.209505 -226.870771) (xy 300.263462 -226.884877) (xy 300.314791 -226.906689)
			(xy 300.362397 -226.935743) (xy 300.405265 -226.971418) (xy 300.442482 -227.012955) (xy 300.473255 -227.059468)
			(xy 300.496927 -227.109965) (xy 300.512995 -227.163372) (xy 300.521115 -227.218548) (xy 300.521624 -227.246434)
			(xy 300.521115 -227.27432) (xy 300.512995 -227.329496) (xy 300.496927 -227.382903) (xy 300.473255 -227.4334)
			(xy 300.442482 -227.479913) (xy 300.405265 -227.52145) (xy 300.362397 -227.557125) (xy 300.314791 -227.586179)
			(xy 300.263462 -227.607991) (xy 300.209505 -227.622097) (xy 300.154068 -227.628197) (xy 300.098334 -227.62616)
			(xy 300.043491 -227.61603) (xy 299.990707 -227.598023) (xy 299.941107 -227.572522) (xy 299.895749 -227.540071)
			(xy 299.8556 -227.501362) (xy 299.821514 -227.457219) (xy 299.794218 -227.408584) (xy 299.774295 -227.356493)
			(xy 299.762169 -227.302056) (xy 299.758098 -227.246434) (xy 298.865642 -227.246434) (xy 298.589703 -228.830886)
			(xy 301.931322 -228.830886) (xy 301.935393 -228.775264) (xy 301.947519 -228.720827) (xy 301.967442 -228.668736)
			(xy 301.994738 -228.620101) (xy 302.028824 -228.575958) (xy 302.068973 -228.537249) (xy 302.114331 -228.504798)
			(xy 302.163931 -228.479297) (xy 302.216715 -228.46129) (xy 302.271558 -228.45116) (xy 302.327292 -228.449123)
			(xy 302.382729 -228.455223) (xy 302.436686 -228.469329) (xy 302.488015 -228.491141) (xy 302.535621 -228.520195)
			(xy 302.578489 -228.55587) (xy 302.615706 -228.597407) (xy 302.646479 -228.64392) (xy 302.670151 -228.694417)
			(xy 302.686219 -228.747824) (xy 302.694339 -228.803) (xy 302.694848 -228.830886) (xy 302.694339 -228.858772)
			(xy 302.686219 -228.913948) (xy 302.670151 -228.967355) (xy 302.646479 -229.017852) (xy 302.615706 -229.064365)
			(xy 302.578489 -229.105902) (xy 302.535621 -229.141577) (xy 302.488015 -229.170631) (xy 302.436686 -229.192443)
			(xy 302.382729 -229.206549) (xy 302.327292 -229.212649) (xy 302.271558 -229.210612) (xy 302.216715 -229.200482)
			(xy 302.163931 -229.182475) (xy 302.114331 -229.156974) (xy 302.068973 -229.124523) (xy 302.028824 -229.085814)
			(xy 301.994738 -229.041671) (xy 301.967442 -228.993036) (xy 301.947519 -228.940945) (xy 301.935393 -228.886508)
			(xy 301.931322 -228.830886) (xy 298.589703 -228.830886) (xy 298.462483 -229.56139) (xy 302.4792 -229.56139)
			(xy 302.483271 -229.505768) (xy 302.495397 -229.451331) (xy 302.51532 -229.39924) (xy 302.542616 -229.350605)
			(xy 302.576702 -229.306462) (xy 302.616851 -229.267753) (xy 302.662209 -229.235302) (xy 302.711809 -229.209801)
			(xy 302.764593 -229.191794) (xy 302.819436 -229.181664) (xy 302.87517 -229.179627) (xy 302.930607 -229.185727)
			(xy 302.984564 -229.199833) (xy 303.035893 -229.221645) (xy 303.083499 -229.250699) (xy 303.126367 -229.286374)
			(xy 303.163584 -229.327911) (xy 303.194357 -229.374424) (xy 303.218029 -229.424921) (xy 303.234097 -229.478328)
			(xy 303.242217 -229.533504) (xy 303.242726 -229.56139) (xy 303.242217 -229.589276) (xy 303.234097 -229.644452)
			(xy 303.218029 -229.697859) (xy 303.194357 -229.748356) (xy 303.163584 -229.794869) (xy 303.126367 -229.836406)
			(xy 303.083499 -229.872081) (xy 303.035893 -229.901135) (xy 302.984564 -229.922947) (xy 302.930607 -229.937053)
			(xy 302.87517 -229.943153) (xy 302.819436 -229.941116) (xy 302.764593 -229.930986) (xy 302.711809 -229.912979)
			(xy 302.662209 -229.887478) (xy 302.616851 -229.855027) (xy 302.576702 -229.816318) (xy 302.542616 -229.772175)
			(xy 302.51532 -229.72354) (xy 302.495397 -229.671449) (xy 302.483271 -229.617012) (xy 302.4792 -229.56139)
			(xy 298.462483 -229.56139) (xy 298.068746 -231.822244) (xy 298.070039 -231.830807) (xy 298.077572 -231.846389)
			(xy 298.083478 -231.852724) (xy 298.151804 -231.912414) (xy 298.156699 -231.916466) (xy 298.168003 -231.92226)
			(xy 298.174156 -231.923844) (xy 298.186602 -231.926638) (xy 298.192698 -231.92486) (xy 298.199556 -231.922574)
			(xy 298.227243 -231.9145) (xy 298.284258 -231.905823) (xy 298.313094 -231.905302) (xy 298.340346 -231.905765)
			(xy 298.394297 -231.913521) (xy 298.446594 -231.928876) (xy 298.496173 -231.951518) (xy 298.542026 -231.980985)
			(xy 298.583218 -232.016677) (xy 298.618912 -232.057869) (xy 298.648379 -232.103721) (xy 298.671022 -232.153301)
			(xy 298.686378 -232.205598) (xy 298.694135 -232.259548) (xy 298.694135 -232.314052) (xy 298.686378 -232.368002)
			(xy 298.671022 -232.420299) (xy 298.648379 -232.469879) (xy 298.618912 -232.515731) (xy 298.583218 -232.556923)
			(xy 298.542026 -232.592615) (xy 298.496173 -232.622082) (xy 298.446594 -232.644724) (xy 298.394297 -232.660079)
			(xy 298.340346 -232.667835) (xy 298.313094 -232.668318) (xy 298.282358 -232.6677) (xy 298.221682 -232.657842)
			(xy 298.163371 -232.638384) (xy 298.108934 -232.609827) (xy 298.083986 -232.591864) (xy 298.083478 -232.59161)
			(xy 298.078249 -232.587919) (xy 298.066419 -232.583039) (xy 298.06011 -232.581958) (xy 298.047156 -232.58018)
			(xy 297.954192 -232.61701) (xy 297.944402 -232.621352) (xy 297.929396 -232.636606) (xy 297.925236 -232.646474)
			(xy 297.798744 -233.371644) (xy 297.701467 -233.934) (xy 301.154336 -233.934) (xy 301.158407 -233.878378)
			(xy 301.170533 -233.823941) (xy 301.190456 -233.77185) (xy 301.217752 -233.723215) (xy 301.251838 -233.679072)
			(xy 301.291987 -233.640363) (xy 301.337345 -233.607912) (xy 301.386945 -233.582411) (xy 301.439729 -233.564404)
			(xy 301.494572 -233.554274) (xy 301.550306 -233.552237) (xy 301.605743 -233.558337) (xy 301.6597 -233.572443)
			(xy 301.711029 -233.594255) (xy 301.758635 -233.623309) (xy 301.801503 -233.658984) (xy 301.83872 -233.700521)
			(xy 301.869493 -233.747034) (xy 301.893165 -233.797531) (xy 301.909233 -233.850938) (xy 301.917353 -233.906114)
			(xy 301.917862 -233.934) (xy 301.917353 -233.961886) (xy 301.909233 -234.017062) (xy 301.893165 -234.070469)
			(xy 301.869493 -234.120966) (xy 301.83872 -234.167479) (xy 301.801503 -234.209016) (xy 301.758635 -234.244691)
			(xy 301.711029 -234.273745) (xy 301.6597 -234.295557) (xy 301.605743 -234.309663) (xy 301.550306 -234.315763)
			(xy 301.494572 -234.313726) (xy 301.439729 -234.303596) (xy 301.386945 -234.285589) (xy 301.337345 -234.260088)
			(xy 301.291987 -234.227637) (xy 301.251838 -234.188928) (xy 301.217752 -234.144785) (xy 301.190456 -234.09615)
			(xy 301.170533 -234.044059) (xy 301.158407 -233.989622) (xy 301.154336 -233.934) (xy 297.701467 -233.934)
			(xy 297.020442 -237.871) (xy 299.845982 -237.871) (xy 299.850053 -237.815378) (xy 299.862179 -237.760941)
			(xy 299.882102 -237.70885) (xy 299.909398 -237.660215) (xy 299.943484 -237.616072) (xy 299.983633 -237.577363)
			(xy 300.028991 -237.544912) (xy 300.078591 -237.519411) (xy 300.131375 -237.501404) (xy 300.186218 -237.491274)
			(xy 300.241952 -237.489237) (xy 300.297389 -237.495337) (xy 300.351346 -237.509443) (xy 300.402675 -237.531255)
			(xy 300.450281 -237.560309) (xy 300.493149 -237.595984) (xy 300.530366 -237.637521) (xy 300.561139 -237.684034)
			(xy 300.584811 -237.734531) (xy 300.600879 -237.787938) (xy 300.605477 -237.819184) (xy 302.170336 -237.819184)
			(xy 302.174407 -237.763562) (xy 302.186533 -237.709125) (xy 302.206456 -237.657034) (xy 302.233752 -237.608399)
			(xy 302.267838 -237.564256) (xy 302.307987 -237.525547) (xy 302.353345 -237.493096) (xy 302.402945 -237.467595)
			(xy 302.455729 -237.449588) (xy 302.510572 -237.439458) (xy 302.566306 -237.437421) (xy 302.621743 -237.443521)
			(xy 302.6757 -237.457627) (xy 302.727029 -237.479439) (xy 302.774635 -237.508493) (xy 302.817503 -237.544168)
			(xy 302.85472 -237.585705) (xy 302.885493 -237.632218) (xy 302.909165 -237.682715) (xy 302.925233 -237.736122)
			(xy 302.933353 -237.791298) (xy 302.933862 -237.819184) (xy 302.933353 -237.84707) (xy 302.925233 -237.902246)
			(xy 302.909165 -237.955653) (xy 302.885493 -238.00615) (xy 302.85472 -238.052663) (xy 302.817503 -238.0942)
			(xy 302.774635 -238.129875) (xy 302.727029 -238.158929) (xy 302.6757 -238.180741) (xy 302.621743 -238.194847)
			(xy 302.566306 -238.200947) (xy 302.510572 -238.19891) (xy 302.455729 -238.18878) (xy 302.402945 -238.170773)
			(xy 302.353345 -238.145272) (xy 302.307987 -238.112821) (xy 302.267838 -238.074112) (xy 302.233752 -238.029969)
			(xy 302.206456 -237.981334) (xy 302.186533 -237.929243) (xy 302.174407 -237.874806) (xy 302.170336 -237.819184)
			(xy 300.605477 -237.819184) (xy 300.608999 -237.843114) (xy 300.609508 -237.871) (xy 300.608999 -237.898886)
			(xy 300.600879 -237.954062) (xy 300.584811 -238.007469) (xy 300.561139 -238.057966) (xy 300.530366 -238.104479)
			(xy 300.493149 -238.146016) (xy 300.450281 -238.181691) (xy 300.402675 -238.210745) (xy 300.351346 -238.232557)
			(xy 300.297389 -238.246663) (xy 300.241952 -238.252763) (xy 300.186218 -238.250726) (xy 300.131375 -238.240596)
			(xy 300.078591 -238.222589) (xy 300.028991 -238.197088) (xy 299.983633 -238.164637) (xy 299.943484 -238.125928)
			(xy 299.909398 -238.081785) (xy 299.882102 -238.03315) (xy 299.862179 -237.981059) (xy 299.850053 -237.926622)
			(xy 299.845982 -237.871) (xy 297.020442 -237.871) (xy 296.835774 -238.938562) (xy 301.679608 -238.938562)
			(xy 301.683679 -238.88294) (xy 301.695805 -238.828503) (xy 301.715728 -238.776412) (xy 301.743024 -238.727777)
			(xy 301.77711 -238.683634) (xy 301.817259 -238.644925) (xy 301.862617 -238.612474) (xy 301.912217 -238.586973)
			(xy 301.965001 -238.568966) (xy 302.019844 -238.558836) (xy 302.075578 -238.556799) (xy 302.131015 -238.562899)
			(xy 302.184972 -238.577005) (xy 302.236301 -238.598817) (xy 302.283907 -238.627871) (xy 302.326775 -238.663546)
			(xy 302.363992 -238.705083) (xy 302.394765 -238.751596) (xy 302.418437 -238.802093) (xy 302.434505 -238.8555)
			(xy 302.442625 -238.910676) (xy 302.443134 -238.938562) (xy 302.695608 -238.938562) (xy 302.699679 -238.88294)
			(xy 302.711805 -238.828503) (xy 302.731728 -238.776412) (xy 302.759024 -238.727777) (xy 302.79311 -238.683634)
			(xy 302.833259 -238.644925) (xy 302.878617 -238.612474) (xy 302.928217 -238.586973) (xy 302.981001 -238.568966)
			(xy 303.035844 -238.558836) (xy 303.091578 -238.556799) (xy 303.147015 -238.562899) (xy 303.200972 -238.577005)
			(xy 303.252301 -238.598817) (xy 303.299907 -238.627871) (xy 303.342775 -238.663546) (xy 303.379992 -238.705083)
			(xy 303.410765 -238.751596) (xy 303.434437 -238.802093) (xy 303.450505 -238.8555) (xy 303.458625 -238.910676)
			(xy 303.458865 -238.92383) (xy 303.699924 -238.92383) (xy 303.703995 -238.868208) (xy 303.716121 -238.813771)
			(xy 303.736044 -238.76168) (xy 303.76334 -238.713045) (xy 303.797426 -238.668902) (xy 303.837575 -238.630193)
			(xy 303.882933 -238.597742) (xy 303.932533 -238.572241) (xy 303.985317 -238.554234) (xy 304.04016 -238.544104)
			(xy 304.095894 -238.542067) (xy 304.151331 -238.548167) (xy 304.205288 -238.562273) (xy 304.256617 -238.584085)
			(xy 304.304223 -238.613139) (xy 304.347091 -238.648814) (xy 304.384308 -238.690351) (xy 304.415081 -238.736864)
			(xy 304.438753 -238.787361) (xy 304.454821 -238.840768) (xy 304.462941 -238.895944) (xy 304.46345 -238.92383)
			(xy 304.462941 -238.951716) (xy 304.454821 -239.006892) (xy 304.438753 -239.060299) (xy 304.415081 -239.110796)
			(xy 304.384308 -239.157309) (xy 304.347091 -239.198846) (xy 304.304223 -239.234521) (xy 304.256617 -239.263575)
			(xy 304.205288 -239.285387) (xy 304.151331 -239.299493) (xy 304.095894 -239.305593) (xy 304.04016 -239.303556)
			(xy 303.985317 -239.293426) (xy 303.932533 -239.275419) (xy 303.882933 -239.249918) (xy 303.837575 -239.217467)
			(xy 303.797426 -239.178758) (xy 303.76334 -239.134615) (xy 303.736044 -239.08598) (xy 303.716121 -239.033889)
			(xy 303.703995 -238.979452) (xy 303.699924 -238.92383) (xy 303.458865 -238.92383) (xy 303.459134 -238.938562)
			(xy 303.458625 -238.966448) (xy 303.450505 -239.021624) (xy 303.434437 -239.075031) (xy 303.410765 -239.125528)
			(xy 303.379992 -239.172041) (xy 303.342775 -239.213578) (xy 303.299907 -239.249253) (xy 303.252301 -239.278307)
			(xy 303.200972 -239.300119) (xy 303.147015 -239.314225) (xy 303.091578 -239.320325) (xy 303.035844 -239.318288)
			(xy 302.981001 -239.308158) (xy 302.928217 -239.290151) (xy 302.878617 -239.26465) (xy 302.833259 -239.232199)
			(xy 302.79311 -239.19349) (xy 302.759024 -239.149347) (xy 302.731728 -239.100712) (xy 302.711805 -239.048621)
			(xy 302.699679 -238.994184) (xy 302.695608 -238.938562) (xy 302.443134 -238.938562) (xy 302.442625 -238.966448)
			(xy 302.434505 -239.021624) (xy 302.418437 -239.075031) (xy 302.394765 -239.125528) (xy 302.363992 -239.172041)
			(xy 302.326775 -239.213578) (xy 302.283907 -239.249253) (xy 302.236301 -239.278307) (xy 302.184972 -239.300119)
			(xy 302.131015 -239.314225) (xy 302.075578 -239.320325) (xy 302.019844 -239.318288) (xy 301.965001 -239.308158)
			(xy 301.912217 -239.290151) (xy 301.862617 -239.26465) (xy 301.817259 -239.232199) (xy 301.77711 -239.19349)
			(xy 301.743024 -239.149347) (xy 301.715728 -239.100712) (xy 301.695805 -239.048621) (xy 301.683679 -238.994184)
			(xy 301.679608 -238.938562) (xy 296.835774 -238.938562) (xy 296.381903 -241.562382) (xy 303.49139 -241.562382)
			(xy 303.495461 -241.50676) (xy 303.507587 -241.452323) (xy 303.52751 -241.400232) (xy 303.554806 -241.351597)
			(xy 303.588892 -241.307454) (xy 303.629041 -241.268745) (xy 303.674399 -241.236294) (xy 303.723999 -241.210793)
			(xy 303.776783 -241.192786) (xy 303.831626 -241.182656) (xy 303.88736 -241.180619) (xy 303.942797 -241.186719)
			(xy 303.996754 -241.200825) (xy 304.048083 -241.222637) (xy 304.095689 -241.251691) (xy 304.138557 -241.287366)
			(xy 304.175774 -241.328903) (xy 304.206547 -241.375416) (xy 304.230219 -241.425913) (xy 304.246287 -241.47932)
			(xy 304.254407 -241.534496) (xy 304.254916 -241.562382) (xy 304.254407 -241.590268) (xy 304.246287 -241.645444)
			(xy 304.230219 -241.698851) (xy 304.206547 -241.749348) (xy 304.175774 -241.795861) (xy 304.138557 -241.837398)
			(xy 304.095689 -241.873073) (xy 304.048083 -241.902127) (xy 303.996754 -241.923939) (xy 303.942797 -241.938045)
			(xy 303.88736 -241.944145) (xy 303.831626 -241.942108) (xy 303.776783 -241.931978) (xy 303.723999 -241.913971)
			(xy 303.674399 -241.88847) (xy 303.629041 -241.856019) (xy 303.588892 -241.81731) (xy 303.554806 -241.773167)
			(xy 303.52751 -241.724532) (xy 303.507587 -241.672441) (xy 303.495461 -241.618004) (xy 303.49139 -241.562382)
			(xy 296.381903 -241.562382) (xy 295.647099 -245.810278) (xy 302.187608 -245.810278) (xy 302.191679 -245.754656)
			(xy 302.203805 -245.700219) (xy 302.223728 -245.648128) (xy 302.251024 -245.599493) (xy 302.28511 -245.55535)
			(xy 302.325259 -245.516641) (xy 302.370617 -245.48419) (xy 302.420217 -245.458689) (xy 302.473001 -245.440682)
			(xy 302.527844 -245.430552) (xy 302.583578 -245.428515) (xy 302.639015 -245.434615) (xy 302.692972 -245.448721)
			(xy 302.744301 -245.470533) (xy 302.791907 -245.499587) (xy 302.834775 -245.535262) (xy 302.871992 -245.576799)
			(xy 302.902765 -245.623312) (xy 302.926437 -245.673809) (xy 302.942505 -245.727216) (xy 302.950625 -245.782392)
			(xy 302.951134 -245.810278) (xy 302.950625 -245.838164) (xy 302.942505 -245.89334) (xy 302.926437 -245.946747)
			(xy 302.902765 -245.997244) (xy 302.871992 -246.043757) (xy 302.834775 -246.085294) (xy 302.791907 -246.120969)
			(xy 302.744301 -246.150023) (xy 302.692972 -246.171835) (xy 302.639015 -246.185941) (xy 302.583578 -246.192041)
			(xy 302.527844 -246.190004) (xy 302.473001 -246.179874) (xy 302.420217 -246.161867) (xy 302.370617 -246.136366)
			(xy 302.325259 -246.103915) (xy 302.28511 -246.065206) (xy 302.251024 -246.021063) (xy 302.223728 -245.972428)
			(xy 302.203805 -245.920337) (xy 302.191679 -245.8659) (xy 302.187608 -245.810278) (xy 295.647099 -245.810278)
			(xy 294.876793 -250.263406) (xy 304.073558 -250.263406) (xy 304.077629 -250.207784) (xy 304.089755 -250.153347)
			(xy 304.109678 -250.101256) (xy 304.136974 -250.052621) (xy 304.17106 -250.008478) (xy 304.211209 -249.969769)
			(xy 304.256567 -249.937318) (xy 304.306167 -249.911817) (xy 304.358951 -249.89381) (xy 304.413794 -249.88368)
			(xy 304.469528 -249.881643) (xy 304.524965 -249.887743) (xy 304.578922 -249.901849) (xy 304.630251 -249.923661)
			(xy 304.677857 -249.952715) (xy 304.720725 -249.98839) (xy 304.757942 -250.029927) (xy 304.788715 -250.07644)
			(xy 304.812387 -250.126937) (xy 304.828455 -250.180344) (xy 304.836575 -250.23552) (xy 304.837084 -250.263406)
			(xy 304.836575 -250.291292) (xy 304.828455 -250.346468) (xy 304.812387 -250.399875) (xy 304.788715 -250.450372)
			(xy 304.757942 -250.496885) (xy 304.720725 -250.538422) (xy 304.677857 -250.574097) (xy 304.630251 -250.603151)
			(xy 304.578922 -250.624963) (xy 304.524965 -250.639069) (xy 304.469528 -250.645169) (xy 304.413794 -250.643132)
			(xy 304.358951 -250.633002) (xy 304.306167 -250.614995) (xy 304.256567 -250.589494) (xy 304.211209 -250.557043)
			(xy 304.17106 -250.518334) (xy 304.136974 -250.474191) (xy 304.109678 -250.425556) (xy 304.089755 -250.373465)
			(xy 304.077629 -250.319028) (xy 304.073558 -250.263406) (xy 294.876793 -250.263406) (xy 294.78782 -250.777756)
			(xy 302.367694 -250.777756) (xy 302.371765 -250.722134) (xy 302.383891 -250.667697) (xy 302.403814 -250.615606)
			(xy 302.43111 -250.566971) (xy 302.465196 -250.522828) (xy 302.505345 -250.484119) (xy 302.550703 -250.451668)
			(xy 302.600303 -250.426167) (xy 302.653087 -250.40816) (xy 302.70793 -250.39803) (xy 302.763664 -250.395993)
			(xy 302.819101 -250.402093) (xy 302.873058 -250.416199) (xy 302.924387 -250.438011) (xy 302.971993 -250.467065)
			(xy 303.014861 -250.50274) (xy 303.052078 -250.544277) (xy 303.082851 -250.59079) (xy 303.106523 -250.641287)
			(xy 303.122591 -250.694694) (xy 303.130711 -250.74987) (xy 303.13122 -250.777756) (xy 303.130711 -250.805642)
			(xy 303.122591 -250.860818) (xy 303.106523 -250.914225) (xy 303.082851 -250.964722) (xy 303.069254 -250.985274)
			(xy 303.34026 -250.985274) (xy 303.344331 -250.929652) (xy 303.356457 -250.875215) (xy 303.37638 -250.823124)
			(xy 303.403676 -250.774489) (xy 303.437762 -250.730346) (xy 303.477911 -250.691637) (xy 303.523269 -250.659186)
			(xy 303.572869 -250.633685) (xy 303.625653 -250.615678) (xy 303.680496 -250.605548) (xy 303.73623 -250.603511)
			(xy 303.791667 -250.609611) (xy 303.845624 -250.623717) (xy 303.896953 -250.645529) (xy 303.944559 -250.674583)
			(xy 303.987427 -250.710258) (xy 304.024644 -250.751795) (xy 304.055417 -250.798308) (xy 304.079089 -250.848805)
			(xy 304.095157 -250.902212) (xy 304.103277 -250.957388) (xy 304.103786 -250.985274) (xy 304.103277 -251.01316)
			(xy 304.095157 -251.068336) (xy 304.079089 -251.121743) (xy 304.055417 -251.17224) (xy 304.024644 -251.218753)
			(xy 303.987427 -251.26029) (xy 303.944559 -251.295965) (xy 303.896953 -251.325019) (xy 303.845624 -251.346831)
			(xy 303.791667 -251.360937) (xy 303.73623 -251.367037) (xy 303.680496 -251.365) (xy 303.625653 -251.35487)
			(xy 303.572869 -251.336863) (xy 303.523269 -251.311362) (xy 303.477911 -251.278911) (xy 303.437762 -251.240202)
			(xy 303.403676 -251.196059) (xy 303.37638 -251.147424) (xy 303.356457 -251.095333) (xy 303.344331 -251.040896)
			(xy 303.34026 -250.985274) (xy 303.069254 -250.985274) (xy 303.052078 -251.011235) (xy 303.014861 -251.052772)
			(xy 302.971993 -251.088447) (xy 302.924387 -251.117501) (xy 302.873058 -251.139313) (xy 302.819101 -251.153419)
			(xy 302.763664 -251.159519) (xy 302.70793 -251.157482) (xy 302.653087 -251.147352) (xy 302.600303 -251.129345)
			(xy 302.550703 -251.103844) (xy 302.505345 -251.071393) (xy 302.465196 -251.032684) (xy 302.43111 -250.988541)
			(xy 302.403814 -250.939906) (xy 302.383891 -250.887815) (xy 302.371765 -250.833378) (xy 302.367694 -250.777756)
			(xy 294.78782 -250.777756) (xy 294.291945 -253.6444) (xy 303.478182 -253.6444) (xy 303.482253 -253.588778)
			(xy 303.494379 -253.534341) (xy 303.514302 -253.48225) (xy 303.541598 -253.433615) (xy 303.575684 -253.389472)
			(xy 303.615833 -253.350763) (xy 303.661191 -253.318312) (xy 303.710791 -253.292811) (xy 303.763575 -253.274804)
			(xy 303.818418 -253.264674) (xy 303.874152 -253.262637) (xy 303.929589 -253.268737) (xy 303.983546 -253.282843)
			(xy 304.034875 -253.304655) (xy 304.082481 -253.333709) (xy 304.125349 -253.369384) (xy 304.162566 -253.410921)
			(xy 304.193339 -253.457434) (xy 304.217011 -253.507931) (xy 304.233079 -253.561338) (xy 304.23592 -253.580646)
			(xy 304.933094 -253.580646) (xy 304.937165 -253.525024) (xy 304.949291 -253.470587) (xy 304.969214 -253.418496)
			(xy 304.99651 -253.369861) (xy 305.030596 -253.325718) (xy 305.070745 -253.287009) (xy 305.116103 -253.254558)
			(xy 305.165703 -253.229057) (xy 305.218487 -253.21105) (xy 305.27333 -253.20092) (xy 305.329064 -253.198883)
			(xy 305.384501 -253.204983) (xy 305.438458 -253.219089) (xy 305.489787 -253.240901) (xy 305.537393 -253.269955)
			(xy 305.580261 -253.30563) (xy 305.617478 -253.347167) (xy 305.648251 -253.39368) (xy 305.671923 -253.444177)
			(xy 305.687991 -253.497584) (xy 305.696111 -253.55276) (xy 305.69662 -253.580646) (xy 305.696111 -253.608532)
			(xy 305.687991 -253.663708) (xy 305.671923 -253.717115) (xy 305.648251 -253.767612) (xy 305.617478 -253.814125)
			(xy 305.580261 -253.855662) (xy 305.537393 -253.891337) (xy 305.489787 -253.920391) (xy 305.438458 -253.942203)
			(xy 305.384501 -253.956309) (xy 305.329064 -253.962409) (xy 305.27333 -253.960372) (xy 305.218487 -253.950242)
			(xy 305.165703 -253.932235) (xy 305.116103 -253.906734) (xy 305.070745 -253.874283) (xy 305.030596 -253.835574)
			(xy 304.99651 -253.791431) (xy 304.969214 -253.742796) (xy 304.949291 -253.690705) (xy 304.937165 -253.636268)
			(xy 304.933094 -253.580646) (xy 304.23592 -253.580646) (xy 304.241199 -253.616514) (xy 304.241708 -253.6444)
			(xy 304.241199 -253.672286) (xy 304.233079 -253.727462) (xy 304.217011 -253.780869) (xy 304.193339 -253.831366)
			(xy 304.162566 -253.877879) (xy 304.125349 -253.919416) (xy 304.082481 -253.955091) (xy 304.034875 -253.984145)
			(xy 303.983546 -254.005957) (xy 303.929589 -254.020063) (xy 303.874152 -254.026163) (xy 303.818418 -254.024126)
			(xy 303.763575 -254.013996) (xy 303.710791 -253.995989) (xy 303.661191 -253.970488) (xy 303.615833 -253.938037)
			(xy 303.575684 -253.899328) (xy 303.541598 -253.855185) (xy 303.514302 -253.80655) (xy 303.494379 -253.754459)
			(xy 303.482253 -253.700022) (xy 303.478182 -253.6444) (xy 294.291945 -253.6444) (xy 294.063152 -254.967051)
			(xy 315.950578 -254.967051) (xy 315.950578 -254.912549) (xy 315.958334 -254.858601) (xy 315.973689 -254.806306)
			(xy 315.996331 -254.756729) (xy 316.025797 -254.710879) (xy 316.061488 -254.669688) (xy 316.102679 -254.633997)
			(xy 316.148529 -254.604531) (xy 316.198106 -254.581889) (xy 316.250401 -254.566534) (xy 316.304349 -254.558778)
			(xy 316.3316 -254.558292) (xy 316.360589 -254.558833) (xy 316.417899 -254.567605) (xy 316.473222 -254.584948)
			(xy 316.525284 -254.610463) (xy 316.572886 -254.643561) (xy 316.614931 -254.68348) (xy 316.650453 -254.729302)
			(xy 316.678632 -254.779971) (xy 316.689232 -254.806958) (xy 316.693042 -254.817372) (xy 316.70879 -254.83312)
			(xy 316.802262 -254.86741) (xy 316.823852 -254.865632) (xy 316.833758 -254.860298) (xy 316.855066 -254.848866)
			(xy 316.899964 -254.830902) (xy 316.946775 -254.818768) (xy 316.994745 -254.81266) (xy 317.018924 -254.812292)
			(xy 317.046174 -254.812779) (xy 317.100119 -254.820539) (xy 317.152411 -254.835896) (xy 317.201985 -254.858538)
			(xy 317.247833 -254.888005) (xy 317.28902 -254.923697) (xy 317.324709 -254.964886) (xy 317.354173 -255.010736)
			(xy 317.376812 -255.060311) (xy 317.392166 -255.112604) (xy 317.399922 -255.16655) (xy 317.399922 -255.22105)
			(xy 317.392166 -255.274996) (xy 317.376812 -255.327289) (xy 317.354173 -255.376864) (xy 317.324709 -255.422714)
			(xy 317.28902 -255.463903) (xy 317.247833 -255.499595) (xy 317.201985 -255.529062) (xy 317.152411 -255.551704)
			(xy 317.100119 -255.567061) (xy 317.046174 -255.574821) (xy 317.018924 -255.575308) (xy 316.989936 -255.574747)
			(xy 316.932627 -255.565978) (xy 316.877304 -255.548638) (xy 316.825242 -255.523126) (xy 316.77764 -255.490031)
			(xy 316.735594 -255.450114) (xy 316.700072 -255.404295) (xy 316.671892 -255.353628) (xy 316.661292 -255.326642)
			(xy 316.657482 -255.316228) (xy 316.641734 -255.30048) (xy 316.548262 -255.26619) (xy 316.526672 -255.267968)
			(xy 316.516766 -255.273302) (xy 316.495453 -255.284725) (xy 316.450557 -255.302691) (xy 316.403748 -255.314828)
			(xy 316.355779 -255.320939) (xy 316.3316 -255.321308) (xy 316.304349 -255.320822) (xy 316.250401 -255.313066)
			(xy 316.198106 -255.297711) (xy 316.148529 -255.275069) (xy 316.102679 -255.245603) (xy 316.061488 -255.209912)
			(xy 316.025797 -255.168721) (xy 315.996331 -255.122871) (xy 315.973689 -255.073294) (xy 315.958334 -255.020999)
			(xy 315.950578 -254.967051) (xy 294.063152 -254.967051) (xy 293.630208 -257.469894) (xy 304.342292 -257.469894)
			(xy 304.342746 -257.442966) (xy 304.350333 -257.389648) (xy 304.36534 -257.337926) (xy 304.38747 -257.288827)
			(xy 304.416283 -257.243327) (xy 304.451206 -257.20233) (xy 304.47107 -257.184144) (xy 304.478182 -257.177794)
			(xy 304.486564 -257.161792) (xy 304.496978 -257.076448) (xy 304.49266 -257.058414) (xy 304.487326 -257.050794)
			(xy 304.47154 -257.026901) (xy 304.446598 -256.975351) (xy 304.429642 -256.920653) (xy 304.421052 -256.864035)
			(xy 304.420524 -256.835402) (xy 304.420524 -256.834894) (xy 304.42101 -256.807643) (xy 304.428766 -256.753695)
			(xy 304.444121 -256.7014) (xy 304.466763 -256.651823) (xy 304.496229 -256.605973) (xy 304.53192 -256.564782)
			(xy 304.573111 -256.529091) (xy 304.618961 -256.499625) (xy 304.668538 -256.476983) (xy 304.720833 -256.461628)
			(xy 304.774781 -256.453872) (xy 304.829283 -256.453872) (xy 304.883231 -256.461628) (xy 304.935526 -256.476983)
			(xy 304.985103 -256.499625) (xy 305.030953 -256.529091) (xy 305.072144 -256.564782) (xy 305.107835 -256.605973)
			(xy 305.137301 -256.651823) (xy 305.159943 -256.7014) (xy 305.175298 -256.753695) (xy 305.183054 -256.807643)
			(xy 305.18354 -256.834894) (xy 305.286408 -256.834894) (xy 305.290479 -256.779272) (xy 305.302605 -256.724835)
			(xy 305.322528 -256.672744) (xy 305.349824 -256.624109) (xy 305.38391 -256.579966) (xy 305.424059 -256.541257)
			(xy 305.469417 -256.508806) (xy 305.519017 -256.483305) (xy 305.571801 -256.465298) (xy 305.626644 -256.455168)
			(xy 305.682378 -256.453131) (xy 305.737815 -256.459231) (xy 305.791772 -256.473337) (xy 305.843101 -256.495149)
			(xy 305.890707 -256.524203) (xy 305.933575 -256.559878) (xy 305.970792 -256.601415) (xy 306.001565 -256.647928)
			(xy 306.025237 -256.698425) (xy 306.041305 -256.751832) (xy 306.049425 -256.807008) (xy 306.049934 -256.834894)
			(xy 306.049425 -256.86278) (xy 306.041305 -256.917956) (xy 306.025237 -256.971363) (xy 306.001565 -257.02186)
			(xy 305.970792 -257.068373) (xy 305.933575 -257.10991) (xy 305.890707 -257.145585) (xy 305.843101 -257.174639)
			(xy 305.791772 -257.196451) (xy 305.737815 -257.210557) (xy 305.682378 -257.216657) (xy 305.626644 -257.21462)
			(xy 305.571801 -257.20449) (xy 305.519017 -257.186483) (xy 305.469417 -257.160982) (xy 305.424059 -257.128531)
			(xy 305.38391 -257.089822) (xy 305.349824 -257.045679) (xy 305.322528 -256.997044) (xy 305.302605 -256.944953)
			(xy 305.290479 -256.890516) (xy 305.286408 -256.834894) (xy 305.18354 -256.834894) (xy 305.183067 -256.861821)
			(xy 305.175483 -256.915138) (xy 305.160479 -256.966859) (xy 305.138352 -257.015958) (xy 305.109543 -257.061458)
			(xy 305.074624 -257.102457) (xy 305.054762 -257.120644) (xy 305.04765 -257.126994) (xy 305.039268 -257.142996)
			(xy 305.028854 -257.22834) (xy 305.033172 -257.246374) (xy 305.038506 -257.253994) (xy 305.054278 -257.277896)
			(xy 305.079225 -257.329441) (xy 305.096185 -257.384137) (xy 305.104778 -257.440754) (xy 305.105308 -257.469386)
			(xy 305.105308 -257.469894) (xy 305.104822 -257.497145) (xy 305.097066 -257.551093) (xy 305.081711 -257.603388)
			(xy 305.059069 -257.652965) (xy 305.029603 -257.698815) (xy 304.993912 -257.740006) (xy 304.952721 -257.775697)
			(xy 304.906871 -257.805163) (xy 304.857294 -257.827805) (xy 304.804999 -257.84316) (xy 304.751051 -257.850916)
			(xy 304.696549 -257.850916) (xy 304.642601 -257.84316) (xy 304.590306 -257.827805) (xy 304.540729 -257.805163)
			(xy 304.494879 -257.775697) (xy 304.453688 -257.740006) (xy 304.417997 -257.698815) (xy 304.388531 -257.652965)
			(xy 304.365889 -257.603388) (xy 304.350534 -257.551093) (xy 304.342778 -257.497145) (xy 304.342292 -257.469894)
			(xy 293.630208 -257.469894) (xy 293.376691 -258.935474) (xy 304.875182 -258.935474) (xy 304.879253 -258.879852)
			(xy 304.891379 -258.825415) (xy 304.911302 -258.773324) (xy 304.938598 -258.724689) (xy 304.972684 -258.680546)
			(xy 305.012833 -258.641837) (xy 305.058191 -258.609386) (xy 305.107791 -258.583885) (xy 305.160575 -258.565878)
			(xy 305.215418 -258.555748) (xy 305.271152 -258.553711) (xy 305.326589 -258.559811) (xy 305.380546 -258.573917)
			(xy 305.431875 -258.595729) (xy 305.479481 -258.624783) (xy 305.522349 -258.660458) (xy 305.559566 -258.701995)
			(xy 305.590339 -258.748508) (xy 305.614011 -258.799005) (xy 305.630079 -258.852412) (xy 305.638199 -258.907588)
			(xy 305.638708 -258.935474) (xy 305.638199 -258.96336) (xy 305.630079 -259.018536) (xy 305.614011 -259.071943)
			(xy 305.590339 -259.12244) (xy 305.559566 -259.168953) (xy 305.522349 -259.21049) (xy 305.479481 -259.246165)
			(xy 305.431875 -259.275219) (xy 305.380546 -259.297031) (xy 305.326589 -259.311137) (xy 305.271152 -259.317237)
			(xy 305.215418 -259.3152) (xy 305.160575 -259.30507) (xy 305.107791 -259.287063) (xy 305.058191 -259.261562)
			(xy 305.012833 -259.229111) (xy 304.972684 -259.190402) (xy 304.938598 -259.146259) (xy 304.911302 -259.097624)
			(xy 304.891379 -259.045533) (xy 304.879253 -258.991096) (xy 304.875182 -258.935474) (xy 293.376691 -258.935474)
			(xy 293.07827 -260.660642) (xy 317.663574 -260.660642) (xy 317.667645 -260.60502) (xy 317.679771 -260.550583)
			(xy 317.699694 -260.498492) (xy 317.72699 -260.449857) (xy 317.761076 -260.405714) (xy 317.801225 -260.367005)
			(xy 317.846583 -260.334554) (xy 317.896183 -260.309053) (xy 317.948967 -260.291046) (xy 318.00381 -260.280916)
			(xy 318.059544 -260.278879) (xy 318.114981 -260.284979) (xy 318.168938 -260.299085) (xy 318.220267 -260.320897)
			(xy 318.267873 -260.349951) (xy 318.310741 -260.385626) (xy 318.347958 -260.427163) (xy 318.378731 -260.473676)
			(xy 318.402403 -260.524173) (xy 318.418471 -260.57758) (xy 318.426591 -260.632756) (xy 318.4271 -260.660642)
			(xy 318.426591 -260.688528) (xy 318.418471 -260.743704) (xy 318.402403 -260.797111) (xy 318.378731 -260.847608)
			(xy 318.347958 -260.894121) (xy 318.310741 -260.935658) (xy 318.267873 -260.971333) (xy 318.220267 -261.000387)
			(xy 318.168938 -261.022199) (xy 318.114981 -261.036305) (xy 318.059544 -261.042405) (xy 318.00381 -261.040368)
			(xy 317.948967 -261.030238) (xy 317.896183 -261.012231) (xy 317.846583 -260.98673) (xy 317.801225 -260.954279)
			(xy 317.761076 -260.91557) (xy 317.72699 -260.871427) (xy 317.699694 -260.822792) (xy 317.679771 -260.770701)
			(xy 317.667645 -260.716264) (xy 317.663574 -260.660642) (xy 293.07827 -260.660642) (xy 293.013638 -261.034276)
			(xy 293.008981 -261.0612) (xy 316.178182 -261.0612) (xy 316.182253 -261.005578) (xy 316.194379 -260.951141)
			(xy 316.214302 -260.89905) (xy 316.241598 -260.850415) (xy 316.275684 -260.806272) (xy 316.315833 -260.767563)
			(xy 316.361191 -260.735112) (xy 316.410791 -260.709611) (xy 316.463575 -260.691604) (xy 316.518418 -260.681474)
			(xy 316.574152 -260.679437) (xy 316.629589 -260.685537) (xy 316.683546 -260.699643) (xy 316.734875 -260.721455)
			(xy 316.782481 -260.750509) (xy 316.825349 -260.786184) (xy 316.862566 -260.827721) (xy 316.893339 -260.874234)
			(xy 316.917011 -260.924731) (xy 316.933079 -260.978138) (xy 316.941199 -261.033314) (xy 316.941708 -261.0612)
			(xy 316.941199 -261.089086) (xy 316.933079 -261.144262) (xy 316.917011 -261.197669) (xy 316.893339 -261.248166)
			(xy 316.862566 -261.294679) (xy 316.825349 -261.336216) (xy 316.782481 -261.371891) (xy 316.734875 -261.400945)
			(xy 316.683546 -261.422757) (xy 316.629589 -261.436863) (xy 316.574152 -261.442963) (xy 316.518418 -261.440926)
			(xy 316.463575 -261.430796) (xy 316.410791 -261.412789) (xy 316.361191 -261.387288) (xy 316.315833 -261.354837)
			(xy 316.275684 -261.316128) (xy 316.241598 -261.271985) (xy 316.214302 -261.22335) (xy 316.194379 -261.171259)
			(xy 316.182253 -261.116822) (xy 316.178182 -261.0612) (xy 293.008981 -261.0612) (xy 292.73373 -262.65251)
			(xy 292.067488 -266.503404) (xy 292.066114 -266.515507) (xy 292.073411 -266.538709) (xy 292.081458 -266.547854)
			(xy 292.083236 -266.549632) (xy 292.083236 -269.931388) (xy 292.084252 -269.94104) (xy 292.085879 -269.948284)
			(xy 292.09272 -269.961454) (xy 292.097714 -269.966948) (xy 292.435534 -270.304768) (xy 292.441036 -270.309749)
			(xy 292.454204 -270.316582) (xy 292.461442 -270.31823) (xy 292.471094 -270.319246) (xy 315.282834 -270.319246)
		)
		(stroke
			(width 0)
			(type solid)
		)
		(fill yes)
		(layer "In7.Cu")
		(net "GND")
	)
	(gr_poly
		(pts
			(xy 254.853186 -95.052134) (xy 254.860793 -95.050623) (xy 254.874632 -95.043642) (xy 254.880364 -95.038418)
			(xy 256.801366 -93.117416) (xy 256.808767 -93.110578) (xy 256.827366 -93.102865) (xy 256.837434 -93.10243)
			(xy 263.68248 -93.10243) (xy 263.692543 -93.102868) (xy 263.711124 -93.110607) (xy 263.718548 -93.117416)
			(xy 265.63955 -95.038418) (xy 265.645301 -95.043613) (xy 265.659134 -95.050585) (xy 265.666728 -95.052134)
			(xy 265.67511 -95.052896) (xy 269.655544 -95.052896) (xy 269.663926 -95.052134) (xy 269.67153 -95.050617)
			(xy 269.685362 -95.043629) (xy 269.691104 -95.038418) (xy 269.846044 -94.883478) (xy 269.846298 -94.883224)
			(xy 269.852798 -94.876078) (xy 269.860357 -94.858318) (xy 269.86103 -94.84868) (xy 269.860776 -94.843346)
			(xy 269.704566 -92.900246) (xy 269.703535 -92.891633) (xy 269.696458 -92.875808) (xy 269.684482 -92.863274)
			(xy 269.67688 -92.859098) (xy 269.67434 -92.857828) (xy 269.67053 -92.85605) (xy 269.665903 -92.854273)
			(xy 269.656181 -92.852348) (xy 269.651226 -92.85224) (xy 269.624556 -92.85224) (xy 269.61211 -92.853764)
			(xy 269.604998 -92.855542) (xy 269.599156 -92.858844) (xy 269.577691 -92.870438) (xy 269.532446 -92.888685)
			(xy 269.485246 -92.90102) (xy 269.436859 -92.907242) (xy 269.412466 -92.907612) (xy 269.385216 -92.907124)
			(xy 269.331271 -92.899363) (xy 269.27898 -92.884005) (xy 269.229407 -92.861362) (xy 269.18356 -92.831894)
			(xy 269.142374 -92.796202) (xy 269.106685 -92.755013) (xy 269.077222 -92.709163) (xy 269.054583 -92.659588)
			(xy 269.039229 -92.607295) (xy 269.031474 -92.55335) (xy 269.031474 -92.49885) (xy 269.039229 -92.444905)
			(xy 269.054583 -92.392612) (xy 269.077222 -92.343037) (xy 269.106685 -92.297187) (xy 269.142374 -92.255998)
			(xy 269.18356 -92.220306) (xy 269.229407 -92.190838) (xy 269.27898 -92.168195) (xy 269.331271 -92.152837)
			(xy 269.385216 -92.145076) (xy 269.412466 -92.144596) (xy 269.41272 -92.144596) (xy 269.435795 -92.144962)
			(xy 269.481605 -92.150553) (xy 269.526409 -92.161616) (xy 269.548102 -92.169488) (xy 269.559278 -92.173806)
			(xy 269.570054 -92.176886) (xy 269.592312 -92.174504) (xy 269.602204 -92.169234) (xy 269.620238 -92.156026)
			(xy 269.627089 -92.150652) (xy 269.636965 -92.136326) (xy 269.641443 -92.119513) (xy 269.641066 -92.110814)
			(xy 269.622778 -91.88323) (xy 269.621262 -91.871635) (xy 269.609344 -91.851546) (xy 269.599918 -91.844622)
			(xy 269.596616 -91.84259) (xy 269.592044 -91.839796) (xy 269.587069 -91.836856) (xy 269.576171 -91.833021)
			(xy 269.570454 -91.832176) (xy 269.55877 -91.830906) (xy 269.54734 -91.835224) (xy 269.514814 -91.846719)
			(xy 269.446956 -91.859107) (xy 269.412466 -91.859862) (xy 269.38522 -91.859374) (xy 269.331282 -91.851614)
			(xy 269.278998 -91.836258) (xy 269.229431 -91.813617) (xy 269.18359 -91.784154) (xy 269.142409 -91.748467)
			(xy 269.106726 -91.707282) (xy 269.077266 -91.661439) (xy 269.05463 -91.61187) (xy 269.039279 -91.559585)
			(xy 269.031524 -91.505646) (xy 269.031524 -91.451154) (xy 269.039279 -91.397215) (xy 269.05463 -91.34493)
			(xy 269.077266 -91.295361) (xy 269.106726 -91.249518) (xy 269.142409 -91.208333) (xy 269.18359 -91.172646)
			(xy 269.229431 -91.143183) (xy 269.278998 -91.120542) (xy 269.331282 -91.105186) (xy 269.38522 -91.097426)
			(xy 269.412466 -91.096846) (xy 269.431844 -91.097107) (xy 269.470399 -91.101052) (xy 269.489428 -91.10472)
			(xy 269.494762 -91.105736) (xy 269.498644 -91.106077) (xy 269.506427 -91.105698) (xy 269.510256 -91.104974)
			(xy 269.514828 -91.103704) (xy 269.519431 -91.102134) (xy 269.527998 -91.097533) (xy 269.531846 -91.09456)
			(xy 269.538958 -91.08821) (xy 269.547345 -91.079929) (xy 269.556101 -91.058078) (xy 269.555722 -91.0463)
			(xy 269.268194 -87.462868) (xy 269.267554 -87.457393) (xy 269.264213 -87.446889) (xy 269.26159 -87.44204)
			(xy 269.26159 -87.441786) (xy 269.249533 -87.420026) (xy 269.230539 -87.374047) (xy 269.217686 -87.325989)
			(xy 269.211192 -87.276668) (xy 269.21079 -87.251794) (xy 269.21079 -87.251286) (xy 269.211512 -87.216996)
			(xy 269.22378 -87.149524) (xy 269.235174 -87.117174) (xy 269.239238 -87.106506) (xy 268.066266 -72.494394)
			(xy 268.065105 -72.484936) (xy 268.056754 -72.467822) (xy 268.042739 -72.454931) (xy 268.024988 -72.448036)
			(xy 268.015466 -72.447658) (xy 263.843262 -72.447658) (xy 263.838371 -72.447522) (xy 263.828778 -72.445605)
			(xy 263.824212 -72.443848) (xy 263.81456 -72.440038) (xy 251.017786 -72.440038) (xy 251.007718 -72.440464)
			(xy 250.98912 -72.448187) (xy 250.981718 -72.455024) (xy 250.901454 -72.535288) (xy 250.8946 -72.542683)
			(xy 250.886852 -72.561282) (xy 250.886468 -72.571356) (xy 250.886468 -73.418192) (xy 250.886046 -73.428262)
			(xy 250.87833 -73.446866) (xy 250.871482 -73.45426) (xy 250.556776 -73.768966) (xy 250.549378 -73.775812)
			(xy 250.530779 -73.783544) (xy 250.520708 -73.783952) (xy 248.910856 -73.783952) (xy 248.900791 -73.784385)
			(xy 248.882203 -73.792116) (xy 248.874788 -73.798938) (xy 248.821956 -73.85177) (xy 251.07595 -73.85177)
			(xy 251.080021 -73.796148) (xy 251.092147 -73.741711) (xy 251.11207 -73.68962) (xy 251.139366 -73.640985)
			(xy 251.173452 -73.596842) (xy 251.213601 -73.558133) (xy 251.258959 -73.525682) (xy 251.308559 -73.500181)
			(xy 251.361343 -73.482174) (xy 251.416186 -73.472044) (xy 251.47192 -73.470007) (xy 251.527357 -73.476107)
			(xy 251.581314 -73.490213) (xy 251.632643 -73.512025) (xy 251.680249 -73.541079) (xy 251.723117 -73.576754)
			(xy 251.760334 -73.618291) (xy 251.791107 -73.664804) (xy 251.814779 -73.715301) (xy 251.830847 -73.768708)
			(xy 251.838967 -73.823884) (xy 251.839476 -73.85177) (xy 252.09195 -73.85177) (xy 252.096021 -73.796148)
			(xy 252.108147 -73.741711) (xy 252.12807 -73.68962) (xy 252.155366 -73.640985) (xy 252.189452 -73.596842)
			(xy 252.229601 -73.558133) (xy 252.274959 -73.525682) (xy 252.324559 -73.500181) (xy 252.377343 -73.482174)
			(xy 252.432186 -73.472044) (xy 252.48792 -73.470007) (xy 252.543357 -73.476107) (xy 252.597314 -73.490213)
			(xy 252.648643 -73.512025) (xy 252.696249 -73.541079) (xy 252.739117 -73.576754) (xy 252.776334 -73.618291)
			(xy 252.807107 -73.664804) (xy 252.830779 -73.715301) (xy 252.846847 -73.768708) (xy 252.854967 -73.823884)
			(xy 252.855476 -73.85177) (xy 253.10795 -73.85177) (xy 253.112021 -73.796148) (xy 253.124147 -73.741711)
			(xy 253.14407 -73.68962) (xy 253.171366 -73.640985) (xy 253.205452 -73.596842) (xy 253.245601 -73.558133)
			(xy 253.290959 -73.525682) (xy 253.340559 -73.500181) (xy 253.393343 -73.482174) (xy 253.448186 -73.472044)
			(xy 253.50392 -73.470007) (xy 253.559357 -73.476107) (xy 253.613314 -73.490213) (xy 253.664643 -73.512025)
			(xy 253.712249 -73.541079) (xy 253.755117 -73.576754) (xy 253.792334 -73.618291) (xy 253.823107 -73.664804)
			(xy 253.846779 -73.715301) (xy 253.862847 -73.768708) (xy 253.870967 -73.823884) (xy 253.871476 -73.85177)
			(xy 253.870967 -73.879656) (xy 253.862847 -73.934832) (xy 253.846779 -73.988239) (xy 253.823107 -74.038736)
			(xy 253.792334 -74.085249) (xy 253.755117 -74.126786) (xy 253.712249 -74.162461) (xy 253.664643 -74.191515)
			(xy 253.613314 -74.213327) (xy 253.559357 -74.227433) (xy 253.50392 -74.233533) (xy 253.448186 -74.231496)
			(xy 253.393343 -74.221366) (xy 253.340559 -74.203359) (xy 253.290959 -74.177858) (xy 253.245601 -74.145407)
			(xy 253.205452 -74.106698) (xy 253.171366 -74.062555) (xy 253.14407 -74.01392) (xy 253.124147 -73.961829)
			(xy 253.112021 -73.907392) (xy 253.10795 -73.85177) (xy 252.855476 -73.85177) (xy 252.854967 -73.879656)
			(xy 252.846847 -73.934832) (xy 252.830779 -73.988239) (xy 252.807107 -74.038736) (xy 252.776334 -74.085249)
			(xy 252.739117 -74.126786) (xy 252.696249 -74.162461) (xy 252.648643 -74.191515) (xy 252.597314 -74.213327)
			(xy 252.543357 -74.227433) (xy 252.48792 -74.233533) (xy 252.432186 -74.231496) (xy 252.377343 -74.221366)
			(xy 252.324559 -74.203359) (xy 252.274959 -74.177858) (xy 252.229601 -74.145407) (xy 252.189452 -74.106698)
			(xy 252.155366 -74.062555) (xy 252.12807 -74.01392) (xy 252.108147 -73.961829) (xy 252.096021 -73.907392)
			(xy 252.09195 -73.85177) (xy 251.839476 -73.85177) (xy 251.838967 -73.879656) (xy 251.830847 -73.934832)
			(xy 251.814779 -73.988239) (xy 251.791107 -74.038736) (xy 251.760334 -74.085249) (xy 251.723117 -74.126786)
			(xy 251.680249 -74.162461) (xy 251.632643 -74.191515) (xy 251.581314 -74.213327) (xy 251.527357 -74.227433)
			(xy 251.47192 -74.233533) (xy 251.416186 -74.231496) (xy 251.361343 -74.221366) (xy 251.308559 -74.203359)
			(xy 251.258959 -74.177858) (xy 251.213601 -74.145407) (xy 251.173452 -74.106698) (xy 251.139366 -74.062555)
			(xy 251.11207 -74.01392) (xy 251.092147 -73.961829) (xy 251.080021 -73.907392) (xy 251.07595 -73.85177)
			(xy 248.821956 -73.85177) (xy 248.087896 -74.58583) (xy 255.158494 -74.58583) (xy 255.158925 -74.559495)
			(xy 255.166159 -74.507325) (xy 255.18048 -74.45664) (xy 255.201618 -74.408399) (xy 255.229173 -74.363512)
			(xy 255.262624 -74.32283) (xy 255.281684 -74.304652) (xy 255.289106 -74.297148) (xy 255.297619 -74.277855)
			(xy 255.298194 -74.267314) (xy 255.298194 -74.193146) (xy 255.297655 -74.182597) (xy 255.289127 -74.163302)
			(xy 255.281684 -74.155808) (xy 255.262652 -74.137602) (xy 255.229193 -74.096929) (xy 255.201631 -74.05205)
			(xy 255.18049 -74.003813) (xy 255.166167 -73.953131) (xy 255.158936 -73.900963) (xy 255.158494 -73.87463)
			(xy 255.158979 -73.84726) (xy 255.166793 -73.793082) (xy 255.182277 -73.740579) (xy 255.205115 -73.690832)
			(xy 255.234835 -73.644864) (xy 255.252474 -73.623932) (xy 255.25857 -73.617074) (xy 255.26492 -73.600056)
			(xy 255.26492 -73.541382) (xy 255.252474 -73.541382) (xy 255.252474 -73.499726) (xy 255.246886 -73.483978)
			(xy 255.241552 -73.47712) (xy 255.225899 -73.456794) (xy 255.199598 -73.412748) (xy 255.179443 -73.365572)
			(xy 255.1658 -73.316118) (xy 255.158914 -73.265281) (xy 255.158494 -73.23963) (xy 255.158983 -73.212378)
			(xy 255.166736 -73.158428) (xy 255.182088 -73.10613) (xy 255.204728 -73.05655) (xy 255.234193 -73.010697)
			(xy 255.269884 -72.969504) (xy 255.311074 -72.93381) (xy 255.356925 -72.904341) (xy 255.406504 -72.881698)
			(xy 255.4588 -72.866342) (xy 255.51275 -72.858585) (xy 255.540002 -72.858122) (xy 255.567373 -72.858582)
			(xy 255.621552 -72.8664) (xy 255.674056 -72.88189) (xy 255.723802 -72.904734) (xy 255.769769 -72.93446)
			(xy 255.7907 -72.952102) (xy 255.797558 -72.958198) (xy 255.814576 -72.964548) (xy 255.87325 -72.964548)
			(xy 255.87325 -72.952102) (xy 255.914906 -72.952102) (xy 255.930654 -72.946514) (xy 255.937512 -72.94118)
			(xy 255.95783 -72.925517) (xy 256.001878 -72.899217) (xy 256.049057 -72.879064) (xy 256.098512 -72.865423)
			(xy 256.149351 -72.85854) (xy 256.175002 -72.858122) (xy 256.202256 -72.858554) (xy 256.25621 -72.866312)
			(xy 256.30851 -72.881669) (xy 256.358092 -72.904314) (xy 256.403947 -72.933785) (xy 256.44514 -72.969482)
			(xy 256.480834 -73.010679) (xy 256.510301 -73.056536) (xy 256.532942 -73.10612) (xy 256.548295 -73.158421)
			(xy 256.556049 -73.212376) (xy 256.55651 -73.23963) (xy 256.556059 -73.267001) (xy 256.548237 -73.32118)
			(xy 256.532744 -73.373684) (xy 256.509899 -73.42343) (xy 256.480172 -73.469397) (xy 256.46253 -73.490328)
			(xy 256.456434 -73.497186) (xy 256.450084 -73.514204) (xy 256.450084 -73.572878) (xy 256.46253 -73.572878)
			(xy 256.46253 -73.614534) (xy 256.468118 -73.630282) (xy 256.473452 -73.63714) (xy 256.489133 -73.657445)
			(xy 256.515429 -73.701497) (xy 256.526127 -73.726548) (xy 259.359398 -73.726548) (xy 259.363469 -73.670926)
			(xy 259.375595 -73.616489) (xy 259.395518 -73.564398) (xy 259.422814 -73.515763) (xy 259.4569 -73.47162)
			(xy 259.497049 -73.432911) (xy 259.542407 -73.40046) (xy 259.592007 -73.374959) (xy 259.644791 -73.356952)
			(xy 259.699634 -73.346822) (xy 259.755368 -73.344785) (xy 259.810805 -73.350885) (xy 259.864762 -73.364991)
			(xy 259.916091 -73.386803) (xy 259.963697 -73.415857) (xy 260.006565 -73.451532) (xy 260.043782 -73.493069)
			(xy 260.074555 -73.539582) (xy 260.077119 -73.545052) (xy 260.531838 -73.545052) (xy 260.531838 -73.490548)
			(xy 260.539594 -73.436597) (xy 260.554949 -73.3843) (xy 260.57759 -73.33472) (xy 260.607056 -73.288866)
			(xy 260.642747 -73.247673) (xy 260.683938 -73.211978) (xy 260.729788 -73.182507) (xy 260.779366 -73.159862)
			(xy 260.831662 -73.144502) (xy 260.885612 -73.13674) (xy 260.912864 -73.136252) (xy 260.939259 -73.136728)
			(xy 260.991544 -73.144007) (xy 261.042329 -73.158417) (xy 261.090645 -73.179685) (xy 261.135572 -73.207404)
			(xy 261.156196 -73.223882) (xy 261.166959 -73.232137) (xy 261.191639 -73.243346) (xy 261.218401 -73.247657)
			(xy 261.245354 -73.244767) (xy 261.270593 -73.23488) (xy 261.292337 -73.218693) (xy 261.309048 -73.19735)
			(xy 261.314692 -73.18502) (xy 261.326017 -73.159373) (xy 261.354963 -73.111362) (xy 261.390623 -73.068104)
			(xy 261.43223 -73.03053) (xy 261.478887 -72.999449) (xy 261.529591 -72.975531) (xy 261.583249 -72.959291)
			(xy 261.638705 -72.951077) (xy 261.666736 -72.950578) (xy 261.693985 -72.951095) (xy 261.747926 -72.958855)
			(xy 261.800215 -72.974213) (xy 261.849786 -72.996855) (xy 261.89563 -73.026321) (xy 261.936814 -73.062011)
			(xy 261.9725 -73.103199) (xy 262.001962 -73.149046) (xy 262.0246 -73.198619) (xy 262.039953 -73.250909)
			(xy 262.047708 -73.304851) (xy 262.047708 -73.359349) (xy 262.039953 -73.413291) (xy 262.0246 -73.465581)
			(xy 262.001962 -73.515154) (xy 261.9725 -73.561001) (xy 261.936814 -73.602189) (xy 261.89563 -73.637879)
			(xy 261.849786 -73.667345) (xy 261.800215 -73.689987) (xy 261.747926 -73.705345) (xy 261.693985 -73.713105)
			(xy 261.666736 -73.713594) (xy 261.640341 -73.713131) (xy 261.588054 -73.70585) (xy 261.537269 -73.691438)
			(xy 261.488953 -73.670167) (xy 261.444027 -73.642444) (xy 261.423404 -73.625964) (xy 261.412653 -73.617691)
			(xy 261.387969 -73.606475) (xy 261.361202 -73.60216) (xy 261.334244 -73.605051) (xy 261.309001 -73.614944)
			(xy 261.287256 -73.631139) (xy 261.270548 -73.652491) (xy 261.264908 -73.664826) (xy 261.253606 -73.690484)
			(xy 261.224654 -73.738493) (xy 261.18899 -73.781749) (xy 261.147379 -73.819321) (xy 261.100719 -73.8504)
			(xy 261.050013 -73.874316) (xy 260.996354 -73.890556) (xy 260.940895 -73.898769) (xy 260.912864 -73.899268)
			(xy 260.885612 -73.89886) (xy 260.831662 -73.891098) (xy 260.779366 -73.875738) (xy 260.729788 -73.853093)
			(xy 260.683938 -73.823622) (xy 260.642747 -73.787927) (xy 260.607056 -73.746734) (xy 260.57759 -73.70088)
			(xy 260.554949 -73.6513) (xy 260.539594 -73.599003) (xy 260.531838 -73.545052) (xy 260.077119 -73.545052)
			(xy 260.098227 -73.590079) (xy 260.114295 -73.643486) (xy 260.122415 -73.698662) (xy 260.122924 -73.726548)
			(xy 260.122415 -73.754434) (xy 260.114295 -73.80961) (xy 260.098227 -73.863017) (xy 260.074555 -73.913514)
			(xy 260.043782 -73.960027) (xy 260.006565 -74.001564) (xy 259.963697 -74.037239) (xy 259.916091 -74.066293)
			(xy 259.864762 -74.088105) (xy 259.810805 -74.102211) (xy 259.755368 -74.108311) (xy 259.699634 -74.106274)
			(xy 259.644791 -74.096144) (xy 259.592007 -74.078137) (xy 259.542407 -74.052636) (xy 259.497049 -74.020185)
			(xy 259.4569 -73.981476) (xy 259.422814 -73.937333) (xy 259.395518 -73.888698) (xy 259.375595 -73.836607)
			(xy 259.363469 -73.78217) (xy 259.359398 -73.726548) (xy 256.526127 -73.726548) (xy 256.535578 -73.748679)
			(xy 256.549216 -73.798137) (xy 256.556094 -73.848978) (xy 256.55651 -73.87463) (xy 256.556051 -73.900964)
			(xy 256.548822 -73.953133) (xy 256.534507 -74.003817) (xy 256.513374 -74.052059) (xy 256.485824 -74.096946)
			(xy 256.452378 -74.137629) (xy 256.43332 -74.155808) (xy 256.425916 -74.163327) (xy 256.417392 -74.182609)
			(xy 256.41681 -74.193146) (xy 256.41681 -74.267314) (xy 256.417315 -74.277867) (xy 256.425867 -74.297162)
			(xy 256.43332 -74.304652) (xy 256.452382 -74.322828) (xy 256.485838 -74.363507) (xy 256.513396 -74.408393)
			(xy 256.534532 -74.456636) (xy 256.548848 -74.507323) (xy 256.556072 -74.559495) (xy 256.55651 -74.58583)
			(xy 256.55605 -74.613082) (xy 256.54829 -74.66703) (xy 256.532931 -74.719326) (xy 256.510286 -74.768903)
			(xy 256.480817 -74.814753) (xy 256.445123 -74.855943) (xy 256.40393 -74.891634) (xy 256.358078 -74.9211)
			(xy 256.308499 -74.943741) (xy 256.256203 -74.959096) (xy 256.202254 -74.966852) (xy 256.175002 -74.967338)
			(xy 256.147631 -74.966886) (xy 256.093451 -74.959067) (xy 256.040947 -74.943576) (xy 255.9912 -74.92073)
			(xy 255.945235 -74.891002) (xy 255.924304 -74.873358) (xy 255.917446 -74.867262) (xy 255.900428 -74.860912)
			(xy 255.841754 -74.860912) (xy 255.841754 -74.873358) (xy 255.800098 -74.873358) (xy 255.78435 -74.878946)
			(xy 255.777492 -74.88428) (xy 255.757179 -74.89995) (xy 255.713129 -74.926248) (xy 255.665949 -74.946398)
			(xy 255.616493 -74.960038) (xy 255.565653 -74.96692) (xy 255.540002 -74.967338) (xy 255.512752 -74.96682)
			(xy 255.458807 -74.959065) (xy 255.406515 -74.943712) (xy 255.35694 -74.921073) (xy 255.311091 -74.89161)
			(xy 255.269901 -74.855922) (xy 255.23421 -74.814735) (xy 255.204742 -74.768889) (xy 255.1821 -74.719315)
			(xy 255.166742 -74.667024) (xy 255.158982 -74.61308) (xy 255.158494 -74.58583) (xy 248.087896 -74.58583)
			(xy 248.030746 -74.64298) (xy 248.027743 -74.646068) (xy 248.022758 -74.653093) (xy 248.02084 -74.65695)
			(xy 248.017538 -74.663808) (xy 248.016268 -74.672444) (xy 248.012533 -74.698314) (xy 247.998902 -74.748774)
			(xy 247.978514 -74.796902) (xy 247.95175 -74.841798) (xy 247.919111 -74.882623) (xy 247.881207 -74.918614)
			(xy 247.838747 -74.949096) (xy 247.792525 -74.973501) (xy 247.76811 -74.982832) (xy 247.767856 -74.982832)
			(xy 247.760557 -74.985818) (xy 247.748137 -74.995523) (xy 247.743472 -75.001882) (xy 247.739154 -75.007978)
			(xy 247.734582 -75.022456) (xy 247.734582 -76.270104) (xy 254.795272 -76.270104) (xy 254.799343 -76.214482)
			(xy 254.811469 -76.160045) (xy 254.831392 -76.107954) (xy 254.858688 -76.059319) (xy 254.892774 -76.015176)
			(xy 254.932923 -75.976467) (xy 254.978281 -75.944016) (xy 255.027881 -75.918515) (xy 255.080665 -75.900508)
			(xy 255.135508 -75.890378) (xy 255.191242 -75.888341) (xy 255.246679 -75.894441) (xy 255.300636 -75.908547)
			(xy 255.351965 -75.930359) (xy 255.399571 -75.959413) (xy 255.442439 -75.995088) (xy 255.479656 -76.036625)
			(xy 255.510429 -76.083138) (xy 255.534101 -76.133635) (xy 255.550169 -76.187042) (xy 255.558289 -76.242218)
			(xy 255.558798 -76.270104) (xy 255.811272 -76.270104) (xy 255.815343 -76.214482) (xy 255.827469 -76.160045)
			(xy 255.847392 -76.107954) (xy 255.874688 -76.059319) (xy 255.908774 -76.015176) (xy 255.948923 -75.976467)
			(xy 255.994281 -75.944016) (xy 256.043881 -75.918515) (xy 256.096665 -75.900508) (xy 256.151508 -75.890378)
			(xy 256.207242 -75.888341) (xy 256.244185 -75.892406) (xy 262.02894 -75.892406) (xy 262.029351 -75.866468)
			(xy 262.03638 -75.815071) (xy 262.050309 -75.7651) (xy 262.070881 -75.717478) (xy 262.097717 -75.673083)
			(xy 262.130321 -75.632734) (xy 262.168093 -75.597175) (xy 262.18896 -75.581764) (xy 262.19658 -75.57643)
			(xy 262.206994 -75.560936) (xy 262.215884 -75.521566) (xy 262.21763 -75.512289) (xy 262.214892 -75.493626)
			(xy 262.21055 -75.485244) (xy 262.196268 -75.459228) (xy 262.173767 -75.404308) (xy 262.15854 -75.346945)
			(xy 262.150841 -75.288097) (xy 262.150352 -75.258422) (xy 262.150828 -75.228436) (xy 262.158653 -75.168978)
			(xy 262.174173 -75.111049) (xy 262.197121 -75.055642) (xy 262.227106 -75.003705) (xy 262.263614 -74.956125)
			(xy 262.306019 -74.913719) (xy 262.353598 -74.87721) (xy 262.405535 -74.847225) (xy 262.460941 -74.824275)
			(xy 262.51887 -74.808755) (xy 262.578328 -74.800928) (xy 262.608314 -74.80046) (xy 263.471914 -74.80046)
			(xy 263.501901 -74.800894) (xy 263.561361 -74.808724) (xy 263.619291 -74.824248) (xy 263.674699 -74.847201)
			(xy 263.726637 -74.87719) (xy 263.774216 -74.913702) (xy 263.816622 -74.956111) (xy 263.85313 -75.003693)
			(xy 263.883115 -75.055633) (xy 263.906063 -75.111043) (xy 263.921583 -75.168974) (xy 263.929408 -75.228435)
			(xy 263.929876 -75.258422) (xy 263.929402 -75.288099) (xy 263.921731 -75.346955) (xy 263.906507 -75.404324)
			(xy 263.883987 -75.45924) (xy 263.869678 -75.485244) (xy 263.866751 -75.490661) (xy 263.863285 -75.502472)
			(xy 263.86282 -75.508612) (xy 263.86409 -75.52182) (xy 263.87298 -75.56119) (xy 263.883394 -75.576684)
			(xy 263.891014 -75.582018) (xy 263.911827 -75.597456) (xy 263.94954 -75.632993) (xy 263.982092 -75.67331)
			(xy 264.008884 -75.717664) (xy 264.029423 -75.765238) (xy 264.043328 -75.815156) (xy 264.050346 -75.866497)
			(xy 264.05078 -75.892406) (xy 264.050294 -75.919657) (xy 264.042538 -75.973605) (xy 264.027183 -76.0259)
			(xy 264.004541 -76.075477) (xy 263.975075 -76.121327) (xy 263.939384 -76.162518) (xy 263.898193 -76.198209)
			(xy 263.852343 -76.227675) (xy 263.802766 -76.250317) (xy 263.750471 -76.265672) (xy 263.719644 -76.270104)
			(xy 264.157966 -76.270104) (xy 264.162037 -76.214482) (xy 264.174163 -76.160045) (xy 264.194086 -76.107954)
			(xy 264.221382 -76.059319) (xy 264.255468 -76.015176) (xy 264.295617 -75.976467) (xy 264.340975 -75.944016)
			(xy 264.390575 -75.918515) (xy 264.443359 -75.900508) (xy 264.498202 -75.890378) (xy 264.553936 -75.888341)
			(xy 264.609373 -75.894441) (xy 264.66333 -75.908547) (xy 264.714659 -75.930359) (xy 264.762265 -75.959413)
			(xy 264.805133 -75.995088) (xy 264.84235 -76.036625) (xy 264.873123 -76.083138) (xy 264.896795 -76.133635)
			(xy 264.912863 -76.187042) (xy 264.920983 -76.242218) (xy 264.921492 -76.270104) (xy 264.920983 -76.29799)
			(xy 264.912863 -76.353166) (xy 264.896795 -76.406573) (xy 264.873123 -76.45707) (xy 264.84235 -76.503583)
			(xy 264.805133 -76.54512) (xy 264.762265 -76.580795) (xy 264.714659 -76.609849) (xy 264.66333 -76.631661)
			(xy 264.609373 -76.645767) (xy 264.553936 -76.651867) (xy 264.498202 -76.64983) (xy 264.443359 -76.6397)
			(xy 264.390575 -76.621693) (xy 264.340975 -76.596192) (xy 264.295617 -76.563741) (xy 264.255468 -76.525032)
			(xy 264.221382 -76.480889) (xy 264.194086 -76.432254) (xy 264.174163 -76.380163) (xy 264.162037 -76.325726)
			(xy 264.157966 -76.270104) (xy 263.719644 -76.270104) (xy 263.696523 -76.273428) (xy 263.642021 -76.273428)
			(xy 263.588073 -76.265672) (xy 263.535778 -76.250317) (xy 263.486201 -76.227675) (xy 263.440351 -76.198209)
			(xy 263.39916 -76.162518) (xy 263.363469 -76.121327) (xy 263.334003 -76.075477) (xy 263.311361 -76.0259)
			(xy 263.296006 -75.973605) (xy 263.28825 -75.919657) (xy 263.287764 -75.892406) (xy 263.287898 -75.877613)
			(xy 263.290188 -75.848115) (xy 263.292336 -75.833478) (xy 263.294114 -75.822302) (xy 263.288272 -75.801474)
			(xy 263.28116 -75.793092) (xy 263.280652 -75.792584) (xy 263.230614 -75.734164) (xy 263.22304 -75.726144)
			(xy 263.203024 -75.716925) (xy 263.192006 -75.716384) (xy 262.887714 -75.716384) (xy 262.876697 -75.716935)
			(xy 262.856681 -75.726146) (xy 262.849106 -75.734164) (xy 262.791702 -75.80122) (xy 262.785606 -75.822302)
			(xy 262.787384 -75.833478) (xy 262.789528 -75.848115) (xy 262.791814 -75.877613) (xy 262.791956 -75.892406)
			(xy 262.79147 -75.919657) (xy 262.783714 -75.973605) (xy 262.768359 -76.0259) (xy 262.745717 -76.075477)
			(xy 262.716251 -76.121327) (xy 262.68056 -76.162518) (xy 262.639369 -76.198209) (xy 262.593519 -76.227675)
			(xy 262.543942 -76.250317) (xy 262.491647 -76.265672) (xy 262.437699 -76.273428) (xy 262.383197 -76.273428)
			(xy 262.329249 -76.265672) (xy 262.276954 -76.250317) (xy 262.227377 -76.227675) (xy 262.181527 -76.198209)
			(xy 262.140336 -76.162518) (xy 262.104645 -76.121327) (xy 262.075179 -76.075477) (xy 262.052537 -76.0259)
			(xy 262.037182 -75.973605) (xy 262.029426 -75.919657) (xy 262.02894 -75.892406) (xy 256.244185 -75.892406)
			(xy 256.262679 -75.894441) (xy 256.316636 -75.908547) (xy 256.367965 -75.930359) (xy 256.415571 -75.959413)
			(xy 256.458439 -75.995088) (xy 256.495656 -76.036625) (xy 256.526429 -76.083138) (xy 256.550101 -76.133635)
			(xy 256.566169 -76.187042) (xy 256.574289 -76.242218) (xy 256.574798 -76.270104) (xy 256.574289 -76.29799)
			(xy 256.566169 -76.353166) (xy 256.550101 -76.406573) (xy 256.526429 -76.45707) (xy 256.495656 -76.503583)
			(xy 256.458439 -76.54512) (xy 256.415571 -76.580795) (xy 256.367965 -76.609849) (xy 256.316636 -76.631661)
			(xy 256.262679 -76.645767) (xy 256.207242 -76.651867) (xy 256.151508 -76.64983) (xy 256.096665 -76.6397)
			(xy 256.043881 -76.621693) (xy 255.994281 -76.596192) (xy 255.948923 -76.563741) (xy 255.908774 -76.525032)
			(xy 255.874688 -76.480889) (xy 255.847392 -76.432254) (xy 255.827469 -76.380163) (xy 255.815343 -76.325726)
			(xy 255.811272 -76.270104) (xy 255.558798 -76.270104) (xy 255.558289 -76.29799) (xy 255.550169 -76.353166)
			(xy 255.534101 -76.406573) (xy 255.510429 -76.45707) (xy 255.479656 -76.503583) (xy 255.442439 -76.54512)
			(xy 255.399571 -76.580795) (xy 255.351965 -76.609849) (xy 255.300636 -76.631661) (xy 255.246679 -76.645767)
			(xy 255.191242 -76.651867) (xy 255.135508 -76.64983) (xy 255.080665 -76.6397) (xy 255.027881 -76.621693)
			(xy 254.978281 -76.596192) (xy 254.932923 -76.563741) (xy 254.892774 -76.525032) (xy 254.858688 -76.480889)
			(xy 254.831392 -76.432254) (xy 254.811469 -76.380163) (xy 254.799343 -76.325726) (xy 254.795272 -76.270104)
			(xy 247.734582 -76.270104) (xy 247.734582 -77.043534) (xy 247.735075 -77.053538) (xy 247.74274 -77.072022)
			(xy 247.756892 -77.086169) (xy 247.775377 -77.093828) (xy 247.785382 -77.094334) (xy 250.61164 -77.094334)
			(xy 250.621706 -77.094765) (xy 250.640297 -77.102494) (xy 250.647708 -77.10932) (xy 251.664724 -78.126336)
			(xy 251.671573 -78.133733) (xy 251.679306 -78.152332) (xy 251.67971 -78.162404) (xy 251.67971 -78.979268)
			(xy 251.87351 -78.979268) (xy 251.877581 -78.923646) (xy 251.889707 -78.869209) (xy 251.90963 -78.817118)
			(xy 251.936926 -78.768483) (xy 251.971012 -78.72434) (xy 252.011161 -78.685631) (xy 252.056519 -78.65318)
			(xy 252.106119 -78.627679) (xy 252.158903 -78.609672) (xy 252.213746 -78.599542) (xy 252.26948 -78.597505)
			(xy 252.324917 -78.603605) (xy 252.378874 -78.617711) (xy 252.430203 -78.639523) (xy 252.43627 -78.643226)
			(xy 254.273302 -78.643226) (xy 254.277373 -78.587604) (xy 254.289499 -78.533167) (xy 254.309422 -78.481076)
			(xy 254.336718 -78.432441) (xy 254.370804 -78.388298) (xy 254.410953 -78.349589) (xy 254.456311 -78.317138)
			(xy 254.505911 -78.291637) (xy 254.558695 -78.27363) (xy 254.613538 -78.2635) (xy 254.669272 -78.261463)
			(xy 254.724709 -78.267563) (xy 254.778666 -78.281669) (xy 254.829995 -78.303481) (xy 254.877601 -78.332535)
			(xy 254.920469 -78.36821) (xy 254.957686 -78.409747) (xy 254.988459 -78.45626) (xy 255.009783 -78.501748)
			(xy 256.284728 -78.501748) (xy 256.288799 -78.446126) (xy 256.300925 -78.391689) (xy 256.320848 -78.339598)
			(xy 256.348144 -78.290963) (xy 256.38223 -78.24682) (xy 256.422379 -78.208111) (xy 256.467737 -78.17566)
			(xy 256.517337 -78.150159) (xy 256.570121 -78.132152) (xy 256.624964 -78.122022) (xy 256.680698 -78.119985)
			(xy 256.736135 -78.126085) (xy 256.790092 -78.140191) (xy 256.841421 -78.162003) (xy 256.889027 -78.191057)
			(xy 256.931895 -78.226732) (xy 256.969112 -78.268269) (xy 256.999885 -78.314782) (xy 257.023557 -78.365279)
			(xy 257.039625 -78.418686) (xy 257.047745 -78.473862) (xy 257.048254 -78.501748) (xy 257.047745 -78.529634)
			(xy 257.039625 -78.58481) (xy 257.023557 -78.638217) (xy 256.999885 -78.688714) (xy 256.969112 -78.735227)
			(xy 256.931895 -78.776764) (xy 256.889027 -78.812439) (xy 256.84291 -78.840584) (xy 259.167884 -78.840584)
			(xy 259.16837 -78.813333) (xy 259.176126 -78.759385) (xy 259.191481 -78.70709) (xy 259.214123 -78.657513)
			(xy 259.243589 -78.611663) (xy 259.27928 -78.570472) (xy 259.320471 -78.534781) (xy 259.366321 -78.505315)
			(xy 259.415898 -78.482673) (xy 259.468193 -78.467318) (xy 259.522141 -78.459562) (xy 259.576643 -78.459562)
			(xy 259.630591 -78.467318) (xy 259.682886 -78.482673) (xy 259.732463 -78.505315) (xy 259.778313 -78.534781)
			(xy 259.819504 -78.570472) (xy 259.855195 -78.611663) (xy 259.884661 -78.657513) (xy 259.907303 -78.70709)
			(xy 259.922658 -78.759385) (xy 259.930414 -78.813333) (xy 259.9309 -78.840584) (xy 259.930296 -78.872151)
			(xy 259.919913 -78.934427) (xy 259.899412 -78.99414) (xy 259.884926 -79.022194) (xy 259.880354 -79.030576)
			(xy 259.877814 -79.048864) (xy 259.895594 -79.124302) (xy 259.898109 -79.133249) (xy 259.908542 -79.148614)
			(xy 259.915914 -79.154274) (xy 259.916168 -79.154274) (xy 259.937487 -79.169642) (xy 259.976117 -79.205275)
			(xy 260.009493 -79.24587) (xy 260.036983 -79.290661) (xy 260.058069 -79.338799) (xy 260.072352 -79.389376)
			(xy 260.07956 -79.441433) (xy 260.079998 -79.46771) (xy 260.079512 -79.494961) (xy 260.071756 -79.548909)
			(xy 260.056401 -79.601204) (xy 260.037442 -79.642716) (xy 261.293862 -79.642716) (xy 261.297933 -79.587094)
			(xy 261.310059 -79.532657) (xy 261.329982 -79.480566) (xy 261.357278 -79.431931) (xy 261.391364 -79.387788)
			(xy 261.431513 -79.349079) (xy 261.476871 -79.316628) (xy 261.526471 -79.291127) (xy 261.579255 -79.27312)
			(xy 261.634098 -79.26299) (xy 261.689832 -79.260953) (xy 261.745269 -79.267053) (xy 261.799226 -79.281159)
			(xy 261.850555 -79.302971) (xy 261.898161 -79.332025) (xy 261.941029 -79.3677) (xy 261.978246 -79.409237)
			(xy 262.009019 -79.45575) (xy 262.032691 -79.506247) (xy 262.048759 -79.559654) (xy 262.056879 -79.61483)
			(xy 262.057388 -79.642716) (xy 262.056879 -79.670602) (xy 262.048759 -79.725778) (xy 262.032691 -79.779185)
			(xy 262.009019 -79.829682) (xy 261.978246 -79.876195) (xy 261.941029 -79.917732) (xy 261.898161 -79.953407)
			(xy 261.850555 -79.982461) (xy 261.799226 -80.004273) (xy 261.745269 -80.018379) (xy 261.689832 -80.024479)
			(xy 261.634098 -80.022442) (xy 261.579255 -80.012312) (xy 261.526471 -79.994305) (xy 261.476871 -79.968804)
			(xy 261.431513 -79.936353) (xy 261.391364 -79.897644) (xy 261.357278 -79.853501) (xy 261.329982 -79.804866)
			(xy 261.310059 -79.752775) (xy 261.297933 -79.698338) (xy 261.293862 -79.642716) (xy 260.037442 -79.642716)
			(xy 260.033759 -79.650781) (xy 260.004293 -79.696631) (xy 259.968602 -79.737822) (xy 259.927411 -79.773513)
			(xy 259.881561 -79.802979) (xy 259.831984 -79.825621) (xy 259.779689 -79.840976) (xy 259.725741 -79.848732)
			(xy 259.671239 -79.848732) (xy 259.617291 -79.840976) (xy 259.564996 -79.825621) (xy 259.515419 -79.802979)
			(xy 259.469569 -79.773513) (xy 259.428378 -79.737822) (xy 259.392687 -79.696631) (xy 259.363221 -79.650781)
			(xy 259.340579 -79.601204) (xy 259.325224 -79.548909) (xy 259.317468 -79.494961) (xy 259.316982 -79.46771)
			(xy 259.317586 -79.436143) (xy 259.327969 -79.373868) (xy 259.34847 -79.314154) (xy 259.362956 -79.2861)
			(xy 259.367528 -79.277718) (xy 259.370068 -79.25943) (xy 259.352288 -79.183992) (xy 259.34974 -79.175056)
			(xy 259.339332 -79.159685) (xy 259.331968 -79.15402) (xy 259.331714 -79.15402) (xy 259.310388 -79.138661)
			(xy 259.271759 -79.103026) (xy 259.238385 -79.062429) (xy 259.210895 -79.017637) (xy 259.18981 -78.969497)
			(xy 259.175529 -78.91892) (xy 259.168321 -78.866861) (xy 259.167884 -78.840584) (xy 256.84291 -78.840584)
			(xy 256.841421 -78.841493) (xy 256.790092 -78.863305) (xy 256.736135 -78.877411) (xy 256.680698 -78.883511)
			(xy 256.624964 -78.881474) (xy 256.570121 -78.871344) (xy 256.517337 -78.853337) (xy 256.467737 -78.827836)
			(xy 256.422379 -78.795385) (xy 256.38223 -78.756676) (xy 256.348144 -78.712533) (xy 256.320848 -78.663898)
			(xy 256.300925 -78.611807) (xy 256.288799 -78.55737) (xy 256.284728 -78.501748) (xy 255.009783 -78.501748)
			(xy 255.012131 -78.506757) (xy 255.028199 -78.560164) (xy 255.036319 -78.61534) (xy 255.036828 -78.643226)
			(xy 255.036319 -78.671112) (xy 255.028199 -78.726288) (xy 255.012131 -78.779695) (xy 254.988459 -78.830192)
			(xy 254.957686 -78.876705) (xy 254.920469 -78.918242) (xy 254.877601 -78.953917) (xy 254.829995 -78.982971)
			(xy 254.778666 -79.004783) (xy 254.724709 -79.018889) (xy 254.669272 -79.024989) (xy 254.613538 -79.022952)
			(xy 254.558695 -79.012822) (xy 254.505911 -78.994815) (xy 254.456311 -78.969314) (xy 254.410953 -78.936863)
			(xy 254.370804 -78.898154) (xy 254.336718 -78.854011) (xy 254.309422 -78.805376) (xy 254.289499 -78.753285)
			(xy 254.277373 -78.698848) (xy 254.273302 -78.643226) (xy 252.43627 -78.643226) (xy 252.477809 -78.668577)
			(xy 252.520677 -78.704252) (xy 252.557894 -78.745789) (xy 252.588667 -78.792302) (xy 252.612339 -78.842799)
			(xy 252.628407 -78.896206) (xy 252.636527 -78.951382) (xy 252.637036 -78.979268) (xy 252.636527 -79.007154)
			(xy 252.628407 -79.06233) (xy 252.612339 -79.115737) (xy 252.588667 -79.166234) (xy 252.557894 -79.212747)
			(xy 252.520677 -79.254284) (xy 252.477809 -79.289959) (xy 252.430203 -79.319013) (xy 252.378874 -79.340825)
			(xy 252.324917 -79.354931) (xy 252.26948 -79.361031) (xy 252.213746 -79.358994) (xy 252.158903 -79.348864)
			(xy 252.106119 -79.330857) (xy 252.056519 -79.305356) (xy 252.011161 -79.272905) (xy 251.971012 -79.234196)
			(xy 251.936926 -79.190053) (xy 251.90963 -79.141418) (xy 251.889707 -79.089327) (xy 251.877581 -79.03489)
			(xy 251.87351 -78.979268) (xy 251.67971 -78.979268) (xy 251.67971 -79.89189) (xy 254.870964 -79.89189)
			(xy 254.875035 -79.836268) (xy 254.887161 -79.781831) (xy 254.907084 -79.72974) (xy 254.93438 -79.681105)
			(xy 254.968466 -79.636962) (xy 255.008615 -79.598253) (xy 255.053973 -79.565802) (xy 255.103573 -79.540301)
			(xy 255.156357 -79.522294) (xy 255.2112 -79.512164) (xy 255.266934 -79.510127) (xy 255.322371 -79.516227)
			(xy 255.376328 -79.530333) (xy 255.427657 -79.552145) (xy 255.475263 -79.581199) (xy 255.518131 -79.616874)
			(xy 255.555348 -79.658411) (xy 255.586121 -79.704924) (xy 255.609793 -79.755421) (xy 255.625861 -79.808828)
			(xy 255.633981 -79.864004) (xy 255.63449 -79.89189) (xy 255.633981 -79.919776) (xy 255.625861 -79.974952)
			(xy 255.609793 -80.028359) (xy 255.586121 -80.078856) (xy 255.555348 -80.125369) (xy 255.518131 -80.166906)
			(xy 255.475263 -80.202581) (xy 255.427657 -80.231635) (xy 255.376328 -80.253447) (xy 255.322371 -80.267553)
			(xy 255.266934 -80.273653) (xy 255.2112 -80.271616) (xy 255.156357 -80.261486) (xy 255.103573 -80.243479)
			(xy 255.053973 -80.217978) (xy 255.008615 -80.185527) (xy 254.968466 -80.146818) (xy 254.93438 -80.102675)
			(xy 254.907084 -80.05404) (xy 254.887161 -80.001949) (xy 254.875035 -79.947512) (xy 254.870964 -79.89189)
			(xy 251.67971 -79.89189) (xy 251.67971 -81.61655) (xy 251.902214 -81.61655) (xy 251.902727 -81.587087)
			(xy 251.911807 -81.528864) (xy 251.929729 -81.472729) (xy 251.956067 -81.420015) (xy 251.990194 -81.371977)
			(xy 252.0313 -81.329755) (xy 252.078407 -81.294353) (xy 252.104144 -81.28) (xy 252.116539 -81.272837)
			(xy 252.137076 -81.252913) (xy 252.15128 -81.228074) (xy 252.158035 -81.200269) (xy 252.156811 -81.171682)
			(xy 252.147704 -81.144556) (xy 252.13143 -81.121021) (xy 252.120654 -81.111598) (xy 252.099177 -81.093401)
			(xy 252.061302 -81.051757) (xy 252.029965 -81.004995) (xy 252.005847 -80.954132) (xy 251.989474 -80.900275)
			(xy 251.981201 -80.844596) (xy 251.9807 -80.81645) (xy 251.981186 -80.789199) (xy 251.988942 -80.735251)
			(xy 252.004297 -80.682956) (xy 252.026939 -80.633379) (xy 252.056405 -80.587529) (xy 252.092096 -80.546338)
			(xy 252.133287 -80.510647) (xy 252.179137 -80.481181) (xy 252.228714 -80.458539) (xy 252.281009 -80.443184)
			(xy 252.334957 -80.435428) (xy 252.389459 -80.435428) (xy 252.443407 -80.443184) (xy 252.495702 -80.458539)
			(xy 252.545279 -80.481181) (xy 252.591129 -80.510647) (xy 252.63232 -80.546338) (xy 252.668011 -80.587529)
			(xy 252.697477 -80.633379) (xy 252.720119 -80.682956) (xy 252.735474 -80.735251) (xy 252.740976 -80.773524)
			(xy 253.898652 -80.773524) (xy 253.902723 -80.717902) (xy 253.914849 -80.663465) (xy 253.934772 -80.611374)
			(xy 253.962068 -80.562739) (xy 253.996154 -80.518596) (xy 254.036303 -80.479887) (xy 254.081661 -80.447436)
			(xy 254.131261 -80.421935) (xy 254.184045 -80.403928) (xy 254.238888 -80.393798) (xy 254.294622 -80.391761)
			(xy 254.350059 -80.397861) (xy 254.404016 -80.411967) (xy 254.455345 -80.433779) (xy 254.502951 -80.462833)
			(xy 254.545819 -80.498508) (xy 254.583036 -80.540045) (xy 254.613809 -80.586558) (xy 254.637481 -80.637055)
			(xy 254.653549 -80.690462) (xy 254.661669 -80.745638) (xy 254.662178 -80.773524) (xy 254.661974 -80.7847)
			(xy 254.772158 -80.7847) (xy 254.776229 -80.729078) (xy 254.788355 -80.674641) (xy 254.808278 -80.62255)
			(xy 254.835574 -80.573915) (xy 254.86966 -80.529772) (xy 254.909809 -80.491063) (xy 254.955167 -80.458612)
			(xy 255.004767 -80.433111) (xy 255.057551 -80.415104) (xy 255.112394 -80.404974) (xy 255.168128 -80.402937)
			(xy 255.223565 -80.409037) (xy 255.277522 -80.423143) (xy 255.328851 -80.444955) (xy 255.376457 -80.474009)
			(xy 255.419325 -80.509684) (xy 255.456542 -80.551221) (xy 255.487315 -80.597734) (xy 255.510987 -80.648231)
			(xy 255.527055 -80.701638) (xy 255.535175 -80.756814) (xy 255.535684 -80.7847) (xy 255.535175 -80.812586)
			(xy 255.527055 -80.867762) (xy 255.510987 -80.921169) (xy 255.487315 -80.971666) (xy 255.456542 -81.018179)
			(xy 255.419325 -81.059716) (xy 255.376457 -81.095391) (xy 255.328851 -81.124445) (xy 255.277522 -81.146257)
			(xy 255.223565 -81.160363) (xy 255.168128 -81.166463) (xy 255.112394 -81.164426) (xy 255.057551 -81.154296)
			(xy 255.004767 -81.136289) (xy 254.955167 -81.110788) (xy 254.909809 -81.078337) (xy 254.86966 -81.039628)
			(xy 254.835574 -80.995485) (xy 254.808278 -80.94685) (xy 254.788355 -80.894759) (xy 254.776229 -80.840322)
			(xy 254.772158 -80.7847) (xy 254.661974 -80.7847) (xy 254.661669 -80.80141) (xy 254.653549 -80.856586)
			(xy 254.637481 -80.909993) (xy 254.613809 -80.96049) (xy 254.583036 -81.007003) (xy 254.545819 -81.04854)
			(xy 254.502951 -81.084215) (xy 254.455345 -81.113269) (xy 254.404016 -81.135081) (xy 254.350059 -81.149187)
			(xy 254.294622 -81.155287) (xy 254.238888 -81.15325) (xy 254.184045 -81.14312) (xy 254.131261 -81.125113)
			(xy 254.081661 -81.099612) (xy 254.036303 -81.067161) (xy 253.996154 -81.028452) (xy 253.962068 -80.984309)
			(xy 253.934772 -80.935674) (xy 253.914849 -80.883583) (xy 253.902723 -80.829146) (xy 253.898652 -80.773524)
			(xy 252.740976 -80.773524) (xy 252.74323 -80.789199) (xy 252.743716 -80.81645) (xy 252.743188 -80.845912)
			(xy 252.734108 -80.904134) (xy 252.716187 -80.960268) (xy 252.689852 -81.012981) (xy 252.655727 -81.061019)
			(xy 252.614625 -81.103242) (xy 252.567521 -81.138646) (xy 252.541786 -81.153) (xy 252.529391 -81.160165)
			(xy 252.508849 -81.180086) (xy 252.494641 -81.204925) (xy 252.487884 -81.232731) (xy 252.489109 -81.26132)
			(xy 252.498218 -81.288447) (xy 252.514497 -81.31198) (xy 252.525276 -81.321402) (xy 252.546759 -81.339592)
			(xy 252.584632 -81.381238) (xy 252.615968 -81.428002) (xy 252.640084 -81.478866) (xy 252.656456 -81.532724)
			(xy 252.664729 -81.588404) (xy 252.66523 -81.61655) (xy 252.664744 -81.643801) (xy 252.656988 -81.697749)
			(xy 252.641633 -81.750044) (xy 252.618991 -81.799621) (xy 252.589525 -81.845471) (xy 252.586722 -81.848706)
			(xy 253.2794 -81.848706) (xy 253.283471 -81.793084) (xy 253.295597 -81.738647) (xy 253.31552 -81.686556)
			(xy 253.342816 -81.637921) (xy 253.376902 -81.593778) (xy 253.417051 -81.555069) (xy 253.462409 -81.522618)
			(xy 253.512009 -81.497117) (xy 253.564793 -81.47911) (xy 253.619636 -81.46898) (xy 253.67537 -81.466943)
			(xy 253.730807 -81.473043) (xy 253.784764 -81.487149) (xy 253.836093 -81.508961) (xy 253.883699 -81.538015)
			(xy 253.913669 -81.562956) (xy 264.230864 -81.562956) (xy 264.234935 -81.507334) (xy 264.247061 -81.452897)
			(xy 264.266984 -81.400806) (xy 264.29428 -81.352171) (xy 264.328366 -81.308028) (xy 264.368515 -81.269319)
			(xy 264.413873 -81.236868) (xy 264.463473 -81.211367) (xy 264.516257 -81.19336) (xy 264.5711 -81.18323)
			(xy 264.626834 -81.181193) (xy 264.682271 -81.187293) (xy 264.736228 -81.201399) (xy 264.787557 -81.223211)
			(xy 264.835163 -81.252265) (xy 264.878031 -81.28794) (xy 264.915248 -81.329477) (xy 264.946021 -81.37599)
			(xy 264.969693 -81.426487) (xy 264.985761 -81.479894) (xy 264.993881 -81.53507) (xy 264.99439 -81.562956)
			(xy 264.993881 -81.590842) (xy 264.985761 -81.646018) (xy 264.969693 -81.699425) (xy 264.946021 -81.749922)
			(xy 264.915248 -81.796435) (xy 264.878031 -81.837972) (xy 264.835163 -81.873647) (xy 264.787557 -81.902701)
			(xy 264.736228 -81.924513) (xy 264.682271 -81.938619) (xy 264.626834 -81.944719) (xy 264.5711 -81.942682)
			(xy 264.516257 -81.932552) (xy 264.463473 -81.914545) (xy 264.413873 -81.889044) (xy 264.368515 -81.856593)
			(xy 264.328366 -81.817884) (xy 264.29428 -81.773741) (xy 264.266984 -81.725106) (xy 264.247061 -81.673015)
			(xy 264.234935 -81.618578) (xy 264.230864 -81.562956) (xy 253.913669 -81.562956) (xy 253.926567 -81.57369)
			(xy 253.963784 -81.615227) (xy 253.994557 -81.66174) (xy 254.018229 -81.712237) (xy 254.034297 -81.765644)
			(xy 254.042417 -81.82082) (xy 254.042926 -81.848706) (xy 254.042417 -81.876592) (xy 254.034297 -81.931768)
			(xy 254.018229 -81.985175) (xy 253.994557 -82.035672) (xy 253.980792 -82.056478) (xy 254.425956 -82.056478)
			(xy 254.430027 -82.000856) (xy 254.442153 -81.946419) (xy 254.462076 -81.894328) (xy 254.489372 -81.845693)
			(xy 254.523458 -81.80155) (xy 254.563607 -81.762841) (xy 254.608965 -81.73039) (xy 254.658565 -81.704889)
			(xy 254.711349 -81.686882) (xy 254.766192 -81.676752) (xy 254.821926 -81.674715) (xy 254.877363 -81.680815)
			(xy 254.93132 -81.694921) (xy 254.982649 -81.716733) (xy 255.030255 -81.745787) (xy 255.073123 -81.781462)
			(xy 255.11034 -81.822999) (xy 255.141113 -81.869512) (xy 255.164785 -81.920009) (xy 255.180853 -81.973416)
			(xy 255.188973 -82.028592) (xy 255.189482 -82.056478) (xy 255.188973 -82.084364) (xy 255.181676 -82.133948)
			(xy 257.009898 -82.133948) (xy 257.013969 -82.078326) (xy 257.026095 -82.023889) (xy 257.046018 -81.971798)
			(xy 257.073314 -81.923163) (xy 257.1074 -81.87902) (xy 257.147549 -81.840311) (xy 257.192907 -81.80786)
			(xy 257.242507 -81.782359) (xy 257.295291 -81.764352) (xy 257.350134 -81.754222) (xy 257.405868 -81.752185)
			(xy 257.461305 -81.758285) (xy 257.515262 -81.772391) (xy 257.566591 -81.794203) (xy 257.614197 -81.823257)
			(xy 257.657065 -81.858932) (xy 257.694282 -81.900469) (xy 257.725055 -81.946982) (xy 257.748727 -81.997479)
			(xy 257.752875 -82.011266) (xy 259.066536 -82.011266) (xy 259.070607 -81.955644) (xy 259.082733 -81.901207)
			(xy 259.102656 -81.849116) (xy 259.129952 -81.800481) (xy 259.164038 -81.756338) (xy 259.204187 -81.717629)
			(xy 259.249545 -81.685178) (xy 259.299145 -81.659677) (xy 259.351929 -81.64167) (xy 259.406772 -81.63154)
			(xy 259.462506 -81.629503) (xy 259.517943 -81.635603) (xy 259.5719 -81.649709) (xy 259.623229 -81.671521)
			(xy 259.670835 -81.700575) (xy 259.713703 -81.73625) (xy 259.75092 -81.777787) (xy 259.781693 -81.8243)
			(xy 259.805365 -81.874797) (xy 259.821433 -81.928204) (xy 259.829553 -81.98338) (xy 259.830062 -82.011266)
			(xy 259.829937 -82.018124) (xy 260.23011 -82.018124) (xy 260.234181 -81.962502) (xy 260.246307 -81.908065)
			(xy 260.26623 -81.855974) (xy 260.293526 -81.807339) (xy 260.327612 -81.763196) (xy 260.367761 -81.724487)
			(xy 260.413119 -81.692036) (xy 260.462719 -81.666535) (xy 260.515503 -81.648528) (xy 260.570346 -81.638398)
			(xy 260.62608 -81.636361) (xy 260.681517 -81.642461) (xy 260.735474 -81.656567) (xy 260.786803 -81.678379)
			(xy 260.834409 -81.707433) (xy 260.877277 -81.743108) (xy 260.914494 -81.784645) (xy 260.945267 -81.831158)
			(xy 260.968939 -81.881655) (xy 260.985007 -81.935062) (xy 260.993127 -81.990238) (xy 260.993636 -82.018124)
			(xy 260.993127 -82.04601) (xy 260.985007 -82.101186) (xy 260.968939 -82.154593) (xy 260.945267 -82.20509)
			(xy 260.914494 -82.251603) (xy 260.877277 -82.29314) (xy 260.834409 -82.328815) (xy 260.786803 -82.357869)
			(xy 260.735474 -82.379681) (xy 260.681517 -82.393787) (xy 260.62608 -82.399887) (xy 260.570346 -82.39785)
			(xy 260.515503 -82.38772) (xy 260.462719 -82.369713) (xy 260.413119 -82.344212) (xy 260.367761 -82.311761)
			(xy 260.327612 -82.273052) (xy 260.293526 -82.228909) (xy 260.26623 -82.180274) (xy 260.246307 -82.128183)
			(xy 260.234181 -82.073746) (xy 260.23011 -82.018124) (xy 259.829937 -82.018124) (xy 259.829553 -82.039152)
			(xy 259.821433 -82.094328) (xy 259.805365 -82.147735) (xy 259.781693 -82.198232) (xy 259.75092 -82.244745)
			(xy 259.713703 -82.286282) (xy 259.670835 -82.321957) (xy 259.623229 -82.351011) (xy 259.5719 -82.372823)
			(xy 259.517943 -82.386929) (xy 259.462506 -82.393029) (xy 259.406772 -82.390992) (xy 259.351929 -82.380862)
			(xy 259.299145 -82.362855) (xy 259.249545 -82.337354) (xy 259.204187 -82.304903) (xy 259.164038 -82.266194)
			(xy 259.129952 -82.222051) (xy 259.102656 -82.173416) (xy 259.082733 -82.121325) (xy 259.070607 -82.066888)
			(xy 259.066536 -82.011266) (xy 257.752875 -82.011266) (xy 257.764795 -82.050886) (xy 257.772915 -82.106062)
			(xy 257.773424 -82.133948) (xy 257.772915 -82.161834) (xy 257.764795 -82.21701) (xy 257.748727 -82.270417)
			(xy 257.725055 -82.320914) (xy 257.694282 -82.367427) (xy 257.657065 -82.408964) (xy 257.614197 -82.444639)
			(xy 257.566591 -82.473693) (xy 257.515262 -82.495505) (xy 257.461305 -82.509611) (xy 257.405868 -82.515711)
			(xy 257.350134 -82.513674) (xy 257.295291 -82.503544) (xy 257.242507 -82.485537) (xy 257.192907 -82.460036)
			(xy 257.147549 -82.427585) (xy 257.1074 -82.388876) (xy 257.073314 -82.344733) (xy 257.046018 -82.296098)
			(xy 257.026095 -82.244007) (xy 257.013969 -82.18957) (xy 257.009898 -82.133948) (xy 255.181676 -82.133948)
			(xy 255.180853 -82.13954) (xy 255.164785 -82.192947) (xy 255.141113 -82.243444) (xy 255.11034 -82.289957)
			(xy 255.073123 -82.331494) (xy 255.030255 -82.367169) (xy 254.982649 -82.396223) (xy 254.93132 -82.418035)
			(xy 254.877363 -82.432141) (xy 254.821926 -82.438241) (xy 254.766192 -82.436204) (xy 254.711349 -82.426074)
			(xy 254.658565 -82.408067) (xy 254.608965 -82.382566) (xy 254.563607 -82.350115) (xy 254.523458 -82.311406)
			(xy 254.489372 -82.267263) (xy 254.462076 -82.218628) (xy 254.442153 -82.166537) (xy 254.430027 -82.1121)
			(xy 254.425956 -82.056478) (xy 253.980792 -82.056478) (xy 253.963784 -82.082185) (xy 253.926567 -82.123722)
			(xy 253.883699 -82.159397) (xy 253.836093 -82.188451) (xy 253.784764 -82.210263) (xy 253.730807 -82.224369)
			(xy 253.67537 -82.230469) (xy 253.619636 -82.228432) (xy 253.564793 -82.218302) (xy 253.512009 -82.200295)
			(xy 253.462409 -82.174794) (xy 253.417051 -82.142343) (xy 253.376902 -82.103634) (xy 253.342816 -82.059491)
			(xy 253.31552 -82.010856) (xy 253.295597 -81.958765) (xy 253.283471 -81.904328) (xy 253.2794 -81.848706)
			(xy 252.586722 -81.848706) (xy 252.553834 -81.886662) (xy 252.512643 -81.922353) (xy 252.466793 -81.951819)
			(xy 252.417216 -81.974461) (xy 252.364921 -81.989816) (xy 252.310973 -81.997572) (xy 252.256471 -81.997572)
			(xy 252.202523 -81.989816) (xy 252.150228 -81.974461) (xy 252.100651 -81.951819) (xy 252.054801 -81.922353)
			(xy 252.01361 -81.886662) (xy 251.977919 -81.845471) (xy 251.948453 -81.799621) (xy 251.925811 -81.750044)
			(xy 251.910456 -81.697749) (xy 251.9027 -81.643801) (xy 251.902214 -81.61655) (xy 251.67971 -81.61655)
			(xy 251.67971 -82.422746) (xy 251.679279 -82.432813) (xy 251.671554 -82.451406) (xy 251.664724 -82.458814)
			(xy 251.344684 -82.778854) (xy 261.582408 -82.778854) (xy 261.58293 -82.750012) (xy 261.591615 -82.692986)
			(xy 261.608779 -82.637915) (xy 261.634032 -82.586053) (xy 261.666799 -82.53858) (xy 261.706335 -82.496576)
			(xy 261.728712 -82.478372) (xy 261.737484 -82.47082) (xy 261.747661 -82.450054) (xy 261.74827 -82.438494)
			(xy 261.74827 -82.35823) (xy 261.747693 -82.346663) (xy 261.737504 -82.325891) (xy 261.728712 -82.318352)
			(xy 261.706325 -82.300159) (xy 261.666787 -82.258155) (xy 261.634019 -82.210681) (xy 261.608768 -82.158816)
			(xy 261.59161 -82.103742) (xy 261.582934 -82.046713) (xy 261.582408 -82.01787) (xy 261.582894 -81.990619)
			(xy 261.59065 -81.936671) (xy 261.606005 -81.884376) (xy 261.628647 -81.834799) (xy 261.658113 -81.788949)
			(xy 261.693804 -81.747758) (xy 261.734995 -81.712067) (xy 261.780845 -81.682601) (xy 261.830422 -81.659959)
			(xy 261.882717 -81.644604) (xy 261.936665 -81.636848) (xy 261.991167 -81.636848) (xy 262.045115 -81.644604)
			(xy 262.09741 -81.659959) (xy 262.146987 -81.682601) (xy 262.192837 -81.712067) (xy 262.234028 -81.747758)
			(xy 262.269719 -81.788949) (xy 262.299185 -81.834799) (xy 262.321827 -81.884376) (xy 262.337182 -81.936671)
			(xy 262.344938 -81.990619) (xy 262.345424 -82.01787) (xy 262.344907 -82.046712) (xy 262.33622 -82.103738)
			(xy 262.319054 -82.158808) (xy 262.2938 -82.21067) (xy 262.261032 -82.258143) (xy 262.221497 -82.300147)
			(xy 262.19912 -82.318352) (xy 262.190371 -82.325925) (xy 262.180184 -82.346676) (xy 262.179562 -82.35823)
			(xy 262.179562 -82.438494) (xy 262.180115 -82.450065) (xy 262.19032 -82.470837) (xy 262.19912 -82.478372)
			(xy 262.221525 -82.496544) (xy 262.261061 -82.538553) (xy 262.293825 -82.586032) (xy 262.319073 -82.637901)
			(xy 262.336228 -82.692979) (xy 262.3449 -82.75001) (xy 262.345424 -82.778854) (xy 262.344908 -82.808427)
			(xy 262.335786 -82.866866) (xy 262.317753 -82.923197) (xy 262.291242 -82.976069) (xy 262.256887 -83.024216)
			(xy 262.215513 -83.066483) (xy 262.168111 -83.101857) (xy 262.142224 -83.116166) (xy 262.13424 -83.120863)
			(xy 262.122031 -83.134768) (xy 262.115606 -83.152122) (xy 262.1153 -83.161378) (xy 262.115808 -83.265518)
			(xy 262.130286 -83.289394) (xy 262.142732 -83.295998) (xy 262.165525 -83.308464) (xy 262.207872 -83.338555)
			(xy 262.245744 -83.374115) (xy 262.278439 -83.414485) (xy 262.305353 -83.458919) (xy 262.325988 -83.506594)
			(xy 262.339961 -83.556629) (xy 262.347015 -83.608097) (xy 262.347456 -83.634072) (xy 262.34697 -83.661323)
			(xy 262.339214 -83.715271) (xy 262.323859 -83.767566) (xy 262.301217 -83.817143) (xy 262.271751 -83.862993)
			(xy 262.23606 -83.904184) (xy 262.194869 -83.939875) (xy 262.149019 -83.969341) (xy 262.099442 -83.991983)
			(xy 262.047147 -84.007338) (xy 261.993199 -84.015094) (xy 261.938697 -84.015094) (xy 261.884749 -84.007338)
			(xy 261.832454 -83.991983) (xy 261.782877 -83.969341) (xy 261.737027 -83.939875) (xy 261.695836 -83.904184)
			(xy 261.660145 -83.862993) (xy 261.630679 -83.817143) (xy 261.608037 -83.767566) (xy 261.592682 -83.715271)
			(xy 261.584926 -83.661323) (xy 261.58444 -83.634072) (xy 261.584996 -83.6045) (xy 261.594113 -83.546064)
			(xy 261.612141 -83.489736) (xy 261.638646 -83.436864) (xy 261.672993 -83.388717) (xy 261.714361 -83.346449)
			(xy 261.761756 -83.311071) (xy 261.78764 -83.29676) (xy 261.795649 -83.2921) (xy 261.807859 -83.278181)
			(xy 261.814269 -83.26081) (xy 261.814564 -83.251548) (xy 261.814056 -83.147408) (xy 261.799578 -83.123532)
			(xy 261.787132 -83.116928) (xy 261.764299 -83.104531) (xy 261.721953 -83.07443) (xy 261.684083 -83.038859)
			(xy 261.651392 -82.998479) (xy 261.624483 -82.954035) (xy 261.603855 -82.90635) (xy 261.589889 -82.856307)
			(xy 261.582844 -82.804832) (xy 261.582408 -82.778854) (xy 251.344684 -82.778854) (xy 250.950476 -83.173062)
			(xy 257.00304 -83.173062) (xy 257.007111 -83.11744) (xy 257.019237 -83.063003) (xy 257.03916 -83.010912)
			(xy 257.066456 -82.962277) (xy 257.100542 -82.918134) (xy 257.140691 -82.879425) (xy 257.186049 -82.846974)
			(xy 257.235649 -82.821473) (xy 257.288433 -82.803466) (xy 257.343276 -82.793336) (xy 257.39901 -82.791299)
			(xy 257.454447 -82.797399) (xy 257.508404 -82.811505) (xy 257.559733 -82.833317) (xy 257.607339 -82.862371)
			(xy 257.650207 -82.898046) (xy 257.687424 -82.939583) (xy 257.718197 -82.986096) (xy 257.741869 -83.036593)
			(xy 257.757937 -83.09) (xy 257.766057 -83.145176) (xy 257.766566 -83.173062) (xy 257.766057 -83.200948)
			(xy 257.757937 -83.256124) (xy 257.741869 -83.309531) (xy 257.718197 -83.360028) (xy 257.687424 -83.406541)
			(xy 257.650207 -83.448078) (xy 257.607339 -83.483753) (xy 257.559733 -83.512807) (xy 257.508404 -83.534619)
			(xy 257.454447 -83.548725) (xy 257.39901 -83.554825) (xy 257.343276 -83.552788) (xy 257.288433 -83.542658)
			(xy 257.235649 -83.524651) (xy 257.186049 -83.49915) (xy 257.140691 -83.466699) (xy 257.100542 -83.42799)
			(xy 257.066456 -83.383847) (xy 257.03916 -83.335212) (xy 257.019237 -83.283121) (xy 257.007111 -83.228684)
			(xy 257.00304 -83.173062) (xy 250.950476 -83.173062) (xy 250.562364 -83.561174) (xy 250.554965 -83.568018)
			(xy 250.536366 -83.575743) (xy 250.526296 -83.57616) (xy 248.589292 -83.57616) (xy 248.579864 -83.576539)
			(xy 248.562286 -83.583363) (xy 248.548367 -83.596082) (xy 248.543826 -83.604354) (xy 248.531442 -83.628292)
			(xy 248.501048 -83.672801) (xy 248.464788 -83.712674) (xy 248.423357 -83.747146) (xy 248.377555 -83.775552)
			(xy 248.328262 -83.797345) (xy 248.276427 -83.812107) (xy 248.223048 -83.819552) (xy 248.1961 -83.82)
			(xy 248.167958 -83.819499) (xy 248.112265 -83.811371) (xy 248.05833 -83.795286) (xy 248.007282 -83.77158)
			(xy 247.960194 -83.740751) (xy 247.938798 -83.722464) (xy 247.931817 -83.71674) (xy 247.915016 -83.710164)
			(xy 247.896978 -83.709808) (xy 247.879932 -83.715716) (xy 247.872758 -83.721194) (xy 247.869202 -83.724496)
			(xy 247.749314 -83.844384) (xy 247.746608 -83.847235) (xy 247.742015 -83.853613) (xy 247.74017 -83.857084)
			(xy 247.737593 -83.862512) (xy 247.73478 -83.874192) (xy 247.734582 -83.880198) (xy 247.734582 -84.748116)
			(xy 253.089916 -84.748116) (xy 253.093987 -84.692494) (xy 253.106113 -84.638057) (xy 253.126036 -84.585966)
			(xy 253.153332 -84.537331) (xy 253.187418 -84.493188) (xy 253.227567 -84.454479) (xy 253.272925 -84.422028)
			(xy 253.322525 -84.396527) (xy 253.375309 -84.37852) (xy 253.430152 -84.36839) (xy 253.485886 -84.366353)
			(xy 253.541323 -84.372453) (xy 253.59528 -84.386559) (xy 253.646609 -84.408371) (xy 253.694215 -84.437425)
			(xy 253.714113 -84.453984) (xy 254.399286 -84.453984) (xy 254.403357 -84.398362) (xy 254.415483 -84.343925)
			(xy 254.435406 -84.291834) (xy 254.462702 -84.243199) (xy 254.496788 -84.199056) (xy 254.536937 -84.160347)
			(xy 254.582295 -84.127896) (xy 254.631895 -84.102395) (xy 254.684679 -84.084388) (xy 254.739522 -84.074258)
			(xy 254.795256 -84.072221) (xy 254.850693 -84.078321) (xy 254.90465 -84.092427) (xy 254.955979 -84.114239)
			(xy 255.003585 -84.143293) (xy 255.046453 -84.178968) (xy 255.08367 -84.220505) (xy 255.114443 -84.267018)
			(xy 255.138115 -84.317515) (xy 255.154183 -84.370922) (xy 255.162303 -84.426098) (xy 255.162812 -84.453984)
			(xy 255.162303 -84.48187) (xy 255.154183 -84.537046) (xy 255.138115 -84.590453) (xy 255.119454 -84.63026)
			(xy 257.000754 -84.63026) (xy 257.004825 -84.574638) (xy 257.016951 -84.520201) (xy 257.036874 -84.46811)
			(xy 257.06417 -84.419475) (xy 257.098256 -84.375332) (xy 257.138405 -84.336623) (xy 257.183763 -84.304172)
			(xy 257.233363 -84.278671) (xy 257.286147 -84.260664) (xy 257.34099 -84.250534) (xy 257.396724 -84.248497)
			(xy 257.452161 -84.254597) (xy 257.506118 -84.268703) (xy 257.557447 -84.290515) (xy 257.605053 -84.319569)
			(xy 257.647921 -84.355244) (xy 257.685138 -84.396781) (xy 257.715911 -84.443294) (xy 257.739583 -84.493791)
			(xy 257.755651 -84.547198) (xy 257.763771 -84.602374) (xy 257.76428 -84.63026) (xy 257.763771 -84.658146)
			(xy 257.755651 -84.713322) (xy 257.743884 -84.752434) (xy 261.58774 -84.752434) (xy 261.591811 -84.696812)
			(xy 261.603937 -84.642375) (xy 261.62386 -84.590284) (xy 261.651156 -84.541649) (xy 261.685242 -84.497506)
			(xy 261.725391 -84.458797) (xy 261.770749 -84.426346) (xy 261.820349 -84.400845) (xy 261.873133 -84.382838)
			(xy 261.927976 -84.372708) (xy 261.98371 -84.370671) (xy 262.039147 -84.376771) (xy 262.093104 -84.390877)
			(xy 262.144433 -84.412689) (xy 262.192039 -84.441743) (xy 262.234907 -84.477418) (xy 262.272124 -84.518955)
			(xy 262.302897 -84.565468) (xy 262.326569 -84.615965) (xy 262.342637 -84.669372) (xy 262.350757 -84.724548)
			(xy 262.351266 -84.752434) (xy 262.35115 -84.758784) (xy 264.526774 -84.758784) (xy 264.530845 -84.703162)
			(xy 264.542971 -84.648725) (xy 264.562894 -84.596634) (xy 264.59019 -84.547999) (xy 264.624276 -84.503856)
			(xy 264.664425 -84.465147) (xy 264.709783 -84.432696) (xy 264.759383 -84.407195) (xy 264.812167 -84.389188)
			(xy 264.86701 -84.379058) (xy 264.922744 -84.377021) (xy 264.978181 -84.383121) (xy 265.032138 -84.397227)
			(xy 265.083467 -84.419039) (xy 265.131073 -84.448093) (xy 265.173941 -84.483768) (xy 265.211158 -84.525305)
			(xy 265.241931 -84.571818) (xy 265.265603 -84.622315) (xy 265.281671 -84.675722) (xy 265.289791 -84.730898)
			(xy 265.2903 -84.758784) (xy 265.289791 -84.78667) (xy 265.281671 -84.841846) (xy 265.265603 -84.895253)
			(xy 265.241931 -84.94575) (xy 265.211158 -84.992263) (xy 265.173941 -85.0338) (xy 265.131073 -85.069475)
			(xy 265.083467 -85.098529) (xy 265.032138 -85.120341) (xy 264.978181 -85.134447) (xy 264.922744 -85.140547)
			(xy 264.86701 -85.13851) (xy 264.812167 -85.12838) (xy 264.759383 -85.110373) (xy 264.709783 -85.084872)
			(xy 264.664425 -85.052421) (xy 264.624276 -85.013712) (xy 264.59019 -84.969569) (xy 264.562894 -84.920934)
			(xy 264.542971 -84.868843) (xy 264.530845 -84.814406) (xy 264.526774 -84.758784) (xy 262.35115 -84.758784)
			(xy 262.350757 -84.78032) (xy 262.342637 -84.835496) (xy 262.326569 -84.888903) (xy 262.302897 -84.9394)
			(xy 262.272124 -84.985913) (xy 262.234907 -85.02745) (xy 262.192039 -85.063125) (xy 262.144433 -85.092179)
			(xy 262.093104 -85.113991) (xy 262.039147 -85.128097) (xy 261.98371 -85.134197) (xy 261.927976 -85.13216)
			(xy 261.873133 -85.12203) (xy 261.820349 -85.104023) (xy 261.770749 -85.078522) (xy 261.725391 -85.046071)
			(xy 261.685242 -85.007362) (xy 261.651156 -84.963219) (xy 261.62386 -84.914584) (xy 261.603937 -84.862493)
			(xy 261.591811 -84.808056) (xy 261.58774 -84.752434) (xy 257.743884 -84.752434) (xy 257.739583 -84.766729)
			(xy 257.715911 -84.817226) (xy 257.685138 -84.863739) (xy 257.647921 -84.905276) (xy 257.605053 -84.940951)
			(xy 257.557447 -84.970005) (xy 257.506118 -84.991817) (xy 257.452161 -85.005923) (xy 257.396724 -85.012023)
			(xy 257.34099 -85.009986) (xy 257.286147 -84.999856) (xy 257.233363 -84.981849) (xy 257.183763 -84.956348)
			(xy 257.138405 -84.923897) (xy 257.098256 -84.885188) (xy 257.06417 -84.841045) (xy 257.036874 -84.79241)
			(xy 257.016951 -84.740319) (xy 257.004825 -84.685882) (xy 257.000754 -84.63026) (xy 255.119454 -84.63026)
			(xy 255.114443 -84.64095) (xy 255.08367 -84.687463) (xy 255.046453 -84.729) (xy 255.003585 -84.764675)
			(xy 254.955979 -84.793729) (xy 254.90465 -84.815541) (xy 254.850693 -84.829647) (xy 254.795256 -84.835747)
			(xy 254.739522 -84.83371) (xy 254.684679 -84.82358) (xy 254.631895 -84.805573) (xy 254.582295 -84.780072)
			(xy 254.536937 -84.747621) (xy 254.496788 -84.708912) (xy 254.462702 -84.664769) (xy 254.435406 -84.616134)
			(xy 254.415483 -84.564043) (xy 254.403357 -84.509606) (xy 254.399286 -84.453984) (xy 253.714113 -84.453984)
			(xy 253.737083 -84.4731) (xy 253.7743 -84.514637) (xy 253.805073 -84.56115) (xy 253.828745 -84.611647)
			(xy 253.844813 -84.665054) (xy 253.852933 -84.72023) (xy 253.853442 -84.748116) (xy 253.852933 -84.776002)
			(xy 253.844813 -84.831178) (xy 253.828745 -84.884585) (xy 253.805073 -84.935082) (xy 253.7743 -84.981595)
			(xy 253.737083 -85.023132) (xy 253.694215 -85.058807) (xy 253.646609 -85.087861) (xy 253.59528 -85.109673)
			(xy 253.541323 -85.123779) (xy 253.485886 -85.129879) (xy 253.430152 -85.127842) (xy 253.375309 -85.117712)
			(xy 253.322525 -85.099705) (xy 253.272925 -85.074204) (xy 253.227567 -85.041753) (xy 253.187418 -85.003044)
			(xy 253.153332 -84.958901) (xy 253.126036 -84.910266) (xy 253.106113 -84.858175) (xy 253.093987 -84.803738)
			(xy 253.089916 -84.748116) (xy 247.734582 -84.748116) (xy 247.734582 -84.889594) (xy 247.736106 -84.90204)
			(xy 247.743472 -84.930996) (xy 247.744996 -84.943188) (xy 247.744996 -85.046312) (xy 247.745486 -85.056318)
			(xy 247.753148 -85.074807) (xy 247.7673 -85.088957) (xy 247.78579 -85.096615) (xy 247.795796 -85.097112)
			(xy 247.805843 -85.096688) (xy 247.8244 -85.088984) (xy 247.838583 -85.074751) (xy 247.842786 -85.065616)
			(xy 247.853944 -85.039683) (xy 247.882781 -84.991148) (xy 247.91845 -84.947388) (xy 247.960173 -84.909357)
			(xy 248.007041 -84.877884) (xy 248.058032 -84.853654) (xy 248.112035 -84.837197) (xy 248.167873 -84.82887)
			(xy 248.1961 -84.82838) (xy 248.223352 -84.828866) (xy 248.277302 -84.836623) (xy 248.329598 -84.851978)
			(xy 248.379177 -84.87462) (xy 248.425029 -84.904087) (xy 248.46622 -84.93978) (xy 248.501913 -84.980971)
			(xy 248.53138 -85.026823) (xy 248.554022 -85.076402) (xy 248.569377 -85.128698) (xy 248.577134 -85.182648)
			(xy 248.577134 -85.237152) (xy 248.569377 -85.291102) (xy 248.554022 -85.343398) (xy 248.53138 -85.392977)
			(xy 248.501913 -85.438829) (xy 248.46622 -85.48002) (xy 248.425029 -85.515713) (xy 248.379177 -85.54518)
			(xy 248.329598 -85.567822) (xy 248.277302 -85.583177) (xy 248.223352 -85.590934) (xy 248.1961 -85.591396)
			(xy 248.167873 -85.590887) (xy 248.112033 -85.582572) (xy 248.058028 -85.566122) (xy 248.007035 -85.541897)
			(xy 247.960166 -85.510425) (xy 247.918444 -85.472393) (xy 247.882779 -85.42863) (xy 247.853949 -85.380092)
			(xy 247.842786 -85.35416) (xy 247.836944 -85.339936) (xy 247.81129 -85.322664) (xy 247.795796 -85.322664)
			(xy 247.785786 -85.323152) (xy 247.76729 -85.330811) (xy 247.753129 -85.344963) (xy 247.745458 -85.363455)
			(xy 247.744996 -85.373464) (xy 247.744996 -85.476588) (xy 247.743472 -85.48878) (xy 247.736106 -85.517736)
			(xy 247.734582 -85.530182) (xy 247.734582 -85.840316) (xy 251.947172 -85.840316) (xy 251.947728 -85.810672)
			(xy 251.956892 -85.752096) (xy 251.975002 -85.695642) (xy 252.001622 -85.642666) (xy 252.036112 -85.594443)
			(xy 252.077644 -85.552133) (xy 252.101096 -85.533992) (xy 252.108347 -85.528089) (xy 252.118376 -85.512326)
			(xy 252.120654 -85.503258) (xy 252.135894 -85.427058) (xy 252.132592 -85.408516) (xy 252.127766 -85.400388)
			(xy 252.115023 -85.37821) (xy 252.094976 -85.331154) (xy 252.081413 -85.281835) (xy 252.074578 -85.231145)
			(xy 252.074172 -85.20557) (xy 252.074172 -85.205316) (xy 252.074658 -85.178065) (xy 252.082414 -85.124117)
			(xy 252.097769 -85.071822) (xy 252.120411 -85.022245) (xy 252.149877 -84.976395) (xy 252.185568 -84.935204)
			(xy 252.226759 -84.899513) (xy 252.272609 -84.870047) (xy 252.322186 -84.847405) (xy 252.374481 -84.83205)
			(xy 252.428429 -84.824294) (xy 252.482931 -84.824294) (xy 252.536879 -84.83205) (xy 252.589174 -84.847405)
			(xy 252.638751 -84.870047) (xy 252.684601 -84.899513) (xy 252.725792 -84.935204) (xy 252.761483 -84.976395)
			(xy 252.790949 -85.022245) (xy 252.813591 -85.071822) (xy 252.828946 -85.124117) (xy 252.836702 -85.178065)
			(xy 252.837188 -85.205316) (xy 252.836632 -85.23496) (xy 252.827465 -85.293534) (xy 252.809353 -85.349987)
			(xy 252.782733 -85.402963) (xy 252.748244 -85.451186) (xy 252.706715 -85.493498) (xy 252.683264 -85.51164)
			(xy 252.676028 -85.517559) (xy 252.665992 -85.53331) (xy 252.663706 -85.542374) (xy 252.648466 -85.618574)
			(xy 252.651768 -85.637116) (xy 252.656594 -85.645244) (xy 252.669306 -85.667439) (xy 252.689362 -85.714489)
			(xy 252.702934 -85.763802) (xy 252.709777 -85.814489) (xy 252.709923 -85.823552) (xy 261.571232 -85.823552)
			(xy 261.571718 -85.796301) (xy 261.579474 -85.742353) (xy 261.594829 -85.690058) (xy 261.617471 -85.640481)
			(xy 261.646937 -85.594631) (xy 261.682628 -85.55344) (xy 261.723819 -85.517749) (xy 261.769669 -85.488283)
			(xy 261.819246 -85.465641) (xy 261.871541 -85.450286) (xy 261.925489 -85.44253) (xy 261.979991 -85.44253)
			(xy 262.033939 -85.450286) (xy 262.086234 -85.465641) (xy 262.135811 -85.488283) (xy 262.181661 -85.517749)
			(xy 262.222852 -85.55344) (xy 262.258543 -85.594631) (xy 262.288009 -85.640481) (xy 262.310651 -85.690058)
			(xy 262.326006 -85.742353) (xy 262.333762 -85.796301) (xy 262.334248 -85.823552) (xy 262.333685 -85.852529)
			(xy 262.324931 -85.909818) (xy 262.307619 -85.965125) (xy 262.282144 -86.01718) (xy 262.249094 -86.064786)
			(xy 262.209227 -86.106848) (xy 262.186674 -86.12505) (xy 262.176201 -86.133708) (xy 262.159887 -86.155428)
			(xy 262.149882 -86.180682) (xy 262.146895 -86.207682) (xy 262.151139 -86.234513) (xy 262.162312 -86.259273)
			(xy 262.179621 -86.280207) (xy 262.190484 -86.288372) (xy 262.211606 -86.303746) (xy 262.249835 -86.339354)
			(xy 262.282849 -86.379843) (xy 262.306354 -86.41842) (xy 264.566906 -86.41842) (xy 264.570977 -86.362798)
			(xy 264.583103 -86.308361) (xy 264.603026 -86.25627) (xy 264.630322 -86.207635) (xy 264.664408 -86.163492)
			(xy 264.704557 -86.124783) (xy 264.749915 -86.092332) (xy 264.799515 -86.066831) (xy 264.852299 -86.048824)
			(xy 264.907142 -86.038694) (xy 264.962876 -86.036657) (xy 265.018313 -86.042757) (xy 265.07227 -86.056863)
			(xy 265.123599 -86.078675) (xy 265.171205 -86.107729) (xy 265.214073 -86.143404) (xy 265.25129 -86.184941)
			(xy 265.282063 -86.231454) (xy 265.305735 -86.281951) (xy 265.321803 -86.335358) (xy 265.326588 -86.367874)
			(xy 265.473178 -86.367874) (xy 265.477249 -86.312252) (xy 265.489375 -86.257815) (xy 265.509298 -86.205724)
			(xy 265.536594 -86.157089) (xy 265.57068 -86.112946) (xy 265.610829 -86.074237) (xy 265.656187 -86.041786)
			(xy 265.705787 -86.016285) (xy 265.758571 -85.998278) (xy 265.813414 -85.988148) (xy 265.869148 -85.986111)
			(xy 265.924585 -85.992211) (xy 265.978542 -86.006317) (xy 266.029871 -86.028129) (xy 266.077477 -86.057183)
			(xy 266.120345 -86.092858) (xy 266.157562 -86.134395) (xy 266.188335 -86.180908) (xy 266.212007 -86.231405)
			(xy 266.228075 -86.284812) (xy 266.236195 -86.339988) (xy 266.236704 -86.367874) (xy 266.236195 -86.39576)
			(xy 266.228075 -86.450936) (xy 266.212007 -86.504343) (xy 266.188335 -86.55484) (xy 266.157562 -86.601353)
			(xy 266.120345 -86.64289) (xy 266.077477 -86.678565) (xy 266.029871 -86.707619) (xy 265.978542 -86.729431)
			(xy 265.924585 -86.743537) (xy 265.869148 -86.749637) (xy 265.813414 -86.7476) (xy 265.758571 -86.73747)
			(xy 265.705787 -86.719463) (xy 265.656187 -86.693962) (xy 265.610829 -86.661511) (xy 265.57068 -86.622802)
			(xy 265.536594 -86.578659) (xy 265.509298 -86.530024) (xy 265.489375 -86.477933) (xy 265.477249 -86.423496)
			(xy 265.473178 -86.367874) (xy 265.326588 -86.367874) (xy 265.329923 -86.390534) (xy 265.330432 -86.41842)
			(xy 265.329923 -86.446306) (xy 265.321803 -86.501482) (xy 265.305735 -86.554889) (xy 265.282063 -86.605386)
			(xy 265.25129 -86.651899) (xy 265.214073 -86.693436) (xy 265.171205 -86.729111) (xy 265.123599 -86.758165)
			(xy 265.07227 -86.779977) (xy 265.018313 -86.794083) (xy 264.962876 -86.800183) (xy 264.907142 -86.798146)
			(xy 264.852299 -86.788016) (xy 264.799515 -86.770009) (xy 264.749915 -86.744508) (xy 264.704557 -86.712057)
			(xy 264.664408 -86.673348) (xy 264.630322 -86.629205) (xy 264.603026 -86.58057) (xy 264.583103 -86.528479)
			(xy 264.570977 -86.474042) (xy 264.566906 -86.41842) (xy 262.306354 -86.41842) (xy 262.310032 -86.424456)
			(xy 262.330876 -86.472361) (xy 262.34499 -86.522661) (xy 262.352111 -86.574417) (xy 262.352536 -86.600538)
			(xy 262.35205 -86.627789) (xy 262.344294 -86.681737) (xy 262.328939 -86.734032) (xy 262.306297 -86.783609)
			(xy 262.276831 -86.829459) (xy 262.24114 -86.87065) (xy 262.199949 -86.906341) (xy 262.154099 -86.935807)
			(xy 262.104522 -86.958449) (xy 262.052227 -86.973804) (xy 261.998279 -86.98156) (xy 261.943777 -86.98156)
			(xy 261.889829 -86.973804) (xy 261.837534 -86.958449) (xy 261.787957 -86.935807) (xy 261.742107 -86.906341)
			(xy 261.700916 -86.87065) (xy 261.665225 -86.829459) (xy 261.635759 -86.783609) (xy 261.613117 -86.734032)
			(xy 261.597762 -86.681737) (xy 261.590006 -86.627789) (xy 261.58952 -86.600538) (xy 261.590089 -86.571561)
			(xy 261.598843 -86.514273) (xy 261.616155 -86.458967) (xy 261.641628 -86.406912) (xy 261.674677 -86.359306)
			(xy 261.714542 -86.317242) (xy 261.737094 -86.29904) (xy 261.74757 -86.290388) (xy 261.763872 -86.268663)
			(xy 261.773869 -86.243409) (xy 261.776852 -86.216412) (xy 261.772609 -86.189584) (xy 261.761443 -86.164825)
			(xy 261.744142 -86.143887) (xy 261.733284 -86.135718) (xy 261.71215 -86.120359) (xy 261.673923 -86.084748)
			(xy 261.640911 -86.044256) (xy 261.61373 -85.99964) (xy 261.592888 -85.951733) (xy 261.578776 -85.901431)
			(xy 261.571657 -85.849674) (xy 261.571232 -85.823552) (xy 252.709923 -85.823552) (xy 252.710188 -85.840062)
			(xy 252.710188 -85.840316) (xy 252.709702 -85.867567) (xy 252.701946 -85.921515) (xy 252.686591 -85.97381)
			(xy 252.663949 -86.023387) (xy 252.634483 -86.069237) (xy 252.598792 -86.110428) (xy 252.557601 -86.146119)
			(xy 252.511751 -86.175585) (xy 252.462174 -86.198227) (xy 252.409879 -86.213582) (xy 252.355931 -86.221338)
			(xy 252.301429 -86.221338) (xy 252.247481 -86.213582) (xy 252.195186 -86.198227) (xy 252.145609 -86.175585)
			(xy 252.099759 -86.146119) (xy 252.058568 -86.110428) (xy 252.022877 -86.069237) (xy 251.993411 -86.023387)
			(xy 251.970769 -85.97381) (xy 251.955414 -85.921515) (xy 251.947658 -85.867567) (xy 251.947172 -85.840316)
			(xy 247.734582 -85.840316) (xy 247.734582 -86.336886) (xy 256.999484 -86.336886) (xy 257.003555 -86.281264)
			(xy 257.015681 -86.226827) (xy 257.035604 -86.174736) (xy 257.0629 -86.126101) (xy 257.096986 -86.081958)
			(xy 257.137135 -86.043249) (xy 257.182493 -86.010798) (xy 257.232093 -85.985297) (xy 257.284877 -85.96729)
			(xy 257.33972 -85.95716) (xy 257.395454 -85.955123) (xy 257.450891 -85.961223) (xy 257.504848 -85.975329)
			(xy 257.556177 -85.997141) (xy 257.603783 -86.026195) (xy 257.646651 -86.06187) (xy 257.683868 -86.103407)
			(xy 257.714641 -86.14992) (xy 257.738313 -86.200417) (xy 257.754381 -86.253824) (xy 257.762501 -86.309)
			(xy 257.76301 -86.336886) (xy 257.762501 -86.364772) (xy 257.754381 -86.419948) (xy 257.738313 -86.473355)
			(xy 257.714641 -86.523852) (xy 257.683868 -86.570365) (xy 257.657516 -86.599776) (xy 259.420612 -86.599776)
			(xy 259.424683 -86.544154) (xy 259.436809 -86.489717) (xy 259.456732 -86.437626) (xy 259.484028 -86.388991)
			(xy 259.518114 -86.344848) (xy 259.558263 -86.306139) (xy 259.603621 -86.273688) (xy 259.653221 -86.248187)
			(xy 259.706005 -86.23018) (xy 259.760848 -86.22005) (xy 259.816582 -86.218013) (xy 259.872019 -86.224113)
			(xy 259.925976 -86.238219) (xy 259.977305 -86.260031) (xy 260.024911 -86.289085) (xy 260.067779 -86.32476)
			(xy 260.104996 -86.366297) (xy 260.135769 -86.41281) (xy 260.159441 -86.463307) (xy 260.175509 -86.516714)
			(xy 260.183629 -86.57189) (xy 260.184138 -86.599776) (xy 260.183629 -86.627662) (xy 260.175509 -86.682838)
			(xy 260.159441 -86.736245) (xy 260.135769 -86.786742) (xy 260.104996 -86.833255) (xy 260.067779 -86.874792)
			(xy 260.024911 -86.910467) (xy 259.977305 -86.939521) (xy 259.925976 -86.961333) (xy 259.872019 -86.975439)
			(xy 259.816582 -86.981539) (xy 259.760848 -86.979502) (xy 259.706005 -86.969372) (xy 259.653221 -86.951365)
			(xy 259.603621 -86.925864) (xy 259.558263 -86.893413) (xy 259.518114 -86.854704) (xy 259.484028 -86.810561)
			(xy 259.456732 -86.761926) (xy 259.436809 -86.709835) (xy 259.424683 -86.655398) (xy 259.420612 -86.599776)
			(xy 257.657516 -86.599776) (xy 257.646651 -86.611902) (xy 257.603783 -86.647577) (xy 257.556177 -86.676631)
			(xy 257.504848 -86.698443) (xy 257.450891 -86.712549) (xy 257.395454 -86.718649) (xy 257.33972 -86.716612)
			(xy 257.284877 -86.706482) (xy 257.232093 -86.688475) (xy 257.182493 -86.662974) (xy 257.137135 -86.630523)
			(xy 257.096986 -86.591814) (xy 257.0629 -86.547671) (xy 257.035604 -86.499036) (xy 257.015681 -86.446945)
			(xy 257.003555 -86.392508) (xy 256.999484 -86.336886) (xy 247.734582 -86.336886) (xy 247.734582 -86.670134)
			(xy 247.736106 -86.68258) (xy 247.744996 -86.717378) (xy 247.746992 -86.724261) (xy 247.754218 -86.736629)
			(xy 247.75922 -86.741762) (xy 247.77319 -86.75497) (xy 247.78051 -86.761356) (xy 247.798537 -86.768549)
			(xy 247.808242 -86.76894) (xy 247.810274 -86.76894) (xy 247.837525 -86.769401) (xy 247.891472 -86.777154)
			(xy 247.911079 -86.78291) (xy 249.4821 -86.78291) (xy 249.486171 -86.727288) (xy 249.498297 -86.672851)
			(xy 249.51822 -86.62076) (xy 249.545516 -86.572125) (xy 249.579602 -86.527982) (xy 249.619751 -86.489273)
			(xy 249.665109 -86.456822) (xy 249.714709 -86.431321) (xy 249.767493 -86.413314) (xy 249.822336 -86.403184)
			(xy 249.87807 -86.401147) (xy 249.933507 -86.407247) (xy 249.987464 -86.421353) (xy 250.038793 -86.443165)
			(xy 250.086399 -86.472219) (xy 250.129267 -86.507894) (xy 250.166484 -86.549431) (xy 250.197257 -86.595944)
			(xy 250.220929 -86.646441) (xy 250.236997 -86.699848) (xy 250.245117 -86.755024) (xy 250.245626 -86.78291)
			(xy 250.245117 -86.810796) (xy 250.236997 -86.865972) (xy 250.220929 -86.919379) (xy 250.197257 -86.969876)
			(xy 250.166484 -87.016389) (xy 250.129267 -87.057926) (xy 250.086399 -87.093601) (xy 250.038793 -87.122655)
			(xy 249.987464 -87.144467) (xy 249.933507 -87.158573) (xy 249.87807 -87.164673) (xy 249.822336 -87.162636)
			(xy 249.767493 -87.152506) (xy 249.714709 -87.134499) (xy 249.665109 -87.108998) (xy 249.619751 -87.076547)
			(xy 249.579602 -87.037838) (xy 249.545516 -86.993695) (xy 249.51822 -86.94506) (xy 249.498297 -86.892969)
			(xy 249.486171 -86.838532) (xy 249.4821 -86.78291) (xy 247.911079 -86.78291) (xy 247.943766 -86.792506)
			(xy 247.993343 -86.815144) (xy 248.039194 -86.844608) (xy 248.080384 -86.880297) (xy 248.116076 -86.921485)
			(xy 248.145543 -86.967334) (xy 248.168185 -87.01691) (xy 248.18354 -87.069203) (xy 248.191297 -87.123149)
			(xy 248.191297 -87.177651) (xy 248.18354 -87.231597) (xy 248.168185 -87.28389) (xy 248.145543 -87.333466)
			(xy 248.140734 -87.340948) (xy 250.984002 -87.340948) (xy 250.988073 -87.285326) (xy 251.000199 -87.230889)
			(xy 251.020122 -87.178798) (xy 251.047418 -87.130163) (xy 251.081504 -87.08602) (xy 251.121653 -87.047311)
			(xy 251.167011 -87.01486) (xy 251.216611 -86.989359) (xy 251.269395 -86.971352) (xy 251.324238 -86.961222)
			(xy 251.379972 -86.959185) (xy 251.435409 -86.965285) (xy 251.489366 -86.979391) (xy 251.540695 -87.001203)
			(xy 251.588301 -87.030257) (xy 251.631169 -87.065932) (xy 251.668386 -87.107469) (xy 251.699159 -87.153982)
			(xy 251.722831 -87.204479) (xy 251.738899 -87.257886) (xy 251.747019 -87.313062) (xy 251.747528 -87.340948)
			(xy 251.747019 -87.368834) (xy 251.738899 -87.42401) (xy 251.722831 -87.477417) (xy 251.699159 -87.527914)
			(xy 251.668386 -87.574427) (xy 251.631169 -87.615964) (xy 251.588301 -87.651639) (xy 251.540695 -87.680693)
			(xy 251.489366 -87.702505) (xy 251.435409 -87.716611) (xy 251.405373 -87.719916) (xy 252.861062 -87.719916)
			(xy 252.865133 -87.664294) (xy 252.877259 -87.609857) (xy 252.897182 -87.557766) (xy 252.924478 -87.509131)
			(xy 252.958564 -87.464988) (xy 252.998713 -87.426279) (xy 253.044071 -87.393828) (xy 253.093671 -87.368327)
			(xy 253.146455 -87.35032) (xy 253.201298 -87.34019) (xy 253.257032 -87.338153) (xy 253.312469 -87.344253)
			(xy 253.366426 -87.358359) (xy 253.417755 -87.380171) (xy 253.465361 -87.409225) (xy 253.508229 -87.4449)
			(xy 253.545446 -87.486437) (xy 253.554051 -87.499444) (xy 256.099562 -87.499444) (xy 256.103633 -87.443822)
			(xy 256.115759 -87.389385) (xy 256.135682 -87.337294) (xy 256.162978 -87.288659) (xy 256.197064 -87.244516)
			(xy 256.237213 -87.205807) (xy 256.282571 -87.173356) (xy 256.332171 -87.147855) (xy 256.384955 -87.129848)
			(xy 256.439798 -87.119718) (xy 256.495532 -87.117681) (xy 256.550969 -87.123781) (xy 256.604926 -87.137887)
			(xy 256.656255 -87.159699) (xy 256.703861 -87.188753) (xy 256.746729 -87.224428) (xy 256.783946 -87.265965)
			(xy 256.814719 -87.312478) (xy 256.838391 -87.362975) (xy 256.854459 -87.416382) (xy 256.862579 -87.471558)
			(xy 256.863088 -87.499444) (xy 256.862579 -87.52733) (xy 256.854459 -87.582506) (xy 256.838391 -87.635913)
			(xy 256.814719 -87.68641) (xy 256.783946 -87.732923) (xy 256.746729 -87.77446) (xy 256.703861 -87.810135)
			(xy 256.656255 -87.839189) (xy 256.604926 -87.861001) (xy 256.550969 -87.875107) (xy 256.495532 -87.881207)
			(xy 256.439798 -87.87917) (xy 256.384955 -87.86904) (xy 256.332171 -87.851033) (xy 256.282571 -87.825532)
			(xy 256.237213 -87.793081) (xy 256.197064 -87.754372) (xy 256.162978 -87.710229) (xy 256.135682 -87.661594)
			(xy 256.115759 -87.609503) (xy 256.103633 -87.555066) (xy 256.099562 -87.499444) (xy 253.554051 -87.499444)
			(xy 253.576219 -87.53295) (xy 253.599891 -87.583447) (xy 253.615959 -87.636854) (xy 253.624079 -87.69203)
			(xy 253.624588 -87.719916) (xy 253.624079 -87.747802) (xy 253.615959 -87.802978) (xy 253.599891 -87.856385)
			(xy 253.576219 -87.906882) (xy 253.545446 -87.953395) (xy 253.508229 -87.994932) (xy 253.465361 -88.030607)
			(xy 253.417755 -88.059661) (xy 253.366426 -88.081473) (xy 253.336747 -88.089232) (xy 265.293346 -88.089232)
			(xy 265.297417 -88.03361) (xy 265.309543 -87.979173) (xy 265.329466 -87.927082) (xy 265.356762 -87.878447)
			(xy 265.390848 -87.834304) (xy 265.430997 -87.795595) (xy 265.476355 -87.763144) (xy 265.525955 -87.737643)
			(xy 265.578739 -87.719636) (xy 265.633582 -87.709506) (xy 265.689316 -87.707469) (xy 265.744753 -87.713569)
			(xy 265.79871 -87.727675) (xy 265.850039 -87.749487) (xy 265.897645 -87.778541) (xy 265.940513 -87.814216)
			(xy 265.97773 -87.855753) (xy 266.008503 -87.902266) (xy 266.032175 -87.952763) (xy 266.048243 -88.00617)
			(xy 266.056363 -88.061346) (xy 266.056872 -88.089232) (xy 266.056363 -88.117118) (xy 266.048243 -88.172294)
			(xy 266.032175 -88.225701) (xy 266.008503 -88.276198) (xy 265.97773 -88.322711) (xy 265.940513 -88.364248)
			(xy 265.897645 -88.399923) (xy 265.850039 -88.428977) (xy 265.79871 -88.450789) (xy 265.744753 -88.464895)
			(xy 265.689316 -88.470995) (xy 265.633582 -88.468958) (xy 265.578739 -88.458828) (xy 265.525955 -88.440821)
			(xy 265.476355 -88.41532) (xy 265.430997 -88.382869) (xy 265.390848 -88.34416) (xy 265.356762 -88.300017)
			(xy 265.329466 -88.251382) (xy 265.309543 -88.199291) (xy 265.297417 -88.144854) (xy 265.293346 -88.089232)
			(xy 253.336747 -88.089232) (xy 253.312469 -88.095579) (xy 253.257032 -88.101679) (xy 253.201298 -88.099642)
			(xy 253.146455 -88.089512) (xy 253.093671 -88.071505) (xy 253.044071 -88.046004) (xy 252.998713 -88.013553)
			(xy 252.958564 -87.974844) (xy 252.924478 -87.930701) (xy 252.897182 -87.882066) (xy 252.877259 -87.829975)
			(xy 252.865133 -87.775538) (xy 252.861062 -87.719916) (xy 251.405373 -87.719916) (xy 251.379972 -87.722711)
			(xy 251.324238 -87.720674) (xy 251.269395 -87.710544) (xy 251.216611 -87.692537) (xy 251.167011 -87.667036)
			(xy 251.121653 -87.634585) (xy 251.081504 -87.595876) (xy 251.047418 -87.551733) (xy 251.020122 -87.503098)
			(xy 251.000199 -87.451007) (xy 250.988073 -87.39657) (xy 250.984002 -87.340948) (xy 248.140734 -87.340948)
			(xy 248.116076 -87.379315) (xy 248.080384 -87.420503) (xy 248.039194 -87.456192) (xy 247.993343 -87.485656)
			(xy 247.943766 -87.508294) (xy 247.891472 -87.523646) (xy 247.837525 -87.531399) (xy 247.810274 -87.531956)
			(xy 247.807988 -87.531956) (xy 247.798382 -87.532377) (xy 247.780514 -87.53944) (xy 247.77319 -87.545672)
			(xy 247.759982 -87.558118) (xy 247.752717 -87.565618) (xy 247.744455 -87.584771) (xy 247.74398 -87.595202)
			(xy 247.74398 -87.605362) (xy 247.752362 -87.624666) (xy 247.77319 -87.644224) (xy 247.779434 -87.649646)
			(xy 247.794468 -87.656508) (xy 247.802654 -87.657686) (xy 247.805448 -87.65794) (xy 247.810274 -87.65794)
			(xy 247.837527 -87.658402) (xy 247.891478 -87.666156) (xy 247.943776 -87.68151) (xy 247.993357 -87.704152)
			(xy 248.03921 -87.73362) (xy 248.080401 -87.769314) (xy 248.116093 -87.810508) (xy 248.145559 -87.856363)
			(xy 248.168198 -87.905944) (xy 248.183549 -87.958244) (xy 248.1913 -88.012195) (xy 248.191782 -88.039448)
			(xy 248.191592 -88.049608) (xy 249.542806 -88.049608) (xy 249.546877 -87.993986) (xy 249.559003 -87.939549)
			(xy 249.578926 -87.887458) (xy 249.606222 -87.838823) (xy 249.640308 -87.79468) (xy 249.680457 -87.755971)
			(xy 249.725815 -87.72352) (xy 249.775415 -87.698019) (xy 249.828199 -87.680012) (xy 249.883042 -87.669882)
			(xy 249.938776 -87.667845) (xy 249.994213 -87.673945) (xy 250.04817 -87.688051) (xy 250.099499 -87.709863)
			(xy 250.147105 -87.738917) (xy 250.189973 -87.774592) (xy 250.22719 -87.816129) (xy 250.257963 -87.862642)
			(xy 250.281635 -87.913139) (xy 250.297703 -87.966546) (xy 250.305823 -88.021722) (xy 250.306332 -88.049608)
			(xy 250.305823 -88.077494) (xy 250.297703 -88.13267) (xy 250.281635 -88.186077) (xy 250.257963 -88.236574)
			(xy 250.22719 -88.283087) (xy 250.189973 -88.324624) (xy 250.147105 -88.360299) (xy 250.099499 -88.389353)
			(xy 250.04817 -88.411165) (xy 249.994213 -88.425271) (xy 249.938776 -88.431371) (xy 249.883042 -88.429334)
			(xy 249.828199 -88.419204) (xy 249.775415 -88.401197) (xy 249.725815 -88.375696) (xy 249.680457 -88.343245)
			(xy 249.640308 -88.304536) (xy 249.606222 -88.260393) (xy 249.578926 -88.211758) (xy 249.559003 -88.159667)
			(xy 249.546877 -88.10523) (xy 249.542806 -88.049608) (xy 248.191592 -88.049608) (xy 248.191242 -88.068397)
			(xy 248.182488 -88.125629) (xy 248.165188 -88.180882) (xy 248.13974 -88.232887) (xy 248.106727 -88.280451)
			(xy 248.066907 -88.322482) (xy 248.021195 -88.358014) (xy 247.970639 -88.386233) (xy 247.9164 -88.40649)
			(xy 247.859724 -88.418321) (xy 247.830848 -88.420448) (xy 247.821184 -88.421365) (xy 247.803565 -88.429475)
			(xy 247.796558 -88.436196) (xy 247.748552 -88.486996) (xy 247.742165 -88.494316) (xy 247.73497 -88.512342)
			(xy 247.734582 -88.522048) (xy 247.734582 -88.771984) (xy 250.730256 -88.771984) (xy 250.734327 -88.716362)
			(xy 250.746453 -88.661925) (xy 250.766376 -88.609834) (xy 250.793672 -88.561199) (xy 250.827758 -88.517056)
			(xy 250.867907 -88.478347) (xy 250.913265 -88.445896) (xy 250.962865 -88.420395) (xy 251.015649 -88.402388)
			(xy 251.070492 -88.392258) (xy 251.126226 -88.390221) (xy 251.181663 -88.396321) (xy 251.23562 -88.410427)
			(xy 251.286949 -88.432239) (xy 251.334555 -88.461293) (xy 251.377423 -88.496968) (xy 251.41464 -88.538505)
			(xy 251.445413 -88.585018) (xy 251.468523 -88.634316) (xy 253.724662 -88.634316) (xy 253.728733 -88.578694)
			(xy 253.740859 -88.524257) (xy 253.760782 -88.472166) (xy 253.788078 -88.423531) (xy 253.822164 -88.379388)
			(xy 253.862313 -88.340679) (xy 253.907671 -88.308228) (xy 253.957271 -88.282727) (xy 254.010055 -88.26472)
			(xy 254.064898 -88.25459) (xy 254.120632 -88.252553) (xy 254.176069 -88.258653) (xy 254.230026 -88.272759)
			(xy 254.281355 -88.294571) (xy 254.328961 -88.323625) (xy 254.371829 -88.3593) (xy 254.409046 -88.400837)
			(xy 254.439819 -88.44735) (xy 254.463491 -88.497847) (xy 254.479559 -88.551254) (xy 254.487679 -88.60643)
			(xy 254.488188 -88.634316) (xy 254.487679 -88.662202) (xy 254.479559 -88.717378) (xy 254.463491 -88.770785)
			(xy 254.439819 -88.821282) (xy 254.409046 -88.867795) (xy 254.371829 -88.909332) (xy 254.328961 -88.945007)
			(xy 254.281355 -88.974061) (xy 254.230026 -88.995873) (xy 254.176069 -89.009979) (xy 254.120632 -89.016079)
			(xy 254.064898 -89.014042) (xy 254.010055 -89.003912) (xy 253.957271 -88.985905) (xy 253.907671 -88.960404)
			(xy 253.862313 -88.927953) (xy 253.822164 -88.889244) (xy 253.788078 -88.845101) (xy 253.760782 -88.796466)
			(xy 253.740859 -88.744375) (xy 253.728733 -88.689938) (xy 253.724662 -88.634316) (xy 251.468523 -88.634316)
			(xy 251.469085 -88.635515) (xy 251.485153 -88.688922) (xy 251.493273 -88.744098) (xy 251.493782 -88.771984)
			(xy 251.493273 -88.79987) (xy 251.485153 -88.855046) (xy 251.469085 -88.908453) (xy 251.445413 -88.95895)
			(xy 251.41464 -89.005463) (xy 251.377423 -89.047) (xy 251.334555 -89.082675) (xy 251.286949 -89.111729)
			(xy 251.23562 -89.133541) (xy 251.181663 -89.147647) (xy 251.126226 -89.153747) (xy 251.070492 -89.15171)
			(xy 251.015649 -89.14158) (xy 250.962865 -89.123573) (xy 250.913265 -89.098072) (xy 250.867907 -89.065621)
			(xy 250.827758 -89.026912) (xy 250.793672 -88.982769) (xy 250.766376 -88.934134) (xy 250.746453 -88.882043)
			(xy 250.734327 -88.827606) (xy 250.730256 -88.771984) (xy 247.734582 -88.771984) (xy 247.734582 -89.463118)
			(xy 248.974608 -89.463118) (xy 248.978679 -89.407496) (xy 248.990805 -89.353059) (xy 249.010728 -89.300968)
			(xy 249.038024 -89.252333) (xy 249.07211 -89.20819) (xy 249.112259 -89.169481) (xy 249.157617 -89.13703)
			(xy 249.207217 -89.111529) (xy 249.260001 -89.093522) (xy 249.314844 -89.083392) (xy 249.370578 -89.081355)
			(xy 249.426015 -89.087455) (xy 249.479972 -89.101561) (xy 249.531301 -89.123373) (xy 249.578907 -89.152427)
			(xy 249.621775 -89.188102) (xy 249.658992 -89.229639) (xy 249.689765 -89.276152) (xy 249.713437 -89.326649)
			(xy 249.729505 -89.380056) (xy 249.737625 -89.435232) (xy 249.73774 -89.441528) (xy 252.608078 -89.441528)
			(xy 252.612149 -89.385906) (xy 252.624275 -89.331469) (xy 252.644198 -89.279378) (xy 252.671494 -89.230743)
			(xy 252.70558 -89.1866) (xy 252.745729 -89.147891) (xy 252.791087 -89.11544) (xy 252.840687 -89.089939)
			(xy 252.893471 -89.071932) (xy 252.948314 -89.061802) (xy 253.004048 -89.059765) (xy 253.059485 -89.065865)
			(xy 253.113442 -89.079971) (xy 253.151369 -89.096088) (xy 258.801106 -89.096088) (xy 258.805177 -89.040466)
			(xy 258.817303 -88.986029) (xy 258.837226 -88.933938) (xy 258.864522 -88.885303) (xy 258.898608 -88.84116)
			(xy 258.938757 -88.802451) (xy 258.984115 -88.77) (xy 259.033715 -88.744499) (xy 259.086499 -88.726492)
			(xy 259.141342 -88.716362) (xy 259.197076 -88.714325) (xy 259.252513 -88.720425) (xy 259.30647 -88.734531)
			(xy 259.357799 -88.756343) (xy 259.405405 -88.785397) (xy 259.448273 -88.821072) (xy 259.48549 -88.862609)
			(xy 259.516263 -88.909122) (xy 259.539935 -88.959619) (xy 259.554629 -89.008458) (xy 261.557768 -89.008458)
			(xy 261.561839 -88.952836) (xy 261.573965 -88.898399) (xy 261.593888 -88.846308) (xy 261.621184 -88.797673)
			(xy 261.65527 -88.75353) (xy 261.695419 -88.714821) (xy 261.740777 -88.68237) (xy 261.790377 -88.656869)
			(xy 261.843161 -88.638862) (xy 261.898004 -88.628732) (xy 261.953738 -88.626695) (xy 262.009175 -88.632795)
			(xy 262.063132 -88.646901) (xy 262.114461 -88.668713) (xy 262.162067 -88.697767) (xy 262.204935 -88.733442)
			(xy 262.242152 -88.774979) (xy 262.272925 -88.821492) (xy 262.296597 -88.871989) (xy 262.312665 -88.925396)
			(xy 262.320785 -88.980572) (xy 262.321294 -89.008458) (xy 262.320785 -89.036344) (xy 262.312665 -89.09152)
			(xy 262.296597 -89.144927) (xy 262.272925 -89.195424) (xy 262.242152 -89.241937) (xy 262.204935 -89.283474)
			(xy 262.162067 -89.319149) (xy 262.114461 -89.348203) (xy 262.063132 -89.370015) (xy 262.009175 -89.384121)
			(xy 261.953738 -89.390221) (xy 261.898004 -89.388184) (xy 261.843161 -89.378054) (xy 261.790377 -89.360047)
			(xy 261.740777 -89.334546) (xy 261.695419 -89.302095) (xy 261.65527 -89.263386) (xy 261.621184 -89.219243)
			(xy 261.593888 -89.170608) (xy 261.573965 -89.118517) (xy 261.561839 -89.06408) (xy 261.557768 -89.008458)
			(xy 259.554629 -89.008458) (xy 259.556003 -89.013026) (xy 259.564123 -89.068202) (xy 259.564632 -89.096088)
			(xy 259.564123 -89.123974) (xy 259.556003 -89.17915) (xy 259.539935 -89.232557) (xy 259.516263 -89.283054)
			(xy 259.48549 -89.329567) (xy 259.448273 -89.371104) (xy 259.405405 -89.406779) (xy 259.357799 -89.435833)
			(xy 259.30647 -89.457645) (xy 259.252513 -89.471751) (xy 259.197076 -89.477851) (xy 259.141342 -89.475814)
			(xy 259.086499 -89.465684) (xy 259.033715 -89.447677) (xy 258.984115 -89.422176) (xy 258.938757 -89.389725)
			(xy 258.898608 -89.351016) (xy 258.864522 -89.306873) (xy 258.837226 -89.258238) (xy 258.817303 -89.206147)
			(xy 258.805177 -89.15171) (xy 258.801106 -89.096088) (xy 253.151369 -89.096088) (xy 253.164771 -89.101783)
			(xy 253.212377 -89.130837) (xy 253.255245 -89.166512) (xy 253.292462 -89.208049) (xy 253.323235 -89.254562)
			(xy 253.346907 -89.305059) (xy 253.362975 -89.358466) (xy 253.371095 -89.413642) (xy 253.371604 -89.441528)
			(xy 253.371095 -89.469414) (xy 253.362975 -89.52459) (xy 253.346907 -89.577997) (xy 253.323235 -89.628494)
			(xy 253.292462 -89.675007) (xy 253.255245 -89.716544) (xy 253.212377 -89.752219) (xy 253.164771 -89.781273)
			(xy 253.113442 -89.803085) (xy 253.059485 -89.817191) (xy 253.004048 -89.823291) (xy 252.948314 -89.821254)
			(xy 252.893471 -89.811124) (xy 252.840687 -89.793117) (xy 252.791087 -89.767616) (xy 252.745729 -89.735165)
			(xy 252.70558 -89.696456) (xy 252.671494 -89.652313) (xy 252.644198 -89.603678) (xy 252.624275 -89.551587)
			(xy 252.612149 -89.49715) (xy 252.608078 -89.441528) (xy 249.73774 -89.441528) (xy 249.738134 -89.463118)
			(xy 249.737625 -89.491004) (xy 249.729505 -89.54618) (xy 249.713437 -89.599587) (xy 249.689765 -89.650084)
			(xy 249.658992 -89.696597) (xy 249.621775 -89.738134) (xy 249.578907 -89.773809) (xy 249.531301 -89.802863)
			(xy 249.479972 -89.824675) (xy 249.426015 -89.838781) (xy 249.370578 -89.844881) (xy 249.314844 -89.842844)
			(xy 249.260001 -89.832714) (xy 249.207217 -89.814707) (xy 249.157617 -89.789206) (xy 249.112259 -89.756755)
			(xy 249.07211 -89.718046) (xy 249.038024 -89.673903) (xy 249.010728 -89.625268) (xy 248.990805 -89.573177)
			(xy 248.978679 -89.51874) (xy 248.974608 -89.463118) (xy 247.734582 -89.463118) (xy 247.734582 -89.700862)
			(xy 247.734662 -89.704605) (xy 247.735811 -89.712002) (xy 247.736868 -89.715594) (xy 247.783202 -89.868502)
			(xy 251.846586 -89.868502) (xy 251.850657 -89.81288) (xy 251.862783 -89.758443) (xy 251.882706 -89.706352)
			(xy 251.910002 -89.657717) (xy 251.944088 -89.613574) (xy 251.984237 -89.574865) (xy 252.029595 -89.542414)
			(xy 252.079195 -89.516913) (xy 252.131979 -89.498906) (xy 252.186822 -89.488776) (xy 252.242556 -89.486739)
			(xy 252.297993 -89.492839) (xy 252.35195 -89.506945) (xy 252.403279 -89.528757) (xy 252.450885 -89.557811)
			(xy 252.493753 -89.593486) (xy 252.53097 -89.635023) (xy 252.561743 -89.681536) (xy 252.585415 -89.732033)
			(xy 252.601483 -89.78544) (xy 252.609603 -89.840616) (xy 252.610112 -89.868502) (xy 252.609603 -89.896388)
			(xy 252.608436 -89.904316) (xy 253.724662 -89.904316) (xy 253.728733 -89.848694) (xy 253.740859 -89.794257)
			(xy 253.760782 -89.742166) (xy 253.788078 -89.693531) (xy 253.822164 -89.649388) (xy 253.862313 -89.610679)
			(xy 253.907671 -89.578228) (xy 253.957271 -89.552727) (xy 254.010055 -89.53472) (xy 254.064898 -89.52459)
			(xy 254.120632 -89.522553) (xy 254.176069 -89.528653) (xy 254.230026 -89.542759) (xy 254.281355 -89.564571)
			(xy 254.328961 -89.593625) (xy 254.371829 -89.6293) (xy 254.409046 -89.670837) (xy 254.439819 -89.71735)
			(xy 254.463491 -89.767847) (xy 254.479559 -89.821254) (xy 254.487679 -89.87643) (xy 254.488188 -89.904316)
			(xy 254.487679 -89.932202) (xy 254.479559 -89.987378) (xy 254.463491 -90.040785) (xy 254.439819 -90.091282)
			(xy 254.409046 -90.137795) (xy 254.371829 -90.179332) (xy 254.328961 -90.215007) (xy 254.281355 -90.244061)
			(xy 254.230026 -90.265873) (xy 254.176069 -90.279979) (xy 254.120632 -90.286079) (xy 254.064898 -90.284042)
			(xy 254.010055 -90.273912) (xy 253.957271 -90.255905) (xy 253.907671 -90.230404) (xy 253.862313 -90.197953)
			(xy 253.822164 -90.159244) (xy 253.788078 -90.115101) (xy 253.760782 -90.066466) (xy 253.740859 -90.014375)
			(xy 253.728733 -89.959938) (xy 253.724662 -89.904316) (xy 252.608436 -89.904316) (xy 252.601483 -89.951564)
			(xy 252.585415 -90.004971) (xy 252.561743 -90.055468) (xy 252.53097 -90.101981) (xy 252.493753 -90.143518)
			(xy 252.450885 -90.179193) (xy 252.403279 -90.208247) (xy 252.35195 -90.230059) (xy 252.297993 -90.244165)
			(xy 252.242556 -90.250265) (xy 252.186822 -90.248228) (xy 252.131979 -90.238098) (xy 252.079195 -90.220091)
			(xy 252.029595 -90.19459) (xy 251.984237 -90.162139) (xy 251.944088 -90.12343) (xy 251.910002 -90.079287)
			(xy 251.882706 -90.030652) (xy 251.862783 -89.978561) (xy 251.850657 -89.924124) (xy 251.846586 -89.868502)
			(xy 247.783202 -89.868502) (xy 248.764217 -93.105986) (xy 249.565412 -93.105986) (xy 249.569483 -93.050364)
			(xy 249.581609 -92.995927) (xy 249.601532 -92.943836) (xy 249.628828 -92.895201) (xy 249.662914 -92.851058)
			(xy 249.703063 -92.812349) (xy 249.748421 -92.779898) (xy 249.798021 -92.754397) (xy 249.850805 -92.73639)
			(xy 249.905648 -92.72626) (xy 249.961382 -92.724223) (xy 250.016819 -92.730323) (xy 250.070776 -92.744429)
			(xy 250.122105 -92.766241) (xy 250.169711 -92.795295) (xy 250.212579 -92.83097) (xy 250.249796 -92.872507)
			(xy 250.280569 -92.91902) (xy 250.304241 -92.969517) (xy 250.320309 -93.022924) (xy 250.328429 -93.0781)
			(xy 250.328938 -93.105986) (xy 250.581412 -93.105986) (xy 250.585483 -93.050364) (xy 250.597609 -92.995927)
			(xy 250.617532 -92.943836) (xy 250.644828 -92.895201) (xy 250.678914 -92.851058) (xy 250.719063 -92.812349)
			(xy 250.764421 -92.779898) (xy 250.814021 -92.754397) (xy 250.866805 -92.73639) (xy 250.921648 -92.72626)
			(xy 250.977382 -92.724223) (xy 251.032819 -92.730323) (xy 251.086776 -92.744429) (xy 251.138105 -92.766241)
			(xy 251.185711 -92.795295) (xy 251.228579 -92.83097) (xy 251.265796 -92.872507) (xy 251.296569 -92.91902)
			(xy 251.320241 -92.969517) (xy 251.336309 -93.022924) (xy 251.344429 -93.0781) (xy 251.344938 -93.105986)
			(xy 251.597412 -93.105986) (xy 251.601483 -93.050364) (xy 251.613609 -92.995927) (xy 251.633532 -92.943836)
			(xy 251.660828 -92.895201) (xy 251.694914 -92.851058) (xy 251.735063 -92.812349) (xy 251.780421 -92.779898)
			(xy 251.830021 -92.754397) (xy 251.882805 -92.73639) (xy 251.937648 -92.72626) (xy 251.993382 -92.724223)
			(xy 252.048819 -92.730323) (xy 252.102776 -92.744429) (xy 252.154105 -92.766241) (xy 252.201711 -92.795295)
			(xy 252.244579 -92.83097) (xy 252.281796 -92.872507) (xy 252.312569 -92.91902) (xy 252.336241 -92.969517)
			(xy 252.352309 -93.022924) (xy 252.360429 -93.0781) (xy 252.360938 -93.105986) (xy 252.360429 -93.133872)
			(xy 252.352309 -93.189048) (xy 252.336241 -93.242455) (xy 252.312569 -93.292952) (xy 252.281796 -93.339465)
			(xy 252.244579 -93.381002) (xy 252.201711 -93.416677) (xy 252.154105 -93.445731) (xy 252.102776 -93.467543)
			(xy 252.048819 -93.481649) (xy 251.993382 -93.487749) (xy 251.937648 -93.485712) (xy 251.882805 -93.475582)
			(xy 251.830021 -93.457575) (xy 251.780421 -93.432074) (xy 251.735063 -93.399623) (xy 251.694914 -93.360914)
			(xy 251.660828 -93.316771) (xy 251.633532 -93.268136) (xy 251.613609 -93.216045) (xy 251.601483 -93.161608)
			(xy 251.597412 -93.105986) (xy 251.344938 -93.105986) (xy 251.344429 -93.133872) (xy 251.336309 -93.189048)
			(xy 251.320241 -93.242455) (xy 251.296569 -93.292952) (xy 251.265796 -93.339465) (xy 251.228579 -93.381002)
			(xy 251.185711 -93.416677) (xy 251.138105 -93.445731) (xy 251.086776 -93.467543) (xy 251.032819 -93.481649)
			(xy 250.977382 -93.487749) (xy 250.921648 -93.485712) (xy 250.866805 -93.475582) (xy 250.814021 -93.457575)
			(xy 250.764421 -93.432074) (xy 250.719063 -93.399623) (xy 250.678914 -93.360914) (xy 250.644828 -93.316771)
			(xy 250.617532 -93.268136) (xy 250.597609 -93.216045) (xy 250.585483 -93.161608) (xy 250.581412 -93.105986)
			(xy 250.328938 -93.105986) (xy 250.328429 -93.133872) (xy 250.320309 -93.189048) (xy 250.304241 -93.242455)
			(xy 250.280569 -93.292952) (xy 250.249796 -93.339465) (xy 250.212579 -93.381002) (xy 250.169711 -93.416677)
			(xy 250.122105 -93.445731) (xy 250.070776 -93.467543) (xy 250.016819 -93.481649) (xy 249.961382 -93.487749)
			(xy 249.905648 -93.485712) (xy 249.850805 -93.475582) (xy 249.798021 -93.457575) (xy 249.748421 -93.432074)
			(xy 249.703063 -93.399623) (xy 249.662914 -93.360914) (xy 249.628828 -93.316771) (xy 249.601532 -93.268136)
			(xy 249.581609 -93.216045) (xy 249.569483 -93.161608) (xy 249.565412 -93.105986) (xy 248.764217 -93.105986)
			(xy 249.047762 -94.041722) (xy 249.049485 -94.046955) (xy 249.054871 -94.056565) (xy 249.05843 -94.060772)
			(xy 249.059446 -94.061788) (xy 249.096276 -94.098618) (xy 250.156724 -94.098618) (xy 250.160795 -94.042996)
			(xy 250.172921 -93.988559) (xy 250.192844 -93.936468) (xy 250.22014 -93.887833) (xy 250.254226 -93.84369)
			(xy 250.294375 -93.804981) (xy 250.339733 -93.77253) (xy 250.389333 -93.747029) (xy 250.442117 -93.729022)
			(xy 250.49696 -93.718892) (xy 250.552694 -93.716855) (xy 250.608131 -93.722955) (xy 250.662088 -93.737061)
			(xy 250.713417 -93.758873) (xy 250.761023 -93.787927) (xy 250.803891 -93.823602) (xy 250.841108 -93.865139)
			(xy 250.871881 -93.911652) (xy 250.895553 -93.962149) (xy 250.911621 -94.015556) (xy 250.919741 -94.070732)
			(xy 250.92025 -94.098618) (xy 250.919741 -94.126504) (xy 250.911621 -94.18168) (xy 250.895553 -94.235087)
			(xy 250.871881 -94.285584) (xy 250.841108 -94.332097) (xy 250.803891 -94.373634) (xy 250.761023 -94.409309)
			(xy 250.713417 -94.438363) (xy 250.662088 -94.460175) (xy 250.608131 -94.474281) (xy 250.552694 -94.480381)
			(xy 250.49696 -94.478344) (xy 250.442117 -94.468214) (xy 250.389333 -94.450207) (xy 250.339733 -94.424706)
			(xy 250.294375 -94.392255) (xy 250.254226 -94.353546) (xy 250.22014 -94.309403) (xy 250.192844 -94.260768)
			(xy 250.172921 -94.208677) (xy 250.160795 -94.15424) (xy 250.156724 -94.098618) (xy 249.096276 -94.098618)
			(xy 250.036076 -95.038418) (xy 250.041828 -95.04361) (xy 250.055662 -95.050575) (xy 250.063254 -95.052134)
			(xy 250.071636 -95.052896) (xy 254.844804 -95.052896)
		)
		(stroke
			(width 0)
			(type solid)
		)
		(fill yes)
		(layer "In7.Cu")
		(net "P3V3")
	)
	(gr_poly
		(pts
			(xy 45.485304 -296.561002) (xy 45.49267 -296.551858) (xy 45.5422 -296.490136) (xy 45.548831 -296.480869)
			(xy 45.553978 -296.458704) (xy 45.552106 -296.447464) (xy 45.552106 -296.44721) (xy 45.548399 -296.429343)
			(xy 45.544448 -296.393066) (xy 45.544232 -296.37482) (xy 45.544742 -296.348833) (xy 45.552872 -296.297498)
			(xy 45.568933 -296.248068) (xy 45.592529 -296.201758) (xy 45.623079 -296.15971) (xy 45.65983 -296.122959)
			(xy 45.701878 -296.092409) (xy 45.748188 -296.068813) (xy 45.797618 -296.052752) (xy 45.848953 -296.044622)
			(xy 45.900927 -296.044622) (xy 45.952262 -296.052752) (xy 46.001692 -296.068813) (xy 46.048002 -296.092409)
			(xy 46.09005 -296.122959) (xy 46.126801 -296.15971) (xy 46.157351 -296.201758) (xy 46.180947 -296.248068)
			(xy 46.197008 -296.297498) (xy 46.205138 -296.348833) (xy 46.205648 -296.37482) (xy 46.20545 -296.393067)
			(xy 46.201506 -296.429347) (xy 46.197774 -296.44721) (xy 46.197774 -296.447464) (xy 46.195933 -296.458704)
			(xy 46.20107 -296.480862) (xy 46.20768 -296.490136) (xy 46.25721 -296.551858) (xy 46.264843 -296.560368)
			(xy 46.28542 -296.570254) (xy 46.296834 -296.570908) (xy 46.41469 -296.570908) (xy 46.435264 -296.561002)
			(xy 46.44263 -296.551858) (xy 46.49216 -296.490136) (xy 46.498796 -296.480871) (xy 46.503947 -296.458704)
			(xy 46.502066 -296.447464) (xy 46.502066 -296.44721) (xy 46.498359 -296.429343) (xy 46.494407 -296.393066)
			(xy 46.494192 -296.37482) (xy 46.494702 -296.348833) (xy 46.502832 -296.297498) (xy 46.518893 -296.248068)
			(xy 46.542489 -296.201758) (xy 46.573039 -296.15971) (xy 46.60979 -296.122959) (xy 46.651838 -296.092409)
			(xy 46.698148 -296.068813) (xy 46.747578 -296.052752) (xy 46.798913 -296.044622) (xy 46.850887 -296.044622)
			(xy 46.902222 -296.052752) (xy 46.951652 -296.068813) (xy 46.997962 -296.092409) (xy 47.04001 -296.122959)
			(xy 47.076761 -296.15971) (xy 47.107311 -296.201758) (xy 47.130907 -296.248068) (xy 47.146968 -296.297498)
			(xy 47.155098 -296.348833) (xy 47.155608 -296.37482) (xy 47.15541 -296.393067) (xy 47.151466 -296.429347)
			(xy 47.147734 -296.44721) (xy 47.147734 -296.447464) (xy 47.145893 -296.458704) (xy 47.151027 -296.480864)
			(xy 47.15764 -296.490136) (xy 47.20717 -296.551858) (xy 47.2148 -296.560375) (xy 47.235377 -296.570277)
			(xy 47.246794 -296.570908) (xy 47.81804 -296.570908) (xy 47.828107 -296.570478) (xy 47.846702 -296.562754)
			(xy 47.854108 -296.555922) (xy 47.868332 -296.541698) (xy 47.87265 -296.536618) (xy 47.873666 -296.535348)
			(xy 47.880117 -296.527072) (xy 47.89397 -296.511309) (xy 47.901352 -296.503852) (xy 48.07204 -296.333164)
			(xy 48.073056 -296.331894) (xy 48.075596 -296.329354) (xy 48.077374 -296.327576) (xy 48.078898 -296.325798)
			(xy 48.080422 -296.324274) (xy 48.08347 -296.32021) (xy 48.088141 -296.31347) (xy 48.093329 -296.297924)
			(xy 48.09363 -296.28973) (xy 48.09363 -296.121836) (xy 48.093122 -296.118026) (xy 48.093122 -296.117772)
			(xy 48.09109 -296.101516) (xy 48.08982 -296.077894) (xy 48.08982 -294.911526) (xy 48.089384 -294.901461)
			(xy 48.081653 -294.882874) (xy 48.074834 -294.875458) (xy 47.980346 -294.78097) (xy 47.974499 -294.775515)
			(xy 47.960257 -294.768261) (xy 47.952406 -294.766746) (xy 47.944914 -294.765773) (xy 47.929939 -294.767708)
			(xy 47.922942 -294.770556) (xy 47.914306 -294.77462) (xy 47.89237 -294.78439) (xy 47.846377 -294.798192)
			(xy 47.798869 -294.805178) (xy 47.77486 -294.805608) (xy 47.747533 -294.805042) (xy 47.693623 -294.796049)
			(xy 47.641926 -294.778315) (xy 47.593848 -294.752322) (xy 47.571914 -294.736012) (xy 47.565564 -294.731186)
			(xy 47.541434 -294.72255) (xy 47.537365 -294.72125) (xy 47.52894 -294.719844) (xy 47.52467 -294.719756)
			(xy 47.07509 -294.719756) (xy 47.070816 -294.719811) (xy 47.062384 -294.721208) (xy 47.058326 -294.72255)
			(xy 47.034196 -294.731186) (xy 47.027846 -294.736012) (xy 47.005924 -294.752338) (xy 46.957841 -294.778327)
			(xy 46.906141 -294.796056) (xy 46.852228 -294.805043) (xy 46.797572 -294.805043) (xy 46.743659 -294.796056)
			(xy 46.691959 -294.778327) (xy 46.643876 -294.752338) (xy 46.621954 -294.736012) (xy 46.615604 -294.731186)
			(xy 46.591474 -294.72255) (xy 46.587404 -294.721255) (xy 46.57898 -294.719859) (xy 46.57471 -294.719756)
			(xy 46.12513 -294.719756) (xy 46.120857 -294.719816) (xy 46.112428 -294.721223) (xy 46.108366 -294.72255)
			(xy 46.084236 -294.731186) (xy 46.077886 -294.736012) (xy 46.055964 -294.752341) (xy 46.007883 -294.778336)
			(xy 45.956182 -294.796071) (xy 45.902269 -294.805065) (xy 45.87494 -294.805608) (xy 45.849831 -294.805144)
			(xy 45.80019 -294.797555) (xy 45.752267 -294.782546) (xy 45.707165 -294.760462) (xy 45.665923 -294.731811)
			(xy 45.629487 -294.697252) (xy 45.598697 -294.657581) (xy 45.574262 -294.613709) (xy 45.556742 -294.566646)
			(xy 45.546541 -294.517475) (xy 45.54474 -294.492426) (xy 45.544361 -294.487635) (xy 45.542055 -294.478305)
			(xy 45.540168 -294.473884) (xy 45.536358 -294.465502) (xy 45.28185 -294.211248) (xy 45.278802 -294.211248)
			(xy 45.197776 -294.12692) (xy 45.197268 -294.126412) (xy 43.991022 -292.920166) (xy 43.987884 -292.917086)
			(xy 43.980727 -292.911981) (xy 43.976798 -292.910006) (xy 43.967146 -292.905688) (xy 43.95724 -292.90518)
			(xy 43.93037 -292.90322) (xy 43.87775 -292.891676) (xy 43.827697 -292.871754) (xy 43.781536 -292.843981)
			(xy 43.740487 -292.809093) (xy 43.705637 -292.768012) (xy 43.677908 -292.721824) (xy 43.658033 -292.671753)
			(xy 43.646539 -292.619122) (xy 43.644566 -292.592252) (xy 43.644058 -292.5826) (xy 43.639994 -292.57371)
			(xy 43.637994 -292.569577) (xy 43.632758 -292.562038) (xy 43.62958 -292.558724) (xy 43.040808 -291.969952)
			(xy 43.037669 -291.966873) (xy 43.03051 -291.961772) (xy 43.026584 -291.959792) (xy 43.016932 -291.955474)
			(xy 43.007026 -291.954966) (xy 42.980183 -291.952992) (xy 42.927618 -291.941432) (xy 42.877619 -291.921512)
			(xy 42.831507 -291.893758) (xy 42.790499 -291.858901) (xy 42.755677 -291.817863) (xy 42.727962 -291.771727)
			(xy 42.708084 -291.721711) (xy 42.69657 -291.669136) (xy 42.694606 -291.642292) (xy 42.694232 -291.637499)
			(xy 42.691936 -291.628165) (xy 42.690034 -291.62375) (xy 42.686224 -291.615368) (xy 42.090848 -291.019992)
			(xy 42.087712 -291.016909) (xy 42.080557 -291.011798) (xy 42.076624 -291.009832) (xy 42.066972 -291.005514)
			(xy 42.057066 -291.005006) (xy 42.03022 -291.003035) (xy 41.977647 -290.991481) (xy 41.92764 -290.971565)
			(xy 41.881519 -290.943813) (xy 41.840502 -290.908957) (xy 41.805671 -290.867919) (xy 41.777946 -290.821781)
			(xy 41.758061 -290.771762) (xy 41.746538 -290.719183) (xy 41.744646 -290.692332) (xy 41.744267 -290.68754)
			(xy 41.741963 -290.67821) (xy 41.740074 -290.67379) (xy 41.736264 -290.665408) (xy 41.140888 -290.070032)
			(xy 41.137751 -290.06695) (xy 41.130597 -290.06184) (xy 41.126664 -290.059872) (xy 41.117012 -290.055554)
			(xy 41.107106 -290.055046) (xy 41.080265 -290.05307) (xy 41.027703 -290.041508) (xy 40.977709 -290.021586)
			(xy 40.931601 -289.99383) (xy 40.890597 -289.958973) (xy 40.85578 -289.917935) (xy 40.828069 -289.871799)
			(xy 40.808196 -289.821785) (xy 40.796686 -289.769213) (xy 40.794686 -289.742372) (xy 40.794311 -289.737579)
			(xy 40.792015 -289.728245) (xy 40.790114 -289.72383) (xy 40.786304 -289.715448) (xy 40.190928 -289.120072)
			(xy 40.187791 -289.116991) (xy 40.180634 -289.111885) (xy 40.176704 -289.109912) (xy 40.167052 -289.105594)
			(xy 40.157146 -289.105086) (xy 40.130301 -289.103113) (xy 40.077733 -289.091557) (xy 40.02773 -289.071639)
			(xy 39.981613 -289.043885) (xy 39.9406 -289.009029) (xy 39.905774 -288.967991) (xy 39.878054 -288.921854)
			(xy 39.858173 -288.871837) (xy 39.846654 -288.819259) (xy 39.844726 -288.792412) (xy 39.844345 -288.787621)
			(xy 39.842037 -288.778292) (xy 39.840154 -288.77387) (xy 39.836344 -288.765488) (xy 39.241222 -288.170366)
			(xy 39.233822 -288.163525) (xy 39.215223 -288.155808) (xy 39.205154 -288.15538) (xy 38.275006 -288.15538)
			(xy 38.248995 -288.154897) (xy 38.197614 -288.14676) (xy 38.148138 -288.130685) (xy 38.101785 -288.107068)
			(xy 38.059698 -288.076491) (xy 38.022913 -288.039706) (xy 37.992335 -287.99762) (xy 37.968717 -287.951268)
			(xy 37.952642 -287.901792) (xy 37.944503 -287.850411) (xy 37.944503 -287.798389) (xy 37.952642 -287.747008)
			(xy 37.968717 -287.697532) (xy 37.992335 -287.65118) (xy 38.022913 -287.609094) (xy 38.059698 -287.572309)
			(xy 38.101785 -287.541732) (xy 38.148138 -287.518115) (xy 38.197614 -287.50204) (xy 38.248995 -287.493903)
			(xy 38.275006 -287.493456) (xy 38.44163 -287.493456) (xy 38.45162 -287.492953) (xy 38.470083 -287.485308)
			(xy 38.484251 -287.471216) (xy 38.48862 -287.462214) (xy 38.494716 -287.447736) (xy 38.48862 -287.417764)
			(xy 38.291008 -287.220152) (xy 38.287869 -287.217073) (xy 38.28071 -287.211972) (xy 38.276784 -287.209992)
			(xy 38.267132 -287.205674) (xy 38.257226 -287.205166) (xy 38.23219 -287.203352) (xy 38.183052 -287.193112)
			(xy 38.136025 -287.175565) (xy 38.09219 -287.151114) (xy 38.052552 -287.120319) (xy 38.018023 -287.083889)
			(xy 37.989395 -287.04266) (xy 37.967325 -286.997578) (xy 37.952321 -286.949679) (xy 37.944727 -286.900063)
			(xy 37.944298 -286.874966) (xy 37.94482 -286.848522) (xy 37.95324 -286.796307) (xy 37.969862 -286.746098)
			(xy 37.99426 -286.699173) (xy 38.025814 -286.656728) (xy 38.06372 -286.619844) (xy 38.107011 -286.589461)
			(xy 38.154585 -286.566354) (xy 38.179756 -286.558228) (xy 38.195758 -286.553402) (xy 38.215824 -286.526478)
			(xy 38.215824 -286.290258) (xy 38.215377 -286.279356) (xy 38.206446 -286.259472) (xy 38.19005 -286.245108)
			(xy 38.179756 -286.24149) (xy 38.179502 -286.24149) (xy 38.154336 -286.233359) (xy 38.106777 -286.210229)
			(xy 38.063505 -286.179827) (xy 38.025622 -286.142926) (xy 37.994092 -286.100469) (xy 37.96972 -286.053535)
			(xy 37.953126 -286.003321) (xy 37.944733 -285.951107) (xy 37.944754 -285.898222) (xy 37.95319 -285.846015)
			(xy 37.969825 -285.795815) (xy 37.994236 -285.748901) (xy 38.025801 -285.706469) (xy 38.063714 -285.6696)
			(xy 38.107011 -285.639233) (xy 38.154588 -285.616142) (xy 38.179756 -285.608014) (xy 38.195758 -285.603188)
			(xy 38.215824 -285.576264) (xy 38.215824 -285.340298) (xy 38.215365 -285.329403) (xy 38.206422 -285.309541)
			(xy 38.190028 -285.295197) (xy 38.179756 -285.29153) (xy 38.179502 -285.29153) (xy 38.154332 -285.283399)
			(xy 38.106768 -285.260268) (xy 38.06349 -285.229864) (xy 38.025601 -285.19296) (xy 37.994066 -285.150499)
			(xy 37.969689 -285.103561) (xy 37.953091 -285.053342) (xy 37.944695 -285.001122) (xy 37.944715 -284.948231)
			(xy 37.95315 -284.896017) (xy 37.969786 -284.845811) (xy 37.994198 -284.798891) (xy 38.025764 -284.756453)
			(xy 38.063681 -284.719578) (xy 38.106982 -284.689206) (xy 38.154564 -284.666111) (xy 38.179756 -284.658054)
			(xy 38.195758 -284.653228) (xy 38.215824 -284.626304) (xy 38.215824 -284.390338) (xy 38.215373 -284.379438)
			(xy 38.206438 -284.359561) (xy 38.190043 -284.345204) (xy 38.179756 -284.34157) (xy 38.179502 -284.34157)
			(xy 38.154337 -284.333439) (xy 38.106782 -284.31031) (xy 38.063513 -284.279908) (xy 38.025632 -284.24301)
			(xy 37.994105 -284.200554) (xy 37.969735 -284.153622) (xy 37.953143 -284.103411) (xy 37.944751 -284.0512)
			(xy 37.944774 -283.998318) (xy 37.95321 -283.946114) (xy 37.969845 -283.895917) (xy 37.994256 -283.849007)
			(xy 38.025819 -283.806578) (xy 38.063731 -283.769711) (xy 38.107026 -283.739347) (xy 38.154601 -283.716258)
			(xy 38.179756 -283.708094) (xy 38.195758 -283.703268) (xy 38.215824 -283.676344) (xy 38.215824 -283.440378)
			(xy 38.215381 -283.429473) (xy 38.206454 -283.409582) (xy 38.190057 -283.395212) (xy 38.179756 -283.39161)
			(xy 38.179502 -283.39161) (xy 38.154334 -283.383479) (xy 38.106773 -283.360349) (xy 38.063497 -283.329945)
			(xy 38.025611 -283.293043) (xy 37.994079 -283.250584) (xy 37.969705 -283.203648) (xy 37.953109 -283.153432)
			(xy 37.944714 -283.101214) (xy 37.944735 -283.048327) (xy 37.95317 -282.996116) (xy 37.969806 -282.945913)
			(xy 37.994217 -282.898996) (xy 38.025782 -282.856561) (xy 38.063698 -282.819689) (xy 38.106996 -282.78932)
			(xy 38.154576 -282.766226) (xy 38.179756 -282.758134) (xy 38.195758 -282.753308) (xy 38.215824 -282.726384)
			(xy 38.215824 -282.490418) (xy 38.215369 -282.479521) (xy 38.20643 -282.459651) (xy 38.190035 -282.445301)
			(xy 38.179756 -282.44165) (xy 38.179502 -282.44165) (xy 38.154339 -282.433519) (xy 38.106787 -282.41039)
			(xy 38.063521 -282.37999) (xy 38.025643 -282.343093) (xy 37.994119 -282.300639) (xy 37.969751 -282.253709)
			(xy 37.95316 -282.203501) (xy 37.94477 -282.151293) (xy 37.944793 -282.098414) (xy 37.95323 -282.046213)
			(xy 37.969865 -281.996019) (xy 37.994275 -281.949112) (xy 38.025837 -281.906686) (xy 38.063747 -281.869822)
			(xy 38.10704 -281.83946) (xy 38.154613 -281.816374) (xy 38.179756 -281.808174) (xy 38.195758 -281.803348)
			(xy 38.215824 -281.776424) (xy 38.215824 -281.540458) (xy 38.215377 -281.529556) (xy 38.206446 -281.509672)
			(xy 38.19005 -281.495308) (xy 38.179756 -281.49169) (xy 38.179502 -281.49169) (xy 38.154336 -281.483559)
			(xy 38.106777 -281.460429) (xy 38.063505 -281.430027) (xy 38.025622 -281.393126) (xy 37.994092 -281.350669)
			(xy 37.96972 -281.303735) (xy 37.953126 -281.253521) (xy 37.944733 -281.201307) (xy 37.944754 -281.148422)
			(xy 37.95319 -281.096215) (xy 37.969825 -281.046015) (xy 37.994236 -280.999101) (xy 38.025801 -280.956669)
			(xy 38.063714 -280.9198) (xy 38.107011 -280.889433) (xy 38.154588 -280.866342) (xy 38.179756 -280.858214)
			(xy 38.195758 -280.853388) (xy 38.215824 -280.826464) (xy 38.215824 -280.590244) (xy 38.215374 -280.579344)
			(xy 38.20644 -280.559464) (xy 38.190045 -280.545106) (xy 38.179756 -280.541476) (xy 38.179502 -280.541476)
			(xy 38.154337 -280.533345) (xy 38.106781 -280.510215) (xy 38.063511 -280.479814) (xy 38.025629 -280.442915)
			(xy 37.994101 -280.400458) (xy 37.969731 -280.353526) (xy 37.953138 -280.303314) (xy 37.944746 -280.251102)
			(xy 37.944768 -280.19822) (xy 37.953204 -280.146014) (xy 37.969839 -280.095817) (xy 37.99425 -280.048905)
			(xy 38.025813 -280.006475) (xy 38.063726 -279.969608) (xy 38.107021 -279.939243) (xy 38.154597 -279.916153)
			(xy 38.179756 -279.908) (xy 38.195758 -279.903174) (xy 38.215824 -279.87625) (xy 38.215824 -279.640284)
			(xy 38.215382 -279.629378) (xy 38.206456 -279.609485) (xy 38.190059 -279.595113) (xy 38.179756 -279.591516)
			(xy 38.179502 -279.591516) (xy 38.154333 -279.583385) (xy 38.106771 -279.560254) (xy 38.063495 -279.529851)
			(xy 38.025608 -279.492949) (xy 37.994075 -279.450488) (xy 37.9697 -279.403552) (xy 37.953103 -279.353335)
			(xy 37.944708 -279.301117) (xy 37.944729 -279.248228) (xy 37.953164 -279.196016) (xy 37.9698 -279.145812)
			(xy 37.994211 -279.098894) (xy 38.025777 -279.056459) (xy 38.063693 -279.019586) (xy 38.106992 -278.989216)
			(xy 38.154572 -278.966122) (xy 38.179756 -278.95804) (xy 38.195758 -278.953214) (xy 38.215824 -278.92629)
			(xy 38.215824 -278.690324) (xy 38.21537 -278.679426) (xy 38.206432 -278.659554) (xy 38.190038 -278.645202)
			(xy 38.179756 -278.641556) (xy 38.179502 -278.641556) (xy 38.154338 -278.633425) (xy 38.106785 -278.610296)
			(xy 38.063518 -278.579895) (xy 38.02564 -278.542998) (xy 37.994115 -278.500543) (xy 37.969746 -278.453613)
			(xy 37.953155 -278.403404) (xy 37.944764 -278.351195) (xy 37.944787 -278.298315) (xy 37.953224 -278.246113)
			(xy 37.969859 -278.195919) (xy 37.994269 -278.14901) (xy 38.025831 -278.106583) (xy 38.063742 -278.069719)
			(xy 38.107036 -278.039356) (xy 38.154609 -278.016269) (xy 38.179756 -278.00808) (xy 38.195758 -278.003254)
			(xy 38.215824 -277.97633) (xy 38.215824 -277.740364) (xy 38.215378 -277.729461) (xy 38.206448 -277.709575)
			(xy 38.190052 -277.695209) (xy 38.179756 -277.691596) (xy 38.179502 -277.691596) (xy 38.154335 -277.683465)
			(xy 38.106776 -277.660335) (xy 38.063503 -277.629932) (xy 38.025619 -277.593032) (xy 37.994088 -277.550573)
			(xy 37.969715 -277.503639) (xy 37.953121 -277.453424) (xy 37.944727 -277.401209) (xy 37.944748 -277.348324)
			(xy 37.953184 -277.296115) (xy 37.969819 -277.245914) (xy 37.99423 -277.199) (xy 38.025795 -277.156567)
			(xy 38.063709 -277.119697) (xy 38.107007 -277.089329) (xy 38.154585 -277.066237) (xy 38.179756 -277.05812)
			(xy 38.195758 -277.053294) (xy 38.215824 -277.02637) (xy 38.215824 -276.790404) (xy 38.215366 -276.779509)
			(xy 38.206425 -276.759644) (xy 38.19003 -276.745298) (xy 38.179756 -276.741636) (xy 38.179502 -276.741636)
			(xy 38.154332 -276.733505) (xy 38.106766 -276.710374) (xy 38.063487 -276.679969) (xy 38.025597 -276.643065)
			(xy 37.994062 -276.600603) (xy 37.969685 -276.553664) (xy 37.953086 -276.503445) (xy 37.94469 -276.451224)
			(xy 37.944709 -276.398332) (xy 37.953144 -276.346118) (xy 37.96978 -276.29591) (xy 37.994192 -276.248989)
			(xy 38.025759 -276.20655) (xy 38.063676 -276.169675) (xy 38.106977 -276.139302) (xy 38.15456 -276.116206)
			(xy 38.179756 -276.10816) (xy 38.195758 -276.103334) (xy 38.215824 -276.07641) (xy 38.215824 -275.840444)
			(xy 38.215374 -275.829544) (xy 38.20644 -275.809664) (xy 38.190045 -275.795306) (xy 38.179756 -275.791676)
			(xy 38.179502 -275.791676) (xy 38.154337 -275.783545) (xy 38.106781 -275.760415) (xy 38.063511 -275.730014)
			(xy 38.025629 -275.693115) (xy 37.994101 -275.650658) (xy 37.969731 -275.603726) (xy 37.953138 -275.553514)
			(xy 37.944746 -275.501302) (xy 37.944768 -275.44842) (xy 37.953204 -275.396214) (xy 37.969839 -275.346017)
			(xy 37.99425 -275.299105) (xy 38.025813 -275.256675) (xy 38.063726 -275.219808) (xy 38.107021 -275.189443)
			(xy 38.154597 -275.166353) (xy 38.179756 -275.1582) (xy 38.195758 -275.153374) (xy 38.215824 -275.12645)
			(xy 38.215824 -274.890484) (xy 38.215382 -274.879578) (xy 38.206456 -274.859685) (xy 38.190059 -274.845313)
			(xy 38.179756 -274.841716) (xy 38.179502 -274.841716) (xy 38.154333 -274.833585) (xy 38.106771 -274.810454)
			(xy 38.063495 -274.780051) (xy 38.025608 -274.743149) (xy 37.994075 -274.700688) (xy 37.9697 -274.653752)
			(xy 37.953103 -274.603535) (xy 37.944708 -274.551317) (xy 37.944729 -274.498428) (xy 37.953164 -274.446216)
			(xy 37.9698 -274.396012) (xy 37.994211 -274.349094) (xy 38.025777 -274.306659) (xy 38.063693 -274.269786)
			(xy 38.106992 -274.239416) (xy 38.154572 -274.216322) (xy 38.179756 -274.20824) (xy 38.195758 -274.203414)
			(xy 38.215824 -274.17649) (xy 38.215824 -273.94027) (xy 38.215379 -273.929366) (xy 38.206451 -273.909478)
			(xy 38.190054 -273.895111) (xy 38.179756 -273.891502) (xy 38.179502 -273.891502) (xy 38.154313 -273.883403)
			(xy 38.106703 -273.860326) (xy 38.063376 -273.829961) (xy 38.025437 -273.793085) (xy 37.993854 -273.750637)
			(xy 37.969434 -273.703702) (xy 37.9528 -273.653477) (xy 37.944376 -273.601244) (xy 37.944378 -273.548336)
			(xy 37.952805 -273.496103) (xy 37.969442 -273.445879) (xy 37.993865 -273.398945) (xy 38.02545 -273.3565)
			(xy 38.063392 -273.319625) (xy 38.106721 -273.289264) (xy 38.154332 -273.266189) (xy 38.179502 -273.258026)
			(xy 38.195758 -273.2532) (xy 38.215824 -273.226276) (xy 38.215824 -272.99031) (xy 38.215368 -272.979414)
			(xy 38.206427 -272.959547) (xy 38.190033 -272.945199) (xy 38.179756 -272.941542) (xy 38.179502 -272.941542)
			(xy 38.154331 -272.933411) (xy 38.106765 -272.91028) (xy 38.063485 -272.879875) (xy 38.025594 -272.842971)
			(xy 37.994058 -272.800508) (xy 37.96968 -272.753568) (xy 37.953081 -272.703348) (xy 37.944684 -272.651126)
			(xy 37.944703 -272.598233) (xy 37.953138 -272.546018) (xy 37.969774 -272.495809) (xy 37.994186 -272.448888)
			(xy 38.025753 -272.406448) (xy 38.063671 -272.369571) (xy 38.106973 -272.339198) (xy 38.154556 -272.316101)
			(xy 38.179756 -272.308066) (xy 38.195758 -272.30324) (xy 38.215824 -272.276316) (xy 38.215824 -264.603484)
			(xy 38.19779 -264.577576) (xy 38.182804 -264.571988) (xy 38.156688 -264.561723) (xy 38.107546 -264.534636)
			(xy 38.0629 -264.500644) (xy 38.023713 -264.460481) (xy 37.99083 -264.415012) (xy 37.96496 -264.365219)
			(xy 37.94666 -264.312174) (xy 37.936325 -264.257021) (xy 37.934178 -264.200949) (xy 37.940264 -264.145167)
			(xy 37.954454 -264.090877) (xy 37.976441 -264.039251) (xy 38.00575 -263.991401) (xy 38.041751 -263.948359)
			(xy 38.062408 -263.929368) (xy 38.062916 -263.92886) (xy 38.083888 -263.907234) (xy 38.131403 -263.870205)
			(xy 38.184138 -263.84109) (xy 38.212268 -263.830308) (xy 38.215824 -263.825228) (xy 38.215824 -260.743446)
			(xy 38.215316 -260.743192) (xy 38.215316 -260.702298) (xy 38.207696 -260.683502) (xy 38.20033 -260.67639)
			(xy 37.382704 -259.85851) (xy 37.375592 -259.851144) (xy 37.356796 -259.843524) (xy 34.981896 -259.843524)
			(xy 34.972376 -259.843924) (xy 34.954636 -259.850843) (xy 34.947352 -259.856986) (xy 34.926114 -259.87584)
			(xy 34.8791 -259.907696) (xy 34.827881 -259.932225) (xy 34.77359 -259.948887) (xy 34.717429 -259.95731)
			(xy 34.660639 -259.95731) (xy 34.604478 -259.948887) (xy 34.550187 -259.932225) (xy 34.498968 -259.907696)
			(xy 34.451954 -259.87584) (xy 34.430716 -259.856986) (xy 34.423459 -259.850795) (xy 34.405704 -259.843863)
			(xy 34.396172 -259.843524) (xy 34.223706 -259.843524) (xy 34.213636 -259.843947) (xy 34.195032 -259.851662)
			(xy 34.187638 -259.85851) (xy 33.99155 -260.054598) (xy 33.984184 -260.06171) (xy 33.976564 -260.080506)
			(xy 33.976564 -260.338316) (xy 36.579046 -260.338316) (xy 36.583117 -260.282694) (xy 36.595243 -260.228257)
			(xy 36.615166 -260.176166) (xy 36.642462 -260.127531) (xy 36.676548 -260.083388) (xy 36.716697 -260.044679)
			(xy 36.762055 -260.012228) (xy 36.811655 -259.986727) (xy 36.864439 -259.96872) (xy 36.919282 -259.95859)
			(xy 36.975016 -259.956553) (xy 37.030453 -259.962653) (xy 37.08441 -259.976759) (xy 37.135739 -259.998571)
			(xy 37.183345 -260.027625) (xy 37.226213 -260.0633) (xy 37.26343 -260.104837) (xy 37.294203 -260.15135)
			(xy 37.317875 -260.201847) (xy 37.333943 -260.255254) (xy 37.342063 -260.31043) (xy 37.342572 -260.338316)
			(xy 37.342063 -260.366202) (xy 37.333943 -260.421378) (xy 37.317875 -260.474785) (xy 37.294203 -260.525282)
			(xy 37.26343 -260.571795) (xy 37.226213 -260.613332) (xy 37.183345 -260.649007) (xy 37.135739 -260.678061)
			(xy 37.08441 -260.699873) (xy 37.030453 -260.713979) (xy 36.975016 -260.720079) (xy 36.919282 -260.718042)
			(xy 36.864439 -260.707912) (xy 36.811655 -260.689905) (xy 36.762055 -260.664404) (xy 36.716697 -260.631953)
			(xy 36.676548 -260.593244) (xy 36.642462 -260.549101) (xy 36.615166 -260.500466) (xy 36.595243 -260.448375)
			(xy 36.583117 -260.393938) (xy 36.579046 -260.338316) (xy 33.976564 -260.338316) (xy 33.976564 -262.676386)
			(xy 33.978088 -262.682482) (xy 33.983094 -262.704558) (xy 33.988439 -262.74951) (xy 33.988756 -262.772144)
			(xy 33.988756 -262.77316) (xy 33.98842 -262.795793) (xy 33.983073 -262.840742) (xy 33.978088 -262.862822)
			(xy 33.976564 -262.868918) (xy 33.976564 -264.017506) (xy 36.356542 -264.017506) (xy 36.360613 -263.961884)
			(xy 36.372739 -263.907447) (xy 36.392662 -263.855356) (xy 36.419958 -263.806721) (xy 36.454044 -263.762578)
			(xy 36.494193 -263.723869) (xy 36.539551 -263.691418) (xy 36.589151 -263.665917) (xy 36.641935 -263.64791)
			(xy 36.696778 -263.63778) (xy 36.752512 -263.635743) (xy 36.807949 -263.641843) (xy 36.861906 -263.655949)
			(xy 36.913235 -263.677761) (xy 36.960841 -263.706815) (xy 37.003709 -263.74249) (xy 37.040926 -263.784027)
			(xy 37.071699 -263.83054) (xy 37.095371 -263.881037) (xy 37.111439 -263.934444) (xy 37.119559 -263.98962)
			(xy 37.120068 -264.017506) (xy 37.119559 -264.045392) (xy 37.111439 -264.100568) (xy 37.095371 -264.153975)
			(xy 37.071699 -264.204472) (xy 37.040926 -264.250985) (xy 37.003709 -264.292522) (xy 36.960841 -264.328197)
			(xy 36.913235 -264.357251) (xy 36.861906 -264.379063) (xy 36.807949 -264.393169) (xy 36.752512 -264.399269)
			(xy 36.696778 -264.397232) (xy 36.641935 -264.387102) (xy 36.589151 -264.369095) (xy 36.539551 -264.343594)
			(xy 36.494193 -264.311143) (xy 36.454044 -264.272434) (xy 36.419958 -264.228291) (xy 36.392662 -264.179656)
			(xy 36.372739 -264.127565) (xy 36.360613 -264.073128) (xy 36.356542 -264.017506) (xy 33.976564 -264.017506)
			(xy 33.976564 -264.683748) (xy 33.976998 -264.693813) (xy 33.984731 -264.712399) (xy 33.99155 -264.719816)
			(xy 34.639758 -265.368024) (xy 34.646605 -265.375422) (xy 34.654338 -265.39402) (xy 34.654744 -265.404092)
			(xy 34.654744 -265.804904) (xy 37.345618 -265.804904) (xy 37.349689 -265.749282) (xy 37.361815 -265.694845)
			(xy 37.381738 -265.642754) (xy 37.409034 -265.594119) (xy 37.44312 -265.549976) (xy 37.483269 -265.511267)
			(xy 37.528627 -265.478816) (xy 37.578227 -265.453315) (xy 37.631011 -265.435308) (xy 37.685854 -265.425178)
			(xy 37.741588 -265.423141) (xy 37.797025 -265.429241) (xy 37.850982 -265.443347) (xy 37.902311 -265.465159)
			(xy 37.949917 -265.494213) (xy 37.992785 -265.529888) (xy 38.030002 -265.571425) (xy 38.060775 -265.617938)
			(xy 38.084447 -265.668435) (xy 38.100515 -265.721842) (xy 38.108635 -265.777018) (xy 38.109144 -265.804904)
			(xy 38.108635 -265.83279) (xy 38.100515 -265.887966) (xy 38.084447 -265.941373) (xy 38.060775 -265.99187)
			(xy 38.030002 -266.038383) (xy 37.992785 -266.07992) (xy 37.949917 -266.115595) (xy 37.902311 -266.144649)
			(xy 37.850982 -266.166461) (xy 37.797025 -266.180567) (xy 37.741588 -266.186667) (xy 37.685854 -266.18463)
			(xy 37.631011 -266.1745) (xy 37.578227 -266.156493) (xy 37.528627 -266.130992) (xy 37.483269 -266.098541)
			(xy 37.44312 -266.059832) (xy 37.409034 -266.015689) (xy 37.381738 -265.967054) (xy 37.361815 -265.914963)
			(xy 37.349689 -265.860526) (xy 37.345618 -265.804904) (xy 34.654744 -265.804904) (xy 34.654744 -267.578078)
			(xy 36.853112 -267.578078) (xy 36.857183 -267.522456) (xy 36.869309 -267.468019) (xy 36.889232 -267.415928)
			(xy 36.916528 -267.367293) (xy 36.950614 -267.32315) (xy 36.990763 -267.284441) (xy 37.036121 -267.25199)
			(xy 37.085721 -267.226489) (xy 37.138505 -267.208482) (xy 37.193348 -267.198352) (xy 37.249082 -267.196315)
			(xy 37.304519 -267.202415) (xy 37.358476 -267.216521) (xy 37.409805 -267.238333) (xy 37.457411 -267.267387)
			(xy 37.500279 -267.303062) (xy 37.537496 -267.344599) (xy 37.568269 -267.391112) (xy 37.591941 -267.441609)
			(xy 37.608009 -267.495016) (xy 37.616129 -267.550192) (xy 37.616638 -267.578078) (xy 37.616129 -267.605964)
			(xy 37.608009 -267.66114) (xy 37.591941 -267.714547) (xy 37.568269 -267.765044) (xy 37.537496 -267.811557)
			(xy 37.500279 -267.853094) (xy 37.457411 -267.888769) (xy 37.409805 -267.917823) (xy 37.358476 -267.939635)
			(xy 37.304519 -267.953741) (xy 37.249082 -267.959841) (xy 37.193348 -267.957804) (xy 37.138505 -267.947674)
			(xy 37.085721 -267.929667) (xy 37.036121 -267.904166) (xy 36.990763 -267.871715) (xy 36.950614 -267.833006)
			(xy 36.916528 -267.788863) (xy 36.889232 -267.740228) (xy 36.869309 -267.688137) (xy 36.857183 -267.6337)
			(xy 36.853112 -267.578078) (xy 34.654744 -267.578078) (xy 34.654744 -273.388328) (xy 34.654314 -273.398395)
			(xy 34.646586 -273.416986) (xy 34.639758 -273.424396) (xy 34.613088 -273.451066) (xy 34.605722 -273.458178)
			(xy 34.598102 -273.476974) (xy 34.598102 -273.574764) (xy 37.018988 -273.574764) (xy 37.022948 -273.52571)
			(xy 37.034725 -273.477926) (xy 37.054016 -273.43265) (xy 37.080319 -273.391054) (xy 37.112954 -273.354217)
			(xy 37.151075 -273.323092) (xy 37.193696 -273.298485) (xy 37.239712 -273.281033) (xy 37.287931 -273.271189)
			(xy 37.337106 -273.269208) (xy 37.385961 -273.27514) (xy 37.433232 -273.288832) (xy 37.477694 -273.30993)
			(xy 37.518197 -273.337886) (xy 37.55369 -273.371978) (xy 37.583255 -273.411322) (xy 37.606126 -273.454899)
			(xy 37.62171 -273.50158) (xy 37.629605 -273.550157) (xy 37.6301 -273.574764) (xy 37.629605 -273.599371)
			(xy 37.62171 -273.647948) (xy 37.606126 -273.694629) (xy 37.583255 -273.738206) (xy 37.55369 -273.77755)
			(xy 37.518197 -273.811642) (xy 37.477694 -273.839598) (xy 37.433232 -273.860696) (xy 37.385961 -273.874388)
			(xy 37.337106 -273.88032) (xy 37.287931 -273.878339) (xy 37.239712 -273.868495) (xy 37.193696 -273.851043)
			(xy 37.151075 -273.826436) (xy 37.112954 -273.795311) (xy 37.080319 -273.758474) (xy 37.054016 -273.716878)
			(xy 37.034725 -273.671602) (xy 37.022948 -273.623818) (xy 37.018988 -273.574764) (xy 34.598102 -273.574764)
			(xy 34.598102 -274.524724) (xy 37.018988 -274.524724) (xy 37.022948 -274.47567) (xy 37.034725 -274.427886)
			(xy 37.054016 -274.38261) (xy 37.080319 -274.341014) (xy 37.112954 -274.304177) (xy 37.151075 -274.273052)
			(xy 37.193696 -274.248445) (xy 37.239712 -274.230993) (xy 37.287931 -274.221149) (xy 37.337106 -274.219168)
			(xy 37.385961 -274.2251) (xy 37.433232 -274.238792) (xy 37.477694 -274.25989) (xy 37.518197 -274.287846)
			(xy 37.55369 -274.321938) (xy 37.583255 -274.361282) (xy 37.606126 -274.404859) (xy 37.62171 -274.45154)
			(xy 37.629605 -274.500117) (xy 37.6301 -274.524724) (xy 37.629605 -274.549331) (xy 37.62171 -274.597908)
			(xy 37.606126 -274.644589) (xy 37.583255 -274.688166) (xy 37.55369 -274.72751) (xy 37.518197 -274.761602)
			(xy 37.477694 -274.789558) (xy 37.433232 -274.810656) (xy 37.385961 -274.824348) (xy 37.337106 -274.83028)
			(xy 37.287931 -274.828299) (xy 37.239712 -274.818455) (xy 37.193696 -274.801003) (xy 37.151075 -274.776396)
			(xy 37.112954 -274.745271) (xy 37.080319 -274.708434) (xy 37.054016 -274.666838) (xy 37.034725 -274.621562)
			(xy 37.022948 -274.573778) (xy 37.018988 -274.524724) (xy 34.598102 -274.524724) (xy 34.598102 -275.474938)
			(xy 36.069028 -275.474938) (xy 36.072988 -275.425884) (xy 36.084765 -275.3781) (xy 36.104056 -275.332824)
			(xy 36.130359 -275.291228) (xy 36.162994 -275.254391) (xy 36.201115 -275.223266) (xy 36.243736 -275.198659)
			(xy 36.289752 -275.181207) (xy 36.337971 -275.171363) (xy 36.387146 -275.169382) (xy 36.436001 -275.175314)
			(xy 36.483272 -275.189006) (xy 36.527734 -275.210104) (xy 36.568237 -275.23806) (xy 36.60373 -275.272152)
			(xy 36.633295 -275.311496) (xy 36.656166 -275.355073) (xy 36.67175 -275.401754) (xy 36.679645 -275.450331)
			(xy 36.68014 -275.474938) (xy 37.018988 -275.474938) (xy 37.022948 -275.425884) (xy 37.034725 -275.3781)
			(xy 37.054016 -275.332824) (xy 37.080319 -275.291228) (xy 37.112954 -275.254391) (xy 37.151075 -275.223266)
			(xy 37.193696 -275.198659) (xy 37.239712 -275.181207) (xy 37.287931 -275.171363) (xy 37.337106 -275.169382)
			(xy 37.385961 -275.175314) (xy 37.433232 -275.189006) (xy 37.477694 -275.210104) (xy 37.518197 -275.23806)
			(xy 37.55369 -275.272152) (xy 37.583255 -275.311496) (xy 37.606126 -275.355073) (xy 37.62171 -275.401754)
			(xy 37.629605 -275.450331) (xy 37.6301 -275.474938) (xy 37.629605 -275.499545) (xy 37.62171 -275.548122)
			(xy 37.606126 -275.594803) (xy 37.583255 -275.63838) (xy 37.55369 -275.677724) (xy 37.518197 -275.711816)
			(xy 37.477694 -275.739772) (xy 37.433232 -275.76087) (xy 37.385961 -275.774562) (xy 37.337106 -275.780494)
			(xy 37.287931 -275.778513) (xy 37.239712 -275.768669) (xy 37.193696 -275.751217) (xy 37.151075 -275.72661)
			(xy 37.112954 -275.695485) (xy 37.080319 -275.658648) (xy 37.054016 -275.617052) (xy 37.034725 -275.571776)
			(xy 37.022948 -275.523992) (xy 37.018988 -275.474938) (xy 36.68014 -275.474938) (xy 36.679645 -275.499545)
			(xy 36.67175 -275.548122) (xy 36.656166 -275.594803) (xy 36.633295 -275.63838) (xy 36.60373 -275.677724)
			(xy 36.568237 -275.711816) (xy 36.527734 -275.739772) (xy 36.483272 -275.76087) (xy 36.436001 -275.774562)
			(xy 36.387146 -275.780494) (xy 36.337971 -275.778513) (xy 36.289752 -275.768669) (xy 36.243736 -275.751217)
			(xy 36.201115 -275.72661) (xy 36.162994 -275.695485) (xy 36.130359 -275.658648) (xy 36.104056 -275.617052)
			(xy 36.084765 -275.571776) (xy 36.072988 -275.523992) (xy 36.069028 -275.474938) (xy 34.598102 -275.474938)
			(xy 34.598102 -276.424898) (xy 36.069028 -276.424898) (xy 36.072988 -276.375844) (xy 36.084765 -276.32806)
			(xy 36.104056 -276.282784) (xy 36.130359 -276.241188) (xy 36.162994 -276.204351) (xy 36.201115 -276.173226)
			(xy 36.243736 -276.148619) (xy 36.289752 -276.131167) (xy 36.337971 -276.121323) (xy 36.387146 -276.119342)
			(xy 36.436001 -276.125274) (xy 36.483272 -276.138966) (xy 36.527734 -276.160064) (xy 36.568237 -276.18802)
			(xy 36.60373 -276.222112) (xy 36.633295 -276.261456) (xy 36.656166 -276.305033) (xy 36.67175 -276.351714)
			(xy 36.679645 -276.400291) (xy 36.68014 -276.424898) (xy 37.018988 -276.424898) (xy 37.022948 -276.375844)
			(xy 37.034725 -276.32806) (xy 37.054016 -276.282784) (xy 37.080319 -276.241188) (xy 37.112954 -276.204351)
			(xy 37.151075 -276.173226) (xy 37.193696 -276.148619) (xy 37.239712 -276.131167) (xy 37.287931 -276.121323)
			(xy 37.337106 -276.119342) (xy 37.385961 -276.125274) (xy 37.433232 -276.138966) (xy 37.477694 -276.160064)
			(xy 37.518197 -276.18802) (xy 37.55369 -276.222112) (xy 37.583255 -276.261456) (xy 37.606126 -276.305033)
			(xy 37.62171 -276.351714) (xy 37.629605 -276.400291) (xy 37.6301 -276.424898) (xy 37.629605 -276.449505)
			(xy 37.62171 -276.498082) (xy 37.606126 -276.544763) (xy 37.583255 -276.58834) (xy 37.55369 -276.627684)
			(xy 37.518197 -276.661776) (xy 37.477694 -276.689732) (xy 37.433232 -276.71083) (xy 37.385961 -276.724522)
			(xy 37.337106 -276.730454) (xy 37.287931 -276.728473) (xy 37.239712 -276.718629) (xy 37.193696 -276.701177)
			(xy 37.151075 -276.67657) (xy 37.112954 -276.645445) (xy 37.080319 -276.608608) (xy 37.054016 -276.567012)
			(xy 37.034725 -276.521736) (xy 37.022948 -276.473952) (xy 37.018988 -276.424898) (xy 36.68014 -276.424898)
			(xy 36.679645 -276.449505) (xy 36.67175 -276.498082) (xy 36.656166 -276.544763) (xy 36.633295 -276.58834)
			(xy 36.60373 -276.627684) (xy 36.568237 -276.661776) (xy 36.527734 -276.689732) (xy 36.483272 -276.71083)
			(xy 36.436001 -276.724522) (xy 36.387146 -276.730454) (xy 36.337971 -276.728473) (xy 36.289752 -276.718629)
			(xy 36.243736 -276.701177) (xy 36.201115 -276.67657) (xy 36.162994 -276.645445) (xy 36.130359 -276.608608)
			(xy 36.104056 -276.567012) (xy 36.084765 -276.521736) (xy 36.072988 -276.473952) (xy 36.069028 -276.424898)
			(xy 34.598102 -276.424898) (xy 34.598102 -277.374858) (xy 36.069028 -277.374858) (xy 36.072988 -277.325804)
			(xy 36.084765 -277.27802) (xy 36.104056 -277.232744) (xy 36.130359 -277.191148) (xy 36.162994 -277.154311)
			(xy 36.201115 -277.123186) (xy 36.243736 -277.098579) (xy 36.289752 -277.081127) (xy 36.337971 -277.071283)
			(xy 36.387146 -277.069302) (xy 36.436001 -277.075234) (xy 36.483272 -277.088926) (xy 36.527734 -277.110024)
			(xy 36.568237 -277.13798) (xy 36.60373 -277.172072) (xy 36.633295 -277.211416) (xy 36.656166 -277.254993)
			(xy 36.67175 -277.301674) (xy 36.679645 -277.350251) (xy 36.68014 -277.374858) (xy 37.018988 -277.374858)
			(xy 37.022948 -277.325804) (xy 37.034725 -277.27802) (xy 37.054016 -277.232744) (xy 37.080319 -277.191148)
			(xy 37.112954 -277.154311) (xy 37.151075 -277.123186) (xy 37.193696 -277.098579) (xy 37.239712 -277.081127)
			(xy 37.287931 -277.071283) (xy 37.337106 -277.069302) (xy 37.385961 -277.075234) (xy 37.433232 -277.088926)
			(xy 37.477694 -277.110024) (xy 37.518197 -277.13798) (xy 37.55369 -277.172072) (xy 37.583255 -277.211416)
			(xy 37.606126 -277.254993) (xy 37.62171 -277.301674) (xy 37.629605 -277.350251) (xy 37.6301 -277.374858)
			(xy 37.629605 -277.399465) (xy 37.62171 -277.448042) (xy 37.606126 -277.494723) (xy 37.583255 -277.5383)
			(xy 37.55369 -277.577644) (xy 37.518197 -277.611736) (xy 37.477694 -277.639692) (xy 37.433232 -277.66079)
			(xy 37.385961 -277.674482) (xy 37.337106 -277.680414) (xy 37.287931 -277.678433) (xy 37.239712 -277.668589)
			(xy 37.193696 -277.651137) (xy 37.151075 -277.62653) (xy 37.112954 -277.595405) (xy 37.080319 -277.558568)
			(xy 37.054016 -277.516972) (xy 37.034725 -277.471696) (xy 37.022948 -277.423912) (xy 37.018988 -277.374858)
			(xy 36.68014 -277.374858) (xy 36.679645 -277.399465) (xy 36.67175 -277.448042) (xy 36.656166 -277.494723)
			(xy 36.633295 -277.5383) (xy 36.60373 -277.577644) (xy 36.568237 -277.611736) (xy 36.527734 -277.639692)
			(xy 36.483272 -277.66079) (xy 36.436001 -277.674482) (xy 36.387146 -277.680414) (xy 36.337971 -277.678433)
			(xy 36.289752 -277.668589) (xy 36.243736 -277.651137) (xy 36.201115 -277.62653) (xy 36.162994 -277.595405)
			(xy 36.130359 -277.558568) (xy 36.104056 -277.516972) (xy 36.084765 -277.471696) (xy 36.072988 -277.423912)
			(xy 36.069028 -277.374858) (xy 34.598102 -277.374858) (xy 34.598102 -278.324818) (xy 36.069028 -278.324818)
			(xy 36.072988 -278.275764) (xy 36.084765 -278.22798) (xy 36.104056 -278.182704) (xy 36.130359 -278.141108)
			(xy 36.162994 -278.104271) (xy 36.201115 -278.073146) (xy 36.243736 -278.048539) (xy 36.289752 -278.031087)
			(xy 36.337971 -278.021243) (xy 36.387146 -278.019262) (xy 36.436001 -278.025194) (xy 36.483272 -278.038886)
			(xy 36.527734 -278.059984) (xy 36.568237 -278.08794) (xy 36.60373 -278.122032) (xy 36.633295 -278.161376)
			(xy 36.656166 -278.204953) (xy 36.67175 -278.251634) (xy 36.679645 -278.300211) (xy 36.68014 -278.324818)
			(xy 37.018988 -278.324818) (xy 37.022948 -278.275764) (xy 37.034725 -278.22798) (xy 37.054016 -278.182704)
			(xy 37.080319 -278.141108) (xy 37.112954 -278.104271) (xy 37.151075 -278.073146) (xy 37.193696 -278.048539)
			(xy 37.239712 -278.031087) (xy 37.287931 -278.021243) (xy 37.337106 -278.019262) (xy 37.385961 -278.025194)
			(xy 37.433232 -278.038886) (xy 37.477694 -278.059984) (xy 37.518197 -278.08794) (xy 37.55369 -278.122032)
			(xy 37.583255 -278.161376) (xy 37.606126 -278.204953) (xy 37.62171 -278.251634) (xy 37.629605 -278.300211)
			(xy 37.6301 -278.324818) (xy 37.629605 -278.349425) (xy 37.62171 -278.398002) (xy 37.606126 -278.444683)
			(xy 37.583255 -278.48826) (xy 37.55369 -278.527604) (xy 37.518197 -278.561696) (xy 37.477694 -278.589652)
			(xy 37.433232 -278.61075) (xy 37.385961 -278.624442) (xy 37.337106 -278.630374) (xy 37.287931 -278.628393)
			(xy 37.239712 -278.618549) (xy 37.193696 -278.601097) (xy 37.151075 -278.57649) (xy 37.112954 -278.545365)
			(xy 37.080319 -278.508528) (xy 37.054016 -278.466932) (xy 37.034725 -278.421656) (xy 37.022948 -278.373872)
			(xy 37.018988 -278.324818) (xy 36.68014 -278.324818) (xy 36.679645 -278.349425) (xy 36.67175 -278.398002)
			(xy 36.656166 -278.444683) (xy 36.633295 -278.48826) (xy 36.60373 -278.527604) (xy 36.568237 -278.561696)
			(xy 36.527734 -278.589652) (xy 36.483272 -278.61075) (xy 36.436001 -278.624442) (xy 36.387146 -278.630374)
			(xy 36.337971 -278.628393) (xy 36.289752 -278.618549) (xy 36.243736 -278.601097) (xy 36.201115 -278.57649)
			(xy 36.162994 -278.545365) (xy 36.130359 -278.508528) (xy 36.104056 -278.466932) (xy 36.084765 -278.421656)
			(xy 36.072988 -278.373872) (xy 36.069028 -278.324818) (xy 34.598102 -278.324818) (xy 34.598102 -279.274778)
			(xy 36.069028 -279.274778) (xy 36.072988 -279.225724) (xy 36.084765 -279.17794) (xy 36.104056 -279.132664)
			(xy 36.130359 -279.091068) (xy 36.162994 -279.054231) (xy 36.201115 -279.023106) (xy 36.243736 -278.998499)
			(xy 36.289752 -278.981047) (xy 36.337971 -278.971203) (xy 36.387146 -278.969222) (xy 36.436001 -278.975154)
			(xy 36.483272 -278.988846) (xy 36.527734 -279.009944) (xy 36.568237 -279.0379) (xy 36.60373 -279.071992)
			(xy 36.633295 -279.111336) (xy 36.656166 -279.154913) (xy 36.67175 -279.201594) (xy 36.679645 -279.250171)
			(xy 36.68014 -279.274778) (xy 37.018988 -279.274778) (xy 37.022948 -279.225724) (xy 37.034725 -279.17794)
			(xy 37.054016 -279.132664) (xy 37.080319 -279.091068) (xy 37.112954 -279.054231) (xy 37.151075 -279.023106)
			(xy 37.193696 -278.998499) (xy 37.239712 -278.981047) (xy 37.287931 -278.971203) (xy 37.337106 -278.969222)
			(xy 37.385961 -278.975154) (xy 37.433232 -278.988846) (xy 37.477694 -279.009944) (xy 37.518197 -279.0379)
			(xy 37.55369 -279.071992) (xy 37.583255 -279.111336) (xy 37.606126 -279.154913) (xy 37.62171 -279.201594)
			(xy 37.629605 -279.250171) (xy 37.6301 -279.274778) (xy 37.629605 -279.299385) (xy 37.62171 -279.347962)
			(xy 37.606126 -279.394643) (xy 37.583255 -279.43822) (xy 37.55369 -279.477564) (xy 37.518197 -279.511656)
			(xy 37.477694 -279.539612) (xy 37.433232 -279.56071) (xy 37.385961 -279.574402) (xy 37.337106 -279.580334)
			(xy 37.287931 -279.578353) (xy 37.239712 -279.568509) (xy 37.193696 -279.551057) (xy 37.151075 -279.52645)
			(xy 37.112954 -279.495325) (xy 37.080319 -279.458488) (xy 37.054016 -279.416892) (xy 37.034725 -279.371616)
			(xy 37.022948 -279.323832) (xy 37.018988 -279.274778) (xy 36.68014 -279.274778) (xy 36.679645 -279.299385)
			(xy 36.67175 -279.347962) (xy 36.656166 -279.394643) (xy 36.633295 -279.43822) (xy 36.60373 -279.477564)
			(xy 36.568237 -279.511656) (xy 36.527734 -279.539612) (xy 36.483272 -279.56071) (xy 36.436001 -279.574402)
			(xy 36.387146 -279.580334) (xy 36.337971 -279.578353) (xy 36.289752 -279.568509) (xy 36.243736 -279.551057)
			(xy 36.201115 -279.52645) (xy 36.162994 -279.495325) (xy 36.130359 -279.458488) (xy 36.104056 -279.416892)
			(xy 36.084765 -279.371616) (xy 36.072988 -279.323832) (xy 36.069028 -279.274778) (xy 34.598102 -279.274778)
			(xy 34.598102 -279.917906) (xy 34.598356 -279.917906) (xy 34.598356 -280.224738) (xy 36.069028 -280.224738)
			(xy 36.072988 -280.175684) (xy 36.084765 -280.1279) (xy 36.104056 -280.082624) (xy 36.130359 -280.041028)
			(xy 36.162994 -280.004191) (xy 36.201115 -279.973066) (xy 36.243736 -279.948459) (xy 36.289752 -279.931007)
			(xy 36.337971 -279.921163) (xy 36.387146 -279.919182) (xy 36.436001 -279.925114) (xy 36.483272 -279.938806)
			(xy 36.527734 -279.959904) (xy 36.568237 -279.98786) (xy 36.60373 -280.021952) (xy 36.633295 -280.061296)
			(xy 36.656166 -280.104873) (xy 36.67175 -280.151554) (xy 36.679645 -280.200131) (xy 36.68014 -280.224738)
			(xy 37.018988 -280.224738) (xy 37.022948 -280.175684) (xy 37.034725 -280.1279) (xy 37.054016 -280.082624)
			(xy 37.080319 -280.041028) (xy 37.112954 -280.004191) (xy 37.151075 -279.973066) (xy 37.193696 -279.948459)
			(xy 37.239712 -279.931007) (xy 37.287931 -279.921163) (xy 37.337106 -279.919182) (xy 37.385961 -279.925114)
			(xy 37.433232 -279.938806) (xy 37.477694 -279.959904) (xy 37.518197 -279.98786) (xy 37.55369 -280.021952)
			(xy 37.583255 -280.061296) (xy 37.606126 -280.104873) (xy 37.62171 -280.151554) (xy 37.629605 -280.200131)
			(xy 37.6301 -280.224738) (xy 37.629605 -280.249345) (xy 37.62171 -280.297922) (xy 37.606126 -280.344603)
			(xy 37.583255 -280.38818) (xy 37.55369 -280.427524) (xy 37.518197 -280.461616) (xy 37.477694 -280.489572)
			(xy 37.433232 -280.51067) (xy 37.385961 -280.524362) (xy 37.337106 -280.530294) (xy 37.287931 -280.528313)
			(xy 37.239712 -280.518469) (xy 37.193696 -280.501017) (xy 37.151075 -280.47641) (xy 37.112954 -280.445285)
			(xy 37.080319 -280.408448) (xy 37.054016 -280.366852) (xy 37.034725 -280.321576) (xy 37.022948 -280.273792)
			(xy 37.018988 -280.224738) (xy 36.68014 -280.224738) (xy 36.679645 -280.249345) (xy 36.67175 -280.297922)
			(xy 36.656166 -280.344603) (xy 36.633295 -280.38818) (xy 36.60373 -280.427524) (xy 36.568237 -280.461616)
			(xy 36.527734 -280.489572) (xy 36.483272 -280.51067) (xy 36.436001 -280.524362) (xy 36.387146 -280.530294)
			(xy 36.337971 -280.528313) (xy 36.289752 -280.518469) (xy 36.243736 -280.501017) (xy 36.201115 -280.47641)
			(xy 36.162994 -280.445285) (xy 36.130359 -280.408448) (xy 36.104056 -280.366852) (xy 36.084765 -280.321576)
			(xy 36.072988 -280.273792) (xy 36.069028 -280.224738) (xy 34.598356 -280.224738) (xy 34.598356 -281.174952)
			(xy 36.069028 -281.174952) (xy 36.072988 -281.125898) (xy 36.084765 -281.078114) (xy 36.104056 -281.032838)
			(xy 36.130359 -280.991242) (xy 36.162994 -280.954405) (xy 36.201115 -280.92328) (xy 36.243736 -280.898673)
			(xy 36.289752 -280.881221) (xy 36.337971 -280.871377) (xy 36.387146 -280.869396) (xy 36.436001 -280.875328)
			(xy 36.483272 -280.88902) (xy 36.527734 -280.910118) (xy 36.568237 -280.938074) (xy 36.60373 -280.972166)
			(xy 36.633295 -281.01151) (xy 36.656166 -281.055087) (xy 36.67175 -281.101768) (xy 36.679645 -281.150345)
			(xy 36.68014 -281.174952) (xy 37.018988 -281.174952) (xy 37.022948 -281.125898) (xy 37.034725 -281.078114)
			(xy 37.054016 -281.032838) (xy 37.080319 -280.991242) (xy 37.112954 -280.954405) (xy 37.151075 -280.92328)
			(xy 37.193696 -280.898673) (xy 37.239712 -280.881221) (xy 37.287931 -280.871377) (xy 37.337106 -280.869396)
			(xy 37.385961 -280.875328) (xy 37.433232 -280.88902) (xy 37.477694 -280.910118) (xy 37.518197 -280.938074)
			(xy 37.55369 -280.972166) (xy 37.583255 -281.01151) (xy 37.606126 -281.055087) (xy 37.62171 -281.101768)
			(xy 37.629605 -281.150345) (xy 37.6301 -281.174952) (xy 37.629605 -281.199559) (xy 37.62171 -281.248136)
			(xy 37.606126 -281.294817) (xy 37.583255 -281.338394) (xy 37.55369 -281.377738) (xy 37.518197 -281.41183)
			(xy 37.477694 -281.439786) (xy 37.433232 -281.460884) (xy 37.385961 -281.474576) (xy 37.337106 -281.480508)
			(xy 37.287931 -281.478527) (xy 37.239712 -281.468683) (xy 37.193696 -281.451231) (xy 37.151075 -281.426624)
			(xy 37.112954 -281.395499) (xy 37.080319 -281.358662) (xy 37.054016 -281.317066) (xy 37.034725 -281.27179)
			(xy 37.022948 -281.224006) (xy 37.018988 -281.174952) (xy 36.68014 -281.174952) (xy 36.679645 -281.199559)
			(xy 36.67175 -281.248136) (xy 36.656166 -281.294817) (xy 36.633295 -281.338394) (xy 36.60373 -281.377738)
			(xy 36.568237 -281.41183) (xy 36.527734 -281.439786) (xy 36.483272 -281.460884) (xy 36.436001 -281.474576)
			(xy 36.387146 -281.480508) (xy 36.337971 -281.478527) (xy 36.289752 -281.468683) (xy 36.243736 -281.451231)
			(xy 36.201115 -281.426624) (xy 36.162994 -281.395499) (xy 36.130359 -281.358662) (xy 36.104056 -281.317066)
			(xy 36.084765 -281.27179) (xy 36.072988 -281.224006) (xy 36.069028 -281.174952) (xy 34.598356 -281.174952)
			(xy 34.598356 -282.124912) (xy 36.069028 -282.124912) (xy 36.072988 -282.075858) (xy 36.084765 -282.028074)
			(xy 36.104056 -281.982798) (xy 36.130359 -281.941202) (xy 36.162994 -281.904365) (xy 36.201115 -281.87324)
			(xy 36.243736 -281.848633) (xy 36.289752 -281.831181) (xy 36.337971 -281.821337) (xy 36.387146 -281.819356)
			(xy 36.436001 -281.825288) (xy 36.483272 -281.83898) (xy 36.527734 -281.860078) (xy 36.568237 -281.888034)
			(xy 36.60373 -281.922126) (xy 36.633295 -281.96147) (xy 36.656166 -282.005047) (xy 36.67175 -282.051728)
			(xy 36.679645 -282.100305) (xy 36.68014 -282.124912) (xy 37.018988 -282.124912) (xy 37.022948 -282.075858)
			(xy 37.034725 -282.028074) (xy 37.054016 -281.982798) (xy 37.080319 -281.941202) (xy 37.112954 -281.904365)
			(xy 37.151075 -281.87324) (xy 37.193696 -281.848633) (xy 37.239712 -281.831181) (xy 37.287931 -281.821337)
			(xy 37.337106 -281.819356) (xy 37.385961 -281.825288) (xy 37.433232 -281.83898) (xy 37.477694 -281.860078)
			(xy 37.518197 -281.888034) (xy 37.55369 -281.922126) (xy 37.583255 -281.96147) (xy 37.606126 -282.005047)
			(xy 37.62171 -282.051728) (xy 37.629605 -282.100305) (xy 37.6301 -282.124912) (xy 37.629605 -282.149519)
			(xy 37.62171 -282.198096) (xy 37.606126 -282.244777) (xy 37.583255 -282.288354) (xy 37.55369 -282.327698)
			(xy 37.518197 -282.36179) (xy 37.477694 -282.389746) (xy 37.433232 -282.410844) (xy 37.385961 -282.424536)
			(xy 37.337106 -282.430468) (xy 37.287931 -282.428487) (xy 37.239712 -282.418643) (xy 37.193696 -282.401191)
			(xy 37.151075 -282.376584) (xy 37.112954 -282.345459) (xy 37.080319 -282.308622) (xy 37.054016 -282.267026)
			(xy 37.034725 -282.22175) (xy 37.022948 -282.173966) (xy 37.018988 -282.124912) (xy 36.68014 -282.124912)
			(xy 36.679645 -282.149519) (xy 36.67175 -282.198096) (xy 36.656166 -282.244777) (xy 36.633295 -282.288354)
			(xy 36.60373 -282.327698) (xy 36.568237 -282.36179) (xy 36.527734 -282.389746) (xy 36.483272 -282.410844)
			(xy 36.436001 -282.424536) (xy 36.387146 -282.430468) (xy 36.337971 -282.428487) (xy 36.289752 -282.418643)
			(xy 36.243736 -282.401191) (xy 36.201115 -282.376584) (xy 36.162994 -282.345459) (xy 36.130359 -282.308622)
			(xy 36.104056 -282.267026) (xy 36.084765 -282.22175) (xy 36.072988 -282.173966) (xy 36.069028 -282.124912)
			(xy 34.598356 -282.124912) (xy 34.598356 -283.074872) (xy 36.069028 -283.074872) (xy 36.072988 -283.025818)
			(xy 36.084765 -282.978034) (xy 36.104056 -282.932758) (xy 36.130359 -282.891162) (xy 36.162994 -282.854325)
			(xy 36.201115 -282.8232) (xy 36.243736 -282.798593) (xy 36.289752 -282.781141) (xy 36.337971 -282.771297)
			(xy 36.387146 -282.769316) (xy 36.436001 -282.775248) (xy 36.483272 -282.78894) (xy 36.527734 -282.810038)
			(xy 36.568237 -282.837994) (xy 36.60373 -282.872086) (xy 36.633295 -282.91143) (xy 36.656166 -282.955007)
			(xy 36.67175 -283.001688) (xy 36.679645 -283.050265) (xy 36.68014 -283.074872) (xy 37.018988 -283.074872)
			(xy 37.022948 -283.025818) (xy 37.034725 -282.978034) (xy 37.054016 -282.932758) (xy 37.080319 -282.891162)
			(xy 37.112954 -282.854325) (xy 37.151075 -282.8232) (xy 37.193696 -282.798593) (xy 37.239712 -282.781141)
			(xy 37.287931 -282.771297) (xy 37.337106 -282.769316) (xy 37.385961 -282.775248) (xy 37.433232 -282.78894)
			(xy 37.477694 -282.810038) (xy 37.518197 -282.837994) (xy 37.55369 -282.872086) (xy 37.583255 -282.91143)
			(xy 37.606126 -282.955007) (xy 37.62171 -283.001688) (xy 37.629605 -283.050265) (xy 37.6301 -283.074872)
			(xy 37.629605 -283.099479) (xy 37.62171 -283.148056) (xy 37.606126 -283.194737) (xy 37.583255 -283.238314)
			(xy 37.55369 -283.277658) (xy 37.518197 -283.31175) (xy 37.477694 -283.339706) (xy 37.433232 -283.360804)
			(xy 37.385961 -283.374496) (xy 37.337106 -283.380428) (xy 37.287931 -283.378447) (xy 37.239712 -283.368603)
			(xy 37.193696 -283.351151) (xy 37.151075 -283.326544) (xy 37.112954 -283.295419) (xy 37.080319 -283.258582)
			(xy 37.054016 -283.216986) (xy 37.034725 -283.17171) (xy 37.022948 -283.123926) (xy 37.018988 -283.074872)
			(xy 36.68014 -283.074872) (xy 36.679645 -283.099479) (xy 36.67175 -283.148056) (xy 36.656166 -283.194737)
			(xy 36.633295 -283.238314) (xy 36.60373 -283.277658) (xy 36.568237 -283.31175) (xy 36.527734 -283.339706)
			(xy 36.483272 -283.360804) (xy 36.436001 -283.374496) (xy 36.387146 -283.380428) (xy 36.337971 -283.378447)
			(xy 36.289752 -283.368603) (xy 36.243736 -283.351151) (xy 36.201115 -283.326544) (xy 36.162994 -283.295419)
			(xy 36.130359 -283.258582) (xy 36.104056 -283.216986) (xy 36.084765 -283.17171) (xy 36.072988 -283.123926)
			(xy 36.069028 -283.074872) (xy 34.598356 -283.074872) (xy 34.598356 -284.024832) (xy 36.069028 -284.024832)
			(xy 36.072988 -283.975778) (xy 36.084765 -283.927994) (xy 36.104056 -283.882718) (xy 36.130359 -283.841122)
			(xy 36.162994 -283.804285) (xy 36.201115 -283.77316) (xy 36.243736 -283.748553) (xy 36.289752 -283.731101)
			(xy 36.337971 -283.721257) (xy 36.387146 -283.719276) (xy 36.436001 -283.725208) (xy 36.483272 -283.7389)
			(xy 36.527734 -283.759998) (xy 36.568237 -283.787954) (xy 36.60373 -283.822046) (xy 36.633295 -283.86139)
			(xy 36.656166 -283.904967) (xy 36.67175 -283.951648) (xy 36.679645 -284.000225) (xy 36.68014 -284.024832)
			(xy 37.018988 -284.024832) (xy 37.022948 -283.975778) (xy 37.034725 -283.927994) (xy 37.054016 -283.882718)
			(xy 37.080319 -283.841122) (xy 37.112954 -283.804285) (xy 37.151075 -283.77316) (xy 37.193696 -283.748553)
			(xy 37.239712 -283.731101) (xy 37.287931 -283.721257) (xy 37.337106 -283.719276) (xy 37.385961 -283.725208)
			(xy 37.433232 -283.7389) (xy 37.477694 -283.759998) (xy 37.518197 -283.787954) (xy 37.55369 -283.822046)
			(xy 37.583255 -283.86139) (xy 37.606126 -283.904967) (xy 37.62171 -283.951648) (xy 37.629605 -284.000225)
			(xy 37.6301 -284.024832) (xy 37.629605 -284.049439) (xy 37.62171 -284.098016) (xy 37.606126 -284.144697)
			(xy 37.583255 -284.188274) (xy 37.55369 -284.227618) (xy 37.518197 -284.26171) (xy 37.477694 -284.289666)
			(xy 37.433232 -284.310764) (xy 37.385961 -284.324456) (xy 37.337106 -284.330388) (xy 37.287931 -284.328407)
			(xy 37.239712 -284.318563) (xy 37.193696 -284.301111) (xy 37.151075 -284.276504) (xy 37.112954 -284.245379)
			(xy 37.080319 -284.208542) (xy 37.054016 -284.166946) (xy 37.034725 -284.12167) (xy 37.022948 -284.073886)
			(xy 37.018988 -284.024832) (xy 36.68014 -284.024832) (xy 36.679645 -284.049439) (xy 36.67175 -284.098016)
			(xy 36.656166 -284.144697) (xy 36.633295 -284.188274) (xy 36.60373 -284.227618) (xy 36.568237 -284.26171)
			(xy 36.527734 -284.289666) (xy 36.483272 -284.310764) (xy 36.436001 -284.324456) (xy 36.387146 -284.330388)
			(xy 36.337971 -284.328407) (xy 36.289752 -284.318563) (xy 36.243736 -284.301111) (xy 36.201115 -284.276504)
			(xy 36.162994 -284.245379) (xy 36.130359 -284.208542) (xy 36.104056 -284.166946) (xy 36.084765 -284.12167)
			(xy 36.072988 -284.073886) (xy 36.069028 -284.024832) (xy 34.598356 -284.024832) (xy 34.598356 -284.974792)
			(xy 36.069028 -284.974792) (xy 36.072988 -284.925738) (xy 36.084765 -284.877954) (xy 36.104056 -284.832678)
			(xy 36.130359 -284.791082) (xy 36.162994 -284.754245) (xy 36.201115 -284.72312) (xy 36.243736 -284.698513)
			(xy 36.289752 -284.681061) (xy 36.337971 -284.671217) (xy 36.387146 -284.669236) (xy 36.436001 -284.675168)
			(xy 36.483272 -284.68886) (xy 36.527734 -284.709958) (xy 36.568237 -284.737914) (xy 36.60373 -284.772006)
			(xy 36.633295 -284.81135) (xy 36.656166 -284.854927) (xy 36.67175 -284.901608) (xy 36.679645 -284.950185)
			(xy 36.68014 -284.974792) (xy 37.018988 -284.974792) (xy 37.022948 -284.925738) (xy 37.034725 -284.877954)
			(xy 37.054016 -284.832678) (xy 37.080319 -284.791082) (xy 37.112954 -284.754245) (xy 37.151075 -284.72312)
			(xy 37.193696 -284.698513) (xy 37.239712 -284.681061) (xy 37.287931 -284.671217) (xy 37.337106 -284.669236)
			(xy 37.385961 -284.675168) (xy 37.433232 -284.68886) (xy 37.477694 -284.709958) (xy 37.518197 -284.737914)
			(xy 37.55369 -284.772006) (xy 37.583255 -284.81135) (xy 37.606126 -284.854927) (xy 37.62171 -284.901608)
			(xy 37.629605 -284.950185) (xy 37.6301 -284.974792) (xy 37.629605 -284.999399) (xy 37.62171 -285.047976)
			(xy 37.606126 -285.094657) (xy 37.583255 -285.138234) (xy 37.55369 -285.177578) (xy 37.518197 -285.21167)
			(xy 37.477694 -285.239626) (xy 37.433232 -285.260724) (xy 37.385961 -285.274416) (xy 37.337106 -285.280348)
			(xy 37.287931 -285.278367) (xy 37.239712 -285.268523) (xy 37.193696 -285.251071) (xy 37.151075 -285.226464)
			(xy 37.112954 -285.195339) (xy 37.080319 -285.158502) (xy 37.054016 -285.116906) (xy 37.034725 -285.07163)
			(xy 37.022948 -285.023846) (xy 37.018988 -284.974792) (xy 36.68014 -284.974792) (xy 36.679645 -284.999399)
			(xy 36.67175 -285.047976) (xy 36.656166 -285.094657) (xy 36.633295 -285.138234) (xy 36.60373 -285.177578)
			(xy 36.568237 -285.21167) (xy 36.527734 -285.239626) (xy 36.483272 -285.260724) (xy 36.436001 -285.274416)
			(xy 36.387146 -285.280348) (xy 36.337971 -285.278367) (xy 36.289752 -285.268523) (xy 36.243736 -285.251071)
			(xy 36.201115 -285.226464) (xy 36.162994 -285.195339) (xy 36.130359 -285.158502) (xy 36.104056 -285.116906)
			(xy 36.084765 -285.07163) (xy 36.072988 -285.023846) (xy 36.069028 -284.974792) (xy 34.598356 -284.974792)
			(xy 34.598356 -285.924752) (xy 36.069028 -285.924752) (xy 36.072988 -285.875698) (xy 36.084765 -285.827914)
			(xy 36.104056 -285.782638) (xy 36.130359 -285.741042) (xy 36.162994 -285.704205) (xy 36.201115 -285.67308)
			(xy 36.243736 -285.648473) (xy 36.289752 -285.631021) (xy 36.337971 -285.621177) (xy 36.387146 -285.619196)
			(xy 36.436001 -285.625128) (xy 36.483272 -285.63882) (xy 36.527734 -285.659918) (xy 36.568237 -285.687874)
			(xy 36.60373 -285.721966) (xy 36.633295 -285.76131) (xy 36.656166 -285.804887) (xy 36.67175 -285.851568)
			(xy 36.679645 -285.900145) (xy 36.68014 -285.924752) (xy 37.018988 -285.924752) (xy 37.022948 -285.875698)
			(xy 37.034725 -285.827914) (xy 37.054016 -285.782638) (xy 37.080319 -285.741042) (xy 37.112954 -285.704205)
			(xy 37.151075 -285.67308) (xy 37.193696 -285.648473) (xy 37.239712 -285.631021) (xy 37.287931 -285.621177)
			(xy 37.337106 -285.619196) (xy 37.385961 -285.625128) (xy 37.433232 -285.63882) (xy 37.477694 -285.659918)
			(xy 37.518197 -285.687874) (xy 37.55369 -285.721966) (xy 37.583255 -285.76131) (xy 37.606126 -285.804887)
			(xy 37.62171 -285.851568) (xy 37.629605 -285.900145) (xy 37.6301 -285.924752) (xy 37.629605 -285.949359)
			(xy 37.62171 -285.997936) (xy 37.606126 -286.044617) (xy 37.583255 -286.088194) (xy 37.55369 -286.127538)
			(xy 37.518197 -286.16163) (xy 37.477694 -286.189586) (xy 37.433232 -286.210684) (xy 37.385961 -286.224376)
			(xy 37.337106 -286.230308) (xy 37.287931 -286.228327) (xy 37.239712 -286.218483) (xy 37.193696 -286.201031)
			(xy 37.151075 -286.176424) (xy 37.112954 -286.145299) (xy 37.080319 -286.108462) (xy 37.054016 -286.066866)
			(xy 37.034725 -286.02159) (xy 37.022948 -285.973806) (xy 37.018988 -285.924752) (xy 36.68014 -285.924752)
			(xy 36.679645 -285.949359) (xy 36.67175 -285.997936) (xy 36.656166 -286.044617) (xy 36.633295 -286.088194)
			(xy 36.60373 -286.127538) (xy 36.568237 -286.16163) (xy 36.527734 -286.189586) (xy 36.483272 -286.210684)
			(xy 36.436001 -286.224376) (xy 36.387146 -286.230308) (xy 36.337971 -286.228327) (xy 36.289752 -286.218483)
			(xy 36.243736 -286.201031) (xy 36.201115 -286.176424) (xy 36.162994 -286.145299) (xy 36.130359 -286.108462)
			(xy 36.104056 -286.066866) (xy 36.084765 -286.02159) (xy 36.072988 -285.973806) (xy 36.069028 -285.924752)
			(xy 34.598356 -285.924752) (xy 34.598356 -286.874966) (xy 36.069028 -286.874966) (xy 36.072988 -286.825912)
			(xy 36.084765 -286.778128) (xy 36.104056 -286.732852) (xy 36.130359 -286.691256) (xy 36.162994 -286.654419)
			(xy 36.201115 -286.623294) (xy 36.243736 -286.598687) (xy 36.289752 -286.581235) (xy 36.337971 -286.571391)
			(xy 36.387146 -286.56941) (xy 36.436001 -286.575342) (xy 36.483272 -286.589034) (xy 36.527734 -286.610132)
			(xy 36.568237 -286.638088) (xy 36.60373 -286.67218) (xy 36.633295 -286.711524) (xy 36.656166 -286.755101)
			(xy 36.67175 -286.801782) (xy 36.679645 -286.850359) (xy 36.68014 -286.874966) (xy 37.018988 -286.874966)
			(xy 37.022948 -286.825912) (xy 37.034725 -286.778128) (xy 37.054016 -286.732852) (xy 37.080319 -286.691256)
			(xy 37.112954 -286.654419) (xy 37.151075 -286.623294) (xy 37.193696 -286.598687) (xy 37.239712 -286.581235)
			(xy 37.287931 -286.571391) (xy 37.337106 -286.56941) (xy 37.385961 -286.575342) (xy 37.433232 -286.589034)
			(xy 37.477694 -286.610132) (xy 37.518197 -286.638088) (xy 37.55369 -286.67218) (xy 37.583255 -286.711524)
			(xy 37.606126 -286.755101) (xy 37.62171 -286.801782) (xy 37.629605 -286.850359) (xy 37.6301 -286.874966)
			(xy 37.629605 -286.899573) (xy 37.62171 -286.94815) (xy 37.606126 -286.994831) (xy 37.583255 -287.038408)
			(xy 37.55369 -287.077752) (xy 37.518197 -287.111844) (xy 37.477694 -287.1398) (xy 37.433232 -287.160898)
			(xy 37.385961 -287.17459) (xy 37.337106 -287.180522) (xy 37.287931 -287.178541) (xy 37.239712 -287.168697)
			(xy 37.193696 -287.151245) (xy 37.151075 -287.126638) (xy 37.112954 -287.095513) (xy 37.080319 -287.058676)
			(xy 37.054016 -287.01708) (xy 37.034725 -286.971804) (xy 37.022948 -286.92402) (xy 37.018988 -286.874966)
			(xy 36.68014 -286.874966) (xy 36.679645 -286.899573) (xy 36.67175 -286.94815) (xy 36.656166 -286.994831)
			(xy 36.633295 -287.038408) (xy 36.60373 -287.077752) (xy 36.568237 -287.111844) (xy 36.527734 -287.1398)
			(xy 36.483272 -287.160898) (xy 36.436001 -287.17459) (xy 36.387146 -287.180522) (xy 36.337971 -287.178541)
			(xy 36.289752 -287.168697) (xy 36.243736 -287.151245) (xy 36.201115 -287.126638) (xy 36.162994 -287.095513)
			(xy 36.130359 -287.058676) (xy 36.104056 -287.01708) (xy 36.084765 -286.971804) (xy 36.072988 -286.92402)
			(xy 36.069028 -286.874966) (xy 34.598356 -286.874966) (xy 34.598356 -287.824926) (xy 36.069028 -287.824926)
			(xy 36.072988 -287.775872) (xy 36.084765 -287.728088) (xy 36.104056 -287.682812) (xy 36.130359 -287.641216)
			(xy 36.162994 -287.604379) (xy 36.201115 -287.573254) (xy 36.243736 -287.548647) (xy 36.289752 -287.531195)
			(xy 36.337971 -287.521351) (xy 36.387146 -287.51937) (xy 36.436001 -287.525302) (xy 36.483272 -287.538994)
			(xy 36.527734 -287.560092) (xy 36.568237 -287.588048) (xy 36.60373 -287.62214) (xy 36.633295 -287.661484)
			(xy 36.656166 -287.705061) (xy 36.67175 -287.751742) (xy 36.679645 -287.800319) (xy 36.68014 -287.824926)
			(xy 37.018988 -287.824926) (xy 37.022948 -287.775872) (xy 37.034725 -287.728088) (xy 37.054016 -287.682812)
			(xy 37.080319 -287.641216) (xy 37.112954 -287.604379) (xy 37.151075 -287.573254) (xy 37.193696 -287.548647)
			(xy 37.239712 -287.531195) (xy 37.287931 -287.521351) (xy 37.337106 -287.51937) (xy 37.385961 -287.525302)
			(xy 37.433232 -287.538994) (xy 37.477694 -287.560092) (xy 37.518197 -287.588048) (xy 37.55369 -287.62214)
			(xy 37.583255 -287.661484) (xy 37.606126 -287.705061) (xy 37.62171 -287.751742) (xy 37.629605 -287.800319)
			(xy 37.6301 -287.824926) (xy 37.629605 -287.849533) (xy 37.62171 -287.89811) (xy 37.606126 -287.944791)
			(xy 37.583255 -287.988368) (xy 37.55369 -288.027712) (xy 37.518197 -288.061804) (xy 37.477694 -288.08976)
			(xy 37.433232 -288.110858) (xy 37.385961 -288.12455) (xy 37.337106 -288.130482) (xy 37.287931 -288.128501)
			(xy 37.239712 -288.118657) (xy 37.193696 -288.101205) (xy 37.151075 -288.076598) (xy 37.112954 -288.045473)
			(xy 37.080319 -288.008636) (xy 37.054016 -287.96704) (xy 37.034725 -287.921764) (xy 37.022948 -287.87398)
			(xy 37.018988 -287.824926) (xy 36.68014 -287.824926) (xy 36.679645 -287.849533) (xy 36.67175 -287.89811)
			(xy 36.656166 -287.944791) (xy 36.633295 -287.988368) (xy 36.60373 -288.027712) (xy 36.568237 -288.061804)
			(xy 36.527734 -288.08976) (xy 36.483272 -288.110858) (xy 36.436001 -288.12455) (xy 36.387146 -288.130482)
			(xy 36.337971 -288.128501) (xy 36.289752 -288.118657) (xy 36.243736 -288.101205) (xy 36.201115 -288.076598)
			(xy 36.162994 -288.045473) (xy 36.130359 -288.008636) (xy 36.104056 -287.96704) (xy 36.084765 -287.921764)
			(xy 36.072988 -287.87398) (xy 36.069028 -287.824926) (xy 34.598356 -287.824926) (xy 34.598356 -288.774886)
			(xy 35.119068 -288.774886) (xy 35.123028 -288.725832) (xy 35.134805 -288.678048) (xy 35.154096 -288.632772)
			(xy 35.180399 -288.591176) (xy 35.213034 -288.554339) (xy 35.251155 -288.523214) (xy 35.293776 -288.498607)
			(xy 35.339792 -288.481155) (xy 35.388011 -288.471311) (xy 35.437186 -288.46933) (xy 35.486041 -288.475262)
			(xy 35.533312 -288.488954) (xy 35.577774 -288.510052) (xy 35.618277 -288.538008) (xy 35.65377 -288.5721)
			(xy 35.683335 -288.611444) (xy 35.706206 -288.655021) (xy 35.72179 -288.701702) (xy 35.729685 -288.750279)
			(xy 35.73018 -288.774886) (xy 35.729685 -288.799493) (xy 35.729535 -288.800413) (xy 36.0443 -288.800413)
			(xy 36.0443 -288.748387) (xy 36.052439 -288.697003) (xy 36.068516 -288.647524) (xy 36.092136 -288.60117)
			(xy 36.122718 -288.559082) (xy 36.159507 -288.522297) (xy 36.201598 -288.49172) (xy 36.247954 -288.468104)
			(xy 36.297434 -288.452031) (xy 36.348819 -288.443897) (xy 36.374832 -288.443416) (xy 37.324792 -288.443416)
			(xy 37.3508 -288.443943) (xy 37.402175 -288.452079) (xy 37.451646 -288.468151) (xy 37.497993 -288.491765)
			(xy 37.540075 -288.522339) (xy 37.576856 -288.559119) (xy 37.60743 -288.601201) (xy 37.631045 -288.647547)
			(xy 37.647119 -288.697017) (xy 37.655257 -288.748392) (xy 37.655257 -288.774886) (xy 37.969202 -288.774886)
			(xy 37.973162 -288.725832) (xy 37.984939 -288.678048) (xy 38.00423 -288.632772) (xy 38.030533 -288.591176)
			(xy 38.063168 -288.554339) (xy 38.101289 -288.523214) (xy 38.14391 -288.498607) (xy 38.189926 -288.481155)
			(xy 38.238145 -288.471311) (xy 38.28732 -288.46933) (xy 38.336175 -288.475262) (xy 38.383446 -288.488954)
			(xy 38.427908 -288.510052) (xy 38.468411 -288.538008) (xy 38.503904 -288.5721) (xy 38.533469 -288.611444)
			(xy 38.55634 -288.655021) (xy 38.571924 -288.701702) (xy 38.579819 -288.750279) (xy 38.580314 -288.774886)
			(xy 38.919162 -288.774886) (xy 38.923122 -288.725832) (xy 38.934899 -288.678048) (xy 38.95419 -288.632772)
			(xy 38.980493 -288.591176) (xy 39.013128 -288.554339) (xy 39.051249 -288.523214) (xy 39.09387 -288.498607)
			(xy 39.139886 -288.481155) (xy 39.188105 -288.471311) (xy 39.23728 -288.46933) (xy 39.286135 -288.475262)
			(xy 39.333406 -288.488954) (xy 39.377868 -288.510052) (xy 39.418371 -288.538008) (xy 39.453864 -288.5721)
			(xy 39.483429 -288.611444) (xy 39.5063 -288.655021) (xy 39.521884 -288.701702) (xy 39.529779 -288.750279)
			(xy 39.530274 -288.774886) (xy 39.529779 -288.799493) (xy 39.521884 -288.84807) (xy 39.5063 -288.894751)
			(xy 39.483429 -288.938328) (xy 39.453864 -288.977672) (xy 39.418371 -289.011764) (xy 39.377868 -289.03972)
			(xy 39.333406 -289.060818) (xy 39.286135 -289.07451) (xy 39.23728 -289.080442) (xy 39.188105 -289.078461)
			(xy 39.139886 -289.068617) (xy 39.09387 -289.051165) (xy 39.051249 -289.026558) (xy 39.013128 -288.995433)
			(xy 38.980493 -288.958596) (xy 38.95419 -288.917) (xy 38.934899 -288.871724) (xy 38.923122 -288.82394)
			(xy 38.919162 -288.774886) (xy 38.580314 -288.774886) (xy 38.579819 -288.799493) (xy 38.571924 -288.84807)
			(xy 38.55634 -288.894751) (xy 38.533469 -288.938328) (xy 38.503904 -288.977672) (xy 38.468411 -289.011764)
			(xy 38.427908 -289.03972) (xy 38.383446 -289.060818) (xy 38.336175 -289.07451) (xy 38.28732 -289.080442)
			(xy 38.238145 -289.078461) (xy 38.189926 -289.068617) (xy 38.14391 -289.051165) (xy 38.101289 -289.026558)
			(xy 38.063168 -288.995433) (xy 38.030533 -288.958596) (xy 38.00423 -288.917) (xy 37.984939 -288.871724)
			(xy 37.973162 -288.82394) (xy 37.969202 -288.774886) (xy 37.655257 -288.774886) (xy 37.655257 -288.800408)
			(xy 37.647119 -288.851783) (xy 37.631045 -288.901253) (xy 37.60743 -288.947599) (xy 37.576856 -288.989681)
			(xy 37.540075 -289.026461) (xy 37.497993 -289.057035) (xy 37.451646 -289.080649) (xy 37.402175 -289.096721)
			(xy 37.3508 -289.104857) (xy 37.324792 -289.10534) (xy 36.374832 -289.10534) (xy 36.348819 -289.104903)
			(xy 36.297434 -289.096769) (xy 36.247954 -289.080696) (xy 36.201598 -289.05708) (xy 36.159507 -289.026503)
			(xy 36.122718 -288.989718) (xy 36.092136 -288.94763) (xy 36.068516 -288.901276) (xy 36.052439 -288.851797)
			(xy 36.0443 -288.800413) (xy 35.729535 -288.800413) (xy 35.72179 -288.84807) (xy 35.706206 -288.894751)
			(xy 35.683335 -288.938328) (xy 35.65377 -288.977672) (xy 35.618277 -289.011764) (xy 35.577774 -289.03972)
			(xy 35.533312 -289.060818) (xy 35.486041 -289.07451) (xy 35.437186 -289.080442) (xy 35.388011 -289.078461)
			(xy 35.339792 -289.068617) (xy 35.293776 -289.051165) (xy 35.251155 -289.026558) (xy 35.213034 -288.995433)
			(xy 35.180399 -288.958596) (xy 35.154096 -288.917) (xy 35.134805 -288.871724) (xy 35.123028 -288.82394)
			(xy 35.119068 -288.774886) (xy 34.598356 -288.774886) (xy 34.598356 -289.1028) (xy 34.598781 -289.112869)
			(xy 34.606501 -289.131468) (xy 34.613342 -289.138868) (xy 35.19932 -289.724846) (xy 36.069028 -289.724846)
			(xy 36.072988 -289.675792) (xy 36.084765 -289.628008) (xy 36.104056 -289.582732) (xy 36.130359 -289.541136)
			(xy 36.162994 -289.504299) (xy 36.201115 -289.473174) (xy 36.243736 -289.448567) (xy 36.289752 -289.431115)
			(xy 36.337971 -289.421271) (xy 36.387146 -289.41929) (xy 36.436001 -289.425222) (xy 36.483272 -289.438914)
			(xy 36.527734 -289.460012) (xy 36.568237 -289.487968) (xy 36.60373 -289.52206) (xy 36.633295 -289.561404)
			(xy 36.656166 -289.604981) (xy 36.67175 -289.651662) (xy 36.679645 -289.700239) (xy 36.68014 -289.724846)
			(xy 37.018988 -289.724846) (xy 37.022948 -289.675792) (xy 37.034725 -289.628008) (xy 37.054016 -289.582732)
			(xy 37.080319 -289.541136) (xy 37.112954 -289.504299) (xy 37.151075 -289.473174) (xy 37.193696 -289.448567)
			(xy 37.239712 -289.431115) (xy 37.287931 -289.421271) (xy 37.337106 -289.41929) (xy 37.385961 -289.425222)
			(xy 37.433232 -289.438914) (xy 37.477694 -289.460012) (xy 37.518197 -289.487968) (xy 37.55369 -289.52206)
			(xy 37.583255 -289.561404) (xy 37.606126 -289.604981) (xy 37.62171 -289.651662) (xy 37.629605 -289.700239)
			(xy 37.6301 -289.724846) (xy 37.969202 -289.724846) (xy 37.973162 -289.675792) (xy 37.984939 -289.628008)
			(xy 38.00423 -289.582732) (xy 38.030533 -289.541136) (xy 38.063168 -289.504299) (xy 38.101289 -289.473174)
			(xy 38.14391 -289.448567) (xy 38.189926 -289.431115) (xy 38.238145 -289.421271) (xy 38.28732 -289.41929)
			(xy 38.336175 -289.425222) (xy 38.383446 -289.438914) (xy 38.427908 -289.460012) (xy 38.468411 -289.487968)
			(xy 38.503904 -289.52206) (xy 38.533469 -289.561404) (xy 38.55634 -289.604981) (xy 38.571924 -289.651662)
			(xy 38.579819 -289.700239) (xy 38.580314 -289.724846) (xy 38.919162 -289.724846) (xy 38.923122 -289.675792)
			(xy 38.934899 -289.628008) (xy 38.95419 -289.582732) (xy 38.980493 -289.541136) (xy 39.013128 -289.504299)
			(xy 39.051249 -289.473174) (xy 39.09387 -289.448567) (xy 39.139886 -289.431115) (xy 39.188105 -289.421271)
			(xy 39.23728 -289.41929) (xy 39.286135 -289.425222) (xy 39.333406 -289.438914) (xy 39.377868 -289.460012)
			(xy 39.418371 -289.487968) (xy 39.453864 -289.52206) (xy 39.483429 -289.561404) (xy 39.5063 -289.604981)
			(xy 39.521884 -289.651662) (xy 39.529779 -289.700239) (xy 39.530274 -289.724846) (xy 39.869122 -289.724846)
			(xy 39.873082 -289.675792) (xy 39.884859 -289.628008) (xy 39.90415 -289.582732) (xy 39.930453 -289.541136)
			(xy 39.963088 -289.504299) (xy 40.001209 -289.473174) (xy 40.04383 -289.448567) (xy 40.089846 -289.431115)
			(xy 40.138065 -289.421271) (xy 40.18724 -289.41929) (xy 40.236095 -289.425222) (xy 40.283366 -289.438914)
			(xy 40.327828 -289.460012) (xy 40.368331 -289.487968) (xy 40.403824 -289.52206) (xy 40.433389 -289.561404)
			(xy 40.45626 -289.604981) (xy 40.471844 -289.651662) (xy 40.479739 -289.700239) (xy 40.480234 -289.724846)
			(xy 40.479739 -289.749453) (xy 40.471844 -289.79803) (xy 40.45626 -289.844711) (xy 40.433389 -289.888288)
			(xy 40.403824 -289.927632) (xy 40.368331 -289.961724) (xy 40.327828 -289.98968) (xy 40.283366 -290.010778)
			(xy 40.236095 -290.02447) (xy 40.18724 -290.030402) (xy 40.138065 -290.028421) (xy 40.089846 -290.018577)
			(xy 40.04383 -290.001125) (xy 40.001209 -289.976518) (xy 39.963088 -289.945393) (xy 39.930453 -289.908556)
			(xy 39.90415 -289.86696) (xy 39.884859 -289.821684) (xy 39.873082 -289.7739) (xy 39.869122 -289.724846)
			(xy 39.530274 -289.724846) (xy 39.529779 -289.749453) (xy 39.521884 -289.79803) (xy 39.5063 -289.844711)
			(xy 39.483429 -289.888288) (xy 39.453864 -289.927632) (xy 39.418371 -289.961724) (xy 39.377868 -289.98968)
			(xy 39.333406 -290.010778) (xy 39.286135 -290.02447) (xy 39.23728 -290.030402) (xy 39.188105 -290.028421)
			(xy 39.139886 -290.018577) (xy 39.09387 -290.001125) (xy 39.051249 -289.976518) (xy 39.013128 -289.945393)
			(xy 38.980493 -289.908556) (xy 38.95419 -289.86696) (xy 38.934899 -289.821684) (xy 38.923122 -289.7739)
			(xy 38.919162 -289.724846) (xy 38.580314 -289.724846) (xy 38.579819 -289.749453) (xy 38.571924 -289.79803)
			(xy 38.55634 -289.844711) (xy 38.533469 -289.888288) (xy 38.503904 -289.927632) (xy 38.468411 -289.961724)
			(xy 38.427908 -289.98968) (xy 38.383446 -290.010778) (xy 38.336175 -290.02447) (xy 38.28732 -290.030402)
			(xy 38.238145 -290.028421) (xy 38.189926 -290.018577) (xy 38.14391 -290.001125) (xy 38.101289 -289.976518)
			(xy 38.063168 -289.945393) (xy 38.030533 -289.908556) (xy 38.00423 -289.86696) (xy 37.984939 -289.821684)
			(xy 37.973162 -289.7739) (xy 37.969202 -289.724846) (xy 37.6301 -289.724846) (xy 37.629605 -289.749453)
			(xy 37.62171 -289.79803) (xy 37.606126 -289.844711) (xy 37.583255 -289.888288) (xy 37.55369 -289.927632)
			(xy 37.518197 -289.961724) (xy 37.477694 -289.98968) (xy 37.433232 -290.010778) (xy 37.385961 -290.02447)
			(xy 37.337106 -290.030402) (xy 37.287931 -290.028421) (xy 37.239712 -290.018577) (xy 37.193696 -290.001125)
			(xy 37.151075 -289.976518) (xy 37.112954 -289.945393) (xy 37.080319 -289.908556) (xy 37.054016 -289.86696)
			(xy 37.034725 -289.821684) (xy 37.022948 -289.7739) (xy 37.018988 -289.724846) (xy 36.68014 -289.724846)
			(xy 36.679645 -289.749453) (xy 36.67175 -289.79803) (xy 36.656166 -289.844711) (xy 36.633295 -289.888288)
			(xy 36.60373 -289.927632) (xy 36.568237 -289.961724) (xy 36.527734 -289.98968) (xy 36.483272 -290.010778)
			(xy 36.436001 -290.02447) (xy 36.387146 -290.030402) (xy 36.337971 -290.028421) (xy 36.289752 -290.018577)
			(xy 36.243736 -290.001125) (xy 36.201115 -289.976518) (xy 36.162994 -289.945393) (xy 36.130359 -289.908556)
			(xy 36.104056 -289.86696) (xy 36.084765 -289.821684) (xy 36.072988 -289.7739) (xy 36.069028 -289.724846)
			(xy 35.19932 -289.724846) (xy 35.959034 -290.48456) (xy 35.961574 -290.486846) (xy 35.967582 -290.491652)
			(xy 35.981659 -290.49784) (xy 35.98926 -290.499038) (xy 35.998404 -290.499292) (xy 36.020756 -290.497768)
			(xy 36.074858 -290.494212) (xy 36.085627 -290.492957) (xy 36.104699 -290.482689) (xy 36.111688 -290.4744)
			(xy 36.127455 -290.454523) (xy 36.164012 -290.419347) (xy 36.205506 -290.390159) (xy 36.250968 -290.367641)
			(xy 36.299331 -290.352321) (xy 36.349466 -290.344557) (xy 36.374832 -290.344098) (xy 36.400817 -290.34461)
			(xy 36.452148 -290.352745) (xy 36.501574 -290.368808) (xy 36.547878 -290.392406) (xy 36.589921 -290.422956)
			(xy 36.626668 -290.459708) (xy 36.657214 -290.501754) (xy 36.680806 -290.548062) (xy 36.696864 -290.597489)
			(xy 36.704993 -290.648821) (xy 36.70554 -290.674806) (xy 37.018988 -290.674806) (xy 37.022948 -290.625752)
			(xy 37.034725 -290.577968) (xy 37.054016 -290.532692) (xy 37.080319 -290.491096) (xy 37.112954 -290.454259)
			(xy 37.151075 -290.423134) (xy 37.193696 -290.398527) (xy 37.239712 -290.381075) (xy 37.287931 -290.371231)
			(xy 37.337106 -290.36925) (xy 37.385961 -290.375182) (xy 37.433232 -290.388874) (xy 37.477694 -290.409972)
			(xy 37.518197 -290.437928) (xy 37.55369 -290.47202) (xy 37.583255 -290.511364) (xy 37.606126 -290.554941)
			(xy 37.62171 -290.601622) (xy 37.629605 -290.650199) (xy 37.6301 -290.674806) (xy 37.969202 -290.674806)
			(xy 37.973162 -290.625752) (xy 37.984939 -290.577968) (xy 38.00423 -290.532692) (xy 38.030533 -290.491096)
			(xy 38.063168 -290.454259) (xy 38.101289 -290.423134) (xy 38.14391 -290.398527) (xy 38.189926 -290.381075)
			(xy 38.238145 -290.371231) (xy 38.28732 -290.36925) (xy 38.336175 -290.375182) (xy 38.383446 -290.388874)
			(xy 38.427908 -290.409972) (xy 38.468411 -290.437928) (xy 38.503904 -290.47202) (xy 38.533469 -290.511364)
			(xy 38.55634 -290.554941) (xy 38.571924 -290.601622) (xy 38.579819 -290.650199) (xy 38.580314 -290.674806)
			(xy 40.819082 -290.674806) (xy 40.823042 -290.625752) (xy 40.834819 -290.577968) (xy 40.85411 -290.532692)
			(xy 40.880413 -290.491096) (xy 40.913048 -290.454259) (xy 40.951169 -290.423134) (xy 40.99379 -290.398527)
			(xy 41.039806 -290.381075) (xy 41.088025 -290.371231) (xy 41.1372 -290.36925) (xy 41.186055 -290.375182)
			(xy 41.233326 -290.388874) (xy 41.277788 -290.409972) (xy 41.318291 -290.437928) (xy 41.353784 -290.47202)
			(xy 41.383349 -290.511364) (xy 41.40622 -290.554941) (xy 41.421804 -290.601622) (xy 41.429699 -290.650199)
			(xy 41.430194 -290.674806) (xy 41.429699 -290.699413) (xy 41.421804 -290.74799) (xy 41.40622 -290.794671)
			(xy 41.383349 -290.838248) (xy 41.353784 -290.877592) (xy 41.318291 -290.911684) (xy 41.277788 -290.93964)
			(xy 41.233326 -290.960738) (xy 41.186055 -290.97443) (xy 41.1372 -290.980362) (xy 41.088025 -290.978381)
			(xy 41.039806 -290.968537) (xy 40.99379 -290.951085) (xy 40.951169 -290.926478) (xy 40.913048 -290.895353)
			(xy 40.880413 -290.858516) (xy 40.85411 -290.81692) (xy 40.834819 -290.771644) (xy 40.823042 -290.72386)
			(xy 40.819082 -290.674806) (xy 38.580314 -290.674806) (xy 38.579819 -290.699413) (xy 38.571924 -290.74799)
			(xy 38.55634 -290.794671) (xy 38.533469 -290.838248) (xy 38.503904 -290.877592) (xy 38.468411 -290.911684)
			(xy 38.427908 -290.93964) (xy 38.383446 -290.960738) (xy 38.336175 -290.97443) (xy 38.28732 -290.980362)
			(xy 38.238145 -290.978381) (xy 38.189926 -290.968537) (xy 38.14391 -290.951085) (xy 38.101289 -290.926478)
			(xy 38.063168 -290.895353) (xy 38.030533 -290.858516) (xy 38.00423 -290.81692) (xy 37.984939 -290.771644)
			(xy 37.973162 -290.72386) (xy 37.969202 -290.674806) (xy 37.6301 -290.674806) (xy 37.629605 -290.699413)
			(xy 37.62171 -290.74799) (xy 37.606126 -290.794671) (xy 37.583255 -290.838248) (xy 37.55369 -290.877592)
			(xy 37.518197 -290.911684) (xy 37.477694 -290.93964) (xy 37.433232 -290.960738) (xy 37.385961 -290.97443)
			(xy 37.337106 -290.980362) (xy 37.287931 -290.978381) (xy 37.239712 -290.968537) (xy 37.193696 -290.951085)
			(xy 37.151075 -290.926478) (xy 37.112954 -290.895353) (xy 37.080319 -290.858516) (xy 37.054016 -290.81692)
			(xy 37.034725 -290.771644) (xy 37.022948 -290.72386) (xy 37.018988 -290.674806) (xy 36.70554 -290.674806)
			(xy 36.705086 -290.700176) (xy 36.697351 -290.750323) (xy 36.682048 -290.7987) (xy 36.659536 -290.844172)
			(xy 36.630343 -290.885673) (xy 36.595154 -290.922229) (xy 36.575238 -290.93795) (xy 36.566948 -290.944936)
			(xy 36.556688 -290.964012) (xy 36.555426 -290.97478) (xy 36.55187 -291.028882) (xy 36.550346 -291.051234)
			(xy 36.5506 -291.060378) (xy 36.551708 -291.068003) (xy 36.557919 -291.082095) (xy 36.562792 -291.088064)
			(xy 36.565078 -291.090604) (xy 36.908994 -291.43452) (xy 36.911534 -291.436806) (xy 36.917539 -291.44162)
			(xy 36.931614 -291.447824) (xy 36.93922 -291.448998) (xy 36.948364 -291.449252) (xy 36.970716 -291.447728)
			(xy 37.024818 -291.444172) (xy 37.035589 -291.442923) (xy 37.054668 -291.432658) (xy 37.061648 -291.42436)
			(xy 37.077418 -291.404489) (xy 37.113978 -291.369323) (xy 37.155474 -291.340146) (xy 37.200935 -291.317639)
			(xy 37.249297 -291.30233) (xy 37.299428 -291.294576) (xy 37.324792 -291.294058) (xy 37.350781 -291.294567)
			(xy 37.402118 -291.302696) (xy 37.451552 -291.318756) (xy 37.497865 -291.342351) (xy 37.539917 -291.3729)
			(xy 37.576673 -291.409651) (xy 37.607227 -291.451699) (xy 37.630828 -291.498009) (xy 37.646894 -291.547441)
			(xy 37.65503 -291.598777) (xy 37.6555 -291.624766) (xy 37.969202 -291.624766) (xy 37.973162 -291.575712)
			(xy 37.984939 -291.527928) (xy 38.00423 -291.482652) (xy 38.030533 -291.441056) (xy 38.063168 -291.404219)
			(xy 38.101289 -291.373094) (xy 38.14391 -291.348487) (xy 38.189926 -291.331035) (xy 38.238145 -291.321191)
			(xy 38.28732 -291.31921) (xy 38.336175 -291.325142) (xy 38.383446 -291.338834) (xy 38.427908 -291.359932)
			(xy 38.468411 -291.387888) (xy 38.503904 -291.42198) (xy 38.533469 -291.461324) (xy 38.55634 -291.504901)
			(xy 38.571924 -291.551582) (xy 38.579819 -291.600159) (xy 38.580314 -291.624766) (xy 40.819082 -291.624766)
			(xy 40.823042 -291.575712) (xy 40.834819 -291.527928) (xy 40.85411 -291.482652) (xy 40.880413 -291.441056)
			(xy 40.913048 -291.404219) (xy 40.951169 -291.373094) (xy 40.99379 -291.348487) (xy 41.039806 -291.331035)
			(xy 41.088025 -291.321191) (xy 41.1372 -291.31921) (xy 41.186055 -291.325142) (xy 41.233326 -291.338834)
			(xy 41.277788 -291.359932) (xy 41.318291 -291.387888) (xy 41.353784 -291.42198) (xy 41.383349 -291.461324)
			(xy 41.40622 -291.504901) (xy 41.421804 -291.551582) (xy 41.429699 -291.600159) (xy 41.430194 -291.624766)
			(xy 41.769042 -291.624766) (xy 41.773002 -291.575712) (xy 41.784779 -291.527928) (xy 41.80407 -291.482652)
			(xy 41.830373 -291.441056) (xy 41.863008 -291.404219) (xy 41.901129 -291.373094) (xy 41.94375 -291.348487)
			(xy 41.989766 -291.331035) (xy 42.037985 -291.321191) (xy 42.08716 -291.31921) (xy 42.136015 -291.325142)
			(xy 42.183286 -291.338834) (xy 42.227748 -291.359932) (xy 42.268251 -291.387888) (xy 42.303744 -291.42198)
			(xy 42.333309 -291.461324) (xy 42.35618 -291.504901) (xy 42.371764 -291.551582) (xy 42.379659 -291.600159)
			(xy 42.380154 -291.624766) (xy 42.379659 -291.649373) (xy 42.371764 -291.69795) (xy 42.35618 -291.744631)
			(xy 42.333309 -291.788208) (xy 42.303744 -291.827552) (xy 42.268251 -291.861644) (xy 42.227748 -291.8896)
			(xy 42.183286 -291.910698) (xy 42.136015 -291.92439) (xy 42.08716 -291.930322) (xy 42.037985 -291.928341)
			(xy 41.989766 -291.918497) (xy 41.94375 -291.901045) (xy 41.901129 -291.876438) (xy 41.863008 -291.845313)
			(xy 41.830373 -291.808476) (xy 41.80407 -291.76688) (xy 41.784779 -291.721604) (xy 41.773002 -291.67382)
			(xy 41.769042 -291.624766) (xy 41.430194 -291.624766) (xy 41.429699 -291.649373) (xy 41.421804 -291.69795)
			(xy 41.40622 -291.744631) (xy 41.383349 -291.788208) (xy 41.353784 -291.827552) (xy 41.318291 -291.861644)
			(xy 41.277788 -291.8896) (xy 41.233326 -291.910698) (xy 41.186055 -291.92439) (xy 41.1372 -291.930322)
			(xy 41.088025 -291.928341) (xy 41.039806 -291.918497) (xy 40.99379 -291.901045) (xy 40.951169 -291.876438)
			(xy 40.913048 -291.845313) (xy 40.880413 -291.808476) (xy 40.85411 -291.76688) (xy 40.834819 -291.721604)
			(xy 40.823042 -291.67382) (xy 40.819082 -291.624766) (xy 38.580314 -291.624766) (xy 38.579819 -291.649373)
			(xy 38.571924 -291.69795) (xy 38.55634 -291.744631) (xy 38.533469 -291.788208) (xy 38.503904 -291.827552)
			(xy 38.468411 -291.861644) (xy 38.427908 -291.8896) (xy 38.383446 -291.910698) (xy 38.336175 -291.92439)
			(xy 38.28732 -291.930322) (xy 38.238145 -291.928341) (xy 38.189926 -291.918497) (xy 38.14391 -291.901045)
			(xy 38.101289 -291.876438) (xy 38.063168 -291.845313) (xy 38.030533 -291.808476) (xy 38.00423 -291.76688)
			(xy 37.984939 -291.721604) (xy 37.973162 -291.67382) (xy 37.969202 -291.624766) (xy 37.6555 -291.624766)
			(xy 37.655041 -291.650135) (xy 37.647299 -291.700278) (xy 37.631992 -291.748651) (xy 37.609478 -291.794119)
			(xy 37.580285 -291.835616) (xy 37.545098 -291.87217) (xy 37.525198 -291.88791) (xy 37.516907 -291.894897)
			(xy 37.506641 -291.913971) (xy 37.505386 -291.92474) (xy 37.50183 -291.978842) (xy 37.500306 -292.001194)
			(xy 37.50056 -292.010338) (xy 37.501661 -292.017966) (xy 37.50786 -292.032069) (xy 37.512752 -292.038024)
			(xy 37.515038 -292.040564) (xy 37.859208 -292.384734) (xy 37.861748 -292.38702) (xy 37.867754 -292.391831)
			(xy 37.88183 -292.398029) (xy 37.889434 -292.399212) (xy 37.898578 -292.399466) (xy 37.92093 -292.397942)
			(xy 37.975032 -292.394386) (xy 37.985803 -292.393135) (xy 38.004879 -292.382869) (xy 38.011862 -292.374574)
			(xy 38.027631 -292.354703) (xy 38.064192 -292.319537) (xy 38.105688 -292.29036) (xy 38.151149 -292.267855)
			(xy 38.199511 -292.252546) (xy 38.249643 -292.244795) (xy 38.275006 -292.244272) (xy 38.300993 -292.244782)
			(xy 38.352328 -292.252913) (xy 38.401759 -292.268974) (xy 38.44807 -292.29257) (xy 38.490119 -292.32312)
			(xy 38.526871 -292.359871) (xy 38.557422 -292.401919) (xy 38.58102 -292.448228) (xy 38.597084 -292.497658)
			(xy 38.605217 -292.548993) (xy 38.605709 -292.574726) (xy 38.919162 -292.574726) (xy 38.923122 -292.525672)
			(xy 38.934899 -292.477888) (xy 38.95419 -292.432612) (xy 38.980493 -292.391016) (xy 39.013128 -292.354179)
			(xy 39.051249 -292.323054) (xy 39.09387 -292.298447) (xy 39.139886 -292.280995) (xy 39.188105 -292.271151)
			(xy 39.23728 -292.26917) (xy 39.286135 -292.275102) (xy 39.333406 -292.288794) (xy 39.377868 -292.309892)
			(xy 39.418371 -292.337848) (xy 39.453864 -292.37194) (xy 39.483429 -292.411284) (xy 39.5063 -292.454861)
			(xy 39.521884 -292.501542) (xy 39.529779 -292.550119) (xy 39.530274 -292.574726) (xy 39.869122 -292.574726)
			(xy 39.873082 -292.525672) (xy 39.884859 -292.477888) (xy 39.90415 -292.432612) (xy 39.930453 -292.391016)
			(xy 39.963088 -292.354179) (xy 40.001209 -292.323054) (xy 40.04383 -292.298447) (xy 40.089846 -292.280995)
			(xy 40.138065 -292.271151) (xy 40.18724 -292.26917) (xy 40.236095 -292.275102) (xy 40.283366 -292.288794)
			(xy 40.327828 -292.309892) (xy 40.368331 -292.337848) (xy 40.403824 -292.37194) (xy 40.433389 -292.411284)
			(xy 40.45626 -292.454861) (xy 40.471844 -292.501542) (xy 40.479739 -292.550119) (xy 40.480234 -292.574726)
			(xy 40.480229 -292.57498) (xy 40.819082 -292.57498) (xy 40.823042 -292.525926) (xy 40.834819 -292.478142)
			(xy 40.85411 -292.432866) (xy 40.880413 -292.39127) (xy 40.913048 -292.354433) (xy 40.951169 -292.323308)
			(xy 40.99379 -292.298701) (xy 41.039806 -292.281249) (xy 41.088025 -292.271405) (xy 41.1372 -292.269424)
			(xy 41.186055 -292.275356) (xy 41.233326 -292.289048) (xy 41.277788 -292.310146) (xy 41.318291 -292.338102)
			(xy 41.353784 -292.372194) (xy 41.383349 -292.411538) (xy 41.40622 -292.455115) (xy 41.421804 -292.501796)
			(xy 41.429699 -292.550373) (xy 41.430194 -292.57498) (xy 41.429699 -292.599587) (xy 41.429367 -292.601629)
			(xy 41.719236 -292.601629) (xy 41.719236 -292.548331) (xy 41.727179 -292.495627) (xy 41.742889 -292.444697)
			(xy 41.766015 -292.396676) (xy 41.796039 -292.352639) (xy 41.832291 -292.313568) (xy 41.873962 -292.280337)
			(xy 41.92012 -292.253688) (xy 41.969734 -292.234216) (xy 42.021696 -292.222356) (xy 42.074846 -292.218373)
			(xy 42.127996 -292.222356) (xy 42.179958 -292.234216) (xy 42.229572 -292.253688) (xy 42.27573 -292.280337)
			(xy 42.317401 -292.313568) (xy 42.353653 -292.352639) (xy 42.383677 -292.396676) (xy 42.406803 -292.444697)
			(xy 42.422513 -292.495627) (xy 42.430456 -292.548331) (xy 42.430954 -292.57498) (xy 42.719002 -292.57498)
			(xy 42.722962 -292.525926) (xy 42.734739 -292.478142) (xy 42.75403 -292.432866) (xy 42.780333 -292.39127)
			(xy 42.812968 -292.354433) (xy 42.851089 -292.323308) (xy 42.89371 -292.298701) (xy 42.939726 -292.281249)
			(xy 42.987945 -292.271405) (xy 43.03712 -292.269424) (xy 43.085975 -292.275356) (xy 43.133246 -292.289048)
			(xy 43.177708 -292.310146) (xy 43.218211 -292.338102) (xy 43.253704 -292.372194) (xy 43.283269 -292.411538)
			(xy 43.30614 -292.455115) (xy 43.321724 -292.501796) (xy 43.329619 -292.550373) (xy 43.330114 -292.57498)
			(xy 43.329619 -292.599587) (xy 43.321724 -292.648164) (xy 43.30614 -292.694845) (xy 43.283269 -292.738422)
			(xy 43.253704 -292.777766) (xy 43.218211 -292.811858) (xy 43.177708 -292.839814) (xy 43.133246 -292.860912)
			(xy 43.085975 -292.874604) (xy 43.03712 -292.880536) (xy 42.987945 -292.878555) (xy 42.939726 -292.868711)
			(xy 42.89371 -292.851259) (xy 42.851089 -292.826652) (xy 42.812968 -292.795527) (xy 42.780333 -292.75869)
			(xy 42.75403 -292.717094) (xy 42.734739 -292.671818) (xy 42.722962 -292.624034) (xy 42.719002 -292.57498)
			(xy 42.430954 -292.57498) (xy 42.430456 -292.601629) (xy 42.422513 -292.654333) (xy 42.406803 -292.705263)
			(xy 42.383677 -292.753284) (xy 42.353653 -292.797321) (xy 42.317401 -292.836392) (xy 42.27573 -292.869623)
			(xy 42.229572 -292.896272) (xy 42.179958 -292.915744) (xy 42.127996 -292.927604) (xy 42.074846 -292.931588)
			(xy 42.021696 -292.927604) (xy 41.969734 -292.915744) (xy 41.92012 -292.896272) (xy 41.873962 -292.869623)
			(xy 41.832291 -292.836392) (xy 41.796039 -292.797321) (xy 41.766015 -292.753284) (xy 41.742889 -292.705263)
			(xy 41.727179 -292.654333) (xy 41.719236 -292.601629) (xy 41.429367 -292.601629) (xy 41.421804 -292.648164)
			(xy 41.40622 -292.694845) (xy 41.383349 -292.738422) (xy 41.353784 -292.777766) (xy 41.318291 -292.811858)
			(xy 41.277788 -292.839814) (xy 41.233326 -292.860912) (xy 41.186055 -292.874604) (xy 41.1372 -292.880536)
			(xy 41.088025 -292.878555) (xy 41.039806 -292.868711) (xy 40.99379 -292.851259) (xy 40.951169 -292.826652)
			(xy 40.913048 -292.795527) (xy 40.880413 -292.75869) (xy 40.85411 -292.717094) (xy 40.834819 -292.671818)
			(xy 40.823042 -292.624034) (xy 40.819082 -292.57498) (xy 40.480229 -292.57498) (xy 40.479739 -292.599333)
			(xy 40.471844 -292.64791) (xy 40.45626 -292.694591) (xy 40.433389 -292.738168) (xy 40.403824 -292.777512)
			(xy 40.368331 -292.811604) (xy 40.327828 -292.83956) (xy 40.283366 -292.860658) (xy 40.236095 -292.87435)
			(xy 40.18724 -292.880282) (xy 40.138065 -292.878301) (xy 40.089846 -292.868457) (xy 40.04383 -292.851005)
			(xy 40.001209 -292.826398) (xy 39.963088 -292.795273) (xy 39.930453 -292.758436) (xy 39.90415 -292.71684)
			(xy 39.884859 -292.671564) (xy 39.873082 -292.62378) (xy 39.869122 -292.574726) (xy 39.530274 -292.574726)
			(xy 39.529779 -292.599333) (xy 39.521884 -292.64791) (xy 39.5063 -292.694591) (xy 39.483429 -292.738168)
			(xy 39.453864 -292.777512) (xy 39.418371 -292.811604) (xy 39.377868 -292.83956) (xy 39.333406 -292.860658)
			(xy 39.286135 -292.87435) (xy 39.23728 -292.880282) (xy 39.188105 -292.878301) (xy 39.139886 -292.868457)
			(xy 39.09387 -292.851005) (xy 39.051249 -292.826398) (xy 39.013128 -292.795273) (xy 38.980493 -292.758436)
			(xy 38.95419 -292.71684) (xy 38.934899 -292.671564) (xy 38.923122 -292.62378) (xy 38.919162 -292.574726)
			(xy 38.605709 -292.574726) (xy 38.605714 -292.57498) (xy 38.605254 -292.600348) (xy 38.597511 -292.65049)
			(xy 38.582202 -292.698862) (xy 38.559688 -292.74433) (xy 38.530495 -292.785827) (xy 38.495309 -292.82238)
			(xy 38.475412 -292.838124) (xy 38.467122 -292.845111) (xy 38.456857 -292.864186) (xy 38.4556 -292.874954)
			(xy 38.452044 -292.929056) (xy 38.45052 -292.951408) (xy 38.450774 -292.960552) (xy 38.451878 -292.968179)
			(xy 38.458081 -292.982278) (xy 38.462966 -292.988238) (xy 38.465252 -292.990778) (xy 38.809168 -293.334694)
			(xy 38.811708 -293.33698) (xy 38.81771 -293.341799) (xy 38.831785 -293.348013) (xy 38.839394 -293.349172)
			(xy 38.848538 -293.349426) (xy 38.87089 -293.347902) (xy 38.924992 -293.344346) (xy 38.935765 -293.343101)
			(xy 38.954848 -293.332839) (xy 38.961822 -293.324534) (xy 38.977589 -293.304657) (xy 39.014145 -293.269482)
			(xy 39.05564 -293.240294) (xy 39.101101 -293.217779) (xy 39.149466 -293.202462) (xy 39.1996 -293.194702)
			(xy 39.224966 -293.194232) (xy 39.250956 -293.194713) (xy 39.302296 -293.20284) (xy 39.351733 -293.2189)
			(xy 39.398048 -293.242496) (xy 39.440101 -293.273049) (xy 39.476855 -293.309804) (xy 39.507407 -293.351857)
			(xy 39.531003 -293.398173) (xy 39.547062 -293.44761) (xy 39.555188 -293.49895) (xy 39.555674 -293.52494)
			(xy 39.869122 -293.52494) (xy 39.873082 -293.475886) (xy 39.884859 -293.428102) (xy 39.90415 -293.382826)
			(xy 39.930453 -293.34123) (xy 39.963088 -293.304393) (xy 40.001209 -293.273268) (xy 40.04383 -293.248661)
			(xy 40.089846 -293.231209) (xy 40.138065 -293.221365) (xy 40.18724 -293.219384) (xy 40.236095 -293.225316)
			(xy 40.283366 -293.239008) (xy 40.327828 -293.260106) (xy 40.368331 -293.288062) (xy 40.403824 -293.322154)
			(xy 40.433389 -293.361498) (xy 40.45626 -293.405075) (xy 40.471844 -293.451756) (xy 40.479739 -293.500333)
			(xy 40.480234 -293.52494) (xy 40.819082 -293.52494) (xy 40.823042 -293.475886) (xy 40.834819 -293.428102)
			(xy 40.85411 -293.382826) (xy 40.880413 -293.34123) (xy 40.913048 -293.304393) (xy 40.951169 -293.273268)
			(xy 40.99379 -293.248661) (xy 41.039806 -293.231209) (xy 41.088025 -293.221365) (xy 41.1372 -293.219384)
			(xy 41.186055 -293.225316) (xy 41.233326 -293.239008) (xy 41.277788 -293.260106) (xy 41.318291 -293.288062)
			(xy 41.353784 -293.322154) (xy 41.383349 -293.361498) (xy 41.40622 -293.405075) (xy 41.421804 -293.451756)
			(xy 41.429699 -293.500333) (xy 41.430194 -293.52494) (xy 41.769042 -293.52494) (xy 41.773002 -293.475886)
			(xy 41.784779 -293.428102) (xy 41.80407 -293.382826) (xy 41.830373 -293.34123) (xy 41.863008 -293.304393)
			(xy 41.901129 -293.273268) (xy 41.94375 -293.248661) (xy 41.989766 -293.231209) (xy 42.037985 -293.221365)
			(xy 42.08716 -293.219384) (xy 42.136015 -293.225316) (xy 42.183286 -293.239008) (xy 42.227748 -293.260106)
			(xy 42.268251 -293.288062) (xy 42.303744 -293.322154) (xy 42.333309 -293.361498) (xy 42.35618 -293.405075)
			(xy 42.371764 -293.451756) (xy 42.379659 -293.500333) (xy 42.380154 -293.52494) (xy 42.379659 -293.549547)
			(xy 42.379327 -293.551589) (xy 42.669196 -293.551589) (xy 42.669196 -293.498291) (xy 42.677139 -293.445587)
			(xy 42.692849 -293.394657) (xy 42.715975 -293.346636) (xy 42.745999 -293.302599) (xy 42.782251 -293.263528)
			(xy 42.823922 -293.230297) (xy 42.87008 -293.203648) (xy 42.919694 -293.184176) (xy 42.971656 -293.172316)
			(xy 43.024806 -293.168333) (xy 43.077956 -293.172316) (xy 43.129918 -293.184176) (xy 43.179532 -293.203648)
			(xy 43.22569 -293.230297) (xy 43.267361 -293.263528) (xy 43.303613 -293.302599) (xy 43.333637 -293.346636)
			(xy 43.356763 -293.394657) (xy 43.372473 -293.445587) (xy 43.380416 -293.498291) (xy 43.380914 -293.52494)
			(xy 43.668962 -293.52494) (xy 43.672922 -293.475886) (xy 43.684699 -293.428102) (xy 43.70399 -293.382826)
			(xy 43.730293 -293.34123) (xy 43.762928 -293.304393) (xy 43.801049 -293.273268) (xy 43.84367 -293.248661)
			(xy 43.889686 -293.231209) (xy 43.937905 -293.221365) (xy 43.98708 -293.219384) (xy 44.035935 -293.225316)
			(xy 44.083206 -293.239008) (xy 44.127668 -293.260106) (xy 44.168171 -293.288062) (xy 44.203664 -293.322154)
			(xy 44.233229 -293.361498) (xy 44.2561 -293.405075) (xy 44.271684 -293.451756) (xy 44.279579 -293.500333)
			(xy 44.280074 -293.52494) (xy 44.279579 -293.549547) (xy 44.271684 -293.598124) (xy 44.2561 -293.644805)
			(xy 44.233229 -293.688382) (xy 44.203664 -293.727726) (xy 44.168171 -293.761818) (xy 44.127668 -293.789774)
			(xy 44.083206 -293.810872) (xy 44.035935 -293.824564) (xy 43.98708 -293.830496) (xy 43.937905 -293.828515)
			(xy 43.889686 -293.818671) (xy 43.84367 -293.801219) (xy 43.801049 -293.776612) (xy 43.762928 -293.745487)
			(xy 43.730293 -293.70865) (xy 43.70399 -293.667054) (xy 43.684699 -293.621778) (xy 43.672922 -293.573994)
			(xy 43.668962 -293.52494) (xy 43.380914 -293.52494) (xy 43.380416 -293.551589) (xy 43.372473 -293.604293)
			(xy 43.356763 -293.655223) (xy 43.333637 -293.703244) (xy 43.303613 -293.747281) (xy 43.267361 -293.786352)
			(xy 43.22569 -293.819583) (xy 43.179532 -293.846232) (xy 43.129918 -293.865704) (xy 43.077956 -293.877564)
			(xy 43.024806 -293.881548) (xy 42.971656 -293.877564) (xy 42.919694 -293.865704) (xy 42.87008 -293.846232)
			(xy 42.823922 -293.819583) (xy 42.782251 -293.786352) (xy 42.745999 -293.747281) (xy 42.715975 -293.703244)
			(xy 42.692849 -293.655223) (xy 42.677139 -293.604293) (xy 42.669196 -293.551589) (xy 42.379327 -293.551589)
			(xy 42.371764 -293.598124) (xy 42.35618 -293.644805) (xy 42.333309 -293.688382) (xy 42.303744 -293.727726)
			(xy 42.268251 -293.761818) (xy 42.227748 -293.789774) (xy 42.183286 -293.810872) (xy 42.136015 -293.824564)
			(xy 42.08716 -293.830496) (xy 42.037985 -293.828515) (xy 41.989766 -293.818671) (xy 41.94375 -293.801219)
			(xy 41.901129 -293.776612) (xy 41.863008 -293.745487) (xy 41.830373 -293.70865) (xy 41.80407 -293.667054)
			(xy 41.784779 -293.621778) (xy 41.773002 -293.573994) (xy 41.769042 -293.52494) (xy 41.430194 -293.52494)
			(xy 41.429699 -293.549547) (xy 41.421804 -293.598124) (xy 41.40622 -293.644805) (xy 41.383349 -293.688382)
			(xy 41.353784 -293.727726) (xy 41.318291 -293.761818) (xy 41.277788 -293.789774) (xy 41.233326 -293.810872)
			(xy 41.186055 -293.824564) (xy 41.1372 -293.830496) (xy 41.088025 -293.828515) (xy 41.039806 -293.818671)
			(xy 40.99379 -293.801219) (xy 40.951169 -293.776612) (xy 40.913048 -293.745487) (xy 40.880413 -293.70865)
			(xy 40.85411 -293.667054) (xy 40.834819 -293.621778) (xy 40.823042 -293.573994) (xy 40.819082 -293.52494)
			(xy 40.480234 -293.52494) (xy 40.479739 -293.549547) (xy 40.471844 -293.598124) (xy 40.45626 -293.644805)
			(xy 40.433389 -293.688382) (xy 40.403824 -293.727726) (xy 40.368331 -293.761818) (xy 40.327828 -293.789774)
			(xy 40.283366 -293.810872) (xy 40.236095 -293.824564) (xy 40.18724 -293.830496) (xy 40.138065 -293.828515)
			(xy 40.089846 -293.818671) (xy 40.04383 -293.801219) (xy 40.001209 -293.776612) (xy 39.963088 -293.745487)
			(xy 39.930453 -293.70865) (xy 39.90415 -293.667054) (xy 39.884859 -293.621778) (xy 39.873082 -293.573994)
			(xy 39.869122 -293.52494) (xy 39.555674 -293.52494) (xy 39.555217 -293.550309) (xy 39.547478 -293.600454)
			(xy 39.532173 -293.648829) (xy 39.50966 -293.694299) (xy 39.480467 -293.735798) (xy 39.445279 -293.772352)
			(xy 39.425372 -293.788084) (xy 39.417096 -293.795078) (xy 39.406862 -293.814154) (xy 39.40556 -293.824914)
			(xy 39.402004 -293.879016) (xy 39.40048 -293.901368) (xy 39.400734 -293.910512) (xy 39.401845 -293.918136)
			(xy 39.408057 -293.932227) (xy 39.412926 -293.938198) (xy 39.415212 -293.940738) (xy 39.949374 -294.4749)
			(xy 40.819082 -294.4749) (xy 40.823042 -294.425846) (xy 40.834819 -294.378062) (xy 40.85411 -294.332786)
			(xy 40.880413 -294.29119) (xy 40.913048 -294.254353) (xy 40.951169 -294.223228) (xy 40.99379 -294.198621)
			(xy 41.039806 -294.181169) (xy 41.088025 -294.171325) (xy 41.1372 -294.169344) (xy 41.186055 -294.175276)
			(xy 41.233326 -294.188968) (xy 41.277788 -294.210066) (xy 41.318291 -294.238022) (xy 41.353784 -294.272114)
			(xy 41.383349 -294.311458) (xy 41.40622 -294.355035) (xy 41.421804 -294.401716) (xy 41.429699 -294.450293)
			(xy 41.430194 -294.4749) (xy 41.429699 -294.499507) (xy 41.429367 -294.501549) (xy 41.719236 -294.501549)
			(xy 41.719236 -294.448251) (xy 41.727179 -294.395547) (xy 41.742889 -294.344617) (xy 41.766015 -294.296596)
			(xy 41.796039 -294.252559) (xy 41.832291 -294.213488) (xy 41.873962 -294.180257) (xy 41.92012 -294.153608)
			(xy 41.969734 -294.134136) (xy 42.021696 -294.122276) (xy 42.074846 -294.118293) (xy 42.127996 -294.122276)
			(xy 42.179958 -294.134136) (xy 42.229572 -294.153608) (xy 42.27573 -294.180257) (xy 42.317401 -294.213488)
			(xy 42.353653 -294.252559) (xy 42.383677 -294.296596) (xy 42.406803 -294.344617) (xy 42.422513 -294.395547)
			(xy 42.430456 -294.448251) (xy 42.430954 -294.4749) (xy 42.719002 -294.4749) (xy 42.722962 -294.425846)
			(xy 42.734739 -294.378062) (xy 42.75403 -294.332786) (xy 42.780333 -294.29119) (xy 42.812968 -294.254353)
			(xy 42.851089 -294.223228) (xy 42.89371 -294.198621) (xy 42.939726 -294.181169) (xy 42.987945 -294.171325)
			(xy 43.03712 -294.169344) (xy 43.085975 -294.175276) (xy 43.133246 -294.188968) (xy 43.177708 -294.210066)
			(xy 43.218211 -294.238022) (xy 43.253704 -294.272114) (xy 43.283269 -294.311458) (xy 43.30614 -294.355035)
			(xy 43.321724 -294.401716) (xy 43.329619 -294.450293) (xy 43.330114 -294.4749) (xy 43.668962 -294.4749)
			(xy 43.672922 -294.425846) (xy 43.684699 -294.378062) (xy 43.70399 -294.332786) (xy 43.730293 -294.29119)
			(xy 43.762928 -294.254353) (xy 43.801049 -294.223228) (xy 43.84367 -294.198621) (xy 43.889686 -294.181169)
			(xy 43.937905 -294.171325) (xy 43.98708 -294.169344) (xy 44.035935 -294.175276) (xy 44.083206 -294.188968)
			(xy 44.127668 -294.210066) (xy 44.168171 -294.238022) (xy 44.203664 -294.272114) (xy 44.233229 -294.311458)
			(xy 44.2561 -294.355035) (xy 44.271684 -294.401716) (xy 44.279579 -294.450293) (xy 44.280074 -294.4749)
			(xy 44.619176 -294.4749) (xy 44.623136 -294.425846) (xy 44.634913 -294.378062) (xy 44.654204 -294.332786)
			(xy 44.680507 -294.29119) (xy 44.713142 -294.254353) (xy 44.751263 -294.223228) (xy 44.793884 -294.198621)
			(xy 44.8399 -294.181169) (xy 44.888119 -294.171325) (xy 44.937294 -294.169344) (xy 44.986149 -294.175276)
			(xy 45.03342 -294.188968) (xy 45.077882 -294.210066) (xy 45.118385 -294.238022) (xy 45.153878 -294.272114)
			(xy 45.183443 -294.311458) (xy 45.206314 -294.355035) (xy 45.221898 -294.401716) (xy 45.229793 -294.450293)
			(xy 45.230288 -294.4749) (xy 45.229793 -294.499507) (xy 45.221898 -294.548084) (xy 45.206314 -294.594765)
			(xy 45.183443 -294.638342) (xy 45.153878 -294.677686) (xy 45.118385 -294.711778) (xy 45.077882 -294.739734)
			(xy 45.03342 -294.760832) (xy 44.986149 -294.774524) (xy 44.937294 -294.780456) (xy 44.888119 -294.778475)
			(xy 44.8399 -294.768631) (xy 44.793884 -294.751179) (xy 44.751263 -294.726572) (xy 44.713142 -294.695447)
			(xy 44.680507 -294.65861) (xy 44.654204 -294.617014) (xy 44.634913 -294.571738) (xy 44.623136 -294.523954)
			(xy 44.619176 -294.4749) (xy 44.280074 -294.4749) (xy 44.279579 -294.499507) (xy 44.271684 -294.548084)
			(xy 44.2561 -294.594765) (xy 44.233229 -294.638342) (xy 44.203664 -294.677686) (xy 44.168171 -294.711778)
			(xy 44.127668 -294.739734) (xy 44.083206 -294.760832) (xy 44.035935 -294.774524) (xy 43.98708 -294.780456)
			(xy 43.937905 -294.778475) (xy 43.889686 -294.768631) (xy 43.84367 -294.751179) (xy 43.801049 -294.726572)
			(xy 43.762928 -294.695447) (xy 43.730293 -294.65861) (xy 43.70399 -294.617014) (xy 43.684699 -294.571738)
			(xy 43.672922 -294.523954) (xy 43.668962 -294.4749) (xy 43.330114 -294.4749) (xy 43.329619 -294.499507)
			(xy 43.321724 -294.548084) (xy 43.30614 -294.594765) (xy 43.283269 -294.638342) (xy 43.253704 -294.677686)
			(xy 43.218211 -294.711778) (xy 43.177708 -294.739734) (xy 43.133246 -294.760832) (xy 43.085975 -294.774524)
			(xy 43.03712 -294.780456) (xy 42.987945 -294.778475) (xy 42.939726 -294.768631) (xy 42.89371 -294.751179)
			(xy 42.851089 -294.726572) (xy 42.812968 -294.695447) (xy 42.780333 -294.65861) (xy 42.75403 -294.617014)
			(xy 42.734739 -294.571738) (xy 42.722962 -294.523954) (xy 42.719002 -294.4749) (xy 42.430954 -294.4749)
			(xy 42.430456 -294.501549) (xy 42.422513 -294.554253) (xy 42.406803 -294.605183) (xy 42.383677 -294.653204)
			(xy 42.353653 -294.697241) (xy 42.317401 -294.736312) (xy 42.27573 -294.769543) (xy 42.229572 -294.796192)
			(xy 42.179958 -294.815664) (xy 42.127996 -294.827524) (xy 42.074846 -294.831508) (xy 42.021696 -294.827524)
			(xy 41.969734 -294.815664) (xy 41.92012 -294.796192) (xy 41.873962 -294.769543) (xy 41.832291 -294.736312)
			(xy 41.796039 -294.697241) (xy 41.766015 -294.653204) (xy 41.742889 -294.605183) (xy 41.727179 -294.554253)
			(xy 41.719236 -294.501549) (xy 41.429367 -294.501549) (xy 41.421804 -294.548084) (xy 41.40622 -294.594765)
			(xy 41.383349 -294.638342) (xy 41.353784 -294.677686) (xy 41.318291 -294.711778) (xy 41.277788 -294.739734)
			(xy 41.233326 -294.760832) (xy 41.186055 -294.774524) (xy 41.1372 -294.780456) (xy 41.088025 -294.778475)
			(xy 41.039806 -294.768631) (xy 40.99379 -294.751179) (xy 40.951169 -294.726572) (xy 40.913048 -294.695447)
			(xy 40.880413 -294.65861) (xy 40.85411 -294.617014) (xy 40.834819 -294.571738) (xy 40.823042 -294.523954)
			(xy 40.819082 -294.4749) (xy 39.949374 -294.4749) (xy 41.659048 -296.184574) (xy 41.661588 -296.18686)
			(xy 41.667593 -296.191671) (xy 41.681671 -296.197866) (xy 41.689274 -296.199052) (xy 41.698418 -296.199306)
			(xy 41.72077 -296.197782) (xy 41.774872 -296.194226) (xy 41.78565 -296.192988) (xy 41.804751 -296.182741)
			(xy 41.811702 -296.174414) (xy 41.827469 -296.154537) (xy 41.864026 -296.119361) (xy 41.90552 -296.090173)
			(xy 41.950981 -296.067657) (xy 41.999345 -296.052338) (xy 42.04948 -296.044576) (xy 42.074846 -296.044112)
			(xy 42.10083 -296.044625) (xy 42.152158 -296.052761) (xy 42.201581 -296.068827) (xy 42.247883 -296.092425)
			(xy 42.289923 -296.122976) (xy 42.326667 -296.159727) (xy 42.357209 -296.201774) (xy 42.380799 -296.24808)
			(xy 42.396854 -296.297506) (xy 42.40498 -296.348836) (xy 42.405554 -296.37482) (xy 42.405306 -296.391513)
			(xy 42.40187 -296.424723) (xy 42.398696 -296.441114) (xy 42.398696 -296.441622) (xy 42.397087 -296.452725)
			(xy 42.402498 -296.474468) (xy 42.40911 -296.483532) (xy 42.458894 -296.545) (xy 42.466512 -296.553397)
			(xy 42.486945 -296.563158) (xy 42.498264 -296.563796) (xy 43.551348 -296.563796) (xy 43.562676 -296.563187)
			(xy 43.583118 -296.553423) (xy 43.590718 -296.545) (xy 43.640502 -296.483532) (xy 43.647107 -296.474468)
			(xy 43.652497 -296.452726) (xy 43.650916 -296.441622) (xy 43.650916 -296.441114) (xy 43.647734 -296.424725)
			(xy 43.644296 -296.391514) (xy 43.644058 -296.37482) (xy 43.644568 -296.348833) (xy 43.652698 -296.297498)
			(xy 43.668759 -296.248068) (xy 43.692355 -296.201758) (xy 43.722905 -296.15971) (xy 43.759656 -296.122959)
			(xy 43.801704 -296.092409) (xy 43.848014 -296.068813) (xy 43.897444 -296.052752) (xy 43.948779 -296.044622)
			(xy 44.000753 -296.044622) (xy 44.052088 -296.052752) (xy 44.101518 -296.068813) (xy 44.147828 -296.092409)
			(xy 44.189876 -296.122959) (xy 44.226627 -296.15971) (xy 44.257177 -296.201758) (xy 44.280773 -296.248068)
			(xy 44.296834 -296.297498) (xy 44.304964 -296.348833) (xy 44.305474 -296.37482) (xy 44.305226 -296.391513)
			(xy 44.30179 -296.424723) (xy 44.298616 -296.441114) (xy 44.298616 -296.441622) (xy 44.297007 -296.452724)
			(xy 44.302419 -296.474467) (xy 44.30903 -296.483532) (xy 44.358814 -296.545) (xy 44.366433 -296.553394)
			(xy 44.386866 -296.563147) (xy 44.398184 -296.563796) (xy 44.501562 -296.563796) (xy 44.512888 -296.563184)
			(xy 44.533326 -296.553416) (xy 44.540932 -296.545) (xy 44.590716 -296.483532) (xy 44.597319 -296.474468)
			(xy 44.602707 -296.452727) (xy 44.60113 -296.441622) (xy 44.60113 -296.441114) (xy 44.597948 -296.424725)
			(xy 44.59451 -296.391514) (xy 44.594272 -296.37482) (xy 44.594782 -296.348833) (xy 44.602912 -296.297498)
			(xy 44.618973 -296.248068) (xy 44.642569 -296.201758) (xy 44.673119 -296.15971) (xy 44.70987 -296.122959)
			(xy 44.751918 -296.092409) (xy 44.798228 -296.068813) (xy 44.847658 -296.052752) (xy 44.898993 -296.044622)
			(xy 44.950967 -296.044622) (xy 45.002302 -296.052752) (xy 45.051732 -296.068813) (xy 45.098042 -296.092409)
			(xy 45.14009 -296.122959) (xy 45.176841 -296.15971) (xy 45.207391 -296.201758) (xy 45.230987 -296.248068)
			(xy 45.247048 -296.297498) (xy 45.255178 -296.348833) (xy 45.255688 -296.37482) (xy 45.25549 -296.393067)
			(xy 45.251545 -296.429347) (xy 45.247814 -296.44721) (xy 45.247814 -296.447464) (xy 45.245972 -296.458703)
			(xy 45.251113 -296.48086) (xy 45.25772 -296.490136) (xy 45.30725 -296.551858) (xy 45.314879 -296.560378)
			(xy 45.335456 -296.570288) (xy 45.346874 -296.570908) (xy 45.46473 -296.570908)
		)
		(stroke
			(width 0)
			(type solid)
		)
		(fill yes)
		(layer "In7.Cu")
		(net "PCEPLL3_VDDA18_PEX0")
	)
	(gr_poly
		(pts
			(xy 277.652988 -296.570908) (xy 277.664407 -296.570277) (xy 277.684988 -296.560382) (xy 277.692612 -296.551858)
			(xy 277.74265 -296.489374) (xy 277.743412 -296.488612) (xy 277.746475 -296.484357) (xy 277.750965 -296.474885)
			(xy 277.752302 -296.469816) (xy 277.754842 -296.459402) (xy 277.752048 -296.44721) (xy 277.748341 -296.429343)
			(xy 277.744389 -296.393066) (xy 277.744174 -296.37482) (xy 277.744684 -296.348833) (xy 277.752814 -296.297498)
			(xy 277.768875 -296.248068) (xy 277.792471 -296.201758) (xy 277.823021 -296.15971) (xy 277.859772 -296.122959)
			(xy 277.90182 -296.092409) (xy 277.94813 -296.068813) (xy 277.99756 -296.052752) (xy 278.048895 -296.044622)
			(xy 278.100869 -296.044622) (xy 278.152204 -296.052752) (xy 278.201634 -296.068813) (xy 278.247944 -296.092409)
			(xy 278.289992 -296.122959) (xy 278.326743 -296.15971) (xy 278.357293 -296.201758) (xy 278.380889 -296.248068)
			(xy 278.39695 -296.297498) (xy 278.40508 -296.348833) (xy 278.40559 -296.37482) (xy 278.405392 -296.393067)
			(xy 278.401447 -296.429347) (xy 278.397716 -296.44721) (xy 278.394922 -296.459402) (xy 278.397462 -296.469816)
			(xy 278.398819 -296.474878) (xy 278.403306 -296.484347) (xy 278.406352 -296.488612) (xy 278.407114 -296.489374)
			(xy 278.457152 -296.551858) (xy 278.464781 -296.560378) (xy 278.485358 -296.570287) (xy 278.496776 -296.570908)
			(xy 278.602948 -296.570908) (xy 278.614371 -296.570286) (xy 278.634965 -296.5604) (xy 278.642572 -296.551858)
			(xy 278.69261 -296.489374) (xy 278.693372 -296.488612) (xy 278.696431 -296.484355) (xy 278.700916 -296.474882)
			(xy 278.702262 -296.469816) (xy 278.704802 -296.459402) (xy 278.702008 -296.44721) (xy 278.698301 -296.429343)
			(xy 278.69435 -296.393066) (xy 278.694134 -296.37482) (xy 278.694644 -296.348833) (xy 278.702774 -296.297498)
			(xy 278.718835 -296.248068) (xy 278.742431 -296.201758) (xy 278.772981 -296.15971) (xy 278.809732 -296.122959)
			(xy 278.85178 -296.092409) (xy 278.89809 -296.068813) (xy 278.94752 -296.052752) (xy 278.998855 -296.044622)
			(xy 279.050829 -296.044622) (xy 279.102164 -296.052752) (xy 279.151594 -296.068813) (xy 279.197904 -296.092409)
			(xy 279.239952 -296.122959) (xy 279.276703 -296.15971) (xy 279.307253 -296.201758) (xy 279.330849 -296.248068)
			(xy 279.34691 -296.297498) (xy 279.35504 -296.348833) (xy 279.35555 -296.37482) (xy 279.355352 -296.393067)
			(xy 279.351408 -296.429347) (xy 279.347676 -296.44721) (xy 279.344882 -296.459402) (xy 279.347422 -296.469816)
			(xy 279.348778 -296.474879) (xy 279.353261 -296.48435) (xy 279.356312 -296.488612) (xy 279.357074 -296.489374)
			(xy 279.407112 -296.551858) (xy 279.414745 -296.560368) (xy 279.435322 -296.570253) (xy 279.446736 -296.570908)
			(xy 280.017982 -296.570908) (xy 280.023991 -296.570737) (xy 280.03567 -296.567907) (xy 280.041096 -296.56532)
			(xy 280.044572 -296.563482) (xy 280.050954 -296.558892) (xy 280.053796 -296.556176) (xy 280.221944 -296.388028)
			(xy 280.278078 -296.33164) (xy 280.27884 -296.330624) (xy 280.273252 -296.334942) (xy 280.285698 -296.322496)
			(xy 280.289329 -296.316296) (xy 280.293317 -296.302499) (xy 280.293572 -296.295318) (xy 280.293572 -294.909494)
			(xy 280.293309 -294.903742) (xy 280.290492 -294.892579) (xy 280.287984 -294.887396) (xy 280.287476 -294.886888)
			(xy 280.284936 -294.882316) (xy 280.284428 -294.8813) (xy 280.28392 -294.880538) (xy 280.282904 -294.879268)
			(xy 280.27884 -294.874696) (xy 280.183336 -294.779192) (xy 280.177449 -294.773796) (xy 280.163221 -294.766565)
			(xy 280.155396 -294.764968) (xy 280.155142 -294.764968) (xy 280.152602 -294.764714) (xy 280.126948 -294.768778)
			(xy 280.124662 -294.769794) (xy 280.124408 -294.769794) (xy 280.119582 -294.772334) (xy 280.096992 -294.782819)
			(xy 280.049444 -294.797633) (xy 280.000211 -294.805141) (xy 279.97531 -294.805608) (xy 279.974802 -294.805608)
			(xy 279.947517 -294.80505) (xy 279.893686 -294.796097) (xy 279.842054 -294.778434) (xy 279.794019 -294.752538)
			(xy 279.77211 -294.736266) (xy 279.76957 -294.734234) (xy 279.765506 -294.731186) (xy 279.742138 -294.722804)
			(xy 279.737959 -294.721395) (xy 279.729275 -294.719864) (xy 279.724866 -294.719756) (xy 279.274778 -294.719756)
			(xy 279.270367 -294.719842) (xy 279.261679 -294.721371) (xy 279.257506 -294.722804) (xy 279.234138 -294.731186)
			(xy 279.230074 -294.734234) (xy 279.227534 -294.736266) (xy 279.205629 -294.752547) (xy 279.157597 -294.778458)
			(xy 279.105964 -294.796133) (xy 279.052129 -294.805092) (xy 278.997555 -294.805092) (xy 278.94372 -294.796133)
			(xy 278.892087 -294.778458) (xy 278.844055 -294.752547) (xy 278.82215 -294.736266) (xy 278.81961 -294.734234)
			(xy 278.815546 -294.731186) (xy 278.792178 -294.722804) (xy 278.788 -294.721391) (xy 278.779315 -294.719853)
			(xy 278.774906 -294.719756) (xy 278.324818 -294.719756) (xy 278.320408 -294.719847) (xy 278.311723 -294.721386)
			(xy 278.307546 -294.722804) (xy 278.284178 -294.731186) (xy 278.280114 -294.734234) (xy 278.277574 -294.736266)
			(xy 278.255665 -294.752539) (xy 278.207631 -294.77844) (xy 278.155999 -294.796111) (xy 278.102168 -294.805075)
			(xy 278.074882 -294.805608) (xy 278.049776 -294.80514) (xy 278.000141 -294.797544) (xy 277.952226 -294.78253)
			(xy 277.907132 -294.760443) (xy 277.865897 -294.73179) (xy 277.829469 -294.697232) (xy 277.798685 -294.657562)
			(xy 277.774255 -294.613694) (xy 277.756739 -294.566635) (xy 277.746541 -294.517469) (xy 277.744682 -294.492426)
			(xy 277.744174 -294.482774) (xy 277.739602 -294.472868) (xy 277.737707 -294.469102) (xy 277.732851 -294.462212)
			(xy 277.72995 -294.459152) (xy 276.19071 -292.919912) (xy 276.187342 -292.916714) (xy 276.179674 -292.911474)
			(xy 276.17547 -292.909498) (xy 276.167088 -292.905688) (xy 276.16404 -292.905434) (xy 276.157436 -292.90518)
			(xy 276.13055 -292.903242) (xy 276.077891 -292.891733) (xy 276.027796 -292.871835) (xy 275.981592 -292.844075)
			(xy 275.940504 -292.809188) (xy 275.905618 -292.768097) (xy 275.877859 -292.721893) (xy 275.857963 -292.671797)
			(xy 275.846457 -292.619138) (xy 275.844508 -292.592252) (xy 275.844 -292.5826) (xy 275.839428 -292.572694)
			(xy 275.837536 -292.568926) (xy 275.832683 -292.562032) (xy 275.829776 -292.558978) (xy 275.240496 -291.969698)
			(xy 275.23713 -291.966496) (xy 275.229465 -291.96125) (xy 275.225256 -291.959284) (xy 275.216874 -291.955474)
			(xy 275.213826 -291.95522) (xy 275.207222 -291.954966) (xy 275.180362 -291.953014) (xy 275.127759 -291.94149)
			(xy 275.077718 -291.921594) (xy 275.031564 -291.893851) (xy 274.990515 -291.858995) (xy 274.955658 -291.817948)
			(xy 274.927913 -291.771795) (xy 274.908015 -291.721755) (xy 274.896488 -291.669152) (xy 274.894548 -291.642292)
			(xy 274.89404 -291.63264) (xy 274.889468 -291.622734) (xy 274.887576 -291.618966) (xy 274.882723 -291.612072)
			(xy 274.879816 -291.609018) (xy 274.290536 -291.019738) (xy 274.287166 -291.016543) (xy 274.279494 -291.01131)
			(xy 274.275296 -291.009324) (xy 274.266914 -291.005514) (xy 274.263866 -291.00526) (xy 274.257262 -291.005006)
			(xy 274.230404 -291.003049) (xy 274.177806 -290.991519) (xy 274.127771 -290.971618) (xy 274.081622 -290.943874)
			(xy 274.040577 -290.909018) (xy 274.005723 -290.867973) (xy 273.977979 -290.821823) (xy 273.958079 -290.771788)
			(xy 273.94655 -290.719189) (xy 273.944588 -290.692332) (xy 273.94408 -290.68268) (xy 273.939508 -290.672774)
			(xy 273.937614 -290.669007) (xy 273.932758 -290.662116) (xy 273.929856 -290.659058) (xy 273.340576 -290.069778)
			(xy 273.337209 -290.066578) (xy 273.329541 -290.061337) (xy 273.325336 -290.059364) (xy 273.316954 -290.055554)
			(xy 273.313906 -290.0553) (xy 273.307302 -290.055046) (xy 273.280441 -290.053092) (xy 273.227835 -290.041567)
			(xy 273.177792 -290.021671) (xy 273.131634 -289.993929) (xy 273.09058 -289.959075) (xy 273.055716 -289.91803)
			(xy 273.027964 -289.871878) (xy 273.008056 -289.821839) (xy 272.996518 -289.769236) (xy 272.994628 -289.742372)
			(xy 272.99412 -289.73272) (xy 272.989548 -289.722814) (xy 272.987658 -289.719045) (xy 272.982809 -289.712147)
			(xy 272.979896 -289.709098) (xy 272.390616 -289.119818) (xy 272.387248 -289.116619) (xy 272.379581 -289.111377)
			(xy 272.375376 -289.109404) (xy 272.366994 -289.105594) (xy 272.363946 -289.10534) (xy 272.357342 -289.105086)
			(xy 272.330486 -289.103128) (xy 272.277891 -289.091594) (xy 272.227861 -289.071692) (xy 272.181715 -289.043946)
			(xy 272.140676 -289.00909) (xy 272.105826 -288.968045) (xy 272.078087 -288.921896) (xy 272.058191 -288.871862)
			(xy 272.046666 -288.819266) (xy 272.044668 -288.792412) (xy 272.04416 -288.78276) (xy 272.039588 -288.772854)
			(xy 272.037698 -288.769084) (xy 272.032849 -288.762187) (xy 272.029936 -288.759138) (xy 270.490696 -287.219898)
			(xy 270.48733 -287.216696) (xy 270.479665 -287.21145) (xy 270.475456 -287.209484) (xy 270.467074 -287.205674)
			(xy 270.464026 -287.20542) (xy 270.457422 -287.205166) (xy 270.432376 -287.203366) (xy 270.383215 -287.193149)
			(xy 270.336163 -287.175617) (xy 270.292302 -287.151175) (xy 270.252639 -287.120384) (xy 270.218087 -287.083951)
			(xy 270.189439 -287.042713) (xy 270.167353 -286.997619) (xy 270.152338 -286.949705) (xy 270.144738 -286.900072)
			(xy 270.14424 -286.874966) (xy 270.144762 -286.84852) (xy 270.153182 -286.796304) (xy 270.169801 -286.746091)
			(xy 270.194198 -286.699163) (xy 270.22575 -286.656713) (xy 270.263653 -286.619824) (xy 270.306943 -286.589434)
			(xy 270.354516 -286.566319) (xy 270.379698 -286.558228) (xy 270.387826 -286.555688) (xy 270.40078 -286.546798)
			(xy 270.405606 -286.53994) (xy 270.410242 -286.533256) (xy 270.415414 -286.517842) (xy 270.415766 -286.509714)
			(xy 270.415766 -286.290004) (xy 270.415469 -286.28295) (xy 270.411479 -286.269414) (xy 270.407892 -286.263334)
			(xy 270.405606 -286.260032) (xy 270.403032 -286.256544) (xy 270.396899 -286.250419) (xy 270.393414 -286.24784)
			(xy 270.38808 -286.24403) (xy 270.379444 -286.24149) (xy 270.354275 -286.233362) (xy 270.306712 -286.210235)
			(xy 270.263434 -286.179835) (xy 270.225546 -286.142936) (xy 270.194012 -286.100477) (xy 270.169636 -286.053542)
			(xy 270.153039 -286.003326) (xy 270.144645 -285.951109) (xy 270.144667 -285.898221) (xy 270.153104 -285.846011)
			(xy 270.169742 -285.795808) (xy 270.194156 -285.748893) (xy 270.225725 -285.70646) (xy 270.263643 -285.669592)
			(xy 270.306945 -285.639227) (xy 270.354528 -285.61614) (xy 270.379698 -285.608014) (xy 270.387826 -285.605474)
			(xy 270.40078 -285.596584) (xy 270.405606 -285.589726) (xy 270.410254 -285.583045) (xy 270.415452 -285.567631)
			(xy 270.415766 -285.5595) (xy 270.415766 -285.340044) (xy 270.415462 -285.332993) (xy 270.411458 -285.319465)
			(xy 270.407892 -285.313374) (xy 270.405606 -285.310072) (xy 270.403034 -285.306582) (xy 270.396903 -285.300453)
			(xy 270.393414 -285.29788) (xy 270.38808 -285.29407) (xy 270.379444 -285.29153) (xy 270.354272 -285.283401)
			(xy 270.306702 -285.260274) (xy 270.263419 -285.229872) (xy 270.225525 -285.192969) (xy 270.193986 -285.150507)
			(xy 270.169605 -285.103567) (xy 270.153005 -285.053346) (xy 270.144608 -285.001123) (xy 270.144627 -284.948229)
			(xy 270.153064 -284.896013) (xy 270.169702 -284.845804) (xy 270.194117 -284.798882) (xy 270.225688 -284.756444)
			(xy 270.26361 -284.71957) (xy 270.306916 -284.6892) (xy 270.354503 -284.666108) (xy 270.379698 -284.658054)
			(xy 270.387826 -284.655514) (xy 270.40078 -284.646624) (xy 270.405606 -284.639766) (xy 270.410246 -284.633083)
			(xy 270.415426 -284.617669) (xy 270.415766 -284.60954) (xy 270.415766 -284.390084) (xy 270.415467 -284.383031)
			(xy 270.411472 -284.369498) (xy 270.407892 -284.363414) (xy 270.405606 -284.360112) (xy 270.403031 -284.356625)
			(xy 270.396896 -284.350502) (xy 270.393414 -284.34792) (xy 270.38808 -284.34411) (xy 270.379444 -284.34157)
			(xy 270.354277 -284.333442) (xy 270.306716 -284.310316) (xy 270.263442 -284.279917) (xy 270.225556 -284.243019)
			(xy 270.194025 -284.200562) (xy 270.169651 -284.153629) (xy 270.153057 -284.103416) (xy 270.144663 -284.051201)
			(xy 270.144686 -283.998317) (xy 270.153124 -283.94611) (xy 270.169761 -283.89591) (xy 270.194175 -283.848998)
			(xy 270.225743 -283.806569) (xy 270.26366 -283.769703) (xy 270.30696 -283.739341) (xy 270.35454 -283.716256)
			(xy 270.379698 -283.708094) (xy 270.387826 -283.705554) (xy 270.40078 -283.696664) (xy 270.405606 -283.689806)
			(xy 270.410251 -283.683124) (xy 270.415443 -283.667711) (xy 270.415766 -283.65958) (xy 270.415766 -283.440124)
			(xy 270.415472 -283.43307) (xy 270.411487 -283.41953) (xy 270.407892 -283.413454) (xy 270.405606 -283.410152)
			(xy 270.403033 -283.406663) (xy 270.396901 -283.400536) (xy 270.393414 -283.39796) (xy 270.38808 -283.39415)
			(xy 270.379444 -283.39161) (xy 270.354274 -283.383481) (xy 270.306707 -283.360355) (xy 270.263427 -283.329953)
			(xy 270.225535 -283.293052) (xy 270.193999 -283.250592) (xy 270.169621 -283.203655) (xy 270.153022 -283.153436)
			(xy 270.144626 -283.101216) (xy 270.144647 -283.048325) (xy 270.153084 -282.996112) (xy 270.169722 -282.945906)
			(xy 270.194137 -282.898988) (xy 270.225706 -282.856552) (xy 270.263627 -282.819681) (xy 270.306931 -282.789314)
			(xy 270.354516 -282.766224) (xy 270.379698 -282.758134) (xy 270.387826 -282.755594) (xy 270.40078 -282.746704)
			(xy 270.405606 -282.739846) (xy 270.410243 -282.733162) (xy 270.415417 -282.717748) (xy 270.415766 -282.70962)
			(xy 270.415766 -282.490164) (xy 270.415464 -282.483112) (xy 270.411465 -282.469581) (xy 270.407892 -282.463494)
			(xy 270.405606 -282.460192) (xy 270.403035 -282.456701) (xy 270.396906 -282.45057) (xy 270.393414 -282.448)
			(xy 270.38808 -282.44419) (xy 270.379444 -282.44165) (xy 270.354278 -282.433522) (xy 270.306721 -282.410396)
			(xy 270.26345 -282.379998) (xy 270.225567 -282.343102) (xy 270.194038 -282.300647) (xy 270.169667 -282.253716)
			(xy 270.153074 -282.203506) (xy 270.144682 -282.151294) (xy 270.144706 -282.098413) (xy 270.153144 -282.046209)
			(xy 270.169781 -281.996012) (xy 270.194194 -281.949103) (xy 270.225761 -281.906677) (xy 270.263677 -281.869814)
			(xy 270.306975 -281.839454) (xy 270.354552 -281.816371) (xy 270.379698 -281.808174) (xy 270.387826 -281.805634)
			(xy 270.40078 -281.796744) (xy 270.405606 -281.789886) (xy 270.410248 -281.783203) (xy 270.415434 -281.76779)
			(xy 270.415766 -281.75966) (xy 270.415766 -281.540204) (xy 270.415469 -281.53315) (xy 270.411479 -281.519614)
			(xy 270.407892 -281.513534) (xy 270.405606 -281.510232) (xy 270.403032 -281.506744) (xy 270.396899 -281.500619)
			(xy 270.393414 -281.49804) (xy 270.38808 -281.49423) (xy 270.379444 -281.49169) (xy 270.354275 -281.483562)
			(xy 270.306712 -281.460435) (xy 270.263434 -281.430035) (xy 270.225546 -281.393136) (xy 270.194012 -281.350677)
			(xy 270.169636 -281.303742) (xy 270.153039 -281.253526) (xy 270.144645 -281.201309) (xy 270.144667 -281.148421)
			(xy 270.153104 -281.096211) (xy 270.169742 -281.046008) (xy 270.194156 -280.999093) (xy 270.225725 -280.95666)
			(xy 270.263643 -280.919792) (xy 270.306945 -280.889427) (xy 270.354528 -280.86634) (xy 270.379698 -280.858214)
			(xy 270.387826 -280.855674) (xy 270.40078 -280.846784) (xy 270.405606 -280.839926) (xy 270.410254 -280.833245)
			(xy 270.415452 -280.817831) (xy 270.415766 -280.8097) (xy 270.415766 -280.58999) (xy 270.415468 -280.582937)
			(xy 270.411474 -280.569403) (xy 270.407892 -280.56332) (xy 270.405606 -280.560018) (xy 270.403032 -280.55653)
			(xy 270.396897 -280.550407) (xy 270.393414 -280.547826) (xy 270.38808 -280.544016) (xy 270.379444 -280.541476)
			(xy 270.354276 -280.533348) (xy 270.306715 -280.510222) (xy 270.26344 -280.479822) (xy 270.225553 -280.442924)
			(xy 270.194021 -280.400467) (xy 270.169647 -280.353533) (xy 270.153051 -280.303319) (xy 270.144658 -280.251104)
			(xy 270.14468 -280.198218) (xy 270.153118 -280.14601) (xy 270.169755 -280.09581) (xy 270.194169 -280.048897)
			(xy 270.225737 -280.006466) (xy 270.263655 -279.9696) (xy 270.306956 -279.939237) (xy 270.354536 -279.916151)
			(xy 270.379698 -279.908) (xy 270.387826 -279.90546) (xy 270.40078 -279.89657) (xy 270.405606 -279.889712)
			(xy 270.410252 -279.88303) (xy 270.415446 -279.867617) (xy 270.415766 -279.859486) (xy 270.415766 -279.64003)
			(xy 270.415473 -279.632975) (xy 270.411489 -279.619435) (xy 270.407892 -279.61336) (xy 270.405606 -279.610058)
			(xy 270.403034 -279.606569) (xy 270.396902 -279.600441) (xy 270.393414 -279.597866) (xy 270.38808 -279.594056)
			(xy 270.379444 -279.591516) (xy 270.354273 -279.583387) (xy 270.306706 -279.560261) (xy 270.263424 -279.529859)
			(xy 270.225532 -279.492958) (xy 270.193995 -279.450497) (xy 270.169616 -279.403558) (xy 270.153017 -279.353339)
			(xy 270.144621 -279.301118) (xy 270.144641 -279.248226) (xy 270.153078 -279.196012) (xy 270.169716 -279.145805)
			(xy 270.194131 -279.098886) (xy 270.225701 -279.05645) (xy 270.263622 -279.019577) (xy 270.306926 -278.989209)
			(xy 270.354512 -278.966119) (xy 270.379698 -278.95804) (xy 270.387826 -278.9555) (xy 270.40078 -278.94661)
			(xy 270.405606 -278.939752) (xy 270.410244 -278.933068) (xy 270.41542 -278.917654) (xy 270.415766 -278.909526)
			(xy 270.415766 -278.69007) (xy 270.415465 -278.683018) (xy 270.411467 -278.669486) (xy 270.407892 -278.6634)
			(xy 270.405606 -278.660098) (xy 270.403035 -278.656607) (xy 270.396906 -278.650475) (xy 270.393414 -278.647906)
			(xy 270.38808 -278.644096) (xy 270.379444 -278.641556) (xy 270.354278 -278.633428) (xy 270.30672 -278.610302)
			(xy 270.263448 -278.579904) (xy 270.225564 -278.543007) (xy 270.194034 -278.500552) (xy 270.169662 -278.45362)
			(xy 270.153069 -278.403409) (xy 270.144677 -278.351196) (xy 270.1447 -278.298314) (xy 270.153138 -278.246109)
			(xy 270.169775 -278.195912) (xy 270.194189 -278.149002) (xy 270.225756 -278.106574) (xy 270.263672 -278.069711)
			(xy 270.30697 -278.03935) (xy 270.354549 -278.016267) (xy 270.379698 -278.00808) (xy 270.387826 -278.00554)
			(xy 270.40078 -277.99665) (xy 270.405606 -277.989792) (xy 270.410249 -277.98311) (xy 270.415437 -277.967696)
			(xy 270.415766 -277.959566) (xy 270.415766 -277.74011) (xy 270.41547 -277.733056) (xy 270.411482 -277.719519)
			(xy 270.407892 -277.71344) (xy 270.405606 -277.710138) (xy 270.403033 -277.706649) (xy 270.396899 -277.700524)
			(xy 270.393414 -277.697946) (xy 270.38808 -277.694136) (xy 270.379444 -277.691596) (xy 270.354275 -277.683468)
			(xy 270.30671 -277.660341) (xy 270.263432 -277.629941) (xy 270.225543 -277.593041) (xy 270.194008 -277.550582)
			(xy 270.169631 -277.503646) (xy 270.153034 -277.453429) (xy 270.144639 -277.401211) (xy 270.144661 -277.348322)
			(xy 270.153098 -277.296111) (xy 270.169736 -277.245907) (xy 270.19415 -277.198991) (xy 270.225719 -277.156558)
			(xy 270.263638 -277.119689) (xy 270.306941 -277.089323) (xy 270.354524 -277.066235) (xy 270.379698 -277.05812)
			(xy 270.387826 -277.05558) (xy 270.40078 -277.04669) (xy 270.405606 -277.039832) (xy 270.410241 -277.033147)
			(xy 270.415411 -277.017733) (xy 270.415766 -277.009606) (xy 270.415766 -276.79015) (xy 270.415462 -276.783099)
			(xy 270.41146 -276.76957) (xy 270.407892 -276.76348) (xy 270.405606 -276.760178) (xy 270.403035 -276.756688)
			(xy 270.396904 -276.750558) (xy 270.393414 -276.747986) (xy 270.38808 -276.744176) (xy 270.379444 -276.741636)
			(xy 270.354271 -276.733507) (xy 270.306701 -276.71038) (xy 270.263416 -276.679977) (xy 270.225521 -276.643075)
			(xy 270.193982 -276.600612) (xy 270.169601 -276.553671) (xy 270.153 -276.503449) (xy 270.144602 -276.451225)
			(xy 270.144622 -276.398331) (xy 270.153058 -276.346113) (xy 270.169696 -276.295903) (xy 270.194111 -276.248981)
			(xy 270.225683 -276.206541) (xy 270.263605 -276.169666) (xy 270.306912 -276.139296) (xy 270.354499 -276.116204)
			(xy 270.379698 -276.10816) (xy 270.387826 -276.10562) (xy 270.40078 -276.09673) (xy 270.405606 -276.089872)
			(xy 270.410246 -276.083189) (xy 270.415428 -276.067775) (xy 270.415766 -276.059646) (xy 270.415766 -275.84019)
			(xy 270.415468 -275.833137) (xy 270.411474 -275.819603) (xy 270.407892 -275.81352) (xy 270.405606 -275.810218)
			(xy 270.403032 -275.80673) (xy 270.396897 -275.800607) (xy 270.393414 -275.798026) (xy 270.38808 -275.794216)
			(xy 270.379444 -275.791676) (xy 270.354276 -275.783548) (xy 270.306715 -275.760422) (xy 270.26344 -275.730022)
			(xy 270.225553 -275.693124) (xy 270.194021 -275.650667) (xy 270.169647 -275.603733) (xy 270.153051 -275.553519)
			(xy 270.144658 -275.501304) (xy 270.14468 -275.448418) (xy 270.153118 -275.39621) (xy 270.169755 -275.34601)
			(xy 270.194169 -275.299097) (xy 270.225737 -275.256666) (xy 270.263655 -275.2198) (xy 270.306956 -275.189437)
			(xy 270.354536 -275.166351) (xy 270.379698 -275.1582) (xy 270.387826 -275.15566) (xy 270.40078 -275.14677)
			(xy 270.405606 -275.139912) (xy 270.410252 -275.13323) (xy 270.415446 -275.117817) (xy 270.415766 -275.109686)
			(xy 270.415766 -274.89023) (xy 270.415473 -274.883175) (xy 270.411489 -274.869635) (xy 270.407892 -274.86356)
			(xy 270.405606 -274.860258) (xy 270.403034 -274.856769) (xy 270.396902 -274.850641) (xy 270.393414 -274.848066)
			(xy 270.38808 -274.844256) (xy 270.379444 -274.841716) (xy 270.354273 -274.833587) (xy 270.306706 -274.810461)
			(xy 270.263424 -274.780059) (xy 270.225532 -274.743158) (xy 270.193995 -274.700697) (xy 270.169616 -274.653758)
			(xy 270.153017 -274.603539) (xy 270.144621 -274.551318) (xy 270.144641 -274.498426) (xy 270.153078 -274.446212)
			(xy 270.169716 -274.396005) (xy 270.194131 -274.349086) (xy 270.225701 -274.30665) (xy 270.263622 -274.269777)
			(xy 270.306926 -274.239409) (xy 270.354512 -274.216319) (xy 270.379698 -274.20824) (xy 270.387826 -274.2057)
			(xy 270.40078 -274.19681) (xy 270.405606 -274.189952) (xy 270.410244 -274.183268) (xy 270.41542 -274.167854)
			(xy 270.415766 -274.159726) (xy 270.415766 -273.940016) (xy 270.415471 -273.932962) (xy 270.411484 -273.919424)
			(xy 270.407892 -273.913346) (xy 270.405606 -273.910044) (xy 270.403033 -273.906555) (xy 270.3969 -273.900429)
			(xy 270.393414 -273.897852) (xy 270.38808 -273.894042) (xy 270.379444 -273.891502) (xy 270.354257 -273.883391)
			(xy 270.306654 -273.860291) (xy 270.263337 -273.829906) (xy 270.225411 -273.793011) (xy 270.193844 -273.750547)
			(xy 270.169441 -273.703599) (xy 270.152826 -273.653364) (xy 270.144421 -273.601124) (xy 270.144442 -273.548212)
			(xy 270.152889 -273.495979) (xy 270.169544 -273.445758) (xy 270.193984 -273.398829) (xy 270.225585 -273.356391)
			(xy 270.263541 -273.319526) (xy 270.306882 -273.289175) (xy 270.354503 -273.266113) (xy 270.379698 -273.258026)
			(xy 270.387826 -273.255486) (xy 270.40078 -273.246596) (xy 270.405606 -273.239738) (xy 270.410242 -273.233054)
			(xy 270.415413 -273.21764) (xy 270.415766 -273.209512) (xy 270.415766 -272.990056) (xy 270.415463 -272.983004)
			(xy 270.411462 -272.969475) (xy 270.407892 -272.963386) (xy 270.405606 -272.960084) (xy 270.403035 -272.956593)
			(xy 270.396905 -272.950463) (xy 270.393414 -272.947892) (xy 270.38808 -272.944082) (xy 270.379444 -272.941542)
			(xy 270.354271 -272.933413) (xy 270.306699 -272.910286) (xy 270.263414 -272.879883) (xy 270.225518 -272.84298)
			(xy 270.193978 -272.800516) (xy 270.169596 -272.753575) (xy 270.152995 -272.703352) (xy 270.144596 -272.651128)
			(xy 270.144616 -272.598232) (xy 270.153052 -272.546013) (xy 270.16969 -272.495803) (xy 270.194106 -272.448879)
			(xy 270.225677 -272.406439) (xy 270.2636 -272.369563) (xy 270.306907 -272.339192) (xy 270.354496 -272.316099)
			(xy 270.379698 -272.308066) (xy 270.387826 -272.305526) (xy 270.40078 -272.296636) (xy 270.405606 -272.289778)
			(xy 270.410247 -272.283095) (xy 270.415431 -272.267681) (xy 270.415766 -272.259552) (xy 270.415766 -266.001754)
			(xy 270.415766 -263.80948) (xy 270.415766 -263.777222) (xy 270.415512 -263.773158) (xy 270.414342 -263.763886)
			(xy 270.406279 -263.747045) (xy 270.392734 -263.734192) (xy 270.38427 -263.730232) (xy 270.358481 -263.719022)
			(xy 270.310237 -263.690132) (xy 270.266756 -263.654474) (xy 270.228981 -263.612819) (xy 270.197729 -263.566071)
			(xy 270.173679 -263.515241) (xy 270.15735 -263.461432) (xy 270.149097 -263.405809) (xy 270.149098 -263.349576)
			(xy 270.157353 -263.293953) (xy 270.173684 -263.240145) (xy 270.197737 -263.189316) (xy 270.22899 -263.142569)
			(xy 270.266767 -263.100916) (xy 270.310249 -263.065259) (xy 270.358494 -263.036371) (xy 270.38427 -263.025128)
			(xy 270.392762 -263.0212) (xy 270.406353 -263.008366) (xy 270.414395 -262.991491) (xy 270.415512 -262.982202)
			(xy 270.415766 -262.978138) (xy 270.415766 -260.712712) (xy 270.415594 -260.706704) (xy 270.412761 -260.695026)
			(xy 270.410178 -260.689598) (xy 270.408339 -260.686124) (xy 270.403745 -260.679745) (xy 270.401034 -260.676898)
			(xy 269.582392 -259.858256) (xy 269.579541 -259.85555) (xy 269.573163 -259.850956) (xy 269.569692 -259.849112)
			(xy 269.564266 -259.846525) (xy 269.552586 -259.843692) (xy 269.546578 -259.843524) (xy 267.181584 -259.843524)
			(xy 267.176972 -259.843625) (xy 267.167899 -259.845287) (xy 267.16355 -259.846826) (xy 267.160017 -259.84822)
			(xy 267.153386 -259.85192) (xy 267.150342 -259.854192) (xy 267.128997 -259.873547) (xy 267.081568 -259.906262)
			(xy 267.029759 -259.931472) (xy 266.974747 -259.948605) (xy 266.917785 -259.95727) (xy 266.860167 -259.95727)
			(xy 266.803205 -259.948605) (xy 266.748193 -259.931472) (xy 266.696384 -259.906262) (xy 266.648955 -259.873547)
			(xy 266.62761 -259.854192) (xy 266.624562 -259.851928) (xy 266.61793 -259.848229) (xy 266.614402 -259.846826)
			(xy 266.610054 -259.845282) (xy 266.600981 -259.843619) (xy 266.596368 -259.843524) (xy 266.423648 -259.843524)
			(xy 266.417639 -259.843692) (xy 266.405957 -259.846517) (xy 266.400534 -259.849112) (xy 266.397058 -259.850949)
			(xy 266.390675 -259.855539) (xy 266.387834 -259.858256) (xy 266.191238 -260.054852) (xy 266.18853 -260.057701)
			(xy 266.183931 -260.064077) (xy 266.182094 -260.067552) (xy 266.179512 -260.072979) (xy 266.176691 -260.084659)
			(xy 266.176506 -260.090666) (xy 266.176506 -260.338316) (xy 268.778988 -260.338316) (xy 268.783059 -260.282694)
			(xy 268.795185 -260.228257) (xy 268.815108 -260.176166) (xy 268.842404 -260.127531) (xy 268.87649 -260.083388)
			(xy 268.916639 -260.044679) (xy 268.961997 -260.012228) (xy 269.011597 -259.986727) (xy 269.064381 -259.96872)
			(xy 269.119224 -259.95859) (xy 269.174958 -259.956553) (xy 269.230395 -259.962653) (xy 269.284352 -259.976759)
			(xy 269.335681 -259.998571) (xy 269.383287 -260.027625) (xy 269.426155 -260.0633) (xy 269.463372 -260.104837)
			(xy 269.494145 -260.15135) (xy 269.517817 -260.201847) (xy 269.533885 -260.255254) (xy 269.542005 -260.31043)
			(xy 269.542514 -260.338316) (xy 269.542005 -260.366202) (xy 269.533885 -260.421378) (xy 269.517817 -260.474785)
			(xy 269.494145 -260.525282) (xy 269.463372 -260.571795) (xy 269.426155 -260.613332) (xy 269.383287 -260.649007)
			(xy 269.335681 -260.678061) (xy 269.284352 -260.699873) (xy 269.230395 -260.713979) (xy 269.174958 -260.720079)
			(xy 269.119224 -260.718042) (xy 269.064381 -260.707912) (xy 269.011597 -260.689905) (xy 268.961997 -260.664404)
			(xy 268.916639 -260.631953) (xy 268.87649 -260.593244) (xy 268.842404 -260.549101) (xy 268.815108 -260.500466)
			(xy 268.795185 -260.448375) (xy 268.783059 -260.393938) (xy 268.778988 -260.338316) (xy 266.176506 -260.338316)
			(xy 266.176506 -262.676386) (xy 266.17803 -262.682482) (xy 266.183036 -262.704558) (xy 266.188383 -262.74951)
			(xy 266.188698 -262.772144) (xy 266.188698 -262.772652) (xy 266.188698 -262.77316) (xy 266.188362 -262.795793)
			(xy 266.183016 -262.840743) (xy 266.17803 -262.862822) (xy 266.176506 -262.868918) (xy 266.176506 -264.250424)
			(xy 268.14983 -264.250424) (xy 268.153901 -264.194802) (xy 268.166027 -264.140365) (xy 268.18595 -264.088274)
			(xy 268.213246 -264.039639) (xy 268.247332 -263.995496) (xy 268.287481 -263.956787) (xy 268.332839 -263.924336)
			(xy 268.382439 -263.898835) (xy 268.435223 -263.880828) (xy 268.490066 -263.870698) (xy 268.5458 -263.868661)
			(xy 268.601237 -263.874761) (xy 268.655194 -263.888867) (xy 268.706523 -263.910679) (xy 268.754129 -263.939733)
			(xy 268.796997 -263.975408) (xy 268.834214 -264.016945) (xy 268.864987 -264.063458) (xy 268.888659 -264.113955)
			(xy 268.904727 -264.167362) (xy 268.912847 -264.222538) (xy 268.913356 -264.250424) (xy 268.912847 -264.27831)
			(xy 268.904727 -264.333486) (xy 268.888659 -264.386893) (xy 268.864987 -264.43739) (xy 268.834214 -264.483903)
			(xy 268.796997 -264.52544) (xy 268.754129 -264.561115) (xy 268.706523 -264.590169) (xy 268.655194 -264.611981)
			(xy 268.601237 -264.626087) (xy 268.5458 -264.632187) (xy 268.490066 -264.63015) (xy 268.435223 -264.62002)
			(xy 268.382439 -264.602013) (xy 268.332839 -264.576512) (xy 268.287481 -264.544061) (xy 268.247332 -264.505352)
			(xy 268.213246 -264.461209) (xy 268.18595 -264.412574) (xy 268.166027 -264.360483) (xy 268.153901 -264.306046)
			(xy 268.14983 -264.250424) (xy 266.176506 -264.250424) (xy 266.176506 -264.683748) (xy 266.176673 -264.689758)
			(xy 266.179497 -264.70144) (xy 266.182094 -264.706862) (xy 266.18393 -264.710339) (xy 266.188518 -264.716723)
			(xy 266.191238 -264.719562) (xy 266.8397 -265.368024) (xy 266.846543 -265.375424) (xy 266.854268 -265.394022)
			(xy 266.854686 -265.404092) (xy 266.854686 -266.822174) (xy 268.90218 -266.822174) (xy 268.902666 -266.794923)
			(xy 268.910422 -266.740975) (xy 268.925777 -266.68868) (xy 268.948419 -266.639103) (xy 268.977885 -266.593253)
			(xy 269.013576 -266.552062) (xy 269.054767 -266.516371) (xy 269.100617 -266.486905) (xy 269.150194 -266.464263)
			(xy 269.202489 -266.448908) (xy 269.256437 -266.441152) (xy 269.310939 -266.441152) (xy 269.364887 -266.448908)
			(xy 269.417182 -266.464263) (xy 269.466759 -266.486905) (xy 269.512609 -266.516371) (xy 269.5538 -266.552062)
			(xy 269.589491 -266.593253) (xy 269.618957 -266.639103) (xy 269.641599 -266.68868) (xy 269.656954 -266.740975)
			(xy 269.66471 -266.794923) (xy 269.665196 -266.822174) (xy 269.664723 -266.849884) (xy 269.65669 -266.90472)
			(xy 269.640803 -266.957815) (xy 269.617398 -267.008051) (xy 269.586966 -267.054369) (xy 269.56893 -267.075412)
			(xy 269.560331 -267.085734) (xy 269.548359 -267.109773) (xy 269.543065 -267.136103) (xy 269.544816 -267.162901)
			(xy 269.55349 -267.188318) (xy 269.568488 -267.210596) (xy 269.588773 -267.228196) (xy 269.60068 -267.234416)
			(xy 269.624563 -267.246491) (xy 269.669059 -267.276219) (xy 269.708964 -267.311875) (xy 269.743492 -267.352759)
			(xy 269.771965 -267.398068) (xy 269.793826 -267.446913) (xy 269.808643 -267.498334) (xy 269.816127 -267.551321)
			(xy 269.81658 -267.578078) (xy 269.816094 -267.605329) (xy 269.808338 -267.659277) (xy 269.792983 -267.711572)
			(xy 269.770341 -267.761149) (xy 269.740875 -267.806999) (xy 269.705184 -267.84819) (xy 269.663993 -267.883881)
			(xy 269.618143 -267.913347) (xy 269.568566 -267.935989) (xy 269.516271 -267.951344) (xy 269.462323 -267.9591)
			(xy 269.407821 -267.9591) (xy 269.353873 -267.951344) (xy 269.301578 -267.935989) (xy 269.252001 -267.913347)
			(xy 269.206151 -267.883881) (xy 269.16496 -267.84819) (xy 269.129269 -267.806999) (xy 269.099803 -267.761149)
			(xy 269.077161 -267.711572) (xy 269.061806 -267.659277) (xy 269.05405 -267.605329) (xy 269.053564 -267.578078)
			(xy 269.054078 -267.550369) (xy 269.062103 -267.495536) (xy 269.07798 -267.442442) (xy 269.101377 -267.392205)
			(xy 269.131798 -267.345885) (xy 269.14983 -267.32484) (xy 269.158498 -267.31457) (xy 269.170472 -267.290516)
			(xy 269.175762 -267.264173) (xy 269.174003 -267.237361) (xy 269.165315 -267.211935) (xy 269.150301 -267.189652)
			(xy 269.129997 -267.172053) (xy 269.11808 -267.165836) (xy 269.094169 -267.153815) (xy 269.049672 -267.124079)
			(xy 269.00977 -267.088414) (xy 268.975245 -267.047522) (xy 268.946775 -267.002205) (xy 268.924919 -266.953353)
			(xy 268.910107 -266.901926) (xy 268.90263 -266.848933) (xy 268.90218 -266.822174) (xy 266.854686 -266.822174)
			(xy 266.854686 -273.388328) (xy 266.854257 -273.398396) (xy 266.846534 -273.416991) (xy 266.8397 -273.424396)
			(xy 266.812776 -273.45132) (xy 266.810069 -273.45417) (xy 266.805475 -273.460548) (xy 266.803632 -273.46402)
			(xy 266.801045 -273.469446) (xy 266.798214 -273.481126) (xy 266.798044 -273.487134) (xy 266.798044 -273.574764)
			(xy 269.21893 -273.574764) (xy 269.22289 -273.52571) (xy 269.234667 -273.477926) (xy 269.253958 -273.43265)
			(xy 269.280261 -273.391054) (xy 269.312896 -273.354217) (xy 269.351017 -273.323092) (xy 269.393638 -273.298485)
			(xy 269.439654 -273.281033) (xy 269.487873 -273.271189) (xy 269.537048 -273.269208) (xy 269.585903 -273.27514)
			(xy 269.633174 -273.288832) (xy 269.677636 -273.30993) (xy 269.718139 -273.337886) (xy 269.753632 -273.371978)
			(xy 269.783197 -273.411322) (xy 269.806068 -273.454899) (xy 269.821652 -273.50158) (xy 269.829547 -273.550157)
			(xy 269.830042 -273.574764) (xy 269.829547 -273.599371) (xy 269.821652 -273.647948) (xy 269.806068 -273.694629)
			(xy 269.783197 -273.738206) (xy 269.753632 -273.77755) (xy 269.718139 -273.811642) (xy 269.677636 -273.839598)
			(xy 269.633174 -273.860696) (xy 269.585903 -273.874388) (xy 269.537048 -273.88032) (xy 269.487873 -273.878339)
			(xy 269.439654 -273.868495) (xy 269.393638 -273.851043) (xy 269.351017 -273.826436) (xy 269.312896 -273.795311)
			(xy 269.280261 -273.758474) (xy 269.253958 -273.716878) (xy 269.234667 -273.671602) (xy 269.22289 -273.623818)
			(xy 269.21893 -273.574764) (xy 266.798044 -273.574764) (xy 266.798044 -274.524724) (xy 269.21893 -274.524724)
			(xy 269.22289 -274.47567) (xy 269.234667 -274.427886) (xy 269.253958 -274.38261) (xy 269.280261 -274.341014)
			(xy 269.312896 -274.304177) (xy 269.351017 -274.273052) (xy 269.393638 -274.248445) (xy 269.439654 -274.230993)
			(xy 269.487873 -274.221149) (xy 269.537048 -274.219168) (xy 269.585903 -274.2251) (xy 269.633174 -274.238792)
			(xy 269.677636 -274.25989) (xy 269.718139 -274.287846) (xy 269.753632 -274.321938) (xy 269.783197 -274.361282)
			(xy 269.806068 -274.404859) (xy 269.821652 -274.45154) (xy 269.829547 -274.500117) (xy 269.830042 -274.524724)
			(xy 269.829547 -274.549331) (xy 269.821652 -274.597908) (xy 269.806068 -274.644589) (xy 269.783197 -274.688166)
			(xy 269.753632 -274.72751) (xy 269.718139 -274.761602) (xy 269.677636 -274.789558) (xy 269.633174 -274.810656)
			(xy 269.585903 -274.824348) (xy 269.537048 -274.83028) (xy 269.487873 -274.828299) (xy 269.439654 -274.818455)
			(xy 269.393638 -274.801003) (xy 269.351017 -274.776396) (xy 269.312896 -274.745271) (xy 269.280261 -274.708434)
			(xy 269.253958 -274.666838) (xy 269.234667 -274.621562) (xy 269.22289 -274.573778) (xy 269.21893 -274.524724)
			(xy 266.798044 -274.524724) (xy 266.798044 -275.474938) (xy 268.26897 -275.474938) (xy 268.27293 -275.425884)
			(xy 268.284707 -275.3781) (xy 268.303998 -275.332824) (xy 268.330301 -275.291228) (xy 268.362936 -275.254391)
			(xy 268.401057 -275.223266) (xy 268.443678 -275.198659) (xy 268.489694 -275.181207) (xy 268.537913 -275.171363)
			(xy 268.587088 -275.169382) (xy 268.635943 -275.175314) (xy 268.683214 -275.189006) (xy 268.727676 -275.210104)
			(xy 268.768179 -275.23806) (xy 268.803672 -275.272152) (xy 268.833237 -275.311496) (xy 268.856108 -275.355073)
			(xy 268.871692 -275.401754) (xy 268.879587 -275.450331) (xy 268.880082 -275.474938) (xy 269.21893 -275.474938)
			(xy 269.22289 -275.425884) (xy 269.234667 -275.3781) (xy 269.253958 -275.332824) (xy 269.280261 -275.291228)
			(xy 269.312896 -275.254391) (xy 269.351017 -275.223266) (xy 269.393638 -275.198659) (xy 269.439654 -275.181207)
			(xy 269.487873 -275.171363) (xy 269.537048 -275.169382) (xy 269.585903 -275.175314) (xy 269.633174 -275.189006)
			(xy 269.677636 -275.210104) (xy 269.718139 -275.23806) (xy 269.753632 -275.272152) (xy 269.783197 -275.311496)
			(xy 269.806068 -275.355073) (xy 269.821652 -275.401754) (xy 269.829547 -275.450331) (xy 269.830042 -275.474938)
			(xy 269.829547 -275.499545) (xy 269.821652 -275.548122) (xy 269.806068 -275.594803) (xy 269.783197 -275.63838)
			(xy 269.753632 -275.677724) (xy 269.718139 -275.711816) (xy 269.677636 -275.739772) (xy 269.633174 -275.76087)
			(xy 269.585903 -275.774562) (xy 269.537048 -275.780494) (xy 269.487873 -275.778513) (xy 269.439654 -275.768669)
			(xy 269.393638 -275.751217) (xy 269.351017 -275.72661) (xy 269.312896 -275.695485) (xy 269.280261 -275.658648)
			(xy 269.253958 -275.617052) (xy 269.234667 -275.571776) (xy 269.22289 -275.523992) (xy 269.21893 -275.474938)
			(xy 268.880082 -275.474938) (xy 268.879587 -275.499545) (xy 268.871692 -275.548122) (xy 268.856108 -275.594803)
			(xy 268.833237 -275.63838) (xy 268.803672 -275.677724) (xy 268.768179 -275.711816) (xy 268.727676 -275.739772)
			(xy 268.683214 -275.76087) (xy 268.635943 -275.774562) (xy 268.587088 -275.780494) (xy 268.537913 -275.778513)
			(xy 268.489694 -275.768669) (xy 268.443678 -275.751217) (xy 268.401057 -275.72661) (xy 268.362936 -275.695485)
			(xy 268.330301 -275.658648) (xy 268.303998 -275.617052) (xy 268.284707 -275.571776) (xy 268.27293 -275.523992)
			(xy 268.26897 -275.474938) (xy 266.798044 -275.474938) (xy 266.798044 -276.424898) (xy 268.26897 -276.424898)
			(xy 268.27293 -276.375844) (xy 268.284707 -276.32806) (xy 268.303998 -276.282784) (xy 268.330301 -276.241188)
			(xy 268.362936 -276.204351) (xy 268.401057 -276.173226) (xy 268.443678 -276.148619) (xy 268.489694 -276.131167)
			(xy 268.537913 -276.121323) (xy 268.587088 -276.119342) (xy 268.635943 -276.125274) (xy 268.683214 -276.138966)
			(xy 268.727676 -276.160064) (xy 268.768179 -276.18802) (xy 268.803672 -276.222112) (xy 268.833237 -276.261456)
			(xy 268.856108 -276.305033) (xy 268.871692 -276.351714) (xy 268.879587 -276.400291) (xy 268.880082 -276.424898)
			(xy 269.21893 -276.424898) (xy 269.22289 -276.375844) (xy 269.234667 -276.32806) (xy 269.253958 -276.282784)
			(xy 269.280261 -276.241188) (xy 269.312896 -276.204351) (xy 269.351017 -276.173226) (xy 269.393638 -276.148619)
			(xy 269.439654 -276.131167) (xy 269.487873 -276.121323) (xy 269.537048 -276.119342) (xy 269.585903 -276.125274)
			(xy 269.633174 -276.138966) (xy 269.677636 -276.160064) (xy 269.718139 -276.18802) (xy 269.753632 -276.222112)
			(xy 269.783197 -276.261456) (xy 269.806068 -276.305033) (xy 269.821652 -276.351714) (xy 269.829547 -276.400291)
			(xy 269.830042 -276.424898) (xy 269.829547 -276.449505) (xy 269.821652 -276.498082) (xy 269.806068 -276.544763)
			(xy 269.783197 -276.58834) (xy 269.753632 -276.627684) (xy 269.718139 -276.661776) (xy 269.677636 -276.689732)
			(xy 269.633174 -276.71083) (xy 269.585903 -276.724522) (xy 269.537048 -276.730454) (xy 269.487873 -276.728473)
			(xy 269.439654 -276.718629) (xy 269.393638 -276.701177) (xy 269.351017 -276.67657) (xy 269.312896 -276.645445)
			(xy 269.280261 -276.608608) (xy 269.253958 -276.567012) (xy 269.234667 -276.521736) (xy 269.22289 -276.473952)
			(xy 269.21893 -276.424898) (xy 268.880082 -276.424898) (xy 268.879587 -276.449505) (xy 268.871692 -276.498082)
			(xy 268.856108 -276.544763) (xy 268.833237 -276.58834) (xy 268.803672 -276.627684) (xy 268.768179 -276.661776)
			(xy 268.727676 -276.689732) (xy 268.683214 -276.71083) (xy 268.635943 -276.724522) (xy 268.587088 -276.730454)
			(xy 268.537913 -276.728473) (xy 268.489694 -276.718629) (xy 268.443678 -276.701177) (xy 268.401057 -276.67657)
			(xy 268.362936 -276.645445) (xy 268.330301 -276.608608) (xy 268.303998 -276.567012) (xy 268.284707 -276.521736)
			(xy 268.27293 -276.473952) (xy 268.26897 -276.424898) (xy 266.798044 -276.424898) (xy 266.798044 -277.374858)
			(xy 268.26897 -277.374858) (xy 268.27293 -277.325804) (xy 268.284707 -277.27802) (xy 268.303998 -277.232744)
			(xy 268.330301 -277.191148) (xy 268.362936 -277.154311) (xy 268.401057 -277.123186) (xy 268.443678 -277.098579)
			(xy 268.489694 -277.081127) (xy 268.537913 -277.071283) (xy 268.587088 -277.069302) (xy 268.635943 -277.075234)
			(xy 268.683214 -277.088926) (xy 268.727676 -277.110024) (xy 268.768179 -277.13798) (xy 268.803672 -277.172072)
			(xy 268.833237 -277.211416) (xy 268.856108 -277.254993) (xy 268.871692 -277.301674) (xy 268.879587 -277.350251)
			(xy 268.880082 -277.374858) (xy 269.21893 -277.374858) (xy 269.22289 -277.325804) (xy 269.234667 -277.27802)
			(xy 269.253958 -277.232744) (xy 269.280261 -277.191148) (xy 269.312896 -277.154311) (xy 269.351017 -277.123186)
			(xy 269.393638 -277.098579) (xy 269.439654 -277.081127) (xy 269.487873 -277.071283) (xy 269.537048 -277.069302)
			(xy 269.585903 -277.075234) (xy 269.633174 -277.088926) (xy 269.677636 -277.110024) (xy 269.718139 -277.13798)
			(xy 269.753632 -277.172072) (xy 269.783197 -277.211416) (xy 269.806068 -277.254993) (xy 269.821652 -277.301674)
			(xy 269.829547 -277.350251) (xy 269.830042 -277.374858) (xy 269.829547 -277.399465) (xy 269.821652 -277.448042)
			(xy 269.806068 -277.494723) (xy 269.783197 -277.5383) (xy 269.753632 -277.577644) (xy 269.718139 -277.611736)
			(xy 269.677636 -277.639692) (xy 269.633174 -277.66079) (xy 269.585903 -277.674482) (xy 269.537048 -277.680414)
			(xy 269.487873 -277.678433) (xy 269.439654 -277.668589) (xy 269.393638 -277.651137) (xy 269.351017 -277.62653)
			(xy 269.312896 -277.595405) (xy 269.280261 -277.558568) (xy 269.253958 -277.516972) (xy 269.234667 -277.471696)
			(xy 269.22289 -277.423912) (xy 269.21893 -277.374858) (xy 268.880082 -277.374858) (xy 268.879587 -277.399465)
			(xy 268.871692 -277.448042) (xy 268.856108 -277.494723) (xy 268.833237 -277.5383) (xy 268.803672 -277.577644)
			(xy 268.768179 -277.611736) (xy 268.727676 -277.639692) (xy 268.683214 -277.66079) (xy 268.635943 -277.674482)
			(xy 268.587088 -277.680414) (xy 268.537913 -277.678433) (xy 268.489694 -277.668589) (xy 268.443678 -277.651137)
			(xy 268.401057 -277.62653) (xy 268.362936 -277.595405) (xy 268.330301 -277.558568) (xy 268.303998 -277.516972)
			(xy 268.284707 -277.471696) (xy 268.27293 -277.423912) (xy 268.26897 -277.374858) (xy 266.798044 -277.374858)
			(xy 266.798044 -278.324818) (xy 268.26897 -278.324818) (xy 268.27293 -278.275764) (xy 268.284707 -278.22798)
			(xy 268.303998 -278.182704) (xy 268.330301 -278.141108) (xy 268.362936 -278.104271) (xy 268.401057 -278.073146)
			(xy 268.443678 -278.048539) (xy 268.489694 -278.031087) (xy 268.537913 -278.021243) (xy 268.587088 -278.019262)
			(xy 268.635943 -278.025194) (xy 268.683214 -278.038886) (xy 268.727676 -278.059984) (xy 268.768179 -278.08794)
			(xy 268.803672 -278.122032) (xy 268.833237 -278.161376) (xy 268.856108 -278.204953) (xy 268.871692 -278.251634)
			(xy 268.879587 -278.300211) (xy 268.880082 -278.324818) (xy 269.21893 -278.324818) (xy 269.22289 -278.275764)
			(xy 269.234667 -278.22798) (xy 269.253958 -278.182704) (xy 269.280261 -278.141108) (xy 269.312896 -278.104271)
			(xy 269.351017 -278.073146) (xy 269.393638 -278.048539) (xy 269.439654 -278.031087) (xy 269.487873 -278.021243)
			(xy 269.537048 -278.019262) (xy 269.585903 -278.025194) (xy 269.633174 -278.038886) (xy 269.677636 -278.059984)
			(xy 269.718139 -278.08794) (xy 269.753632 -278.122032) (xy 269.783197 -278.161376) (xy 269.806068 -278.204953)
			(xy 269.821652 -278.251634) (xy 269.829547 -278.300211) (xy 269.830042 -278.324818) (xy 269.829547 -278.349425)
			(xy 269.821652 -278.398002) (xy 269.806068 -278.444683) (xy 269.783197 -278.48826) (xy 269.753632 -278.527604)
			(xy 269.718139 -278.561696) (xy 269.677636 -278.589652) (xy 269.633174 -278.61075) (xy 269.585903 -278.624442)
			(xy 269.537048 -278.630374) (xy 269.487873 -278.628393) (xy 269.439654 -278.618549) (xy 269.393638 -278.601097)
			(xy 269.351017 -278.57649) (xy 269.312896 -278.545365) (xy 269.280261 -278.508528) (xy 269.253958 -278.466932)
			(xy 269.234667 -278.421656) (xy 269.22289 -278.373872) (xy 269.21893 -278.324818) (xy 268.880082 -278.324818)
			(xy 268.879587 -278.349425) (xy 268.871692 -278.398002) (xy 268.856108 -278.444683) (xy 268.833237 -278.48826)
			(xy 268.803672 -278.527604) (xy 268.768179 -278.561696) (xy 268.727676 -278.589652) (xy 268.683214 -278.61075)
			(xy 268.635943 -278.624442) (xy 268.587088 -278.630374) (xy 268.537913 -278.628393) (xy 268.489694 -278.618549)
			(xy 268.443678 -278.601097) (xy 268.401057 -278.57649) (xy 268.362936 -278.545365) (xy 268.330301 -278.508528)
			(xy 268.303998 -278.466932) (xy 268.284707 -278.421656) (xy 268.27293 -278.373872) (xy 268.26897 -278.324818)
			(xy 266.798044 -278.324818) (xy 266.798044 -279.274778) (xy 268.26897 -279.274778) (xy 268.27293 -279.225724)
			(xy 268.284707 -279.17794) (xy 268.303998 -279.132664) (xy 268.330301 -279.091068) (xy 268.362936 -279.054231)
			(xy 268.401057 -279.023106) (xy 268.443678 -278.998499) (xy 268.489694 -278.981047) (xy 268.537913 -278.971203)
			(xy 268.587088 -278.969222) (xy 268.635943 -278.975154) (xy 268.683214 -278.988846) (xy 268.727676 -279.009944)
			(xy 268.768179 -279.0379) (xy 268.803672 -279.071992) (xy 268.833237 -279.111336) (xy 268.856108 -279.154913)
			(xy 268.871692 -279.201594) (xy 268.879587 -279.250171) (xy 268.880082 -279.274778) (xy 269.21893 -279.274778)
			(xy 269.22289 -279.225724) (xy 269.234667 -279.17794) (xy 269.253958 -279.132664) (xy 269.280261 -279.091068)
			(xy 269.312896 -279.054231) (xy 269.351017 -279.023106) (xy 269.393638 -278.998499) (xy 269.439654 -278.981047)
			(xy 269.487873 -278.971203) (xy 269.537048 -278.969222) (xy 269.585903 -278.975154) (xy 269.633174 -278.988846)
			(xy 269.677636 -279.009944) (xy 269.718139 -279.0379) (xy 269.753632 -279.071992) (xy 269.783197 -279.111336)
			(xy 269.806068 -279.154913) (xy 269.821652 -279.201594) (xy 269.829547 -279.250171) (xy 269.830042 -279.274778)
			(xy 269.829547 -279.299385) (xy 269.821652 -279.347962) (xy 269.806068 -279.394643) (xy 269.783197 -279.43822)
			(xy 269.753632 -279.477564) (xy 269.718139 -279.511656) (xy 269.677636 -279.539612) (xy 269.633174 -279.56071)
			(xy 269.585903 -279.574402) (xy 269.537048 -279.580334) (xy 269.487873 -279.578353) (xy 269.439654 -279.568509)
			(xy 269.393638 -279.551057) (xy 269.351017 -279.52645) (xy 269.312896 -279.495325) (xy 269.280261 -279.458488)
			(xy 269.253958 -279.416892) (xy 269.234667 -279.371616) (xy 269.22289 -279.323832) (xy 269.21893 -279.274778)
			(xy 268.880082 -279.274778) (xy 268.879587 -279.299385) (xy 268.871692 -279.347962) (xy 268.856108 -279.394643)
			(xy 268.833237 -279.43822) (xy 268.803672 -279.477564) (xy 268.768179 -279.511656) (xy 268.727676 -279.539612)
			(xy 268.683214 -279.56071) (xy 268.635943 -279.574402) (xy 268.587088 -279.580334) (xy 268.537913 -279.578353)
			(xy 268.489694 -279.568509) (xy 268.443678 -279.551057) (xy 268.401057 -279.52645) (xy 268.362936 -279.495325)
			(xy 268.330301 -279.458488) (xy 268.303998 -279.416892) (xy 268.284707 -279.371616) (xy 268.27293 -279.323832)
			(xy 268.26897 -279.274778) (xy 266.798044 -279.274778) (xy 266.798044 -279.917906) (xy 266.798298 -279.917906)
			(xy 266.798298 -280.224738) (xy 268.26897 -280.224738) (xy 268.27293 -280.175684) (xy 268.284707 -280.1279)
			(xy 268.303998 -280.082624) (xy 268.330301 -280.041028) (xy 268.362936 -280.004191) (xy 268.401057 -279.973066)
			(xy 268.443678 -279.948459) (xy 268.489694 -279.931007) (xy 268.537913 -279.921163) (xy 268.587088 -279.919182)
			(xy 268.635943 -279.925114) (xy 268.683214 -279.938806) (xy 268.727676 -279.959904) (xy 268.768179 -279.98786)
			(xy 268.803672 -280.021952) (xy 268.833237 -280.061296) (xy 268.856108 -280.104873) (xy 268.871692 -280.151554)
			(xy 268.879587 -280.200131) (xy 268.880082 -280.224738) (xy 269.21893 -280.224738) (xy 269.22289 -280.175684)
			(xy 269.234667 -280.1279) (xy 269.253958 -280.082624) (xy 269.280261 -280.041028) (xy 269.312896 -280.004191)
			(xy 269.351017 -279.973066) (xy 269.393638 -279.948459) (xy 269.439654 -279.931007) (xy 269.487873 -279.921163)
			(xy 269.537048 -279.919182) (xy 269.585903 -279.925114) (xy 269.633174 -279.938806) (xy 269.677636 -279.959904)
			(xy 269.718139 -279.98786) (xy 269.753632 -280.021952) (xy 269.783197 -280.061296) (xy 269.806068 -280.104873)
			(xy 269.821652 -280.151554) (xy 269.829547 -280.200131) (xy 269.830042 -280.224738) (xy 269.829547 -280.249345)
			(xy 269.821652 -280.297922) (xy 269.806068 -280.344603) (xy 269.783197 -280.38818) (xy 269.753632 -280.427524)
			(xy 269.718139 -280.461616) (xy 269.677636 -280.489572) (xy 269.633174 -280.51067) (xy 269.585903 -280.524362)
			(xy 269.537048 -280.530294) (xy 269.487873 -280.528313) (xy 269.439654 -280.518469) (xy 269.393638 -280.501017)
			(xy 269.351017 -280.47641) (xy 269.312896 -280.445285) (xy 269.280261 -280.408448) (xy 269.253958 -280.366852)
			(xy 269.234667 -280.321576) (xy 269.22289 -280.273792) (xy 269.21893 -280.224738) (xy 268.880082 -280.224738)
			(xy 268.879587 -280.249345) (xy 268.871692 -280.297922) (xy 268.856108 -280.344603) (xy 268.833237 -280.38818)
			(xy 268.803672 -280.427524) (xy 268.768179 -280.461616) (xy 268.727676 -280.489572) (xy 268.683214 -280.51067)
			(xy 268.635943 -280.524362) (xy 268.587088 -280.530294) (xy 268.537913 -280.528313) (xy 268.489694 -280.518469)
			(xy 268.443678 -280.501017) (xy 268.401057 -280.47641) (xy 268.362936 -280.445285) (xy 268.330301 -280.408448)
			(xy 268.303998 -280.366852) (xy 268.284707 -280.321576) (xy 268.27293 -280.273792) (xy 268.26897 -280.224738)
			(xy 266.798298 -280.224738) (xy 266.798298 -281.174952) (xy 268.26897 -281.174952) (xy 268.27293 -281.125898)
			(xy 268.284707 -281.078114) (xy 268.303998 -281.032838) (xy 268.330301 -280.991242) (xy 268.362936 -280.954405)
			(xy 268.401057 -280.92328) (xy 268.443678 -280.898673) (xy 268.489694 -280.881221) (xy 268.537913 -280.871377)
			(xy 268.587088 -280.869396) (xy 268.635943 -280.875328) (xy 268.683214 -280.88902) (xy 268.727676 -280.910118)
			(xy 268.768179 -280.938074) (xy 268.803672 -280.972166) (xy 268.833237 -281.01151) (xy 268.856108 -281.055087)
			(xy 268.871692 -281.101768) (xy 268.879587 -281.150345) (xy 268.880082 -281.174952) (xy 269.21893 -281.174952)
			(xy 269.22289 -281.125898) (xy 269.234667 -281.078114) (xy 269.253958 -281.032838) (xy 269.280261 -280.991242)
			(xy 269.312896 -280.954405) (xy 269.351017 -280.92328) (xy 269.393638 -280.898673) (xy 269.439654 -280.881221)
			(xy 269.487873 -280.871377) (xy 269.537048 -280.869396) (xy 269.585903 -280.875328) (xy 269.633174 -280.88902)
			(xy 269.677636 -280.910118) (xy 269.718139 -280.938074) (xy 269.753632 -280.972166) (xy 269.783197 -281.01151)
			(xy 269.806068 -281.055087) (xy 269.821652 -281.101768) (xy 269.829547 -281.150345) (xy 269.830042 -281.174952)
			(xy 269.829547 -281.199559) (xy 269.821652 -281.248136) (xy 269.806068 -281.294817) (xy 269.783197 -281.338394)
			(xy 269.753632 -281.377738) (xy 269.718139 -281.41183) (xy 269.677636 -281.439786) (xy 269.633174 -281.460884)
			(xy 269.585903 -281.474576) (xy 269.537048 -281.480508) (xy 269.487873 -281.478527) (xy 269.439654 -281.468683)
			(xy 269.393638 -281.451231) (xy 269.351017 -281.426624) (xy 269.312896 -281.395499) (xy 269.280261 -281.358662)
			(xy 269.253958 -281.317066) (xy 269.234667 -281.27179) (xy 269.22289 -281.224006) (xy 269.21893 -281.174952)
			(xy 268.880082 -281.174952) (xy 268.879587 -281.199559) (xy 268.871692 -281.248136) (xy 268.856108 -281.294817)
			(xy 268.833237 -281.338394) (xy 268.803672 -281.377738) (xy 268.768179 -281.41183) (xy 268.727676 -281.439786)
			(xy 268.683214 -281.460884) (xy 268.635943 -281.474576) (xy 268.587088 -281.480508) (xy 268.537913 -281.478527)
			(xy 268.489694 -281.468683) (xy 268.443678 -281.451231) (xy 268.401057 -281.426624) (xy 268.362936 -281.395499)
			(xy 268.330301 -281.358662) (xy 268.303998 -281.317066) (xy 268.284707 -281.27179) (xy 268.27293 -281.224006)
			(xy 268.26897 -281.174952) (xy 266.798298 -281.174952) (xy 266.798298 -282.124912) (xy 268.26897 -282.124912)
			(xy 268.27293 -282.075858) (xy 268.284707 -282.028074) (xy 268.303998 -281.982798) (xy 268.330301 -281.941202)
			(xy 268.362936 -281.904365) (xy 268.401057 -281.87324) (xy 268.443678 -281.848633) (xy 268.489694 -281.831181)
			(xy 268.537913 -281.821337) (xy 268.587088 -281.819356) (xy 268.635943 -281.825288) (xy 268.683214 -281.83898)
			(xy 268.727676 -281.860078) (xy 268.768179 -281.888034) (xy 268.803672 -281.922126) (xy 268.833237 -281.96147)
			(xy 268.856108 -282.005047) (xy 268.871692 -282.051728) (xy 268.879587 -282.100305) (xy 268.880082 -282.124912)
			(xy 269.21893 -282.124912) (xy 269.22289 -282.075858) (xy 269.234667 -282.028074) (xy 269.253958 -281.982798)
			(xy 269.280261 -281.941202) (xy 269.312896 -281.904365) (xy 269.351017 -281.87324) (xy 269.393638 -281.848633)
			(xy 269.439654 -281.831181) (xy 269.487873 -281.821337) (xy 269.537048 -281.819356) (xy 269.585903 -281.825288)
			(xy 269.633174 -281.83898) (xy 269.677636 -281.860078) (xy 269.718139 -281.888034) (xy 269.753632 -281.922126)
			(xy 269.783197 -281.96147) (xy 269.806068 -282.005047) (xy 269.821652 -282.051728) (xy 269.829547 -282.100305)
			(xy 269.830042 -282.124912) (xy 269.829547 -282.149519) (xy 269.821652 -282.198096) (xy 269.806068 -282.244777)
			(xy 269.783197 -282.288354) (xy 269.753632 -282.327698) (xy 269.718139 -282.36179) (xy 269.677636 -282.389746)
			(xy 269.633174 -282.410844) (xy 269.585903 -282.424536) (xy 269.537048 -282.430468) (xy 269.487873 -282.428487)
			(xy 269.439654 -282.418643) (xy 269.393638 -282.401191) (xy 269.351017 -282.376584) (xy 269.312896 -282.345459)
			(xy 269.280261 -282.308622) (xy 269.253958 -282.267026) (xy 269.234667 -282.22175) (xy 269.22289 -282.173966)
			(xy 269.21893 -282.124912) (xy 268.880082 -282.124912) (xy 268.879587 -282.149519) (xy 268.871692 -282.198096)
			(xy 268.856108 -282.244777) (xy 268.833237 -282.288354) (xy 268.803672 -282.327698) (xy 268.768179 -282.36179)
			(xy 268.727676 -282.389746) (xy 268.683214 -282.410844) (xy 268.635943 -282.424536) (xy 268.587088 -282.430468)
			(xy 268.537913 -282.428487) (xy 268.489694 -282.418643) (xy 268.443678 -282.401191) (xy 268.401057 -282.376584)
			(xy 268.362936 -282.345459) (xy 268.330301 -282.308622) (xy 268.303998 -282.267026) (xy 268.284707 -282.22175)
			(xy 268.27293 -282.173966) (xy 268.26897 -282.124912) (xy 266.798298 -282.124912) (xy 266.798298 -283.074872)
			(xy 268.26897 -283.074872) (xy 268.27293 -283.025818) (xy 268.284707 -282.978034) (xy 268.303998 -282.932758)
			(xy 268.330301 -282.891162) (xy 268.362936 -282.854325) (xy 268.401057 -282.8232) (xy 268.443678 -282.798593)
			(xy 268.489694 -282.781141) (xy 268.537913 -282.771297) (xy 268.587088 -282.769316) (xy 268.635943 -282.775248)
			(xy 268.683214 -282.78894) (xy 268.727676 -282.810038) (xy 268.768179 -282.837994) (xy 268.803672 -282.872086)
			(xy 268.833237 -282.91143) (xy 268.856108 -282.955007) (xy 268.871692 -283.001688) (xy 268.879587 -283.050265)
			(xy 268.880082 -283.074872) (xy 269.21893 -283.074872) (xy 269.22289 -283.025818) (xy 269.234667 -282.978034)
			(xy 269.253958 -282.932758) (xy 269.280261 -282.891162) (xy 269.312896 -282.854325) (xy 269.351017 -282.8232)
			(xy 269.393638 -282.798593) (xy 269.439654 -282.781141) (xy 269.487873 -282.771297) (xy 269.537048 -282.769316)
			(xy 269.585903 -282.775248) (xy 269.633174 -282.78894) (xy 269.677636 -282.810038) (xy 269.718139 -282.837994)
			(xy 269.753632 -282.872086) (xy 269.783197 -282.91143) (xy 269.806068 -282.955007) (xy 269.821652 -283.001688)
			(xy 269.829547 -283.050265) (xy 269.830042 -283.074872) (xy 269.829547 -283.099479) (xy 269.821652 -283.148056)
			(xy 269.806068 -283.194737) (xy 269.783197 -283.238314) (xy 269.753632 -283.277658) (xy 269.718139 -283.31175)
			(xy 269.677636 -283.339706) (xy 269.633174 -283.360804) (xy 269.585903 -283.374496) (xy 269.537048 -283.380428)
			(xy 269.487873 -283.378447) (xy 269.439654 -283.368603) (xy 269.393638 -283.351151) (xy 269.351017 -283.326544)
			(xy 269.312896 -283.295419) (xy 269.280261 -283.258582) (xy 269.253958 -283.216986) (xy 269.234667 -283.17171)
			(xy 269.22289 -283.123926) (xy 269.21893 -283.074872) (xy 268.880082 -283.074872) (xy 268.879587 -283.099479)
			(xy 268.871692 -283.148056) (xy 268.856108 -283.194737) (xy 268.833237 -283.238314) (xy 268.803672 -283.277658)
			(xy 268.768179 -283.31175) (xy 268.727676 -283.339706) (xy 268.683214 -283.360804) (xy 268.635943 -283.374496)
			(xy 268.587088 -283.380428) (xy 268.537913 -283.378447) (xy 268.489694 -283.368603) (xy 268.443678 -283.351151)
			(xy 268.401057 -283.326544) (xy 268.362936 -283.295419) (xy 268.330301 -283.258582) (xy 268.303998 -283.216986)
			(xy 268.284707 -283.17171) (xy 268.27293 -283.123926) (xy 268.26897 -283.074872) (xy 266.798298 -283.074872)
			(xy 266.798298 -284.024832) (xy 268.26897 -284.024832) (xy 268.27293 -283.975778) (xy 268.284707 -283.927994)
			(xy 268.303998 -283.882718) (xy 268.330301 -283.841122) (xy 268.362936 -283.804285) (xy 268.401057 -283.77316)
			(xy 268.443678 -283.748553) (xy 268.489694 -283.731101) (xy 268.537913 -283.721257) (xy 268.587088 -283.719276)
			(xy 268.635943 -283.725208) (xy 268.683214 -283.7389) (xy 268.727676 -283.759998) (xy 268.768179 -283.787954)
			(xy 268.803672 -283.822046) (xy 268.833237 -283.86139) (xy 268.856108 -283.904967) (xy 268.871692 -283.951648)
			(xy 268.879587 -284.000225) (xy 268.880082 -284.024832) (xy 269.21893 -284.024832) (xy 269.22289 -283.975778)
			(xy 269.234667 -283.927994) (xy 269.253958 -283.882718) (xy 269.280261 -283.841122) (xy 269.312896 -283.804285)
			(xy 269.351017 -283.77316) (xy 269.393638 -283.748553) (xy 269.439654 -283.731101) (xy 269.487873 -283.721257)
			(xy 269.537048 -283.719276) (xy 269.585903 -283.725208) (xy 269.633174 -283.7389) (xy 269.677636 -283.759998)
			(xy 269.718139 -283.787954) (xy 269.753632 -283.822046) (xy 269.783197 -283.86139) (xy 269.806068 -283.904967)
			(xy 269.821652 -283.951648) (xy 269.829547 -284.000225) (xy 269.830042 -284.024832) (xy 269.829547 -284.049439)
			(xy 269.821652 -284.098016) (xy 269.806068 -284.144697) (xy 269.783197 -284.188274) (xy 269.753632 -284.227618)
			(xy 269.718139 -284.26171) (xy 269.677636 -284.289666) (xy 269.633174 -284.310764) (xy 269.585903 -284.324456)
			(xy 269.537048 -284.330388) (xy 269.487873 -284.328407) (xy 269.439654 -284.318563) (xy 269.393638 -284.301111)
			(xy 269.351017 -284.276504) (xy 269.312896 -284.245379) (xy 269.280261 -284.208542) (xy 269.253958 -284.166946)
			(xy 269.234667 -284.12167) (xy 269.22289 -284.073886) (xy 269.21893 -284.024832) (xy 268.880082 -284.024832)
			(xy 268.879587 -284.049439) (xy 268.871692 -284.098016) (xy 268.856108 -284.144697) (xy 268.833237 -284.188274)
			(xy 268.803672 -284.227618) (xy 268.768179 -284.26171) (xy 268.727676 -284.289666) (xy 268.683214 -284.310764)
			(xy 268.635943 -284.324456) (xy 268.587088 -284.330388) (xy 268.537913 -284.328407) (xy 268.489694 -284.318563)
			(xy 268.443678 -284.301111) (xy 268.401057 -284.276504) (xy 268.362936 -284.245379) (xy 268.330301 -284.208542)
			(xy 268.303998 -284.166946) (xy 268.284707 -284.12167) (xy 268.27293 -284.073886) (xy 268.26897 -284.024832)
			(xy 266.798298 -284.024832) (xy 266.798298 -284.974792) (xy 268.26897 -284.974792) (xy 268.27293 -284.925738)
			(xy 268.284707 -284.877954) (xy 268.303998 -284.832678) (xy 268.330301 -284.791082) (xy 268.362936 -284.754245)
			(xy 268.401057 -284.72312) (xy 268.443678 -284.698513) (xy 268.489694 -284.681061) (xy 268.537913 -284.671217)
			(xy 268.587088 -284.669236) (xy 268.635943 -284.675168) (xy 268.683214 -284.68886) (xy 268.727676 -284.709958)
			(xy 268.768179 -284.737914) (xy 268.803672 -284.772006) (xy 268.833237 -284.81135) (xy 268.856108 -284.854927)
			(xy 268.871692 -284.901608) (xy 268.879587 -284.950185) (xy 268.880082 -284.974792) (xy 269.21893 -284.974792)
			(xy 269.22289 -284.925738) (xy 269.234667 -284.877954) (xy 269.253958 -284.832678) (xy 269.280261 -284.791082)
			(xy 269.312896 -284.754245) (xy 269.351017 -284.72312) (xy 269.393638 -284.698513) (xy 269.439654 -284.681061)
			(xy 269.487873 -284.671217) (xy 269.537048 -284.669236) (xy 269.585903 -284.675168) (xy 269.633174 -284.68886)
			(xy 269.677636 -284.709958) (xy 269.718139 -284.737914) (xy 269.753632 -284.772006) (xy 269.783197 -284.81135)
			(xy 269.806068 -284.854927) (xy 269.821652 -284.901608) (xy 269.829547 -284.950185) (xy 269.830042 -284.974792)
			(xy 269.829547 -284.999399) (xy 269.821652 -285.047976) (xy 269.806068 -285.094657) (xy 269.783197 -285.138234)
			(xy 269.753632 -285.177578) (xy 269.718139 -285.21167) (xy 269.677636 -285.239626) (xy 269.633174 -285.260724)
			(xy 269.585903 -285.274416) (xy 269.537048 -285.280348) (xy 269.487873 -285.278367) (xy 269.439654 -285.268523)
			(xy 269.393638 -285.251071) (xy 269.351017 -285.226464) (xy 269.312896 -285.195339) (xy 269.280261 -285.158502)
			(xy 269.253958 -285.116906) (xy 269.234667 -285.07163) (xy 269.22289 -285.023846) (xy 269.21893 -284.974792)
			(xy 268.880082 -284.974792) (xy 268.879587 -284.999399) (xy 268.871692 -285.047976) (xy 268.856108 -285.094657)
			(xy 268.833237 -285.138234) (xy 268.803672 -285.177578) (xy 268.768179 -285.21167) (xy 268.727676 -285.239626)
			(xy 268.683214 -285.260724) (xy 268.635943 -285.274416) (xy 268.587088 -285.280348) (xy 268.537913 -285.278367)
			(xy 268.489694 -285.268523) (xy 268.443678 -285.251071) (xy 268.401057 -285.226464) (xy 268.362936 -285.195339)
			(xy 268.330301 -285.158502) (xy 268.303998 -285.116906) (xy 268.284707 -285.07163) (xy 268.27293 -285.023846)
			(xy 268.26897 -284.974792) (xy 266.798298 -284.974792) (xy 266.798298 -285.924752) (xy 268.26897 -285.924752)
			(xy 268.27293 -285.875698) (xy 268.284707 -285.827914) (xy 268.303998 -285.782638) (xy 268.330301 -285.741042)
			(xy 268.362936 -285.704205) (xy 268.401057 -285.67308) (xy 268.443678 -285.648473) (xy 268.489694 -285.631021)
			(xy 268.537913 -285.621177) (xy 268.587088 -285.619196) (xy 268.635943 -285.625128) (xy 268.683214 -285.63882)
			(xy 268.727676 -285.659918) (xy 268.768179 -285.687874) (xy 268.803672 -285.721966) (xy 268.833237 -285.76131)
			(xy 268.856108 -285.804887) (xy 268.871692 -285.851568) (xy 268.879587 -285.900145) (xy 268.880082 -285.924752)
			(xy 269.21893 -285.924752) (xy 269.22289 -285.875698) (xy 269.234667 -285.827914) (xy 269.253958 -285.782638)
			(xy 269.280261 -285.741042) (xy 269.312896 -285.704205) (xy 269.351017 -285.67308) (xy 269.393638 -285.648473)
			(xy 269.439654 -285.631021) (xy 269.487873 -285.621177) (xy 269.537048 -285.619196) (xy 269.585903 -285.625128)
			(xy 269.633174 -285.63882) (xy 269.677636 -285.659918) (xy 269.718139 -285.687874) (xy 269.753632 -285.721966)
			(xy 269.783197 -285.76131) (xy 269.806068 -285.804887) (xy 269.821652 -285.851568) (xy 269.829547 -285.900145)
			(xy 269.830042 -285.924752) (xy 269.829547 -285.949359) (xy 269.821652 -285.997936) (xy 269.806068 -286.044617)
			(xy 269.783197 -286.088194) (xy 269.753632 -286.127538) (xy 269.718139 -286.16163) (xy 269.677636 -286.189586)
			(xy 269.633174 -286.210684) (xy 269.585903 -286.224376) (xy 269.537048 -286.230308) (xy 269.487873 -286.228327)
			(xy 269.439654 -286.218483) (xy 269.393638 -286.201031) (xy 269.351017 -286.176424) (xy 269.312896 -286.145299)
			(xy 269.280261 -286.108462) (xy 269.253958 -286.066866) (xy 269.234667 -286.02159) (xy 269.22289 -285.973806)
			(xy 269.21893 -285.924752) (xy 268.880082 -285.924752) (xy 268.879587 -285.949359) (xy 268.871692 -285.997936)
			(xy 268.856108 -286.044617) (xy 268.833237 -286.088194) (xy 268.803672 -286.127538) (xy 268.768179 -286.16163)
			(xy 268.727676 -286.189586) (xy 268.683214 -286.210684) (xy 268.635943 -286.224376) (xy 268.587088 -286.230308)
			(xy 268.537913 -286.228327) (xy 268.489694 -286.218483) (xy 268.443678 -286.201031) (xy 268.401057 -286.176424)
			(xy 268.362936 -286.145299) (xy 268.330301 -286.108462) (xy 268.303998 -286.066866) (xy 268.284707 -286.02159)
			(xy 268.27293 -285.973806) (xy 268.26897 -285.924752) (xy 266.798298 -285.924752) (xy 266.798298 -286.874966)
			(xy 268.26897 -286.874966) (xy 268.27293 -286.825912) (xy 268.284707 -286.778128) (xy 268.303998 -286.732852)
			(xy 268.330301 -286.691256) (xy 268.362936 -286.654419) (xy 268.401057 -286.623294) (xy 268.443678 -286.598687)
			(xy 268.489694 -286.581235) (xy 268.537913 -286.571391) (xy 268.587088 -286.56941) (xy 268.635943 -286.575342)
			(xy 268.683214 -286.589034) (xy 268.727676 -286.610132) (xy 268.768179 -286.638088) (xy 268.803672 -286.67218)
			(xy 268.833237 -286.711524) (xy 268.856108 -286.755101) (xy 268.871692 -286.801782) (xy 268.879587 -286.850359)
			(xy 268.880082 -286.874966) (xy 269.21893 -286.874966) (xy 269.22289 -286.825912) (xy 269.234667 -286.778128)
			(xy 269.253958 -286.732852) (xy 269.280261 -286.691256) (xy 269.312896 -286.654419) (xy 269.351017 -286.623294)
			(xy 269.393638 -286.598687) (xy 269.439654 -286.581235) (xy 269.487873 -286.571391) (xy 269.537048 -286.56941)
			(xy 269.585903 -286.575342) (xy 269.633174 -286.589034) (xy 269.677636 -286.610132) (xy 269.718139 -286.638088)
			(xy 269.753632 -286.67218) (xy 269.783197 -286.711524) (xy 269.806068 -286.755101) (xy 269.821652 -286.801782)
			(xy 269.829547 -286.850359) (xy 269.830042 -286.874966) (xy 269.829547 -286.899573) (xy 269.821652 -286.94815)
			(xy 269.806068 -286.994831) (xy 269.783197 -287.038408) (xy 269.753632 -287.077752) (xy 269.718139 -287.111844)
			(xy 269.677636 -287.1398) (xy 269.633174 -287.160898) (xy 269.585903 -287.17459) (xy 269.537048 -287.180522)
			(xy 269.487873 -287.178541) (xy 269.439654 -287.168697) (xy 269.393638 -287.151245) (xy 269.351017 -287.126638)
			(xy 269.312896 -287.095513) (xy 269.280261 -287.058676) (xy 269.253958 -287.01708) (xy 269.234667 -286.971804)
			(xy 269.22289 -286.92402) (xy 269.21893 -286.874966) (xy 268.880082 -286.874966) (xy 268.879587 -286.899573)
			(xy 268.871692 -286.94815) (xy 268.856108 -286.994831) (xy 268.833237 -287.038408) (xy 268.803672 -287.077752)
			(xy 268.768179 -287.111844) (xy 268.727676 -287.1398) (xy 268.683214 -287.160898) (xy 268.635943 -287.17459)
			(xy 268.587088 -287.180522) (xy 268.537913 -287.178541) (xy 268.489694 -287.168697) (xy 268.443678 -287.151245)
			(xy 268.401057 -287.126638) (xy 268.362936 -287.095513) (xy 268.330301 -287.058676) (xy 268.303998 -287.01708)
			(xy 268.284707 -286.971804) (xy 268.27293 -286.92402) (xy 268.26897 -286.874966) (xy 266.798298 -286.874966)
			(xy 266.798298 -287.824926) (xy 268.26897 -287.824926) (xy 268.27293 -287.775872) (xy 268.284707 -287.728088)
			(xy 268.303998 -287.682812) (xy 268.330301 -287.641216) (xy 268.362936 -287.604379) (xy 268.401057 -287.573254)
			(xy 268.443678 -287.548647) (xy 268.489694 -287.531195) (xy 268.537913 -287.521351) (xy 268.587088 -287.51937)
			(xy 268.635943 -287.525302) (xy 268.683214 -287.538994) (xy 268.727676 -287.560092) (xy 268.768179 -287.588048)
			(xy 268.803672 -287.62214) (xy 268.833237 -287.661484) (xy 268.856108 -287.705061) (xy 268.871692 -287.751742)
			(xy 268.879587 -287.800319) (xy 268.880082 -287.824926) (xy 269.21893 -287.824926) (xy 269.22289 -287.775872)
			(xy 269.234667 -287.728088) (xy 269.253958 -287.682812) (xy 269.280261 -287.641216) (xy 269.312896 -287.604379)
			(xy 269.351017 -287.573254) (xy 269.393638 -287.548647) (xy 269.439654 -287.531195) (xy 269.487873 -287.521351)
			(xy 269.537048 -287.51937) (xy 269.585903 -287.525302) (xy 269.633174 -287.538994) (xy 269.677636 -287.560092)
			(xy 269.718139 -287.588048) (xy 269.753632 -287.62214) (xy 269.783197 -287.661484) (xy 269.806068 -287.705061)
			(xy 269.821652 -287.751742) (xy 269.829547 -287.800319) (xy 269.830042 -287.824926) (xy 270.169144 -287.824926)
			(xy 270.173104 -287.775872) (xy 270.184881 -287.728088) (xy 270.204172 -287.682812) (xy 270.230475 -287.641216)
			(xy 270.26311 -287.604379) (xy 270.301231 -287.573254) (xy 270.343852 -287.548647) (xy 270.389868 -287.531195)
			(xy 270.438087 -287.521351) (xy 270.487262 -287.51937) (xy 270.536117 -287.525302) (xy 270.583388 -287.538994)
			(xy 270.62785 -287.560092) (xy 270.668353 -287.588048) (xy 270.703846 -287.62214) (xy 270.733411 -287.661484)
			(xy 270.756282 -287.705061) (xy 270.771866 -287.751742) (xy 270.779761 -287.800319) (xy 270.780256 -287.824926)
			(xy 270.779761 -287.849533) (xy 270.771866 -287.89811) (xy 270.756282 -287.944791) (xy 270.733411 -287.988368)
			(xy 270.703846 -288.027712) (xy 270.668353 -288.061804) (xy 270.62785 -288.08976) (xy 270.583388 -288.110858)
			(xy 270.536117 -288.12455) (xy 270.487262 -288.130482) (xy 270.438087 -288.128501) (xy 270.389868 -288.118657)
			(xy 270.343852 -288.101205) (xy 270.301231 -288.076598) (xy 270.26311 -288.045473) (xy 270.230475 -288.008636)
			(xy 270.204172 -287.96704) (xy 270.184881 -287.921764) (xy 270.173104 -287.87398) (xy 270.169144 -287.824926)
			(xy 269.830042 -287.824926) (xy 269.829547 -287.849533) (xy 269.821652 -287.89811) (xy 269.806068 -287.944791)
			(xy 269.783197 -287.988368) (xy 269.753632 -288.027712) (xy 269.718139 -288.061804) (xy 269.677636 -288.08976)
			(xy 269.633174 -288.110858) (xy 269.585903 -288.12455) (xy 269.537048 -288.130482) (xy 269.487873 -288.128501)
			(xy 269.439654 -288.118657) (xy 269.393638 -288.101205) (xy 269.351017 -288.076598) (xy 269.312896 -288.045473)
			(xy 269.280261 -288.008636) (xy 269.253958 -287.96704) (xy 269.234667 -287.921764) (xy 269.22289 -287.87398)
			(xy 269.21893 -287.824926) (xy 268.880082 -287.824926) (xy 268.879587 -287.849533) (xy 268.871692 -287.89811)
			(xy 268.856108 -287.944791) (xy 268.833237 -287.988368) (xy 268.803672 -288.027712) (xy 268.768179 -288.061804)
			(xy 268.727676 -288.08976) (xy 268.683214 -288.110858) (xy 268.635943 -288.12455) (xy 268.587088 -288.130482)
			(xy 268.537913 -288.128501) (xy 268.489694 -288.118657) (xy 268.443678 -288.101205) (xy 268.401057 -288.076598)
			(xy 268.362936 -288.045473) (xy 268.330301 -288.008636) (xy 268.303998 -287.96704) (xy 268.284707 -287.921764)
			(xy 268.27293 -287.87398) (xy 268.26897 -287.824926) (xy 266.798298 -287.824926) (xy 266.798298 -288.774886)
			(xy 268.26897 -288.774886) (xy 268.27293 -288.725832) (xy 268.284707 -288.678048) (xy 268.303998 -288.632772)
			(xy 268.330301 -288.591176) (xy 268.362936 -288.554339) (xy 268.401057 -288.523214) (xy 268.443678 -288.498607)
			(xy 268.489694 -288.481155) (xy 268.537913 -288.471311) (xy 268.587088 -288.46933) (xy 268.635943 -288.475262)
			(xy 268.683214 -288.488954) (xy 268.727676 -288.510052) (xy 268.768179 -288.538008) (xy 268.803672 -288.5721)
			(xy 268.833237 -288.611444) (xy 268.856108 -288.655021) (xy 268.871692 -288.701702) (xy 268.879587 -288.750279)
			(xy 268.880082 -288.774886) (xy 269.21893 -288.774886) (xy 269.22289 -288.725832) (xy 269.234667 -288.678048)
			(xy 269.253958 -288.632772) (xy 269.280261 -288.591176) (xy 269.312896 -288.554339) (xy 269.351017 -288.523214)
			(xy 269.393638 -288.498607) (xy 269.439654 -288.481155) (xy 269.487873 -288.471311) (xy 269.537048 -288.46933)
			(xy 269.585903 -288.475262) (xy 269.633174 -288.488954) (xy 269.677636 -288.510052) (xy 269.718139 -288.538008)
			(xy 269.753632 -288.5721) (xy 269.783197 -288.611444) (xy 269.806068 -288.655021) (xy 269.821652 -288.701702)
			(xy 269.829547 -288.750279) (xy 269.830042 -288.774886) (xy 270.169144 -288.774886) (xy 270.173104 -288.725832)
			(xy 270.184881 -288.678048) (xy 270.204172 -288.632772) (xy 270.230475 -288.591176) (xy 270.26311 -288.554339)
			(xy 270.301231 -288.523214) (xy 270.343852 -288.498607) (xy 270.389868 -288.481155) (xy 270.438087 -288.471311)
			(xy 270.487262 -288.46933) (xy 270.536117 -288.475262) (xy 270.583388 -288.488954) (xy 270.62785 -288.510052)
			(xy 270.668353 -288.538008) (xy 270.703846 -288.5721) (xy 270.733411 -288.611444) (xy 270.756282 -288.655021)
			(xy 270.771866 -288.701702) (xy 270.779761 -288.750279) (xy 270.780256 -288.774886) (xy 271.119104 -288.774886)
			(xy 271.123064 -288.725832) (xy 271.134841 -288.678048) (xy 271.154132 -288.632772) (xy 271.180435 -288.591176)
			(xy 271.21307 -288.554339) (xy 271.251191 -288.523214) (xy 271.293812 -288.498607) (xy 271.339828 -288.481155)
			(xy 271.388047 -288.471311) (xy 271.437222 -288.46933) (xy 271.486077 -288.475262) (xy 271.533348 -288.488954)
			(xy 271.57781 -288.510052) (xy 271.618313 -288.538008) (xy 271.653806 -288.5721) (xy 271.683371 -288.611444)
			(xy 271.706242 -288.655021) (xy 271.721826 -288.701702) (xy 271.729721 -288.750279) (xy 271.730216 -288.774886)
			(xy 271.729721 -288.799493) (xy 271.721826 -288.84807) (xy 271.706242 -288.894751) (xy 271.683371 -288.938328)
			(xy 271.653806 -288.977672) (xy 271.618313 -289.011764) (xy 271.57781 -289.03972) (xy 271.533348 -289.060818)
			(xy 271.486077 -289.07451) (xy 271.437222 -289.080442) (xy 271.388047 -289.078461) (xy 271.339828 -289.068617)
			(xy 271.293812 -289.051165) (xy 271.251191 -289.026558) (xy 271.21307 -288.995433) (xy 271.180435 -288.958596)
			(xy 271.154132 -288.917) (xy 271.134841 -288.871724) (xy 271.123064 -288.82394) (xy 271.119104 -288.774886)
			(xy 270.780256 -288.774886) (xy 270.779761 -288.799493) (xy 270.771866 -288.84807) (xy 270.756282 -288.894751)
			(xy 270.733411 -288.938328) (xy 270.703846 -288.977672) (xy 270.668353 -289.011764) (xy 270.62785 -289.03972)
			(xy 270.583388 -289.060818) (xy 270.536117 -289.07451) (xy 270.487262 -289.080442) (xy 270.438087 -289.078461)
			(xy 270.389868 -289.068617) (xy 270.343852 -289.051165) (xy 270.301231 -289.026558) (xy 270.26311 -288.995433)
			(xy 270.230475 -288.958596) (xy 270.204172 -288.917) (xy 270.184881 -288.871724) (xy 270.173104 -288.82394)
			(xy 270.169144 -288.774886) (xy 269.830042 -288.774886) (xy 269.829547 -288.799493) (xy 269.821652 -288.84807)
			(xy 269.806068 -288.894751) (xy 269.783197 -288.938328) (xy 269.753632 -288.977672) (xy 269.718139 -289.011764)
			(xy 269.677636 -289.03972) (xy 269.633174 -289.060818) (xy 269.585903 -289.07451) (xy 269.537048 -289.080442)
			(xy 269.487873 -289.078461) (xy 269.439654 -289.068617) (xy 269.393638 -289.051165) (xy 269.351017 -289.026558)
			(xy 269.312896 -288.995433) (xy 269.280261 -288.958596) (xy 269.253958 -288.917) (xy 269.234667 -288.871724)
			(xy 269.22289 -288.82394) (xy 269.21893 -288.774886) (xy 268.880082 -288.774886) (xy 268.879587 -288.799493)
			(xy 268.871692 -288.84807) (xy 268.856108 -288.894751) (xy 268.833237 -288.938328) (xy 268.803672 -288.977672)
			(xy 268.768179 -289.011764) (xy 268.727676 -289.03972) (xy 268.683214 -289.060818) (xy 268.635943 -289.07451)
			(xy 268.587088 -289.080442) (xy 268.537913 -289.078461) (xy 268.489694 -289.068617) (xy 268.443678 -289.051165)
			(xy 268.401057 -289.026558) (xy 268.362936 -288.995433) (xy 268.330301 -288.958596) (xy 268.303998 -288.917)
			(xy 268.284707 -288.871724) (xy 268.27293 -288.82394) (xy 268.26897 -288.774886) (xy 266.798298 -288.774886)
			(xy 266.798298 -289.1028) (xy 266.798772 -289.112768) (xy 266.806343 -289.131209) (xy 266.81303 -289.138614)
			(xy 267.399262 -289.724846) (xy 268.26897 -289.724846) (xy 268.27293 -289.675792) (xy 268.284707 -289.628008)
			(xy 268.303998 -289.582732) (xy 268.330301 -289.541136) (xy 268.362936 -289.504299) (xy 268.401057 -289.473174)
			(xy 268.443678 -289.448567) (xy 268.489694 -289.431115) (xy 268.537913 -289.421271) (xy 268.587088 -289.41929)
			(xy 268.635943 -289.425222) (xy 268.683214 -289.438914) (xy 268.727676 -289.460012) (xy 268.768179 -289.487968)
			(xy 268.803672 -289.52206) (xy 268.833237 -289.561404) (xy 268.856108 -289.604981) (xy 268.871692 -289.651662)
			(xy 268.879587 -289.700239) (xy 268.880082 -289.724846) (xy 269.21893 -289.724846) (xy 269.22289 -289.675792)
			(xy 269.234667 -289.628008) (xy 269.253958 -289.582732) (xy 269.280261 -289.541136) (xy 269.312896 -289.504299)
			(xy 269.351017 -289.473174) (xy 269.393638 -289.448567) (xy 269.439654 -289.431115) (xy 269.487873 -289.421271)
			(xy 269.537048 -289.41929) (xy 269.585903 -289.425222) (xy 269.633174 -289.438914) (xy 269.677636 -289.460012)
			(xy 269.718139 -289.487968) (xy 269.753632 -289.52206) (xy 269.783197 -289.561404) (xy 269.806068 -289.604981)
			(xy 269.821652 -289.651662) (xy 269.829547 -289.700239) (xy 269.830042 -289.724846) (xy 270.169144 -289.724846)
			(xy 270.173104 -289.675792) (xy 270.184881 -289.628008) (xy 270.204172 -289.582732) (xy 270.230475 -289.541136)
			(xy 270.26311 -289.504299) (xy 270.301231 -289.473174) (xy 270.343852 -289.448567) (xy 270.389868 -289.431115)
			(xy 270.438087 -289.421271) (xy 270.487262 -289.41929) (xy 270.536117 -289.425222) (xy 270.583388 -289.438914)
			(xy 270.62785 -289.460012) (xy 270.668353 -289.487968) (xy 270.703846 -289.52206) (xy 270.733411 -289.561404)
			(xy 270.756282 -289.604981) (xy 270.771866 -289.651662) (xy 270.779761 -289.700239) (xy 270.780256 -289.724846)
			(xy 271.119104 -289.724846) (xy 271.123064 -289.675792) (xy 271.134841 -289.628008) (xy 271.154132 -289.582732)
			(xy 271.180435 -289.541136) (xy 271.21307 -289.504299) (xy 271.251191 -289.473174) (xy 271.293812 -289.448567)
			(xy 271.339828 -289.431115) (xy 271.388047 -289.421271) (xy 271.437222 -289.41929) (xy 271.486077 -289.425222)
			(xy 271.533348 -289.438914) (xy 271.57781 -289.460012) (xy 271.618313 -289.487968) (xy 271.653806 -289.52206)
			(xy 271.683371 -289.561404) (xy 271.706242 -289.604981) (xy 271.721826 -289.651662) (xy 271.729721 -289.700239)
			(xy 271.730216 -289.724846) (xy 272.069064 -289.724846) (xy 272.073024 -289.675792) (xy 272.084801 -289.628008)
			(xy 272.104092 -289.582732) (xy 272.130395 -289.541136) (xy 272.16303 -289.504299) (xy 272.201151 -289.473174)
			(xy 272.243772 -289.448567) (xy 272.289788 -289.431115) (xy 272.338007 -289.421271) (xy 272.387182 -289.41929)
			(xy 272.436037 -289.425222) (xy 272.483308 -289.438914) (xy 272.52777 -289.460012) (xy 272.568273 -289.487968)
			(xy 272.603766 -289.52206) (xy 272.633331 -289.561404) (xy 272.656202 -289.604981) (xy 272.671786 -289.651662)
			(xy 272.679681 -289.700239) (xy 272.680176 -289.724846) (xy 272.679681 -289.749453) (xy 272.671786 -289.79803)
			(xy 272.656202 -289.844711) (xy 272.633331 -289.888288) (xy 272.603766 -289.927632) (xy 272.568273 -289.961724)
			(xy 272.52777 -289.98968) (xy 272.483308 -290.010778) (xy 272.436037 -290.02447) (xy 272.387182 -290.030402)
			(xy 272.338007 -290.028421) (xy 272.289788 -290.018577) (xy 272.243772 -290.001125) (xy 272.201151 -289.976518)
			(xy 272.16303 -289.945393) (xy 272.130395 -289.908556) (xy 272.104092 -289.86696) (xy 272.084801 -289.821684)
			(xy 272.073024 -289.7739) (xy 272.069064 -289.724846) (xy 271.730216 -289.724846) (xy 271.729721 -289.749453)
			(xy 271.721826 -289.79803) (xy 271.706242 -289.844711) (xy 271.683371 -289.888288) (xy 271.653806 -289.927632)
			(xy 271.618313 -289.961724) (xy 271.57781 -289.98968) (xy 271.533348 -290.010778) (xy 271.486077 -290.02447)
			(xy 271.437222 -290.030402) (xy 271.388047 -290.028421) (xy 271.339828 -290.018577) (xy 271.293812 -290.001125)
			(xy 271.251191 -289.976518) (xy 271.21307 -289.945393) (xy 271.180435 -289.908556) (xy 271.154132 -289.86696)
			(xy 271.134841 -289.821684) (xy 271.123064 -289.7739) (xy 271.119104 -289.724846) (xy 270.780256 -289.724846)
			(xy 270.779761 -289.749453) (xy 270.771866 -289.79803) (xy 270.756282 -289.844711) (xy 270.733411 -289.888288)
			(xy 270.703846 -289.927632) (xy 270.668353 -289.961724) (xy 270.62785 -289.98968) (xy 270.583388 -290.010778)
			(xy 270.536117 -290.02447) (xy 270.487262 -290.030402) (xy 270.438087 -290.028421) (xy 270.389868 -290.018577)
			(xy 270.343852 -290.001125) (xy 270.301231 -289.976518) (xy 270.26311 -289.945393) (xy 270.230475 -289.908556)
			(xy 270.204172 -289.86696) (xy 270.184881 -289.821684) (xy 270.173104 -289.7739) (xy 270.169144 -289.724846)
			(xy 269.830042 -289.724846) (xy 269.829547 -289.749453) (xy 269.821652 -289.79803) (xy 269.806068 -289.844711)
			(xy 269.783197 -289.888288) (xy 269.753632 -289.927632) (xy 269.718139 -289.961724) (xy 269.677636 -289.98968)
			(xy 269.633174 -290.010778) (xy 269.585903 -290.02447) (xy 269.537048 -290.030402) (xy 269.487873 -290.028421)
			(xy 269.439654 -290.018577) (xy 269.393638 -290.001125) (xy 269.351017 -289.976518) (xy 269.312896 -289.945393)
			(xy 269.280261 -289.908556) (xy 269.253958 -289.86696) (xy 269.234667 -289.821684) (xy 269.22289 -289.7739)
			(xy 269.21893 -289.724846) (xy 268.880082 -289.724846) (xy 268.879587 -289.749453) (xy 268.871692 -289.79803)
			(xy 268.856108 -289.844711) (xy 268.833237 -289.888288) (xy 268.803672 -289.927632) (xy 268.768179 -289.961724)
			(xy 268.727676 -289.98968) (xy 268.683214 -290.010778) (xy 268.635943 -290.02447) (xy 268.587088 -290.030402)
			(xy 268.537913 -290.028421) (xy 268.489694 -290.018577) (xy 268.443678 -290.001125) (xy 268.401057 -289.976518)
			(xy 268.362936 -289.945393) (xy 268.330301 -289.908556) (xy 268.303998 -289.86696) (xy 268.284707 -289.821684)
			(xy 268.27293 -289.7739) (xy 268.26897 -289.724846) (xy 267.399262 -289.724846) (xy 268.158976 -290.48456)
			(xy 268.166831 -290.491627) (xy 268.186511 -290.499254) (xy 268.197076 -290.499292) (xy 268.220698 -290.497768)
			(xy 268.276832 -290.493958) (xy 268.281595 -290.493393) (xy 268.290802 -290.490711) (xy 268.29512 -290.488624)
			(xy 268.304518 -290.483544) (xy 268.311376 -290.474654) (xy 268.311884 -290.474146) (xy 268.327642 -290.454304)
			(xy 268.364173 -290.419193) (xy 268.405633 -290.390068) (xy 268.451051 -290.367608) (xy 268.499363 -290.35234)
			(xy 268.54944 -290.344621) (xy 268.574774 -290.344098) (xy 268.600764 -290.344579) (xy 268.652106 -290.352707)
			(xy 268.701543 -290.368767) (xy 268.74786 -290.392364) (xy 268.789914 -290.422916) (xy 268.826671 -290.45967)
			(xy 268.857226 -290.501723) (xy 268.880825 -290.548038) (xy 268.896888 -290.597475) (xy 268.905019 -290.648816)
			(xy 268.905482 -290.674806) (xy 269.21893 -290.674806) (xy 269.22289 -290.625752) (xy 269.234667 -290.577968)
			(xy 269.253958 -290.532692) (xy 269.280261 -290.491096) (xy 269.312896 -290.454259) (xy 269.351017 -290.423134)
			(xy 269.393638 -290.398527) (xy 269.439654 -290.381075) (xy 269.487873 -290.371231) (xy 269.537048 -290.36925)
			(xy 269.585903 -290.375182) (xy 269.633174 -290.388874) (xy 269.677636 -290.409972) (xy 269.718139 -290.437928)
			(xy 269.753632 -290.47202) (xy 269.783197 -290.511364) (xy 269.806068 -290.554941) (xy 269.821652 -290.601622)
			(xy 269.829547 -290.650199) (xy 269.830042 -290.674806) (xy 270.169144 -290.674806) (xy 270.173104 -290.625752)
			(xy 270.184881 -290.577968) (xy 270.204172 -290.532692) (xy 270.230475 -290.491096) (xy 270.26311 -290.454259)
			(xy 270.301231 -290.423134) (xy 270.343852 -290.398527) (xy 270.389868 -290.381075) (xy 270.438087 -290.371231)
			(xy 270.487262 -290.36925) (xy 270.536117 -290.375182) (xy 270.583388 -290.388874) (xy 270.62785 -290.409972)
			(xy 270.668353 -290.437928) (xy 270.703846 -290.47202) (xy 270.733411 -290.511364) (xy 270.756282 -290.554941)
			(xy 270.771866 -290.601622) (xy 270.779761 -290.650199) (xy 270.780256 -290.674806) (xy 273.019024 -290.674806)
			(xy 273.022984 -290.625752) (xy 273.034761 -290.577968) (xy 273.054052 -290.532692) (xy 273.080355 -290.491096)
			(xy 273.11299 -290.454259) (xy 273.151111 -290.423134) (xy 273.193732 -290.398527) (xy 273.239748 -290.381075)
			(xy 273.287967 -290.371231) (xy 273.337142 -290.36925) (xy 273.385997 -290.375182) (xy 273.433268 -290.388874)
			(xy 273.47773 -290.409972) (xy 273.518233 -290.437928) (xy 273.553726 -290.47202) (xy 273.583291 -290.511364)
			(xy 273.606162 -290.554941) (xy 273.621746 -290.601622) (xy 273.629641 -290.650199) (xy 273.630136 -290.674806)
			(xy 273.629641 -290.699413) (xy 273.621746 -290.74799) (xy 273.606162 -290.794671) (xy 273.583291 -290.838248)
			(xy 273.553726 -290.877592) (xy 273.518233 -290.911684) (xy 273.47773 -290.93964) (xy 273.433268 -290.960738)
			(xy 273.385997 -290.97443) (xy 273.337142 -290.980362) (xy 273.287967 -290.978381) (xy 273.239748 -290.968537)
			(xy 273.193732 -290.951085) (xy 273.151111 -290.926478) (xy 273.11299 -290.895353) (xy 273.080355 -290.858516)
			(xy 273.054052 -290.81692) (xy 273.034761 -290.771644) (xy 273.022984 -290.72386) (xy 273.019024 -290.674806)
			(xy 270.780256 -290.674806) (xy 270.779761 -290.699413) (xy 270.771866 -290.74799) (xy 270.756282 -290.794671)
			(xy 270.733411 -290.838248) (xy 270.703846 -290.877592) (xy 270.668353 -290.911684) (xy 270.62785 -290.93964)
			(xy 270.583388 -290.960738) (xy 270.536117 -290.97443) (xy 270.487262 -290.980362) (xy 270.438087 -290.978381)
			(xy 270.389868 -290.968537) (xy 270.343852 -290.951085) (xy 270.301231 -290.926478) (xy 270.26311 -290.895353)
			(xy 270.230475 -290.858516) (xy 270.204172 -290.81692) (xy 270.184881 -290.771644) (xy 270.173104 -290.72386)
			(xy 270.169144 -290.674806) (xy 269.830042 -290.674806) (xy 269.829547 -290.699413) (xy 269.821652 -290.74799)
			(xy 269.806068 -290.794671) (xy 269.783197 -290.838248) (xy 269.753632 -290.877592) (xy 269.718139 -290.911684)
			(xy 269.677636 -290.93964) (xy 269.633174 -290.960738) (xy 269.585903 -290.97443) (xy 269.537048 -290.980362)
			(xy 269.487873 -290.978381) (xy 269.439654 -290.968537) (xy 269.393638 -290.951085) (xy 269.351017 -290.926478)
			(xy 269.312896 -290.895353) (xy 269.280261 -290.858516) (xy 269.253958 -290.81692) (xy 269.234667 -290.771644)
			(xy 269.22289 -290.72386) (xy 269.21893 -290.674806) (xy 268.905482 -290.674806) (xy 268.905028 -290.700176)
			(xy 268.897294 -290.750324) (xy 268.881992 -290.798703) (xy 268.859482 -290.844177) (xy 268.830291 -290.885681)
			(xy 268.795105 -290.92224) (xy 268.77518 -290.93795) (xy 268.7701 -290.94176) (xy 268.763242 -290.949888)
			(xy 268.760956 -290.95446) (xy 268.758867 -290.958778) (xy 268.756173 -290.967983) (xy 268.755622 -290.972748)
			(xy 268.751812 -291.028882) (xy 268.750288 -291.052504) (xy 268.750341 -291.063067) (xy 268.757962 -291.082743)
			(xy 268.76502 -291.090604) (xy 269.108936 -291.43452) (xy 269.116797 -291.44157) (xy 269.136475 -291.449165)
			(xy 269.147036 -291.449252) (xy 269.170658 -291.447728) (xy 269.226792 -291.443918) (xy 269.231553 -291.443347)
			(xy 269.240754 -291.440654) (xy 269.24508 -291.438584) (xy 269.254478 -291.433504) (xy 269.261336 -291.424614)
			(xy 269.261844 -291.424106) (xy 269.277599 -291.404258) (xy 269.314127 -291.369138) (xy 269.355585 -291.340002)
			(xy 269.401003 -291.317532) (xy 269.449318 -291.302255) (xy 269.499398 -291.294529) (xy 269.524734 -291.294058)
			(xy 269.55072 -291.29457) (xy 269.602053 -291.302705) (xy 269.651481 -291.318768) (xy 269.697788 -291.342365)
			(xy 269.739835 -291.372915) (xy 269.776585 -291.409665) (xy 269.807135 -291.451712) (xy 269.830732 -291.498019)
			(xy 269.846795 -291.547447) (xy 269.85493 -291.59878) (xy 269.855442 -291.624766) (xy 270.169144 -291.624766)
			(xy 270.173104 -291.575712) (xy 270.184881 -291.527928) (xy 270.204172 -291.482652) (xy 270.230475 -291.441056)
			(xy 270.26311 -291.404219) (xy 270.301231 -291.373094) (xy 270.343852 -291.348487) (xy 270.389868 -291.331035)
			(xy 270.438087 -291.321191) (xy 270.487262 -291.31921) (xy 270.536117 -291.325142) (xy 270.583388 -291.338834)
			(xy 270.62785 -291.359932) (xy 270.668353 -291.387888) (xy 270.703846 -291.42198) (xy 270.733411 -291.461324)
			(xy 270.756282 -291.504901) (xy 270.771866 -291.551582) (xy 270.779761 -291.600159) (xy 270.780256 -291.624766)
			(xy 273.019024 -291.624766) (xy 273.022984 -291.575712) (xy 273.034761 -291.527928) (xy 273.054052 -291.482652)
			(xy 273.080355 -291.441056) (xy 273.11299 -291.404219) (xy 273.151111 -291.373094) (xy 273.193732 -291.348487)
			(xy 273.239748 -291.331035) (xy 273.287967 -291.321191) (xy 273.337142 -291.31921) (xy 273.385997 -291.325142)
			(xy 273.433268 -291.338834) (xy 273.47773 -291.359932) (xy 273.518233 -291.387888) (xy 273.553726 -291.42198)
			(xy 273.583291 -291.461324) (xy 273.606162 -291.504901) (xy 273.621746 -291.551582) (xy 273.629641 -291.600159)
			(xy 273.630136 -291.624766) (xy 273.968984 -291.624766) (xy 273.972944 -291.575712) (xy 273.984721 -291.527928)
			(xy 274.004012 -291.482652) (xy 274.030315 -291.441056) (xy 274.06295 -291.404219) (xy 274.101071 -291.373094)
			(xy 274.143692 -291.348487) (xy 274.189708 -291.331035) (xy 274.237927 -291.321191) (xy 274.287102 -291.31921)
			(xy 274.335957 -291.325142) (xy 274.383228 -291.338834) (xy 274.42769 -291.359932) (xy 274.468193 -291.387888)
			(xy 274.503686 -291.42198) (xy 274.533251 -291.461324) (xy 274.556122 -291.504901) (xy 274.571706 -291.551582)
			(xy 274.579601 -291.600159) (xy 274.580096 -291.624766) (xy 274.579601 -291.649373) (xy 274.571706 -291.69795)
			(xy 274.556122 -291.744631) (xy 274.533251 -291.788208) (xy 274.503686 -291.827552) (xy 274.468193 -291.861644)
			(xy 274.42769 -291.8896) (xy 274.383228 -291.910698) (xy 274.335957 -291.92439) (xy 274.287102 -291.930322)
			(xy 274.237927 -291.928341) (xy 274.189708 -291.918497) (xy 274.143692 -291.901045) (xy 274.101071 -291.876438)
			(xy 274.06295 -291.845313) (xy 274.030315 -291.808476) (xy 274.004012 -291.76688) (xy 273.984721 -291.721604)
			(xy 273.972944 -291.67382) (xy 273.968984 -291.624766) (xy 273.630136 -291.624766) (xy 273.629641 -291.649373)
			(xy 273.621746 -291.69795) (xy 273.606162 -291.744631) (xy 273.583291 -291.788208) (xy 273.553726 -291.827552)
			(xy 273.518233 -291.861644) (xy 273.47773 -291.8896) (xy 273.433268 -291.910698) (xy 273.385997 -291.92439)
			(xy 273.337142 -291.930322) (xy 273.287967 -291.928341) (xy 273.239748 -291.918497) (xy 273.193732 -291.901045)
			(xy 273.151111 -291.876438) (xy 273.11299 -291.845313) (xy 273.080355 -291.808476) (xy 273.054052 -291.76688)
			(xy 273.034761 -291.721604) (xy 273.022984 -291.67382) (xy 273.019024 -291.624766) (xy 270.780256 -291.624766)
			(xy 270.779761 -291.649373) (xy 270.771866 -291.69795) (xy 270.756282 -291.744631) (xy 270.733411 -291.788208)
			(xy 270.703846 -291.827552) (xy 270.668353 -291.861644) (xy 270.62785 -291.8896) (xy 270.583388 -291.910698)
			(xy 270.536117 -291.92439) (xy 270.487262 -291.930322) (xy 270.438087 -291.928341) (xy 270.389868 -291.918497)
			(xy 270.343852 -291.901045) (xy 270.301231 -291.876438) (xy 270.26311 -291.845313) (xy 270.230475 -291.808476)
			(xy 270.204172 -291.76688) (xy 270.184881 -291.721604) (xy 270.173104 -291.67382) (xy 270.169144 -291.624766)
			(xy 269.855442 -291.624766) (xy 269.854983 -291.650134) (xy 269.84724 -291.700276) (xy 269.831931 -291.748647)
			(xy 269.809414 -291.794112) (xy 269.780218 -291.835606) (xy 269.745028 -291.872155) (xy 269.72514 -291.88791)
			(xy 269.72006 -291.89172) (xy 269.713202 -291.899848) (xy 269.710916 -291.90442) (xy 269.708834 -291.90874)
			(xy 269.706153 -291.917946) (xy 269.705582 -291.922708) (xy 269.701772 -291.978842) (xy 269.700248 -292.002464)
			(xy 269.700293 -292.013031) (xy 269.707898 -292.032722) (xy 269.71498 -292.040564) (xy 270.05915 -292.384734)
			(xy 270.067012 -292.39178) (xy 270.08669 -292.399367) (xy 270.09725 -292.399466) (xy 270.120872 -292.397942)
			(xy 270.177006 -292.394132) (xy 270.181769 -292.393569) (xy 270.190978 -292.39089) (xy 270.195294 -292.388798)
			(xy 270.204692 -292.383718) (xy 270.21155 -292.374828) (xy 270.212058 -292.37432) (xy 270.227813 -292.354472)
			(xy 270.26434 -292.319352) (xy 270.305798 -292.290216) (xy 270.351217 -292.267747) (xy 270.399532 -292.252472)
			(xy 270.449612 -292.244747) (xy 270.474948 -292.244272) (xy 270.500933 -292.244785) (xy 270.552263 -292.252922)
			(xy 270.601689 -292.268986) (xy 270.647993 -292.292585) (xy 270.690036 -292.323135) (xy 270.726783 -292.359885)
			(xy 270.75733 -292.401931) (xy 270.780924 -292.448237) (xy 270.796985 -292.497664) (xy 270.805117 -292.548995)
			(xy 270.805651 -292.574726) (xy 271.119104 -292.574726) (xy 271.123064 -292.525672) (xy 271.134841 -292.477888)
			(xy 271.154132 -292.432612) (xy 271.180435 -292.391016) (xy 271.21307 -292.354179) (xy 271.251191 -292.323054)
			(xy 271.293812 -292.298447) (xy 271.339828 -292.280995) (xy 271.388047 -292.271151) (xy 271.437222 -292.26917)
			(xy 271.486077 -292.275102) (xy 271.533348 -292.288794) (xy 271.57781 -292.309892) (xy 271.618313 -292.337848)
			(xy 271.653806 -292.37194) (xy 271.683371 -292.411284) (xy 271.706242 -292.454861) (xy 271.721826 -292.501542)
			(xy 271.729721 -292.550119) (xy 271.730216 -292.574726) (xy 272.069064 -292.574726) (xy 272.073024 -292.525672)
			(xy 272.084801 -292.477888) (xy 272.104092 -292.432612) (xy 272.130395 -292.391016) (xy 272.16303 -292.354179)
			(xy 272.201151 -292.323054) (xy 272.243772 -292.298447) (xy 272.289788 -292.280995) (xy 272.338007 -292.271151)
			(xy 272.387182 -292.26917) (xy 272.436037 -292.275102) (xy 272.483308 -292.288794) (xy 272.52777 -292.309892)
			(xy 272.568273 -292.337848) (xy 272.603766 -292.37194) (xy 272.633331 -292.411284) (xy 272.656202 -292.454861)
			(xy 272.671786 -292.501542) (xy 272.679681 -292.550119) (xy 272.680176 -292.574726) (xy 272.680171 -292.57498)
			(xy 273.019024 -292.57498) (xy 273.022984 -292.525926) (xy 273.034761 -292.478142) (xy 273.054052 -292.432866)
			(xy 273.080355 -292.39127) (xy 273.11299 -292.354433) (xy 273.151111 -292.323308) (xy 273.193732 -292.298701)
			(xy 273.239748 -292.281249) (xy 273.287967 -292.271405) (xy 273.337142 -292.269424) (xy 273.385997 -292.275356)
			(xy 273.433268 -292.289048) (xy 273.47773 -292.310146) (xy 273.518233 -292.338102) (xy 273.553726 -292.372194)
			(xy 273.583291 -292.411538) (xy 273.606162 -292.455115) (xy 273.621746 -292.501796) (xy 273.629641 -292.550373)
			(xy 273.630136 -292.57498) (xy 273.629641 -292.599587) (xy 273.629309 -292.601629) (xy 273.919178 -292.601629)
			(xy 273.919178 -292.548331) (xy 273.927121 -292.495627) (xy 273.942831 -292.444697) (xy 273.965957 -292.396676)
			(xy 273.995981 -292.352639) (xy 274.032233 -292.313568) (xy 274.073904 -292.280337) (xy 274.120062 -292.253688)
			(xy 274.169676 -292.234216) (xy 274.221638 -292.222356) (xy 274.274788 -292.218373) (xy 274.327938 -292.222356)
			(xy 274.3799 -292.234216) (xy 274.429514 -292.253688) (xy 274.475672 -292.280337) (xy 274.517343 -292.313568)
			(xy 274.553595 -292.352639) (xy 274.583619 -292.396676) (xy 274.606745 -292.444697) (xy 274.622455 -292.495627)
			(xy 274.630398 -292.548331) (xy 274.630896 -292.57498) (xy 274.918944 -292.57498) (xy 274.922904 -292.525926)
			(xy 274.934681 -292.478142) (xy 274.953972 -292.432866) (xy 274.980275 -292.39127) (xy 275.01291 -292.354433)
			(xy 275.051031 -292.323308) (xy 275.093652 -292.298701) (xy 275.139668 -292.281249) (xy 275.187887 -292.271405)
			(xy 275.237062 -292.269424) (xy 275.285917 -292.275356) (xy 275.333188 -292.289048) (xy 275.37765 -292.310146)
			(xy 275.418153 -292.338102) (xy 275.453646 -292.372194) (xy 275.483211 -292.411538) (xy 275.506082 -292.455115)
			(xy 275.521666 -292.501796) (xy 275.529561 -292.550373) (xy 275.530056 -292.57498) (xy 275.529561 -292.599587)
			(xy 275.521666 -292.648164) (xy 275.506082 -292.694845) (xy 275.483211 -292.738422) (xy 275.453646 -292.777766)
			(xy 275.418153 -292.811858) (xy 275.37765 -292.839814) (xy 275.333188 -292.860912) (xy 275.285917 -292.874604)
			(xy 275.237062 -292.880536) (xy 275.187887 -292.878555) (xy 275.139668 -292.868711) (xy 275.093652 -292.851259)
			(xy 275.051031 -292.826652) (xy 275.01291 -292.795527) (xy 274.980275 -292.75869) (xy 274.953972 -292.717094)
			(xy 274.934681 -292.671818) (xy 274.922904 -292.624034) (xy 274.918944 -292.57498) (xy 274.630896 -292.57498)
			(xy 274.630398 -292.601629) (xy 274.622455 -292.654333) (xy 274.606745 -292.705263) (xy 274.583619 -292.753284)
			(xy 274.553595 -292.797321) (xy 274.517343 -292.836392) (xy 274.475672 -292.869623) (xy 274.429514 -292.896272)
			(xy 274.3799 -292.915744) (xy 274.327938 -292.927604) (xy 274.274788 -292.931588) (xy 274.221638 -292.927604)
			(xy 274.169676 -292.915744) (xy 274.120062 -292.896272) (xy 274.073904 -292.869623) (xy 274.032233 -292.836392)
			(xy 273.995981 -292.797321) (xy 273.965957 -292.753284) (xy 273.942831 -292.705263) (xy 273.927121 -292.654333)
			(xy 273.919178 -292.601629) (xy 273.629309 -292.601629) (xy 273.621746 -292.648164) (xy 273.606162 -292.694845)
			(xy 273.583291 -292.738422) (xy 273.553726 -292.777766) (xy 273.518233 -292.811858) (xy 273.47773 -292.839814)
			(xy 273.433268 -292.860912) (xy 273.385997 -292.874604) (xy 273.337142 -292.880536) (xy 273.287967 -292.878555)
			(xy 273.239748 -292.868711) (xy 273.193732 -292.851259) (xy 273.151111 -292.826652) (xy 273.11299 -292.795527)
			(xy 273.080355 -292.75869) (xy 273.054052 -292.717094) (xy 273.034761 -292.671818) (xy 273.022984 -292.624034)
			(xy 273.019024 -292.57498) (xy 272.680171 -292.57498) (xy 272.679681 -292.599333) (xy 272.671786 -292.64791)
			(xy 272.656202 -292.694591) (xy 272.633331 -292.738168) (xy 272.603766 -292.777512) (xy 272.568273 -292.811604)
			(xy 272.52777 -292.83956) (xy 272.483308 -292.860658) (xy 272.436037 -292.87435) (xy 272.387182 -292.880282)
			(xy 272.338007 -292.878301) (xy 272.289788 -292.868457) (xy 272.243772 -292.851005) (xy 272.201151 -292.826398)
			(xy 272.16303 -292.795273) (xy 272.130395 -292.758436) (xy 272.104092 -292.71684) (xy 272.084801 -292.671564)
			(xy 272.073024 -292.62378) (xy 272.069064 -292.574726) (xy 271.730216 -292.574726) (xy 271.729721 -292.599333)
			(xy 271.721826 -292.64791) (xy 271.706242 -292.694591) (xy 271.683371 -292.738168) (xy 271.653806 -292.777512)
			(xy 271.618313 -292.811604) (xy 271.57781 -292.83956) (xy 271.533348 -292.860658) (xy 271.486077 -292.87435)
			(xy 271.437222 -292.880282) (xy 271.388047 -292.878301) (xy 271.339828 -292.868457) (xy 271.293812 -292.851005)
			(xy 271.251191 -292.826398) (xy 271.21307 -292.795273) (xy 271.180435 -292.758436) (xy 271.154132 -292.71684)
			(xy 271.134841 -292.671564) (xy 271.123064 -292.62378) (xy 271.119104 -292.574726) (xy 270.805651 -292.574726)
			(xy 270.805656 -292.57498) (xy 270.805196 -292.600348) (xy 270.797452 -292.650488) (xy 270.782141 -292.698859)
			(xy 270.759624 -292.744323) (xy 270.730428 -292.785816) (xy 270.695238 -292.822364) (xy 270.675354 -292.838124)
			(xy 270.670274 -292.841934) (xy 270.663416 -292.850062) (xy 270.66113 -292.854634) (xy 270.659049 -292.858954)
			(xy 270.656369 -292.868161) (xy 270.655796 -292.872922) (xy 270.651986 -292.929056) (xy 270.650462 -292.952678)
			(xy 270.65051 -292.963244) (xy 270.65812 -292.982929) (xy 270.665194 -292.990778) (xy 271.00911 -293.334694)
			(xy 271.016968 -293.341752) (xy 271.036648 -293.34936) (xy 271.04721 -293.349426) (xy 271.070832 -293.347902)
			(xy 271.126966 -293.344092) (xy 271.131727 -293.343523) (xy 271.14093 -293.340833) (xy 271.145254 -293.338758)
			(xy 271.154652 -293.333678) (xy 271.16151 -293.324788) (xy 271.162018 -293.32428) (xy 271.177774 -293.304432)
			(xy 271.214301 -293.269311) (xy 271.255759 -293.240174) (xy 271.301177 -293.217703) (xy 271.349492 -293.202424)
			(xy 271.399572 -293.194694) (xy 271.424908 -293.194232) (xy 271.450896 -293.194716) (xy 271.502231 -293.202848)
			(xy 271.551662 -293.218912) (xy 271.597971 -293.242511) (xy 271.640018 -293.273064) (xy 271.676768 -293.309818)
			(xy 271.707315 -293.35187) (xy 271.730907 -293.398183) (xy 271.746963 -293.447616) (xy 271.755088 -293.498952)
			(xy 271.755616 -293.52494) (xy 272.069064 -293.52494) (xy 272.073024 -293.475886) (xy 272.084801 -293.428102)
			(xy 272.104092 -293.382826) (xy 272.130395 -293.34123) (xy 272.16303 -293.304393) (xy 272.201151 -293.273268)
			(xy 272.243772 -293.248661) (xy 272.289788 -293.231209) (xy 272.338007 -293.221365) (xy 272.387182 -293.219384)
			(xy 272.436037 -293.225316) (xy 272.483308 -293.239008) (xy 272.52777 -293.260106) (xy 272.568273 -293.288062)
			(xy 272.603766 -293.322154) (xy 272.633331 -293.361498) (xy 272.656202 -293.405075) (xy 272.671786 -293.451756)
			(xy 272.679681 -293.500333) (xy 272.680176 -293.52494) (xy 273.019024 -293.52494) (xy 273.022984 -293.475886)
			(xy 273.034761 -293.428102) (xy 273.054052 -293.382826) (xy 273.080355 -293.34123) (xy 273.11299 -293.304393)
			(xy 273.151111 -293.273268) (xy 273.193732 -293.248661) (xy 273.239748 -293.231209) (xy 273.287967 -293.221365)
			(xy 273.337142 -293.219384) (xy 273.385997 -293.225316) (xy 273.433268 -293.239008) (xy 273.47773 -293.260106)
			(xy 273.518233 -293.288062) (xy 273.553726 -293.322154) (xy 273.583291 -293.361498) (xy 273.606162 -293.405075)
			(xy 273.621746 -293.451756) (xy 273.629641 -293.500333) (xy 273.630136 -293.52494) (xy 273.968984 -293.52494)
			(xy 273.972944 -293.475886) (xy 273.984721 -293.428102) (xy 274.004012 -293.382826) (xy 274.030315 -293.34123)
			(xy 274.06295 -293.304393) (xy 274.101071 -293.273268) (xy 274.143692 -293.248661) (xy 274.189708 -293.231209)
			(xy 274.237927 -293.221365) (xy 274.287102 -293.219384) (xy 274.335957 -293.225316) (xy 274.383228 -293.239008)
			(xy 274.42769 -293.260106) (xy 274.468193 -293.288062) (xy 274.503686 -293.322154) (xy 274.533251 -293.361498)
			(xy 274.556122 -293.405075) (xy 274.571706 -293.451756) (xy 274.579601 -293.500333) (xy 274.580096 -293.52494)
			(xy 274.579601 -293.549547) (xy 274.579269 -293.551589) (xy 274.869138 -293.551589) (xy 274.869138 -293.498291)
			(xy 274.877081 -293.445587) (xy 274.892791 -293.394657) (xy 274.915917 -293.346636) (xy 274.945941 -293.302599)
			(xy 274.982193 -293.263528) (xy 275.023864 -293.230297) (xy 275.070022 -293.203648) (xy 275.119636 -293.184176)
			(xy 275.171598 -293.172316) (xy 275.224748 -293.168333) (xy 275.277898 -293.172316) (xy 275.32986 -293.184176)
			(xy 275.379474 -293.203648) (xy 275.425632 -293.230297) (xy 275.467303 -293.263528) (xy 275.503555 -293.302599)
			(xy 275.533579 -293.346636) (xy 275.556705 -293.394657) (xy 275.572415 -293.445587) (xy 275.580358 -293.498291)
			(xy 275.580856 -293.52494) (xy 275.868904 -293.52494) (xy 275.872864 -293.475886) (xy 275.884641 -293.428102)
			(xy 275.903932 -293.382826) (xy 275.930235 -293.34123) (xy 275.96287 -293.304393) (xy 276.000991 -293.273268)
			(xy 276.043612 -293.248661) (xy 276.089628 -293.231209) (xy 276.137847 -293.221365) (xy 276.187022 -293.219384)
			(xy 276.235877 -293.225316) (xy 276.283148 -293.239008) (xy 276.32761 -293.260106) (xy 276.368113 -293.288062)
			(xy 276.403606 -293.322154) (xy 276.433171 -293.361498) (xy 276.456042 -293.405075) (xy 276.471626 -293.451756)
			(xy 276.479521 -293.500333) (xy 276.480016 -293.52494) (xy 276.479521 -293.549547) (xy 276.471626 -293.598124)
			(xy 276.456042 -293.644805) (xy 276.433171 -293.688382) (xy 276.403606 -293.727726) (xy 276.368113 -293.761818)
			(xy 276.32761 -293.789774) (xy 276.283148 -293.810872) (xy 276.235877 -293.824564) (xy 276.187022 -293.830496)
			(xy 276.137847 -293.828515) (xy 276.089628 -293.818671) (xy 276.043612 -293.801219) (xy 276.000991 -293.776612)
			(xy 275.96287 -293.745487) (xy 275.930235 -293.70865) (xy 275.903932 -293.667054) (xy 275.884641 -293.621778)
			(xy 275.872864 -293.573994) (xy 275.868904 -293.52494) (xy 275.580856 -293.52494) (xy 275.580358 -293.551589)
			(xy 275.572415 -293.604293) (xy 275.556705 -293.655223) (xy 275.533579 -293.703244) (xy 275.503555 -293.747281)
			(xy 275.467303 -293.786352) (xy 275.425632 -293.819583) (xy 275.379474 -293.846232) (xy 275.32986 -293.865704)
			(xy 275.277898 -293.877564) (xy 275.224748 -293.881548) (xy 275.171598 -293.877564) (xy 275.119636 -293.865704)
			(xy 275.070022 -293.846232) (xy 275.023864 -293.819583) (xy 274.982193 -293.786352) (xy 274.945941 -293.747281)
			(xy 274.915917 -293.703244) (xy 274.892791 -293.655223) (xy 274.877081 -293.604293) (xy 274.869138 -293.551589)
			(xy 274.579269 -293.551589) (xy 274.571706 -293.598124) (xy 274.556122 -293.644805) (xy 274.533251 -293.688382)
			(xy 274.503686 -293.727726) (xy 274.468193 -293.761818) (xy 274.42769 -293.789774) (xy 274.383228 -293.810872)
			(xy 274.335957 -293.824564) (xy 274.287102 -293.830496) (xy 274.237927 -293.828515) (xy 274.189708 -293.818671)
			(xy 274.143692 -293.801219) (xy 274.101071 -293.776612) (xy 274.06295 -293.745487) (xy 274.030315 -293.70865)
			(xy 274.004012 -293.667054) (xy 273.984721 -293.621778) (xy 273.972944 -293.573994) (xy 273.968984 -293.52494)
			(xy 273.630136 -293.52494) (xy 273.629641 -293.549547) (xy 273.621746 -293.598124) (xy 273.606162 -293.644805)
			(xy 273.583291 -293.688382) (xy 273.553726 -293.727726) (xy 273.518233 -293.761818) (xy 273.47773 -293.789774)
			(xy 273.433268 -293.810872) (xy 273.385997 -293.824564) (xy 273.337142 -293.830496) (xy 273.287967 -293.828515)
			(xy 273.239748 -293.818671) (xy 273.193732 -293.801219) (xy 273.151111 -293.776612) (xy 273.11299 -293.745487)
			(xy 273.080355 -293.70865) (xy 273.054052 -293.667054) (xy 273.034761 -293.621778) (xy 273.022984 -293.573994)
			(xy 273.019024 -293.52494) (xy 272.680176 -293.52494) (xy 272.679681 -293.549547) (xy 272.671786 -293.598124)
			(xy 272.656202 -293.644805) (xy 272.633331 -293.688382) (xy 272.603766 -293.727726) (xy 272.568273 -293.761818)
			(xy 272.52777 -293.789774) (xy 272.483308 -293.810872) (xy 272.436037 -293.824564) (xy 272.387182 -293.830496)
			(xy 272.338007 -293.828515) (xy 272.289788 -293.818671) (xy 272.243772 -293.801219) (xy 272.201151 -293.776612)
			(xy 272.16303 -293.745487) (xy 272.130395 -293.70865) (xy 272.104092 -293.667054) (xy 272.084801 -293.621778)
			(xy 272.073024 -293.573994) (xy 272.069064 -293.52494) (xy 271.755616 -293.52494) (xy 271.755159 -293.55031)
			(xy 271.747421 -293.600455) (xy 271.732117 -293.648831) (xy 271.709606 -293.694303) (xy 271.680415 -293.735805)
			(xy 271.64523 -293.772363) (xy 271.625314 -293.788084) (xy 271.620234 -293.791894) (xy 271.613376 -293.800022)
			(xy 271.61109 -293.804594) (xy 271.609007 -293.808914) (xy 271.606322 -293.81812) (xy 271.605756 -293.822882)
			(xy 271.601946 -293.879016) (xy 271.600422 -293.902638) (xy 271.600481 -293.9132) (xy 271.608103 -293.932872)
			(xy 271.615154 -293.940738) (xy 272.149316 -294.4749) (xy 273.019024 -294.4749) (xy 273.022984 -294.425846)
			(xy 273.034761 -294.378062) (xy 273.054052 -294.332786) (xy 273.080355 -294.29119) (xy 273.11299 -294.254353)
			(xy 273.151111 -294.223228) (xy 273.193732 -294.198621) (xy 273.239748 -294.181169) (xy 273.287967 -294.171325)
			(xy 273.337142 -294.169344) (xy 273.385997 -294.175276) (xy 273.433268 -294.188968) (xy 273.47773 -294.210066)
			(xy 273.518233 -294.238022) (xy 273.553726 -294.272114) (xy 273.583291 -294.311458) (xy 273.606162 -294.355035)
			(xy 273.621746 -294.401716) (xy 273.629641 -294.450293) (xy 273.630136 -294.4749) (xy 273.629641 -294.499507)
			(xy 273.629309 -294.501549) (xy 273.919178 -294.501549) (xy 273.919178 -294.448251) (xy 273.927121 -294.395547)
			(xy 273.942831 -294.344617) (xy 273.965957 -294.296596) (xy 273.995981 -294.252559) (xy 274.032233 -294.213488)
			(xy 274.073904 -294.180257) (xy 274.120062 -294.153608) (xy 274.169676 -294.134136) (xy 274.221638 -294.122276)
			(xy 274.274788 -294.118293) (xy 274.327938 -294.122276) (xy 274.3799 -294.134136) (xy 274.429514 -294.153608)
			(xy 274.475672 -294.180257) (xy 274.517343 -294.213488) (xy 274.553595 -294.252559) (xy 274.583619 -294.296596)
			(xy 274.606745 -294.344617) (xy 274.622455 -294.395547) (xy 274.630398 -294.448251) (xy 274.630896 -294.4749)
			(xy 274.918944 -294.4749) (xy 274.922904 -294.425846) (xy 274.934681 -294.378062) (xy 274.953972 -294.332786)
			(xy 274.980275 -294.29119) (xy 275.01291 -294.254353) (xy 275.051031 -294.223228) (xy 275.093652 -294.198621)
			(xy 275.139668 -294.181169) (xy 275.187887 -294.171325) (xy 275.237062 -294.169344) (xy 275.285917 -294.175276)
			(xy 275.333188 -294.188968) (xy 275.37765 -294.210066) (xy 275.418153 -294.238022) (xy 275.453646 -294.272114)
			(xy 275.483211 -294.311458) (xy 275.506082 -294.355035) (xy 275.521666 -294.401716) (xy 275.529561 -294.450293)
			(xy 275.530056 -294.4749) (xy 275.868904 -294.4749) (xy 275.872864 -294.425846) (xy 275.884641 -294.378062)
			(xy 275.903932 -294.332786) (xy 275.930235 -294.29119) (xy 275.96287 -294.254353) (xy 276.000991 -294.223228)
			(xy 276.043612 -294.198621) (xy 276.089628 -294.181169) (xy 276.137847 -294.171325) (xy 276.187022 -294.169344)
			(xy 276.235877 -294.175276) (xy 276.283148 -294.188968) (xy 276.32761 -294.210066) (xy 276.368113 -294.238022)
			(xy 276.403606 -294.272114) (xy 276.433171 -294.311458) (xy 276.456042 -294.355035) (xy 276.471626 -294.401716)
			(xy 276.479521 -294.450293) (xy 276.480016 -294.4749) (xy 276.819118 -294.4749) (xy 276.823078 -294.425846)
			(xy 276.834855 -294.378062) (xy 276.854146 -294.332786) (xy 276.880449 -294.29119) (xy 276.913084 -294.254353)
			(xy 276.951205 -294.223228) (xy 276.993826 -294.198621) (xy 277.039842 -294.181169) (xy 277.088061 -294.171325)
			(xy 277.137236 -294.169344) (xy 277.186091 -294.175276) (xy 277.233362 -294.188968) (xy 277.277824 -294.210066)
			(xy 277.318327 -294.238022) (xy 277.35382 -294.272114) (xy 277.383385 -294.311458) (xy 277.406256 -294.355035)
			(xy 277.42184 -294.401716) (xy 277.429735 -294.450293) (xy 277.43023 -294.4749) (xy 277.429735 -294.499507)
			(xy 277.42184 -294.548084) (xy 277.406256 -294.594765) (xy 277.383385 -294.638342) (xy 277.35382 -294.677686)
			(xy 277.318327 -294.711778) (xy 277.277824 -294.739734) (xy 277.233362 -294.760832) (xy 277.186091 -294.774524)
			(xy 277.137236 -294.780456) (xy 277.088061 -294.778475) (xy 277.039842 -294.768631) (xy 276.993826 -294.751179)
			(xy 276.951205 -294.726572) (xy 276.913084 -294.695447) (xy 276.880449 -294.65861) (xy 276.854146 -294.617014)
			(xy 276.834855 -294.571738) (xy 276.823078 -294.523954) (xy 276.819118 -294.4749) (xy 276.480016 -294.4749)
			(xy 276.479521 -294.499507) (xy 276.471626 -294.548084) (xy 276.456042 -294.594765) (xy 276.433171 -294.638342)
			(xy 276.403606 -294.677686) (xy 276.368113 -294.711778) (xy 276.32761 -294.739734) (xy 276.283148 -294.760832)
			(xy 276.235877 -294.774524) (xy 276.187022 -294.780456) (xy 276.137847 -294.778475) (xy 276.089628 -294.768631)
			(xy 276.043612 -294.751179) (xy 276.000991 -294.726572) (xy 275.96287 -294.695447) (xy 275.930235 -294.65861)
			(xy 275.903932 -294.617014) (xy 275.884641 -294.571738) (xy 275.872864 -294.523954) (xy 275.868904 -294.4749)
			(xy 275.530056 -294.4749) (xy 275.529561 -294.499507) (xy 275.521666 -294.548084) (xy 275.506082 -294.594765)
			(xy 275.483211 -294.638342) (xy 275.453646 -294.677686) (xy 275.418153 -294.711778) (xy 275.37765 -294.739734)
			(xy 275.333188 -294.760832) (xy 275.285917 -294.774524) (xy 275.237062 -294.780456) (xy 275.187887 -294.778475)
			(xy 275.139668 -294.768631) (xy 275.093652 -294.751179) (xy 275.051031 -294.726572) (xy 275.01291 -294.695447)
			(xy 274.980275 -294.65861) (xy 274.953972 -294.617014) (xy 274.934681 -294.571738) (xy 274.922904 -294.523954)
			(xy 274.918944 -294.4749) (xy 274.630896 -294.4749) (xy 274.630398 -294.501549) (xy 274.622455 -294.554253)
			(xy 274.606745 -294.605183) (xy 274.583619 -294.653204) (xy 274.553595 -294.697241) (xy 274.517343 -294.736312)
			(xy 274.475672 -294.769543) (xy 274.429514 -294.796192) (xy 274.3799 -294.815664) (xy 274.327938 -294.827524)
			(xy 274.274788 -294.831508) (xy 274.221638 -294.827524) (xy 274.169676 -294.815664) (xy 274.120062 -294.796192)
			(xy 274.073904 -294.769543) (xy 274.032233 -294.736312) (xy 273.995981 -294.697241) (xy 273.965957 -294.653204)
			(xy 273.942831 -294.605183) (xy 273.927121 -294.554253) (xy 273.919178 -294.501549) (xy 273.629309 -294.501549)
			(xy 273.621746 -294.548084) (xy 273.606162 -294.594765) (xy 273.583291 -294.638342) (xy 273.553726 -294.677686)
			(xy 273.518233 -294.711778) (xy 273.47773 -294.739734) (xy 273.433268 -294.760832) (xy 273.385997 -294.774524)
			(xy 273.337142 -294.780456) (xy 273.287967 -294.778475) (xy 273.239748 -294.768631) (xy 273.193732 -294.751179)
			(xy 273.151111 -294.726572) (xy 273.11299 -294.695447) (xy 273.080355 -294.65861) (xy 273.054052 -294.617014)
			(xy 273.034761 -294.571738) (xy 273.022984 -294.523954) (xy 273.019024 -294.4749) (xy 272.149316 -294.4749)
			(xy 273.85899 -296.184574) (xy 273.866846 -296.191637) (xy 273.886526 -296.199256) (xy 273.89709 -296.199306)
			(xy 273.920712 -296.197782) (xy 273.976846 -296.193972) (xy 273.981608 -296.193404) (xy 273.990812 -296.190717)
			(xy 273.995134 -296.188638) (xy 274.004532 -296.183558) (xy 274.01139 -296.174668) (xy 274.011898 -296.17416)
			(xy 274.027656 -296.154318) (xy 274.064187 -296.119208) (xy 274.105647 -296.090082) (xy 274.151065 -296.067623)
			(xy 274.199378 -296.052357) (xy 274.249454 -296.04464) (xy 274.274788 -296.044112) (xy 274.300777 -296.044594)
			(xy 274.352116 -296.052724) (xy 274.401551 -296.068786) (xy 274.447864 -296.092383) (xy 274.489916 -296.122935)
			(xy 274.52667 -296.15969) (xy 274.557221 -296.201742) (xy 274.580818 -296.248056) (xy 274.596878 -296.297492)
			(xy 274.605006 -296.348831) (xy 274.605496 -296.37482) (xy 274.605267 -296.39164) (xy 274.601831 -296.425106)
			(xy 274.598638 -296.441622) (xy 274.596352 -296.453052) (xy 274.598892 -296.46372) (xy 274.600259 -296.46872)
			(xy 274.604744 -296.478062) (xy 274.607782 -296.482262) (xy 274.633944 -296.51452) (xy 274.658836 -296.545)
			(xy 274.666457 -296.55339) (xy 274.68689 -296.563134) (xy 274.698206 -296.563796) (xy 275.75129 -296.563796)
			(xy 275.762624 -296.563199) (xy 275.783085 -296.553449) (xy 275.79066 -296.545) (xy 275.815552 -296.51452)
			(xy 275.841714 -296.482262) (xy 275.844751 -296.478062) (xy 275.849229 -296.468717) (xy 275.850604 -296.46372)
			(xy 275.853144 -296.453052) (xy 275.850858 -296.441622) (xy 275.847648 -296.425108) (xy 275.844209 -296.391641)
			(xy 275.844 -296.37482) (xy 275.84451 -296.348833) (xy 275.85264 -296.297498) (xy 275.868701 -296.248068)
			(xy 275.892297 -296.201758) (xy 275.922847 -296.15971) (xy 275.959598 -296.122959) (xy 276.001646 -296.092409)
			(xy 276.047956 -296.068813) (xy 276.097386 -296.052752) (xy 276.148721 -296.044622) (xy 276.200695 -296.044622)
			(xy 276.25203 -296.052752) (xy 276.30146 -296.068813) (xy 276.34777 -296.092409) (xy 276.389818 -296.122959)
			(xy 276.426569 -296.15971) (xy 276.457119 -296.201758) (xy 276.480715 -296.248068) (xy 276.496776 -296.297498)
			(xy 276.504906 -296.348833) (xy 276.505416 -296.37482) (xy 276.505187 -296.39164) (xy 276.501752 -296.425106)
			(xy 276.498558 -296.441622) (xy 276.496272 -296.453052) (xy 276.498812 -296.46372) (xy 276.50018 -296.468719)
			(xy 276.504666 -296.478061) (xy 276.507702 -296.482262) (xy 276.533864 -296.51452) (xy 276.558756 -296.545)
			(xy 276.566378 -296.553387) (xy 276.586811 -296.563123) (xy 276.598126 -296.563796) (xy 276.701504 -296.563796)
			(xy 276.712836 -296.563196) (xy 276.733293 -296.553443) (xy 276.740874 -296.545) (xy 276.765766 -296.51452)
			(xy 276.791928 -296.482262) (xy 276.794964 -296.478062) (xy 276.799441 -296.468717) (xy 276.800818 -296.46372)
			(xy 276.803358 -296.453052) (xy 276.801072 -296.441622) (xy 276.797862 -296.425108) (xy 276.794423 -296.391641)
			(xy 276.794214 -296.37482) (xy 276.794724 -296.348833) (xy 276.802854 -296.297498) (xy 276.818915 -296.248068)
			(xy 276.842511 -296.201758) (xy 276.873061 -296.15971) (xy 276.909812 -296.122959) (xy 276.95186 -296.092409)
			(xy 276.99817 -296.068813) (xy 277.0476 -296.052752) (xy 277.098935 -296.044622) (xy 277.150909 -296.044622)
			(xy 277.202244 -296.052752) (xy 277.251674 -296.068813) (xy 277.297984 -296.092409) (xy 277.340032 -296.122959)
			(xy 277.376783 -296.15971) (xy 277.407333 -296.201758) (xy 277.430929 -296.248068) (xy 277.44699 -296.297498)
			(xy 277.45512 -296.348833) (xy 277.45563 -296.37482) (xy 277.455432 -296.393067) (xy 277.451488 -296.429347)
			(xy 277.447756 -296.44721) (xy 277.444962 -296.459402) (xy 277.447502 -296.469816) (xy 277.44886 -296.474877)
			(xy 277.45335 -296.484344) (xy 277.456392 -296.488612) (xy 277.457154 -296.489374) (xy 277.507192 -296.551858)
			(xy 277.514824 -296.560371) (xy 277.535401 -296.570264) (xy 277.546816 -296.570908)
		)
		(stroke
			(width 0)
			(type solid)
		)
		(fill yes)
		(layer "In7.Cu")
		(net "PCEPLL3_VDDA18_PEX2")
	)
	(gr_poly
		(pts
			(xy 45.595794 -293.95674) (xy 45.606196 -293.956243) (xy 45.625291 -293.947985) (xy 45.639537 -293.932824)
			(xy 45.643546 -293.923212) (xy 45.672248 -293.844726) (xy 45.681646 -293.818564) (xy 45.673518 -293.78783)
			(xy 45.661326 -293.77767) (xy 45.643328 -293.761867) (xy 45.611626 -293.725966) (xy 45.585424 -293.685874)
			(xy 45.565267 -293.642427) (xy 45.551577 -293.596531) (xy 45.544639 -293.549141) (xy 45.544232 -293.525194)
			(xy 45.544232 -293.52494) (xy 45.544742 -293.498953) (xy 45.552872 -293.447618) (xy 45.568933 -293.398188)
			(xy 45.592529 -293.351878) (xy 45.623079 -293.30983) (xy 45.65983 -293.273079) (xy 45.701878 -293.242529)
			(xy 45.748188 -293.218933) (xy 45.797618 -293.202872) (xy 45.848953 -293.194742) (xy 45.900927 -293.194742)
			(xy 45.952262 -293.202872) (xy 46.001692 -293.218933) (xy 46.048002 -293.242529) (xy 46.09005 -293.273079)
			(xy 46.126801 -293.30983) (xy 46.157351 -293.351878) (xy 46.180947 -293.398188) (xy 46.197008 -293.447618)
			(xy 46.205138 -293.498953) (xy 46.205648 -293.52494) (xy 46.205648 -293.525194) (xy 46.205058 -293.553234)
			(xy 46.195602 -293.608511) (xy 46.176959 -293.661401) (xy 46.149663 -293.71039) (xy 46.114497 -293.754075)
			(xy 46.093888 -293.773098) (xy 46.0883 -293.777924) (xy 46.07941 -293.791894) (xy 46.073667 -293.802041)
			(xy 46.071164 -293.825196) (xy 46.074584 -293.836344) (xy 46.077632 -293.844726) (xy 46.106334 -293.923212)
			(xy 46.110343 -293.932819) (xy 46.124599 -293.947959) (xy 46.143688 -293.956208) (xy 46.154086 -293.95674)
			(xy 46.545754 -293.95674) (xy 46.556161 -293.95625) (xy 46.575268 -293.948) (xy 46.589527 -293.932839)
			(xy 46.593506 -293.923212) (xy 46.622208 -293.844726) (xy 46.631606 -293.818564) (xy 46.623478 -293.78783)
			(xy 46.611286 -293.77767) (xy 46.59329 -293.761866) (xy 46.561592 -293.725963) (xy 46.535392 -293.685871)
			(xy 46.515239 -293.642424) (xy 46.50155 -293.596529) (xy 46.494613 -293.54914) (xy 46.494192 -293.525194)
			(xy 46.494192 -293.52494) (xy 46.494702 -293.498953) (xy 46.502832 -293.447618) (xy 46.518893 -293.398188)
			(xy 46.542489 -293.351878) (xy 46.573039 -293.30983) (xy 46.60979 -293.273079) (xy 46.651838 -293.242529)
			(xy 46.698148 -293.218933) (xy 46.747578 -293.202872) (xy 46.798913 -293.194742) (xy 46.850887 -293.194742)
			(xy 46.902222 -293.202872) (xy 46.951652 -293.218933) (xy 46.997962 -293.242529) (xy 47.04001 -293.273079)
			(xy 47.076761 -293.30983) (xy 47.107311 -293.351878) (xy 47.130907 -293.398188) (xy 47.146968 -293.447618)
			(xy 47.155098 -293.498953) (xy 47.155608 -293.52494) (xy 47.155608 -293.525194) (xy 47.155018 -293.553234)
			(xy 47.145561 -293.60851) (xy 47.126916 -293.661399) (xy 47.099618 -293.710385) (xy 47.064449 -293.754066)
			(xy 47.043848 -293.773098) (xy 47.03826 -293.777924) (xy 47.02937 -293.791894) (xy 47.02363 -293.802042)
			(xy 47.021129 -293.825195) (xy 47.024544 -293.836344) (xy 47.027592 -293.844726) (xy 47.056294 -293.923212)
			(xy 47.060301 -293.932823) (xy 47.074555 -293.947975) (xy 47.093645 -293.956238) (xy 47.104046 -293.95674)
			(xy 47.71898 -293.95674) (xy 47.729042 -293.956301) (xy 47.74762 -293.948559) (xy 47.755048 -293.941754)
			(xy 47.998634 -293.698168) (xy 47.995586 -293.693088) (xy 48.002444 -293.68623) (xy 48.002698 -293.685976)
			(xy 48.009291 -293.678599) (xy 48.01676 -293.660299) (xy 48.017176 -293.650416) (xy 48.017176 -292.984936)
			(xy 48.016576 -292.972614) (xy 48.005114 -292.950799) (xy 47.995332 -292.94328) (xy 47.944024 -292.907466)
			(xy 47.943262 -292.906704) (xy 47.939452 -292.904164) (xy 47.930054 -292.897306) (xy 47.925228 -292.893496)
			(xy 47.917354 -292.88994) (xy 47.908672 -292.886496) (xy 47.890039 -292.885441) (xy 47.881032 -292.887908)
			(xy 47.880524 -292.888162) (xy 47.854992 -292.896275) (xy 47.802151 -292.905081) (xy 47.775368 -292.905688)
			(xy 47.77486 -292.905688) (xy 47.748876 -292.905176) (xy 47.69755 -292.89704) (xy 47.648128 -292.880977)
			(xy 47.601827 -292.85738) (xy 47.559786 -292.826832) (xy 47.523042 -292.790083) (xy 47.492499 -292.748039)
			(xy 47.468908 -292.701735) (xy 47.45285 -292.652311) (xy 47.444721 -292.600984) (xy 47.444721 -292.549016)
			(xy 47.45285 -292.497689) (xy 47.468908 -292.448265) (xy 47.492499 -292.401961) (xy 47.523042 -292.359917)
			(xy 47.559786 -292.323168) (xy 47.601827 -292.29262) (xy 47.648128 -292.269023) (xy 47.69755 -292.25296)
			(xy 47.748876 -292.244824) (xy 47.77486 -292.244272) (xy 47.775368 -292.244272) (xy 47.802087 -292.244891)
			(xy 47.854799 -292.253702) (xy 47.88027 -292.261798) (xy 47.880778 -292.261798) (xy 47.881032 -292.262052)
			(xy 47.890043 -292.264491) (xy 47.908666 -292.263437) (xy 47.917354 -292.26002) (xy 47.925228 -292.256464)
			(xy 47.930054 -292.252654) (xy 47.943516 -292.243002) (xy 47.98568 -292.214554) (xy 47.985172 -292.213792)
			(xy 47.995332 -292.20668) (xy 47.996094 -292.206172) (xy 48.005474 -292.198559) (xy 48.016468 -292.177085)
			(xy 48.017176 -292.165024) (xy 48.017176 -292.034722) (xy 48.016594 -292.02239) (xy 48.005154 -292.000544)
			(xy 47.995332 -291.993066) (xy 47.944024 -291.957252) (xy 47.943262 -291.95649) (xy 47.939452 -291.95395)
			(xy 47.930054 -291.947092) (xy 47.925228 -291.943282) (xy 47.917354 -291.939726) (xy 47.908672 -291.936283)
			(xy 47.89004 -291.935228) (xy 47.881032 -291.937694) (xy 47.880524 -291.937948) (xy 47.854992 -291.946061)
			(xy 47.802151 -291.954867) (xy 47.775368 -291.955474) (xy 47.77486 -291.955474) (xy 47.748878 -291.954962)
			(xy 47.697553 -291.946827) (xy 47.648133 -291.930764) (xy 47.601834 -291.907168) (xy 47.559795 -291.876621)
			(xy 47.523053 -291.839874) (xy 47.492511 -291.797832) (xy 47.468921 -291.75153) (xy 47.452864 -291.702108)
			(xy 47.444735 -291.650783) (xy 47.444735 -291.598817) (xy 47.452864 -291.547492) (xy 47.468921 -291.49807)
			(xy 47.492511 -291.451768) (xy 47.523053 -291.409726) (xy 47.559795 -291.372979) (xy 47.601834 -291.342432)
			(xy 47.648133 -291.318836) (xy 47.697553 -291.302773) (xy 47.748878 -291.294638) (xy 47.77486 -291.294058)
			(xy 47.775368 -291.294058) (xy 47.802087 -291.294676) (xy 47.854799 -291.303487) (xy 47.88027 -291.311584)
			(xy 47.880778 -291.311584) (xy 47.881032 -291.311838) (xy 47.890043 -291.314277) (xy 47.908665 -291.313223)
			(xy 47.917354 -291.309806) (xy 47.925228 -291.30625) (xy 47.930054 -291.30244) (xy 47.943516 -291.292788)
			(xy 47.98568 -291.26434) (xy 47.985172 -291.263578) (xy 47.995332 -291.256466) (xy 47.996094 -291.255958)
			(xy 48.005471 -291.248344) (xy 48.01646 -291.22687) (xy 48.017176 -291.21481) (xy 48.017176 -291.084762)
			(xy 48.016581 -291.072437) (xy 48.005126 -291.050613) (xy 47.995332 -291.043106) (xy 47.944024 -291.007292)
			(xy 47.943262 -291.00653) (xy 47.939452 -291.00399) (xy 47.930054 -290.997132) (xy 47.925228 -290.993322)
			(xy 47.917354 -290.989766) (xy 47.908672 -290.986321) (xy 47.890039 -290.985265) (xy 47.881032 -290.987734)
			(xy 47.880524 -290.987988) (xy 47.854992 -290.996101) (xy 47.802151 -291.004905) (xy 47.775368 -291.005514)
			(xy 47.77486 -291.005514) (xy 47.748874 -291.005001) (xy 47.697544 -290.996866) (xy 47.648118 -290.980801)
			(xy 47.601813 -290.957203) (xy 47.559769 -290.926652) (xy 47.523022 -290.8899) (xy 47.492477 -290.847853)
			(xy 47.468884 -290.801545) (xy 47.452825 -290.752117) (xy 47.444695 -290.700786) (xy 47.444695 -290.648814)
			(xy 47.452825 -290.597483) (xy 47.468884 -290.548055) (xy 47.492477 -290.501747) (xy 47.523022 -290.4597)
			(xy 47.559769 -290.422948) (xy 47.601813 -290.392397) (xy 47.648118 -290.368799) (xy 47.697544 -290.352734)
			(xy 47.748874 -290.344599) (xy 47.77486 -290.344098) (xy 47.775368 -290.344098) (xy 47.802087 -290.344717)
			(xy 47.854799 -290.353528) (xy 47.88027 -290.361624) (xy 47.880778 -290.361624) (xy 47.881032 -290.361878)
			(xy 47.890043 -290.364316) (xy 47.908666 -290.363263) (xy 47.917354 -290.359846) (xy 47.925228 -290.35629)
			(xy 47.930054 -290.35248) (xy 47.943516 -290.342828) (xy 47.98568 -290.31438) (xy 47.985172 -290.313618)
			(xy 47.995332 -290.306506) (xy 47.996094 -290.305998) (xy 48.005478 -290.298387) (xy 48.016483 -290.276913)
			(xy 48.017176 -290.26485) (xy 48.017176 -290.178998) (xy 48.016752 -290.168928) (xy 48.009034 -290.150327)
			(xy 48.00219 -290.14293) (xy 47.905162 -290.045902) (xy 47.878492 -290.039044) (xy 47.865284 -290.042854)
			(xy 47.843207 -290.04875) (xy 47.79796 -290.055128) (xy 47.775114 -290.055554) (xy 47.77486 -290.055554)
			(xy 47.748874 -290.055042) (xy 47.697541 -290.046906) (xy 47.648113 -290.030842) (xy 47.601806 -290.007245)
			(xy 47.559759 -289.976695) (xy 47.523008 -289.939945) (xy 47.492458 -289.897899) (xy 47.46886 -289.851592)
			(xy 47.452795 -289.802165) (xy 47.444659 -289.750832) (xy 47.444152 -289.724846) (xy 47.444152 -289.724592)
			(xy 47.444649 -289.70042) (xy 47.451787 -289.652604) (xy 47.458376 -289.629342) (xy 47.458376 -289.629088)
			(xy 47.45863 -289.62858) (xy 47.460301 -289.621893) (xy 47.460437 -289.608117) (xy 47.458884 -289.601402)
			(xy 47.456852 -289.59429) (xy 47.450248 -289.58286) (xy 47.445422 -289.578034) (xy 46.971712 -289.104324)
			(xy 46.966886 -289.099498) (xy 46.955456 -289.092894) (xy 46.948344 -289.090862) (xy 46.94163 -289.089292)
			(xy 46.927849 -289.089419) (xy 46.921166 -289.091116) (xy 46.920658 -289.09137) (xy 46.920404 -289.09137)
			(xy 46.897148 -289.097986) (xy 46.849328 -289.105123) (xy 46.825154 -289.105594) (xy 46.8249 -289.105594)
			(xy 46.798911 -289.105111) (xy 46.747573 -289.09698) (xy 46.69814 -289.080917) (xy 46.651828 -289.057319)
			(xy 46.609777 -289.026767) (xy 46.573024 -288.990012) (xy 46.542474 -288.94796) (xy 46.518878 -288.901647)
			(xy 46.502817 -288.852213) (xy 46.494688 -288.800875) (xy 46.494192 -288.774886) (xy 46.494192 -288.774632)
			(xy 46.494693 -288.750461) (xy 46.50184 -288.702647) (xy 46.508416 -288.679382) (xy 46.508416 -288.679128)
			(xy 46.50867 -288.67862) (xy 46.510334 -288.671934) (xy 46.510454 -288.658161) (xy 46.508924 -288.651442)
			(xy 46.506892 -288.64433) (xy 46.500288 -288.6329) (xy 46.495462 -288.628074) (xy 46.021752 -288.154364)
			(xy 46.016926 -288.149538) (xy 46.005496 -288.142934) (xy 45.998384 -288.140902) (xy 45.99167 -288.139327)
			(xy 45.977885 -288.139442) (xy 45.971206 -288.141156) (xy 45.970698 -288.14141) (xy 45.970444 -288.14141)
			(xy 45.947189 -288.14803) (xy 45.899369 -288.155175) (xy 45.875194 -288.155634) (xy 45.87494 -288.155634)
			(xy 45.848948 -288.155154) (xy 45.797603 -288.147028) (xy 45.748161 -288.130969) (xy 45.701841 -288.107374)
			(xy 45.659782 -288.076823) (xy 45.62302 -288.040069) (xy 45.59246 -287.998016) (xy 45.568856 -287.9517)
			(xy 45.552788 -287.902261) (xy 45.544651 -287.850918) (xy 45.544232 -287.824926) (xy 45.544232 -287.824672)
			(xy 45.54473 -287.8005) (xy 45.551871 -287.752685) (xy 45.558456 -287.729422) (xy 45.558456 -287.729168)
			(xy 45.55871 -287.72866) (xy 45.560379 -287.721974) (xy 45.560509 -287.708198) (xy 45.558964 -287.701482)
			(xy 45.556932 -287.69437) (xy 45.550328 -287.68294) (xy 45.545502 -287.678114) (xy 45.071792 -287.204404)
			(xy 45.066966 -287.199578) (xy 45.055536 -287.192974) (xy 45.048424 -287.190942) (xy 45.04171 -287.189374)
			(xy 45.02793 -287.189505) (xy 45.021246 -287.191196) (xy 45.020738 -287.19145) (xy 45.020484 -287.19145)
			(xy 44.997228 -287.198065) (xy 44.949408 -287.2052) (xy 44.925234 -287.205674) (xy 44.92498 -287.205674)
			(xy 44.898993 -287.205189) (xy 44.847659 -287.197055) (xy 44.798229 -287.180991) (xy 44.751921 -287.157392)
			(xy 44.709875 -287.126838) (xy 44.673126 -287.090084) (xy 44.64258 -287.048033) (xy 44.618988 -287.001721)
			(xy 44.602932 -286.952289) (xy 44.594806 -286.900953) (xy 44.594272 -286.874966) (xy 44.594272 -286.874712)
			(xy 44.594767 -286.85054) (xy 44.601903 -286.802723) (xy 44.608496 -286.779462) (xy 44.608496 -286.779208)
			(xy 44.60875 -286.7787) (xy 44.610423 -286.772013) (xy 44.610564 -286.758235) (xy 44.609004 -286.751522)
			(xy 44.606972 -286.74441) (xy 44.600368 -286.73298) (xy 44.595542 -286.728154) (xy 43.171618 -285.30423)
			(xy 43.166792 -285.299404) (xy 43.155362 -285.2928) (xy 43.14825 -285.290768) (xy 43.141536 -285.289198)
			(xy 43.127754 -285.289322) (xy 43.121072 -285.291022) (xy 43.120564 -285.291276) (xy 43.12031 -285.291276)
			(xy 43.097054 -285.297892) (xy 43.049234 -285.305031) (xy 43.02506 -285.3055) (xy 43.024806 -285.3055)
			(xy 42.998817 -285.305017) (xy 42.947478 -285.296887) (xy 42.898043 -285.280825) (xy 42.85173 -285.257227)
			(xy 42.809678 -285.226675) (xy 42.772924 -285.189921) (xy 42.742372 -285.147869) (xy 42.718774 -285.101555)
			(xy 42.702713 -285.05212) (xy 42.694583 -285.000781) (xy 42.694098 -284.974792) (xy 42.694098 -284.974538)
			(xy 42.694599 -284.950367) (xy 42.701745 -284.902553) (xy 42.708322 -284.879288) (xy 42.708322 -284.879034)
			(xy 42.708576 -284.878526) (xy 42.710241 -284.87184) (xy 42.710363 -284.858066) (xy 42.70883 -284.851348)
			(xy 42.706798 -284.844236) (xy 42.700194 -284.832806) (xy 42.695368 -284.82798) (xy 42.221658 -284.35427)
			(xy 42.216832 -284.349444) (xy 42.205402 -284.34284) (xy 42.19829 -284.340808) (xy 42.191576 -284.339245)
			(xy 42.177799 -284.339386) (xy 42.171112 -284.341062) (xy 42.170604 -284.341316) (xy 42.17035 -284.341316)
			(xy 42.147095 -284.347936) (xy 42.099275 -284.355082) (xy 42.0751 -284.35554) (xy 42.074846 -284.35554)
			(xy 42.048853 -284.35506) (xy 41.997507 -284.346935) (xy 41.948065 -284.330877) (xy 41.901743 -284.307282)
			(xy 41.859682 -284.276732) (xy 41.822919 -284.239977) (xy 41.792358 -284.197924) (xy 41.768753 -284.151607)
			(xy 41.752683 -284.102169) (xy 41.744546 -284.050824) (xy 41.744138 -284.024832) (xy 41.744599 -284.000179)
			(xy 41.751933 -283.951422) (xy 41.766427 -283.904294) (xy 41.787761 -283.859843) (xy 41.815461 -283.819053)
			(xy 41.848912 -283.78283) (xy 41.867836 -283.767022) (xy 41.86809 -283.766768) (xy 41.872408 -283.763212)
			(xy 41.879266 -283.75483) (xy 41.891458 -283.730192) (xy 41.891458 -283.729938) (xy 41.893893 -283.724671)
			(xy 41.896577 -283.713385) (xy 41.896792 -283.707586) (xy 41.896792 -283.392118) (xy 41.896624 -283.386253)
			(xy 41.893925 -283.374836) (xy 41.891458 -283.369512) (xy 41.879012 -283.34462) (xy 41.872154 -283.336238)
			(xy 41.867836 -283.332682) (xy 41.84721 -283.315423) (xy 41.811302 -283.27539) (xy 41.782344 -283.230075)
			(xy 41.761097 -283.180672) (xy 41.748123 -283.128483) (xy 41.743761 -283.074882) (xy 41.748128 -283.021282)
			(xy 41.761109 -282.969095) (xy 41.78236 -282.919694) (xy 41.811324 -282.874382) (xy 41.847236 -282.834352)
			(xy 41.867836 -282.817062) (xy 41.872154 -282.813506) (xy 41.879012 -282.805124) (xy 41.891458 -282.780232)
			(xy 41.893917 -282.774906) (xy 41.896607 -282.76349) (xy 41.896792 -282.757626) (xy 41.896792 -282.442158)
			(xy 41.896629 -282.436291) (xy 41.893938 -282.424871) (xy 41.891458 -282.419552) (xy 41.879012 -282.39466)
			(xy 41.872154 -282.386278) (xy 41.867836 -282.382722) (xy 41.847207 -282.365463) (xy 41.811293 -282.325429)
			(xy 41.782328 -282.280112) (xy 41.761076 -282.230706) (xy 41.748096 -282.178513) (xy 41.74373 -282.124908)
			(xy 41.748093 -282.071302) (xy 41.761071 -282.019108) (xy 41.782321 -281.969702) (xy 41.811284 -281.924383)
			(xy 41.847196 -281.884347) (xy 41.867836 -281.867102) (xy 41.872154 -281.863546) (xy 41.879012 -281.855164)
			(xy 41.891458 -281.830272) (xy 41.893922 -281.824947) (xy 41.89662 -281.813531) (xy 41.896792 -281.807666)
			(xy 41.896792 -281.492198) (xy 41.896633 -281.48633) (xy 41.89395 -281.474906) (xy 41.891458 -281.469592)
			(xy 41.879012 -281.4447) (xy 41.872154 -281.436318) (xy 41.867836 -281.432762) (xy 41.847212 -281.415503)
			(xy 41.811307 -281.37547) (xy 41.782352 -281.330156) (xy 41.761108 -281.280755) (xy 41.748136 -281.228568)
			(xy 41.743777 -281.17497) (xy 41.748146 -281.121372) (xy 41.761127 -281.069188) (xy 41.78238 -281.01979)
			(xy 41.811344 -280.974482) (xy 41.847255 -280.934455) (xy 41.867836 -280.917142) (xy 41.872154 -280.913586)
			(xy 41.879012 -280.905204) (xy 41.891458 -280.880312) (xy 41.893915 -280.874986) (xy 41.8966 -280.863569)
			(xy 41.896792 -280.857706) (xy 41.896792 -280.541984) (xy 41.896632 -280.536117) (xy 41.893946 -280.524694)
			(xy 41.891458 -280.519378) (xy 41.879012 -280.494486) (xy 41.872154 -280.486104) (xy 41.867836 -280.482548)
			(xy 41.847205 -280.465289) (xy 41.811287 -280.425254) (xy 41.782318 -280.379936) (xy 41.761062 -280.330528)
			(xy 41.748079 -280.278332) (xy 41.74371 -280.224724) (xy 41.748071 -280.171115) (xy 41.761047 -280.118917)
			(xy 41.782296 -280.069507) (xy 41.811258 -280.024184) (xy 41.84717 -279.984144) (xy 41.867836 -279.966928)
			(xy 41.872154 -279.963372) (xy 41.879012 -279.95499) (xy 41.891458 -279.930098) (xy 41.893925 -279.924773)
			(xy 41.896629 -279.913357) (xy 41.896792 -279.907492) (xy 41.896792 -279.592024) (xy 41.896625 -279.586158)
			(xy 41.893927 -279.574742) (xy 41.891458 -279.569418) (xy 41.879012 -279.544526) (xy 41.872154 -279.536144)
			(xy 41.867836 -279.532588) (xy 41.84721 -279.515329) (xy 41.811301 -279.475296) (xy 41.782342 -279.42998)
			(xy 41.761094 -279.380577) (xy 41.748119 -279.328387) (xy 41.743757 -279.274786) (xy 41.748123 -279.221185)
			(xy 41.761103 -279.168997) (xy 41.782355 -279.119595) (xy 41.811318 -279.074282) (xy 41.84723 -279.034252)
			(xy 41.867836 -279.016968) (xy 41.872154 -279.013412) (xy 41.879012 -279.00503) (xy 41.891458 -278.980138)
			(xy 41.893918 -278.974812) (xy 41.896608 -278.963396) (xy 41.896792 -278.957532) (xy 41.896792 -278.642064)
			(xy 41.896629 -278.636197) (xy 41.89394 -278.624776) (xy 41.891458 -278.619458) (xy 41.879012 -278.594566)
			(xy 41.872154 -278.586184) (xy 41.867836 -278.582628) (xy 41.847206 -278.565369) (xy 41.811291 -278.525335)
			(xy 41.782326 -278.480017) (xy 41.761073 -278.430611) (xy 41.748092 -278.378417) (xy 41.743725 -278.324811)
			(xy 41.748088 -278.271205) (xy 41.761065 -278.219011) (xy 41.782315 -278.169603) (xy 41.811278 -278.124283)
			(xy 41.84719 -278.084246) (xy 41.867836 -278.067008) (xy 41.872154 -278.063452) (xy 41.879012 -278.05507)
			(xy 41.891458 -278.030178) (xy 41.893923 -278.024853) (xy 41.896622 -278.013437) (xy 41.896792 -278.007572)
			(xy 41.896792 -277.692104) (xy 41.896623 -277.686239) (xy 41.893921 -277.674824) (xy 41.891458 -277.669498)
			(xy 41.879012 -277.644606) (xy 41.872154 -277.636224) (xy 41.867836 -277.632668) (xy 41.847211 -277.615409)
			(xy 41.811306 -277.575376) (xy 41.782349 -277.530062) (xy 41.761105 -277.48066) (xy 41.748132 -277.428473)
			(xy 41.743772 -277.374874) (xy 41.748141 -277.321275) (xy 41.761122 -277.26909) (xy 41.782374 -277.219691)
			(xy 41.811338 -277.174382) (xy 41.847249 -277.134354) (xy 41.867836 -277.117048) (xy 41.872154 -277.113492)
			(xy 41.879012 -277.10511) (xy 41.891458 -277.080218) (xy 41.893916 -277.074892) (xy 41.896602 -277.063476)
			(xy 41.896792 -277.057612) (xy 41.896792 -276.742144) (xy 41.896627 -276.736278) (xy 41.893933 -276.724859)
			(xy 41.891458 -276.719538) (xy 41.879012 -276.694646) (xy 41.872154 -276.686264) (xy 41.867836 -276.682708)
			(xy 41.847208 -276.665449) (xy 41.811296 -276.625415) (xy 41.782334 -276.580099) (xy 41.761083 -276.530694)
			(xy 41.748105 -276.478502) (xy 41.743741 -276.424899) (xy 41.748106 -276.371295) (xy 41.761084 -276.319104)
			(xy 41.782335 -276.269699) (xy 41.811298 -276.224383) (xy 41.84721 -276.184349) (xy 41.867836 -276.167088)
			(xy 41.872154 -276.163532) (xy 41.879012 -276.15515) (xy 41.891458 -276.130258) (xy 41.893921 -276.124933)
			(xy 41.896616 -276.113516) (xy 41.896792 -276.107652) (xy 41.896792 -275.792184) (xy 41.896632 -275.786317)
			(xy 41.893946 -275.774894) (xy 41.891458 -275.769578) (xy 41.879012 -275.744686) (xy 41.872154 -275.736304)
			(xy 41.867836 -275.732748) (xy 41.847205 -275.715489) (xy 41.811287 -275.675454) (xy 41.782318 -275.630136)
			(xy 41.761062 -275.580728) (xy 41.748079 -275.528532) (xy 41.74371 -275.474924) (xy 41.748071 -275.421315)
			(xy 41.761047 -275.369117) (xy 41.782296 -275.319707) (xy 41.811258 -275.274384) (xy 41.84717 -275.234344)
			(xy 41.867836 -275.217128) (xy 41.872154 -275.213572) (xy 41.879012 -275.20519) (xy 41.891458 -275.180298)
			(xy 41.893925 -275.174973) (xy 41.896629 -275.163557) (xy 41.896792 -275.157692) (xy 41.896792 -274.842224)
			(xy 41.896625 -274.836358) (xy 41.893927 -274.824942) (xy 41.891458 -274.819618) (xy 41.879012 -274.794726)
			(xy 41.872154 -274.786344) (xy 41.867836 -274.782788) (xy 41.84721 -274.765529) (xy 41.811301 -274.725496)
			(xy 41.782342 -274.68018) (xy 41.761094 -274.630777) (xy 41.748119 -274.578587) (xy 41.743757 -274.524986)
			(xy 41.748123 -274.471385) (xy 41.761103 -274.419197) (xy 41.782355 -274.369795) (xy 41.811318 -274.324482)
			(xy 41.84723 -274.284452) (xy 41.867836 -274.267168) (xy 41.872154 -274.263612) (xy 41.879012 -274.25523)
			(xy 41.891458 -274.230338) (xy 41.893918 -274.225012) (xy 41.896608 -274.213596) (xy 41.896792 -274.207732)
			(xy 41.896792 -273.89201) (xy 41.896623 -273.886145) (xy 41.893923 -273.874729) (xy 41.891458 -273.869404)
			(xy 41.879012 -273.844512) (xy 41.872154 -273.83613) (xy 41.867836 -273.832574) (xy 41.847211 -273.815315)
			(xy 41.811304 -273.775282) (xy 41.782347 -273.729967) (xy 41.761102 -273.680565) (xy 41.748128 -273.628377)
			(xy 41.743768 -273.574777) (xy 41.748135 -273.521178) (xy 41.761116 -273.468992) (xy 41.782368 -273.419593)
			(xy 41.811332 -273.374282) (xy 41.847244 -273.334253) (xy 41.867836 -273.316954) (xy 41.872154 -273.313398)
			(xy 41.879012 -273.305016) (xy 41.891458 -273.280124) (xy 41.893917 -273.274798) (xy 41.896604 -273.263382)
			(xy 41.896792 -273.257518) (xy 41.896792 -272.94205) (xy 41.896628 -272.936184) (xy 41.893935 -272.924764)
			(xy 41.891458 -272.919444) (xy 41.879012 -272.894552) (xy 41.872154 -272.88617) (xy 41.867836 -272.882614)
			(xy 41.847207 -272.865355) (xy 41.811295 -272.825321) (xy 41.782331 -272.780004) (xy 41.76108 -272.730599)
			(xy 41.748101 -272.678407) (xy 41.743736 -272.624803) (xy 41.7481 -272.571198) (xy 41.761079 -272.519006)
			(xy 41.782329 -272.4696) (xy 41.811292 -272.424283) (xy 41.847204 -272.384248) (xy 41.867836 -272.366994)
			(xy 41.872154 -272.363438) (xy 41.879012 -272.355056) (xy 41.891458 -272.330164) (xy 41.893921 -272.324839)
			(xy 41.896617 -272.313423) (xy 41.896792 -272.307558) (xy 41.896792 -271.134332) (xy 41.896518 -271.127215)
			(xy 41.892523 -271.113551) (xy 41.888918 -271.107408) (xy 41.875582 -271.085443) (xy 41.854296 -271.038673)
			(xy 41.839497 -270.989464) (xy 41.83507 -270.964152) (xy 41.832784 -270.950944) (xy 41.816782 -270.93037)
			(xy 41.71188 -270.886936) (xy 41.685718 -270.889984) (xy 41.67505 -270.898112) (xy 41.650437 -270.915307)
			(xy 41.596941 -270.942563) (xy 41.539837 -270.961106) (xy 41.480534 -270.970478) (xy 41.450514 -270.97101)
			(xy 41.42326 -270.970548) (xy 41.369308 -270.962792) (xy 41.317008 -270.947437) (xy 41.267426 -270.924796)
			(xy 41.221571 -270.895328) (xy 41.180376 -270.859634) (xy 41.144681 -270.818441) (xy 41.115211 -270.772587)
			(xy 41.092568 -270.723005) (xy 41.077211 -270.670706) (xy 41.069453 -270.616754) (xy 41.069453 -270.562246)
			(xy 41.077211 -270.508294) (xy 41.092568 -270.455995) (xy 41.115211 -270.406413) (xy 41.144681 -270.360559)
			(xy 41.180376 -270.319366) (xy 41.221571 -270.283672) (xy 41.267426 -270.254204) (xy 41.317008 -270.231563)
			(xy 41.369308 -270.216208) (xy 41.42326 -270.208452) (xy 41.450514 -270.207994) (xy 41.480853 -270.208581)
			(xy 41.540765 -270.218191) (xy 41.5984 -270.237164) (xy 41.652304 -270.265024) (xy 41.701116 -270.301067)
			(xy 41.722802 -270.322294) (xy 41.733724 -270.333216) (xy 41.763696 -270.339566) (xy 41.865296 -270.29791)
			(xy 41.87443 -270.293702) (xy 41.888672 -270.279524) (xy 41.896388 -270.260968) (xy 41.896792 -270.25092)
			(xy 41.896792 -265.331702) (xy 41.896538 -265.327384) (xy 41.867582 -264.995914) (xy 41.867018 -264.990884)
			(xy 41.864205 -264.981163) (xy 41.861994 -264.97661) (xy 41.859151 -264.971583) (xy 41.851585 -264.96286)
			(xy 41.847008 -264.959338) (xy 41.77665 -264.907776) (xy 41.755314 -264.903204) (xy 41.744646 -264.90549)
			(xy 41.724516 -264.909628) (xy 41.683661 -264.914082) (xy 41.663112 -264.91438) (xy 41.635861 -264.913918)
			(xy 41.581912 -264.906163) (xy 41.529617 -264.890809) (xy 41.480039 -264.868169) (xy 41.434188 -264.838703)
			(xy 41.392997 -264.803012) (xy 41.357304 -264.761822) (xy 41.327837 -264.715972) (xy 41.305196 -264.666394)
			(xy 41.28984 -264.614099) (xy 41.282083 -264.560151) (xy 41.282083 -264.505649) (xy 41.28984 -264.451701)
			(xy 41.305196 -264.399406) (xy 41.327837 -264.349828) (xy 41.357304 -264.303978) (xy 41.392997 -264.262788)
			(xy 41.434188 -264.227097) (xy 41.480039 -264.197631) (xy 41.529617 -264.174991) (xy 41.581912 -264.159637)
			(xy 41.635861 -264.151882) (xy 41.663112 -264.151364) (xy 41.678098 -264.151618) (xy 41.689274 -264.152126)
			(xy 41.70934 -264.143998) (xy 41.769538 -264.080752) (xy 41.7764 -264.072814) (xy 41.783636 -264.053142)
			(xy 41.783508 -264.042652) (xy 41.783508 -264.041128) (xy 41.30929 -258.657852) (xy 41.308098 -258.649032)
			(xy 41.300564 -258.632923) (xy 41.294558 -258.626356) (xy 39.22014 -256.551938) (xy 39.213028 -256.544572)
			(xy 39.194232 -256.536952) (xy 35.079686 -256.536952) (xy 35.072953 -256.537116) (xy 35.059943 -256.540582)
			(xy 35.054032 -256.54381) (xy 35.027616 -256.559558) (xy 35.018726 -256.568194) (xy 35.015424 -256.573528)
			(xy 35.000509 -256.597211) (xy 34.964834 -256.640335) (xy 34.92324 -256.677783) (xy 34.876619 -256.708749)
			(xy 34.825972 -256.732568) (xy 34.772389 -256.748729) (xy 34.717018 -256.756885) (xy 34.689034 -256.757424)
			(xy 34.662637 -256.756979) (xy 34.610348 -256.749705) (xy 34.559561 -256.735291) (xy 34.511246 -256.714012)
			(xy 34.466326 -256.686275) (xy 34.445702 -256.669794) (xy 34.430462 -256.657094) (xy 34.391346 -256.659126)
			(xy 33.99155 -257.058922) (xy 33.984184 -257.066034) (xy 33.976564 -257.08483) (xy 33.976564 -257.137916)
			(xy 36.579046 -257.137916) (xy 36.583117 -257.082294) (xy 36.595243 -257.027857) (xy 36.615166 -256.975766)
			(xy 36.642462 -256.927131) (xy 36.676548 -256.882988) (xy 36.716697 -256.844279) (xy 36.762055 -256.811828)
			(xy 36.811655 -256.786327) (xy 36.864439 -256.76832) (xy 36.919282 -256.75819) (xy 36.975016 -256.756153)
			(xy 37.030453 -256.762253) (xy 37.08441 -256.776359) (xy 37.135739 -256.798171) (xy 37.183345 -256.827225)
			(xy 37.226213 -256.8629) (xy 37.26343 -256.904437) (xy 37.294203 -256.95095) (xy 37.317875 -257.001447)
			(xy 37.333943 -257.054854) (xy 37.342063 -257.11003) (xy 37.342572 -257.137916) (xy 37.342063 -257.165802)
			(xy 37.333943 -257.220978) (xy 37.317875 -257.274385) (xy 37.294203 -257.324882) (xy 37.26343 -257.371395)
			(xy 37.226213 -257.412932) (xy 37.183345 -257.448607) (xy 37.135739 -257.477661) (xy 37.08441 -257.499473)
			(xy 37.030453 -257.513579) (xy 36.975016 -257.519679) (xy 36.919282 -257.517642) (xy 36.864439 -257.507512)
			(xy 36.811655 -257.489505) (xy 36.762055 -257.464004) (xy 36.716697 -257.431553) (xy 36.676548 -257.392844)
			(xy 36.642462 -257.348701) (xy 36.615166 -257.300066) (xy 36.595243 -257.247975) (xy 36.583117 -257.193538)
			(xy 36.579046 -257.137916) (xy 33.976564 -257.137916) (xy 33.976564 -258.691888) (xy 33.976987 -258.701958)
			(xy 33.984705 -258.720559) (xy 33.99155 -258.727956) (xy 34.385758 -259.122164) (xy 34.39287 -259.129276)
			(xy 34.411412 -259.13715) (xy 37.092382 -259.13715) (xy 37.102444 -259.13759) (xy 37.121022 -259.14533)
			(xy 37.12845 -259.152136) (xy 38.454838 -260.478524) (xy 38.461687 -260.485921) (xy 38.469423 -260.50452)
			(xy 38.469824 -260.514592) (xy 38.469824 -260.53923) (xy 38.471856 -260.5532) (xy 38.473634 -260.55955)
			(xy 38.47719 -260.565646) (xy 38.477444 -260.5659) (xy 38.480738 -260.571866) (xy 38.484358 -260.584997)
			(xy 38.484556 -260.591808) (xy 38.484556 -263.8171) (xy 38.499542 -263.841484) (xy 38.512496 -263.847834)
			(xy 38.535942 -263.860037) (xy 38.579525 -263.889943) (xy 38.618561 -263.92558) (xy 38.652302 -263.966266)
			(xy 38.680102 -264.011221) (xy 38.701427 -264.059585) (xy 38.71587 -264.110429) (xy 38.723154 -264.162782)
			(xy 38.72357 -264.18921) (xy 38.723102 -264.216015) (xy 38.71557 -264.269093) (xy 38.700686 -264.320594)
			(xy 38.678741 -264.369507) (xy 38.650167 -264.414867) (xy 38.615527 -264.455782) (xy 38.595808 -264.473944)
			(xy 38.594792 -264.47496) (xy 38.59276 -264.476992) (xy 38.59149 -264.478262) (xy 38.59022 -264.479532)
			(xy 38.589966 -264.479786) (xy 38.571554 -264.498154) (xy 38.530642 -264.530262) (xy 38.508432 -264.543794)
			(xy 38.500443 -264.548944) (xy 38.488695 -264.563871) (xy 38.48318 -264.582048) (xy 38.48354 -264.591546)
			(xy 38.484556 -264.618978) (xy 38.484556 -265.16457) (xy 40.46296 -265.16457) (xy 40.467031 -265.108948)
			(xy 40.479157 -265.054511) (xy 40.49908 -265.00242) (xy 40.526376 -264.953785) (xy 40.560462 -264.909642)
			(xy 40.600611 -264.870933) (xy 40.645969 -264.838482) (xy 40.695569 -264.812981) (xy 40.748353 -264.794974)
			(xy 40.803196 -264.784844) (xy 40.85893 -264.782807) (xy 40.914367 -264.788907) (xy 40.968324 -264.803013)
			(xy 41.019653 -264.824825) (xy 41.067259 -264.853879) (xy 41.110127 -264.889554) (xy 41.147344 -264.931091)
			(xy 41.178117 -264.977604) (xy 41.201789 -265.028101) (xy 41.217857 -265.081508) (xy 41.225977 -265.136684)
			(xy 41.226486 -265.16457) (xy 41.225977 -265.192456) (xy 41.217857 -265.247632) (xy 41.201789 -265.301039)
			(xy 41.178117 -265.351536) (xy 41.147344 -265.398049) (xy 41.110127 -265.439586) (xy 41.067259 -265.475261)
			(xy 41.019653 -265.504315) (xy 40.968324 -265.526127) (xy 40.914367 -265.540233) (xy 40.85893 -265.546333)
			(xy 40.803196 -265.544296) (xy 40.748353 -265.534166) (xy 40.695569 -265.516159) (xy 40.645969 -265.490658)
			(xy 40.600611 -265.458207) (xy 40.560462 -265.419498) (xy 40.526376 -265.375355) (xy 40.49908 -265.32672)
			(xy 40.479157 -265.274629) (xy 40.467031 -265.220192) (xy 40.46296 -265.16457) (xy 38.484556 -265.16457)
			(xy 38.484556 -266.517882) (xy 40.39692 -266.517882) (xy 40.400991 -266.46226) (xy 40.413117 -266.407823)
			(xy 40.43304 -266.355732) (xy 40.460336 -266.307097) (xy 40.494422 -266.262954) (xy 40.534571 -266.224245)
			(xy 40.579929 -266.191794) (xy 40.629529 -266.166293) (xy 40.682313 -266.148286) (xy 40.737156 -266.138156)
			(xy 40.79289 -266.136119) (xy 40.848327 -266.142219) (xy 40.902284 -266.156325) (xy 40.953613 -266.178137)
			(xy 41.001219 -266.207191) (xy 41.044087 -266.242866) (xy 41.081304 -266.284403) (xy 41.112077 -266.330916)
			(xy 41.135749 -266.381413) (xy 41.151817 -266.43482) (xy 41.159937 -266.489996) (xy 41.160446 -266.517882)
			(xy 41.159937 -266.545768) (xy 41.151817 -266.600944) (xy 41.135749 -266.654351) (xy 41.112077 -266.704848)
			(xy 41.081304 -266.751361) (xy 41.044087 -266.792898) (xy 41.001219 -266.828573) (xy 40.953613 -266.857627)
			(xy 40.902284 -266.879439) (xy 40.848327 -266.893545) (xy 40.79289 -266.899645) (xy 40.737156 -266.897608)
			(xy 40.682313 -266.887478) (xy 40.629529 -266.869471) (xy 40.579929 -266.84397) (xy 40.534571 -266.811519)
			(xy 40.494422 -266.77281) (xy 40.460336 -266.728667) (xy 40.43304 -266.680032) (xy 40.413117 -266.627941)
			(xy 40.400991 -266.573504) (xy 40.39692 -266.517882) (xy 38.484556 -266.517882) (xy 38.484556 -266.963398)
			(xy 38.656004 -266.963398) (xy 38.660075 -266.907776) (xy 38.672201 -266.853339) (xy 38.692124 -266.801248)
			(xy 38.71942 -266.752613) (xy 38.753506 -266.70847) (xy 38.793655 -266.669761) (xy 38.839013 -266.63731)
			(xy 38.888613 -266.611809) (xy 38.941397 -266.593802) (xy 38.99624 -266.583672) (xy 39.051974 -266.581635)
			(xy 39.107411 -266.587735) (xy 39.161368 -266.601841) (xy 39.212697 -266.623653) (xy 39.260303 -266.652707)
			(xy 39.303171 -266.688382) (xy 39.340388 -266.729919) (xy 39.371161 -266.776432) (xy 39.394833 -266.826929)
			(xy 39.410901 -266.880336) (xy 39.419021 -266.935512) (xy 39.41953 -266.963398) (xy 39.419021 -266.991284)
			(xy 39.410901 -267.04646) (xy 39.394833 -267.099867) (xy 39.371161 -267.150364) (xy 39.340388 -267.196877)
			(xy 39.303171 -267.238414) (xy 39.260303 -267.274089) (xy 39.212697 -267.303143) (xy 39.161368 -267.324955)
			(xy 39.107411 -267.339061) (xy 39.051974 -267.345161) (xy 38.99624 -267.343124) (xy 38.941397 -267.332994)
			(xy 38.888613 -267.314987) (xy 38.839013 -267.289486) (xy 38.793655 -267.257035) (xy 38.753506 -267.218326)
			(xy 38.71942 -267.174183) (xy 38.692124 -267.125548) (xy 38.672201 -267.073457) (xy 38.660075 -267.01902)
			(xy 38.656004 -266.963398) (xy 38.484556 -266.963398) (xy 38.484556 -267.604494) (xy 40.41775 -267.604494)
			(xy 40.418236 -267.577243) (xy 40.425992 -267.523295) (xy 40.441347 -267.471) (xy 40.463989 -267.421423)
			(xy 40.493455 -267.375573) (xy 40.529146 -267.334382) (xy 40.570337 -267.298691) (xy 40.616187 -267.269225)
			(xy 40.665764 -267.246583) (xy 40.718059 -267.231228) (xy 40.772007 -267.223472) (xy 40.826509 -267.223472)
			(xy 40.880457 -267.231228) (xy 40.932752 -267.246583) (xy 40.982329 -267.269225) (xy 41.028179 -267.298691)
			(xy 41.06937 -267.334382) (xy 41.105061 -267.375573) (xy 41.134527 -267.421423) (xy 41.157169 -267.471)
			(xy 41.172524 -267.523295) (xy 41.18028 -267.577243) (xy 41.180766 -267.604494) (xy 41.180261 -267.632763)
			(xy 41.17193 -267.688683) (xy 41.155434 -267.74276) (xy 41.131135 -267.79381) (xy 41.099566 -267.840712)
			(xy 41.061418 -267.88244) (xy 41.039796 -267.900658) (xy 41.029673 -267.909485) (xy 41.013976 -267.931265)
			(xy 41.004494 -267.956382) (xy 41.001881 -267.983101) (xy 41.006318 -268.009579) (xy 41.017498 -268.033987)
			(xy 41.034649 -268.05464) (xy 41.045384 -268.06271) (xy 41.066526 -268.078075) (xy 41.104806 -268.113657)
			(xy 41.13787 -268.154133) (xy 41.165096 -268.198745) (xy 41.185977 -268.246657) (xy 41.200119 -268.29697)
			(xy 41.207259 -268.348744) (xy 41.20769 -268.374876) (xy 41.207204 -268.402127) (xy 41.199448 -268.456075)
			(xy 41.184093 -268.50837) (xy 41.161451 -268.557947) (xy 41.131985 -268.603797) (xy 41.096294 -268.644988)
			(xy 41.055103 -268.680679) (xy 41.009253 -268.710145) (xy 40.959676 -268.732787) (xy 40.907381 -268.748142)
			(xy 40.853433 -268.755898) (xy 40.798931 -268.755898) (xy 40.744983 -268.748142) (xy 40.692688 -268.732787)
			(xy 40.643111 -268.710145) (xy 40.597261 -268.680679) (xy 40.55607 -268.644988) (xy 40.520379 -268.603797)
			(xy 40.490913 -268.557947) (xy 40.468271 -268.50837) (xy 40.452916 -268.456075) (xy 40.44516 -268.402127)
			(xy 40.444674 -268.374876) (xy 40.445179 -268.346607) (xy 40.453513 -268.290688) (xy 40.470011 -268.236612)
			(xy 40.49431 -268.185563) (xy 40.525878 -268.13866) (xy 40.564023 -268.096931) (xy 40.585644 -268.078712)
			(xy 40.595805 -268.069923) (xy 40.611512 -268.048137) (xy 40.620998 -268.02301) (xy 40.623608 -267.99628)
			(xy 40.619163 -267.969793) (xy 40.607969 -267.945379) (xy 40.5908 -267.924726) (xy 40.580056 -267.91666)
			(xy 40.558934 -267.90127) (xy 40.520655 -267.86569) (xy 40.487592 -267.825217) (xy 40.460364 -267.78061)
			(xy 40.439481 -267.732703) (xy 40.425333 -267.682394) (xy 40.418186 -267.630624) (xy 40.41775 -267.604494)
			(xy 38.484556 -267.604494) (xy 38.484556 -268.882622) (xy 38.485247 -268.89536) (xy 38.497371 -268.917768)
			(xy 38.50767 -268.925294) (xy 38.575742 -268.969744) (xy 38.601142 -268.971776) (xy 38.61308 -268.966442)
			(xy 38.637541 -268.956092) (xy 38.68861 -268.941495) (xy 38.741209 -268.934124) (xy 38.767766 -268.933676)
			(xy 38.795022 -268.934137) (xy 38.848979 -268.94189) (xy 38.901283 -268.957244) (xy 38.950869 -268.979885)
			(xy 38.996729 -269.009354) (xy 39.037927 -269.045049) (xy 39.073626 -269.086244) (xy 39.103098 -269.132101)
			(xy 39.125744 -269.181685) (xy 39.141103 -269.233988) (xy 39.148861 -269.287944) (xy 39.148861 -269.342456)
			(xy 39.141103 -269.396412) (xy 39.125744 -269.448715) (xy 39.103098 -269.498299) (xy 39.073626 -269.544156)
			(xy 39.037927 -269.585351) (xy 38.996729 -269.621046) (xy 38.950869 -269.650515) (xy 38.901283 -269.673156)
			(xy 38.848979 -269.68851) (xy 38.795022 -269.696263) (xy 38.767766 -269.696692) (xy 38.74121 -269.696232)
			(xy 38.688612 -269.688861) (xy 38.637544 -269.674268) (xy 38.61308 -269.663926) (xy 38.601142 -269.658592)
			(xy 38.575742 -269.660624) (xy 38.562534 -269.66926) (xy 38.50767 -269.705074) (xy 38.500738 -269.709937)
			(xy 38.490319 -269.723274) (xy 38.484832 -269.739283) (xy 38.484556 -269.747746) (xy 38.484556 -270.547592)
			(xy 39.118284 -270.547592) (xy 39.122355 -270.49197) (xy 39.134481 -270.437533) (xy 39.154404 -270.385442)
			(xy 39.1817 -270.336807) (xy 39.215786 -270.292664) (xy 39.255935 -270.253955) (xy 39.301293 -270.221504)
			(xy 39.350893 -270.196003) (xy 39.403677 -270.177996) (xy 39.45852 -270.167866) (xy 39.514254 -270.165829)
			(xy 39.569691 -270.171929) (xy 39.623648 -270.186035) (xy 39.674977 -270.207847) (xy 39.722583 -270.236901)
			(xy 39.765451 -270.272576) (xy 39.802668 -270.314113) (xy 39.833441 -270.360626) (xy 39.857113 -270.411123)
			(xy 39.873181 -270.46453) (xy 39.881301 -270.519706) (xy 39.88181 -270.547592) (xy 39.881301 -270.575478)
			(xy 39.873181 -270.630654) (xy 39.862636 -270.665702) (xy 40.061894 -270.665702) (xy 40.065965 -270.61008)
			(xy 40.078091 -270.555643) (xy 40.098014 -270.503552) (xy 40.12531 -270.454917) (xy 40.159396 -270.410774)
			(xy 40.199545 -270.372065) (xy 40.244903 -270.339614) (xy 40.294503 -270.314113) (xy 40.347287 -270.296106)
			(xy 40.40213 -270.285976) (xy 40.457864 -270.283939) (xy 40.513301 -270.290039) (xy 40.567258 -270.304145)
			(xy 40.618587 -270.325957) (xy 40.666193 -270.355011) (xy 40.709061 -270.390686) (xy 40.746278 -270.432223)
			(xy 40.777051 -270.478736) (xy 40.800723 -270.529233) (xy 40.816791 -270.58264) (xy 40.824911 -270.637816)
			(xy 40.82542 -270.665702) (xy 40.824911 -270.693588) (xy 40.816791 -270.748764) (xy 40.800723 -270.802171)
			(xy 40.777051 -270.852668) (xy 40.746278 -270.899181) (xy 40.709061 -270.940718) (xy 40.666193 -270.976393)
			(xy 40.618587 -271.005447) (xy 40.567258 -271.027259) (xy 40.513301 -271.041365) (xy 40.457864 -271.047465)
			(xy 40.40213 -271.045428) (xy 40.347287 -271.035298) (xy 40.294503 -271.017291) (xy 40.244903 -270.99179)
			(xy 40.199545 -270.959339) (xy 40.159396 -270.92063) (xy 40.12531 -270.876487) (xy 40.098014 -270.827852)
			(xy 40.078091 -270.775761) (xy 40.065965 -270.721324) (xy 40.061894 -270.665702) (xy 39.862636 -270.665702)
			(xy 39.857113 -270.684061) (xy 39.833441 -270.734558) (xy 39.802668 -270.781071) (xy 39.765451 -270.822608)
			(xy 39.722583 -270.858283) (xy 39.674977 -270.887337) (xy 39.623648 -270.909149) (xy 39.569691 -270.923255)
			(xy 39.514254 -270.929355) (xy 39.45852 -270.927318) (xy 39.403677 -270.917188) (xy 39.350893 -270.899181)
			(xy 39.301293 -270.87368) (xy 39.255935 -270.841229) (xy 39.215786 -270.80252) (xy 39.1817 -270.758377)
			(xy 39.154404 -270.709742) (xy 39.134481 -270.657651) (xy 39.122355 -270.603214) (xy 39.118284 -270.547592)
			(xy 38.484556 -270.547592) (xy 38.484556 -272.259806) (xy 38.484329 -272.276248) (xy 38.480897 -272.308954)
			(xy 38.477698 -272.325084) (xy 38.47592 -272.333466) (xy 38.477698 -272.349214) (xy 38.487858 -272.371312)
			(xy 38.495732 -272.378424) (xy 38.514241 -272.39565) (xy 38.546327 -272.434727) (xy 38.572092 -272.478231)
			(xy 38.590936 -272.525149) (xy 38.602421 -272.574389) (xy 38.606279 -272.624803) (xy 38.606279 -272.624804)
			(xy 38.919162 -272.624804) (xy 38.923122 -272.57575) (xy 38.934899 -272.527966) (xy 38.95419 -272.48269)
			(xy 38.980493 -272.441094) (xy 39.013128 -272.404257) (xy 39.051249 -272.373132) (xy 39.09387 -272.348525)
			(xy 39.139886 -272.331073) (xy 39.188105 -272.321229) (xy 39.23728 -272.319248) (xy 39.286135 -272.32518)
			(xy 39.333406 -272.338872) (xy 39.377868 -272.35997) (xy 39.418371 -272.387926) (xy 39.453864 -272.422018)
			(xy 39.483429 -272.461362) (xy 39.5063 -272.504939) (xy 39.521884 -272.55162) (xy 39.529779 -272.600197)
			(xy 39.530274 -272.624804) (xy 39.869122 -272.624804) (xy 39.873082 -272.57575) (xy 39.884859 -272.527966)
			(xy 39.90415 -272.48269) (xy 39.930453 -272.441094) (xy 39.963088 -272.404257) (xy 40.001209 -272.373132)
			(xy 40.04383 -272.348525) (xy 40.089846 -272.331073) (xy 40.138065 -272.321229) (xy 40.18724 -272.319248)
			(xy 40.236095 -272.32518) (xy 40.283366 -272.338872) (xy 40.327828 -272.35997) (xy 40.368331 -272.387926)
			(xy 40.403824 -272.422018) (xy 40.433389 -272.461362) (xy 40.45626 -272.504939) (xy 40.471844 -272.55162)
			(xy 40.479739 -272.600197) (xy 40.480234 -272.624804) (xy 40.819082 -272.624804) (xy 40.823042 -272.57575)
			(xy 40.834819 -272.527966) (xy 40.85411 -272.48269) (xy 40.880413 -272.441094) (xy 40.913048 -272.404257)
			(xy 40.951169 -272.373132) (xy 40.99379 -272.348525) (xy 41.039806 -272.331073) (xy 41.088025 -272.321229)
			(xy 41.1372 -272.319248) (xy 41.186055 -272.32518) (xy 41.233326 -272.338872) (xy 41.277788 -272.35997)
			(xy 41.318291 -272.387926) (xy 41.353784 -272.422018) (xy 41.383349 -272.461362) (xy 41.40622 -272.504939)
			(xy 41.421804 -272.55162) (xy 41.429699 -272.600197) (xy 41.430194 -272.624804) (xy 41.429699 -272.649411)
			(xy 41.421804 -272.697988) (xy 41.40622 -272.744669) (xy 41.383349 -272.788246) (xy 41.353784 -272.82759)
			(xy 41.318291 -272.861682) (xy 41.277788 -272.889638) (xy 41.233326 -272.910736) (xy 41.186055 -272.924428)
			(xy 41.1372 -272.93036) (xy 41.088025 -272.928379) (xy 41.039806 -272.918535) (xy 40.99379 -272.901083)
			(xy 40.951169 -272.876476) (xy 40.913048 -272.845351) (xy 40.880413 -272.808514) (xy 40.85411 -272.766918)
			(xy 40.834819 -272.721642) (xy 40.823042 -272.673858) (xy 40.819082 -272.624804) (xy 40.480234 -272.624804)
			(xy 40.479739 -272.649411) (xy 40.471844 -272.697988) (xy 40.45626 -272.744669) (xy 40.433389 -272.788246)
			(xy 40.403824 -272.82759) (xy 40.368331 -272.861682) (xy 40.327828 -272.889638) (xy 40.283366 -272.910736)
			(xy 40.236095 -272.924428) (xy 40.18724 -272.93036) (xy 40.138065 -272.928379) (xy 40.089846 -272.918535)
			(xy 40.04383 -272.901083) (xy 40.001209 -272.876476) (xy 39.963088 -272.845351) (xy 39.930453 -272.808514)
			(xy 39.90415 -272.766918) (xy 39.884859 -272.721642) (xy 39.873082 -272.673858) (xy 39.869122 -272.624804)
			(xy 39.530274 -272.624804) (xy 39.529779 -272.649411) (xy 39.521884 -272.697988) (xy 39.5063 -272.744669)
			(xy 39.483429 -272.788246) (xy 39.453864 -272.82759) (xy 39.418371 -272.861682) (xy 39.377868 -272.889638)
			(xy 39.333406 -272.910736) (xy 39.286135 -272.924428) (xy 39.23728 -272.93036) (xy 39.188105 -272.928379)
			(xy 39.139886 -272.918535) (xy 39.09387 -272.901083) (xy 39.051249 -272.876476) (xy 39.013128 -272.845351)
			(xy 38.980493 -272.808514) (xy 38.95419 -272.766918) (xy 38.934899 -272.721642) (xy 38.923122 -272.673858)
			(xy 38.919162 -272.624804) (xy 38.606279 -272.624804) (xy 38.60242 -272.675216) (xy 38.590934 -272.724456)
			(xy 38.572089 -272.771374) (xy 38.546323 -272.814877) (xy 38.514237 -272.853953) (xy 38.495732 -272.871184)
			(xy 38.487858 -272.878296) (xy 38.477698 -272.900394) (xy 38.47592 -272.916142) (xy 38.477698 -272.924524)
			(xy 38.480876 -272.940657) (xy 38.484312 -272.973361) (xy 38.484556 -272.989802) (xy 38.484556 -273.210274)
			(xy 38.484319 -273.225679) (xy 38.481263 -273.256338) (xy 38.47846 -273.271488) (xy 38.476936 -273.279362)
			(xy 38.478714 -273.294856) (xy 38.492938 -273.326606) (xy 38.500558 -273.333464) (xy 38.519965 -273.352352)
			(xy 38.552968 -273.395283) (xy 38.578541 -273.443015) (xy 38.596004 -273.494273) (xy 38.60489 -273.547689)
			(xy 38.60546 -273.574764) (xy 38.919162 -273.574764) (xy 38.923122 -273.52571) (xy 38.934899 -273.477926)
			(xy 38.95419 -273.43265) (xy 38.980493 -273.391054) (xy 39.013128 -273.354217) (xy 39.051249 -273.323092)
			(xy 39.09387 -273.298485) (xy 39.139886 -273.281033) (xy 39.188105 -273.271189) (xy 39.23728 -273.269208)
			(xy 39.286135 -273.27514) (xy 39.333406 -273.288832) (xy 39.377868 -273.30993) (xy 39.418371 -273.337886)
			(xy 39.453864 -273.371978) (xy 39.483429 -273.411322) (xy 39.5063 -273.454899) (xy 39.521884 -273.50158)
			(xy 39.529779 -273.550157) (xy 39.530274 -273.574764) (xy 39.869122 -273.574764) (xy 39.873082 -273.52571)
			(xy 39.884859 -273.477926) (xy 39.90415 -273.43265) (xy 39.930453 -273.391054) (xy 39.963088 -273.354217)
			(xy 40.001209 -273.323092) (xy 40.04383 -273.298485) (xy 40.089846 -273.281033) (xy 40.138065 -273.271189)
			(xy 40.18724 -273.269208) (xy 40.236095 -273.27514) (xy 40.283366 -273.288832) (xy 40.327828 -273.30993)
			(xy 40.368331 -273.337886) (xy 40.403824 -273.371978) (xy 40.433389 -273.411322) (xy 40.45626 -273.454899)
			(xy 40.471844 -273.50158) (xy 40.479739 -273.550157) (xy 40.480234 -273.574764) (xy 40.819082 -273.574764)
			(xy 40.823042 -273.52571) (xy 40.834819 -273.477926) (xy 40.85411 -273.43265) (xy 40.880413 -273.391054)
			(xy 40.913048 -273.354217) (xy 40.951169 -273.323092) (xy 40.99379 -273.298485) (xy 41.039806 -273.281033)
			(xy 41.088025 -273.271189) (xy 41.1372 -273.269208) (xy 41.186055 -273.27514) (xy 41.233326 -273.288832)
			(xy 41.277788 -273.30993) (xy 41.318291 -273.337886) (xy 41.353784 -273.371978) (xy 41.383349 -273.411322)
			(xy 41.40622 -273.454899) (xy 41.421804 -273.50158) (xy 41.429699 -273.550157) (xy 41.430194 -273.574764)
			(xy 41.429699 -273.599371) (xy 41.421804 -273.647948) (xy 41.40622 -273.694629) (xy 41.383349 -273.738206)
			(xy 41.353784 -273.77755) (xy 41.318291 -273.811642) (xy 41.277788 -273.839598) (xy 41.233326 -273.860696)
			(xy 41.186055 -273.874388) (xy 41.1372 -273.88032) (xy 41.088025 -273.878339) (xy 41.039806 -273.868495)
			(xy 40.99379 -273.851043) (xy 40.951169 -273.826436) (xy 40.913048 -273.795311) (xy 40.880413 -273.758474)
			(xy 40.85411 -273.716878) (xy 40.834819 -273.671602) (xy 40.823042 -273.623818) (xy 40.819082 -273.574764)
			(xy 40.480234 -273.574764) (xy 40.479739 -273.599371) (xy 40.471844 -273.647948) (xy 40.45626 -273.694629)
			(xy 40.433389 -273.738206) (xy 40.403824 -273.77755) (xy 40.368331 -273.811642) (xy 40.327828 -273.839598)
			(xy 40.283366 -273.860696) (xy 40.236095 -273.874388) (xy 40.18724 -273.88032) (xy 40.138065 -273.878339)
			(xy 40.089846 -273.868495) (xy 40.04383 -273.851043) (xy 40.001209 -273.826436) (xy 39.963088 -273.795311)
			(xy 39.930453 -273.758474) (xy 39.90415 -273.716878) (xy 39.884859 -273.671602) (xy 39.873082 -273.623818)
			(xy 39.869122 -273.574764) (xy 39.530274 -273.574764) (xy 39.529779 -273.599371) (xy 39.521884 -273.647948)
			(xy 39.5063 -273.694629) (xy 39.483429 -273.738206) (xy 39.453864 -273.77755) (xy 39.418371 -273.811642)
			(xy 39.377868 -273.839598) (xy 39.333406 -273.860696) (xy 39.286135 -273.874388) (xy 39.23728 -273.88032)
			(xy 39.188105 -273.878339) (xy 39.139886 -273.868495) (xy 39.09387 -273.851043) (xy 39.051249 -273.826436)
			(xy 39.013128 -273.795311) (xy 38.980493 -273.758474) (xy 38.95419 -273.716878) (xy 38.934899 -273.671602)
			(xy 38.923122 -273.623818) (xy 38.919162 -273.574764) (xy 38.60546 -273.574764) (xy 38.604904 -273.601843)
			(xy 38.596046 -273.655272) (xy 38.578595 -273.706541) (xy 38.553018 -273.754279) (xy 38.519999 -273.797207)
			(xy 38.500558 -273.816064) (xy 38.492938 -273.822922) (xy 38.478714 -273.854672) (xy 38.476936 -273.870166)
			(xy 38.47846 -273.87804) (xy 38.481285 -273.893186) (xy 38.484335 -273.923848) (xy 38.484556 -273.939254)
			(xy 38.484556 -274.15998) (xy 38.484325 -274.176422) (xy 38.480886 -274.209126) (xy 38.477698 -274.225258)
			(xy 38.47592 -274.23364) (xy 38.477698 -274.249388) (xy 38.487858 -274.271486) (xy 38.495732 -274.278598)
			(xy 38.514243 -274.295824) (xy 38.546333 -274.334901) (xy 38.572102 -274.378407) (xy 38.59095 -274.425327)
			(xy 38.602438 -274.474569) (xy 38.606298 -274.524978) (xy 38.919162 -274.524978) (xy 38.923122 -274.475924)
			(xy 38.934899 -274.42814) (xy 38.95419 -274.382864) (xy 38.980493 -274.341268) (xy 39.013128 -274.304431)
			(xy 39.051249 -274.273306) (xy 39.09387 -274.248699) (xy 39.139886 -274.231247) (xy 39.188105 -274.221403)
			(xy 39.23728 -274.219422) (xy 39.286135 -274.225354) (xy 39.333406 -274.239046) (xy 39.377868 -274.260144)
			(xy 39.418371 -274.2881) (xy 39.453864 -274.322192) (xy 39.483429 -274.361536) (xy 39.5063 -274.405113)
			(xy 39.521884 -274.451794) (xy 39.529779 -274.500371) (xy 39.530274 -274.524978) (xy 39.869122 -274.524978)
			(xy 39.873082 -274.475924) (xy 39.884859 -274.42814) (xy 39.90415 -274.382864) (xy 39.930453 -274.341268)
			(xy 39.963088 -274.304431) (xy 40.001209 -274.273306) (xy 40.04383 -274.248699) (xy 40.089846 -274.231247)
			(xy 40.138065 -274.221403) (xy 40.18724 -274.219422) (xy 40.236095 -274.225354) (xy 40.283366 -274.239046)
			(xy 40.327828 -274.260144) (xy 40.368331 -274.2881) (xy 40.403824 -274.322192) (xy 40.433389 -274.361536)
			(xy 40.45626 -274.405113) (xy 40.471844 -274.451794) (xy 40.479739 -274.500371) (xy 40.480234 -274.524978)
			(xy 40.819082 -274.524978) (xy 40.823042 -274.475924) (xy 40.834819 -274.42814) (xy 40.85411 -274.382864)
			(xy 40.880413 -274.341268) (xy 40.913048 -274.304431) (xy 40.951169 -274.273306) (xy 40.99379 -274.248699)
			(xy 41.039806 -274.231247) (xy 41.088025 -274.221403) (xy 41.1372 -274.219422) (xy 41.186055 -274.225354)
			(xy 41.233326 -274.239046) (xy 41.277788 -274.260144) (xy 41.318291 -274.2881) (xy 41.353784 -274.322192)
			(xy 41.383349 -274.361536) (xy 41.40622 -274.405113) (xy 41.421804 -274.451794) (xy 41.429699 -274.500371)
			(xy 41.430194 -274.524978) (xy 41.429699 -274.549585) (xy 41.421804 -274.598162) (xy 41.40622 -274.644843)
			(xy 41.383349 -274.68842) (xy 41.353784 -274.727764) (xy 41.318291 -274.761856) (xy 41.277788 -274.789812)
			(xy 41.233326 -274.81091) (xy 41.186055 -274.824602) (xy 41.1372 -274.830534) (xy 41.088025 -274.828553)
			(xy 41.039806 -274.818709) (xy 40.99379 -274.801257) (xy 40.951169 -274.77665) (xy 40.913048 -274.745525)
			(xy 40.880413 -274.708688) (xy 40.85411 -274.667092) (xy 40.834819 -274.621816) (xy 40.823042 -274.574032)
			(xy 40.819082 -274.524978) (xy 40.480234 -274.524978) (xy 40.479739 -274.549585) (xy 40.471844 -274.598162)
			(xy 40.45626 -274.644843) (xy 40.433389 -274.68842) (xy 40.403824 -274.727764) (xy 40.368331 -274.761856)
			(xy 40.327828 -274.789812) (xy 40.283366 -274.81091) (xy 40.236095 -274.824602) (xy 40.18724 -274.830534)
			(xy 40.138065 -274.828553) (xy 40.089846 -274.818709) (xy 40.04383 -274.801257) (xy 40.001209 -274.77665)
			(xy 39.963088 -274.745525) (xy 39.930453 -274.708688) (xy 39.90415 -274.667092) (xy 39.884859 -274.621816)
			(xy 39.873082 -274.574032) (xy 39.869122 -274.524978) (xy 39.530274 -274.524978) (xy 39.529779 -274.549585)
			(xy 39.521884 -274.598162) (xy 39.5063 -274.644843) (xy 39.483429 -274.68842) (xy 39.453864 -274.727764)
			(xy 39.418371 -274.761856) (xy 39.377868 -274.789812) (xy 39.333406 -274.81091) (xy 39.286135 -274.824602)
			(xy 39.23728 -274.830534) (xy 39.188105 -274.828553) (xy 39.139886 -274.818709) (xy 39.09387 -274.801257)
			(xy 39.051249 -274.77665) (xy 39.013128 -274.745525) (xy 38.980493 -274.708688) (xy 38.95419 -274.667092)
			(xy 38.934899 -274.621816) (xy 38.923122 -274.574032) (xy 38.919162 -274.524978) (xy 38.606298 -274.524978)
			(xy 38.606299 -274.524985) (xy 38.602443 -274.575402) (xy 38.590959 -274.624645) (xy 38.572115 -274.671567)
			(xy 38.54635 -274.715075) (xy 38.514264 -274.754155) (xy 38.495732 -274.771358) (xy 38.487858 -274.77847)
			(xy 38.477698 -274.800568) (xy 38.47592 -274.816316) (xy 38.477698 -274.824698) (xy 38.480877 -274.840831)
			(xy 38.484316 -274.873535) (xy 38.484556 -274.889976) (xy 38.484556 -275.10994) (xy 38.484327 -275.126382)
			(xy 38.480892 -275.159087) (xy 38.477698 -275.175218) (xy 38.47592 -275.1836) (xy 38.477698 -275.199348)
			(xy 38.487858 -275.221446) (xy 38.495732 -275.228558) (xy 38.514239 -275.245784) (xy 38.546319 -275.28486)
			(xy 38.572079 -275.328363) (xy 38.590919 -275.375279) (xy 38.6024 -275.424515) (xy 38.606254 -275.474925)
			(xy 38.606253 -275.474938) (xy 38.919162 -275.474938) (xy 38.923122 -275.425884) (xy 38.934899 -275.3781)
			(xy 38.95419 -275.332824) (xy 38.980493 -275.291228) (xy 39.013128 -275.254391) (xy 39.051249 -275.223266)
			(xy 39.09387 -275.198659) (xy 39.139886 -275.181207) (xy 39.188105 -275.171363) (xy 39.23728 -275.169382)
			(xy 39.286135 -275.175314) (xy 39.333406 -275.189006) (xy 39.377868 -275.210104) (xy 39.418371 -275.23806)
			(xy 39.453864 -275.272152) (xy 39.483429 -275.311496) (xy 39.5063 -275.355073) (xy 39.521884 -275.401754)
			(xy 39.529779 -275.450331) (xy 39.530274 -275.474938) (xy 39.869122 -275.474938) (xy 39.873082 -275.425884)
			(xy 39.884859 -275.3781) (xy 39.90415 -275.332824) (xy 39.930453 -275.291228) (xy 39.963088 -275.254391)
			(xy 40.001209 -275.223266) (xy 40.04383 -275.198659) (xy 40.089846 -275.181207) (xy 40.138065 -275.171363)
			(xy 40.18724 -275.169382) (xy 40.236095 -275.175314) (xy 40.283366 -275.189006) (xy 40.327828 -275.210104)
			(xy 40.368331 -275.23806) (xy 40.403824 -275.272152) (xy 40.433389 -275.311496) (xy 40.45626 -275.355073)
			(xy 40.471844 -275.401754) (xy 40.479739 -275.450331) (xy 40.480234 -275.474938) (xy 40.819082 -275.474938)
			(xy 40.823042 -275.425884) (xy 40.834819 -275.3781) (xy 40.85411 -275.332824) (xy 40.880413 -275.291228)
			(xy 40.913048 -275.254391) (xy 40.951169 -275.223266) (xy 40.99379 -275.198659) (xy 41.039806 -275.181207)
			(xy 41.088025 -275.171363) (xy 41.1372 -275.169382) (xy 41.186055 -275.175314) (xy 41.233326 -275.189006)
			(xy 41.277788 -275.210104) (xy 41.318291 -275.23806) (xy 41.353784 -275.272152) (xy 41.383349 -275.311496)
			(xy 41.40622 -275.355073) (xy 41.421804 -275.401754) (xy 41.429699 -275.450331) (xy 41.430194 -275.474938)
			(xy 41.429699 -275.499545) (xy 41.421804 -275.548122) (xy 41.40622 -275.594803) (xy 41.383349 -275.63838)
			(xy 41.353784 -275.677724) (xy 41.318291 -275.711816) (xy 41.277788 -275.739772) (xy 41.233326 -275.76087)
			(xy 41.186055 -275.774562) (xy 41.1372 -275.780494) (xy 41.088025 -275.778513) (xy 41.039806 -275.768669)
			(xy 40.99379 -275.751217) (xy 40.951169 -275.72661) (xy 40.913048 -275.695485) (xy 40.880413 -275.658648)
			(xy 40.85411 -275.617052) (xy 40.834819 -275.571776) (xy 40.823042 -275.523992) (xy 40.819082 -275.474938)
			(xy 40.480234 -275.474938) (xy 40.479739 -275.499545) (xy 40.471844 -275.548122) (xy 40.45626 -275.594803)
			(xy 40.433389 -275.63838) (xy 40.403824 -275.677724) (xy 40.368331 -275.711816) (xy 40.327828 -275.739772)
			(xy 40.283366 -275.76087) (xy 40.236095 -275.774562) (xy 40.18724 -275.780494) (xy 40.138065 -275.778513)
			(xy 40.089846 -275.768669) (xy 40.04383 -275.751217) (xy 40.001209 -275.72661) (xy 39.963088 -275.695485)
			(xy 39.930453 -275.658648) (xy 39.90415 -275.617052) (xy 39.884859 -275.571776) (xy 39.873082 -275.523992)
			(xy 39.869122 -275.474938) (xy 39.530274 -275.474938) (xy 39.529779 -275.499545) (xy 39.521884 -275.548122)
			(xy 39.5063 -275.594803) (xy 39.483429 -275.63838) (xy 39.453864 -275.677724) (xy 39.418371 -275.711816)
			(xy 39.377868 -275.739772) (xy 39.333406 -275.76087) (xy 39.286135 -275.774562) (xy 39.23728 -275.780494)
			(xy 39.188105 -275.778513) (xy 39.139886 -275.768669) (xy 39.09387 -275.751217) (xy 39.051249 -275.72661)
			(xy 39.013128 -275.695485) (xy 38.980493 -275.658648) (xy 38.95419 -275.617052) (xy 38.934899 -275.571776)
			(xy 38.923122 -275.523992) (xy 38.919162 -275.474938) (xy 38.606253 -275.474938) (xy 38.602392 -275.525335)
			(xy 38.590903 -275.57457) (xy 38.572056 -275.621483) (xy 38.54629 -275.664982) (xy 38.514203 -275.704052)
			(xy 38.495732 -275.721318) (xy 38.487858 -275.72843) (xy 38.477698 -275.750528) (xy 38.47592 -275.766276)
			(xy 38.477698 -275.774658) (xy 38.480874 -275.790791) (xy 38.484306 -275.823495) (xy 38.484556 -275.839936)
			(xy 38.484556 -276.0599) (xy 38.484329 -276.076342) (xy 38.480898 -276.109048) (xy 38.477698 -276.125178)
			(xy 38.47592 -276.13356) (xy 38.477698 -276.149308) (xy 38.487858 -276.171406) (xy 38.495732 -276.178518)
			(xy 38.514242 -276.195744) (xy 38.546328 -276.234821) (xy 38.572094 -276.278325) (xy 38.590939 -276.325244)
			(xy 38.602425 -276.374484) (xy 38.606284 -276.424898) (xy 38.919162 -276.424898) (xy 38.923122 -276.375844)
			(xy 38.934899 -276.32806) (xy 38.95419 -276.282784) (xy 38.980493 -276.241188) (xy 39.013128 -276.204351)
			(xy 39.051249 -276.173226) (xy 39.09387 -276.148619) (xy 39.139886 -276.131167) (xy 39.188105 -276.121323)
			(xy 39.23728 -276.119342) (xy 39.286135 -276.125274) (xy 39.333406 -276.138966) (xy 39.377868 -276.160064)
			(xy 39.418371 -276.18802) (xy 39.453864 -276.222112) (xy 39.483429 -276.261456) (xy 39.5063 -276.305033)
			(xy 39.521884 -276.351714) (xy 39.529779 -276.400291) (xy 39.530274 -276.424898) (xy 39.869122 -276.424898)
			(xy 39.873082 -276.375844) (xy 39.884859 -276.32806) (xy 39.90415 -276.282784) (xy 39.930453 -276.241188)
			(xy 39.963088 -276.204351) (xy 40.001209 -276.173226) (xy 40.04383 -276.148619) (xy 40.089846 -276.131167)
			(xy 40.138065 -276.121323) (xy 40.18724 -276.119342) (xy 40.236095 -276.125274) (xy 40.283366 -276.138966)
			(xy 40.327828 -276.160064) (xy 40.368331 -276.18802) (xy 40.403824 -276.222112) (xy 40.433389 -276.261456)
			(xy 40.45626 -276.305033) (xy 40.471844 -276.351714) (xy 40.479739 -276.400291) (xy 40.480234 -276.424898)
			(xy 40.819082 -276.424898) (xy 40.823042 -276.375844) (xy 40.834819 -276.32806) (xy 40.85411 -276.282784)
			(xy 40.880413 -276.241188) (xy 40.913048 -276.204351) (xy 40.951169 -276.173226) (xy 40.99379 -276.148619)
			(xy 41.039806 -276.131167) (xy 41.088025 -276.121323) (xy 41.1372 -276.119342) (xy 41.186055 -276.125274)
			(xy 41.233326 -276.138966) (xy 41.277788 -276.160064) (xy 41.318291 -276.18802) (xy 41.353784 -276.222112)
			(xy 41.383349 -276.261456) (xy 41.40622 -276.305033) (xy 41.421804 -276.351714) (xy 41.429699 -276.400291)
			(xy 41.430194 -276.424898) (xy 41.429699 -276.449505) (xy 41.421804 -276.498082) (xy 41.40622 -276.544763)
			(xy 41.383349 -276.58834) (xy 41.353784 -276.627684) (xy 41.318291 -276.661776) (xy 41.277788 -276.689732)
			(xy 41.233326 -276.71083) (xy 41.186055 -276.724522) (xy 41.1372 -276.730454) (xy 41.088025 -276.728473)
			(xy 41.039806 -276.718629) (xy 40.99379 -276.701177) (xy 40.951169 -276.67657) (xy 40.913048 -276.645445)
			(xy 40.880413 -276.608608) (xy 40.85411 -276.567012) (xy 40.834819 -276.521736) (xy 40.823042 -276.473952)
			(xy 40.819082 -276.424898) (xy 40.480234 -276.424898) (xy 40.479739 -276.449505) (xy 40.471844 -276.498082)
			(xy 40.45626 -276.544763) (xy 40.433389 -276.58834) (xy 40.403824 -276.627684) (xy 40.368331 -276.661776)
			(xy 40.327828 -276.689732) (xy 40.283366 -276.71083) (xy 40.236095 -276.724522) (xy 40.18724 -276.730454)
			(xy 40.138065 -276.728473) (xy 40.089846 -276.718629) (xy 40.04383 -276.701177) (xy 40.001209 -276.67657)
			(xy 39.963088 -276.645445) (xy 39.930453 -276.608608) (xy 39.90415 -276.567012) (xy 39.884859 -276.521736)
			(xy 39.873082 -276.473952) (xy 39.869122 -276.424898) (xy 39.530274 -276.424898) (xy 39.529779 -276.449505)
			(xy 39.521884 -276.498082) (xy 39.5063 -276.544763) (xy 39.483429 -276.58834) (xy 39.453864 -276.627684)
			(xy 39.418371 -276.661776) (xy 39.377868 -276.689732) (xy 39.333406 -276.71083) (xy 39.286135 -276.724522)
			(xy 39.23728 -276.730454) (xy 39.188105 -276.728473) (xy 39.139886 -276.718629) (xy 39.09387 -276.701177)
			(xy 39.051249 -276.67657) (xy 39.013128 -276.645445) (xy 38.980493 -276.608608) (xy 38.95419 -276.567012)
			(xy 38.934899 -276.521736) (xy 38.923122 -276.473952) (xy 38.919162 -276.424898) (xy 38.606284 -276.424898)
			(xy 38.606284 -276.424899) (xy 38.602425 -276.475313) (xy 38.59094 -276.524553) (xy 38.572095 -276.571472)
			(xy 38.546329 -276.614977) (xy 38.514243 -276.654054) (xy 38.495732 -276.671278) (xy 38.487858 -276.67839)
			(xy 38.477698 -276.700488) (xy 38.47592 -276.716236) (xy 38.477698 -276.724618) (xy 38.480876 -276.740751)
			(xy 38.484313 -276.773455) (xy 38.484556 -276.789896) (xy 38.484556 -277.00986) (xy 38.484326 -277.026302)
			(xy 38.480889 -277.059007) (xy 38.477698 -277.075138) (xy 38.47592 -277.08352) (xy 38.477698 -277.099268)
			(xy 38.487858 -277.121366) (xy 38.495732 -277.128478) (xy 38.514245 -277.145704) (xy 38.546337 -277.184782)
			(xy 38.572109 -277.228288) (xy 38.59096 -277.275209) (xy 38.602451 -277.324453) (xy 38.606313 -277.374858)
			(xy 38.919162 -277.374858) (xy 38.923122 -277.325804) (xy 38.934899 -277.27802) (xy 38.95419 -277.232744)
			(xy 38.980493 -277.191148) (xy 39.013128 -277.154311) (xy 39.051249 -277.123186) (xy 39.09387 -277.098579)
			(xy 39.139886 -277.081127) (xy 39.188105 -277.071283) (xy 39.23728 -277.069302) (xy 39.286135 -277.075234)
			(xy 39.333406 -277.088926) (xy 39.377868 -277.110024) (xy 39.418371 -277.13798) (xy 39.453864 -277.172072)
			(xy 39.483429 -277.211416) (xy 39.5063 -277.254993) (xy 39.521884 -277.301674) (xy 39.529779 -277.350251)
			(xy 39.530274 -277.374858) (xy 39.869122 -277.374858) (xy 39.873082 -277.325804) (xy 39.884859 -277.27802)
			(xy 39.90415 -277.232744) (xy 39.930453 -277.191148) (xy 39.963088 -277.154311) (xy 40.001209 -277.123186)
			(xy 40.04383 -277.098579) (xy 40.089846 -277.081127) (xy 40.138065 -277.071283) (xy 40.18724 -277.069302)
			(xy 40.236095 -277.075234) (xy 40.283366 -277.088926) (xy 40.327828 -277.110024) (xy 40.368331 -277.13798)
			(xy 40.403824 -277.172072) (xy 40.433389 -277.211416) (xy 40.45626 -277.254993) (xy 40.471844 -277.301674)
			(xy 40.479739 -277.350251) (xy 40.480234 -277.374858) (xy 40.819082 -277.374858) (xy 40.823042 -277.325804)
			(xy 40.834819 -277.27802) (xy 40.85411 -277.232744) (xy 40.880413 -277.191148) (xy 40.913048 -277.154311)
			(xy 40.951169 -277.123186) (xy 40.99379 -277.098579) (xy 41.039806 -277.081127) (xy 41.088025 -277.071283)
			(xy 41.1372 -277.069302) (xy 41.186055 -277.075234) (xy 41.233326 -277.088926) (xy 41.277788 -277.110024)
			(xy 41.318291 -277.13798) (xy 41.353784 -277.172072) (xy 41.383349 -277.211416) (xy 41.40622 -277.254993)
			(xy 41.421804 -277.301674) (xy 41.429699 -277.350251) (xy 41.430194 -277.374858) (xy 41.429699 -277.399465)
			(xy 41.421804 -277.448042) (xy 41.40622 -277.494723) (xy 41.383349 -277.5383) (xy 41.353784 -277.577644)
			(xy 41.318291 -277.611736) (xy 41.277788 -277.639692) (xy 41.233326 -277.66079) (xy 41.186055 -277.674482)
			(xy 41.1372 -277.680414) (xy 41.088025 -277.678433) (xy 41.039806 -277.668589) (xy 40.99379 -277.651137)
			(xy 40.951169 -277.62653) (xy 40.913048 -277.595405) (xy 40.880413 -277.558568) (xy 40.85411 -277.516972)
			(xy 40.834819 -277.471696) (xy 40.823042 -277.423912) (xy 40.819082 -277.374858) (xy 40.480234 -277.374858)
			(xy 40.479739 -277.399465) (xy 40.471844 -277.448042) (xy 40.45626 -277.494723) (xy 40.433389 -277.5383)
			(xy 40.403824 -277.577644) (xy 40.368331 -277.611736) (xy 40.327828 -277.639692) (xy 40.283366 -277.66079)
			(xy 40.236095 -277.674482) (xy 40.18724 -277.680414) (xy 40.138065 -277.678433) (xy 40.089846 -277.668589)
			(xy 40.04383 -277.651137) (xy 40.001209 -277.62653) (xy 39.963088 -277.595405) (xy 39.930453 -277.558568)
			(xy 39.90415 -277.516972) (xy 39.884859 -277.471696) (xy 39.873082 -277.423912) (xy 39.869122 -277.374858)
			(xy 39.530274 -277.374858) (xy 39.529779 -277.399465) (xy 39.521884 -277.448042) (xy 39.5063 -277.494723)
			(xy 39.483429 -277.5383) (xy 39.453864 -277.577644) (xy 39.418371 -277.611736) (xy 39.377868 -277.639692)
			(xy 39.333406 -277.66079) (xy 39.286135 -277.674482) (xy 39.23728 -277.680414) (xy 39.188105 -277.678433)
			(xy 39.139886 -277.668589) (xy 39.09387 -277.651137) (xy 39.051249 -277.62653) (xy 39.013128 -277.595405)
			(xy 38.980493 -277.558568) (xy 38.95419 -277.516972) (xy 38.934899 -277.471696) (xy 38.923122 -277.423912)
			(xy 38.919162 -277.374858) (xy 38.606313 -277.374858) (xy 38.606314 -277.374872) (xy 38.602459 -277.425291)
			(xy 38.590977 -277.474537) (xy 38.572134 -277.521462) (xy 38.54637 -277.564972) (xy 38.514284 -277.604055)
			(xy 38.495732 -277.621238) (xy 38.487858 -277.62835) (xy 38.477698 -277.650448) (xy 38.47592 -277.666196)
			(xy 38.477698 -277.674578) (xy 38.480878 -277.690711) (xy 38.484319 -277.723414) (xy 38.484556 -277.739856)
			(xy 38.484556 -277.95982) (xy 38.484328 -277.976262) (xy 38.480895 -278.008968) (xy 38.477698 -278.025098)
			(xy 38.47592 -278.03348) (xy 38.477698 -278.049228) (xy 38.487858 -278.071326) (xy 38.495732 -278.078438)
			(xy 38.51424 -278.095664) (xy 38.546323 -278.134741) (xy 38.572086 -278.178244) (xy 38.590929 -278.225161)
			(xy 38.602412 -278.2744) (xy 38.606269 -278.324812) (xy 38.606269 -278.324818) (xy 38.919162 -278.324818)
			(xy 38.923122 -278.275764) (xy 38.934899 -278.22798) (xy 38.95419 -278.182704) (xy 38.980493 -278.141108)
			(xy 39.013128 -278.104271) (xy 39.051249 -278.073146) (xy 39.09387 -278.048539) (xy 39.139886 -278.031087)
			(xy 39.188105 -278.021243) (xy 39.23728 -278.019262) (xy 39.286135 -278.025194) (xy 39.333406 -278.038886)
			(xy 39.377868 -278.059984) (xy 39.418371 -278.08794) (xy 39.453864 -278.122032) (xy 39.483429 -278.161376)
			(xy 39.5063 -278.204953) (xy 39.521884 -278.251634) (xy 39.529779 -278.300211) (xy 39.530274 -278.324818)
			(xy 39.869122 -278.324818) (xy 39.873082 -278.275764) (xy 39.884859 -278.22798) (xy 39.90415 -278.182704)
			(xy 39.930453 -278.141108) (xy 39.963088 -278.104271) (xy 40.001209 -278.073146) (xy 40.04383 -278.048539)
			(xy 40.089846 -278.031087) (xy 40.138065 -278.021243) (xy 40.18724 -278.019262) (xy 40.236095 -278.025194)
			(xy 40.283366 -278.038886) (xy 40.327828 -278.059984) (xy 40.368331 -278.08794) (xy 40.403824 -278.122032)
			(xy 40.433389 -278.161376) (xy 40.45626 -278.204953) (xy 40.471844 -278.251634) (xy 40.479739 -278.300211)
			(xy 40.480234 -278.324818) (xy 40.819082 -278.324818) (xy 40.823042 -278.275764) (xy 40.834819 -278.22798)
			(xy 40.85411 -278.182704) (xy 40.880413 -278.141108) (xy 40.913048 -278.104271) (xy 40.951169 -278.073146)
			(xy 40.99379 -278.048539) (xy 41.039806 -278.031087) (xy 41.088025 -278.021243) (xy 41.1372 -278.019262)
			(xy 41.186055 -278.025194) (xy 41.233326 -278.038886) (xy 41.277788 -278.059984) (xy 41.318291 -278.08794)
			(xy 41.353784 -278.122032) (xy 41.383349 -278.161376) (xy 41.40622 -278.204953) (xy 41.421804 -278.251634)
			(xy 41.429699 -278.300211) (xy 41.430194 -278.324818) (xy 41.429699 -278.349425) (xy 41.421804 -278.398002)
			(xy 41.40622 -278.444683) (xy 41.383349 -278.48826) (xy 41.353784 -278.527604) (xy 41.318291 -278.561696)
			(xy 41.277788 -278.589652) (xy 41.233326 -278.61075) (xy 41.186055 -278.624442) (xy 41.1372 -278.630374)
			(xy 41.088025 -278.628393) (xy 41.039806 -278.618549) (xy 40.99379 -278.601097) (xy 40.951169 -278.57649)
			(xy 40.913048 -278.545365) (xy 40.880413 -278.508528) (xy 40.85411 -278.466932) (xy 40.834819 -278.421656)
			(xy 40.823042 -278.373872) (xy 40.819082 -278.324818) (xy 40.480234 -278.324818) (xy 40.479739 -278.349425)
			(xy 40.471844 -278.398002) (xy 40.45626 -278.444683) (xy 40.433389 -278.48826) (xy 40.403824 -278.527604)
			(xy 40.368331 -278.561696) (xy 40.327828 -278.589652) (xy 40.283366 -278.61075) (xy 40.236095 -278.624442)
			(xy 40.18724 -278.630374) (xy 40.138065 -278.628393) (xy 40.089846 -278.618549) (xy 40.04383 -278.601097)
			(xy 40.001209 -278.57649) (xy 39.963088 -278.545365) (xy 39.930453 -278.508528) (xy 39.90415 -278.466932)
			(xy 39.884859 -278.421656) (xy 39.873082 -278.373872) (xy 39.869122 -278.324818) (xy 39.530274 -278.324818)
			(xy 39.529779 -278.349425) (xy 39.521884 -278.398002) (xy 39.5063 -278.444683) (xy 39.483429 -278.48826)
			(xy 39.453864 -278.527604) (xy 39.418371 -278.561696) (xy 39.377868 -278.589652) (xy 39.333406 -278.61075)
			(xy 39.286135 -278.624442) (xy 39.23728 -278.630374) (xy 39.188105 -278.628393) (xy 39.139886 -278.618549)
			(xy 39.09387 -278.601097) (xy 39.051249 -278.57649) (xy 39.013128 -278.545365) (xy 38.980493 -278.508528)
			(xy 38.95419 -278.466932) (xy 38.934899 -278.421656) (xy 38.923122 -278.373872) (xy 38.919162 -278.324818)
			(xy 38.606269 -278.324818) (xy 38.602409 -278.375224) (xy 38.590922 -278.424462) (xy 38.572076 -278.471378)
			(xy 38.54631 -278.514879) (xy 38.514223 -278.553953) (xy 38.495732 -278.571198) (xy 38.487858 -278.57831)
			(xy 38.477698 -278.600408) (xy 38.47592 -278.616156) (xy 38.477698 -278.624538) (xy 38.480875 -278.640671)
			(xy 38.48431 -278.673375) (xy 38.484556 -278.689816) (xy 38.484556 -278.90978) (xy 38.484325 -278.926222)
			(xy 38.480886 -278.958926) (xy 38.477698 -278.975058) (xy 38.47592 -278.98344) (xy 38.477698 -278.999188)
			(xy 38.487858 -279.021286) (xy 38.495732 -279.028398) (xy 38.514243 -279.045624) (xy 38.546333 -279.084701)
			(xy 38.572102 -279.128207) (xy 38.59095 -279.175127) (xy 38.602438 -279.224369) (xy 38.606298 -279.274778)
			(xy 38.919162 -279.274778) (xy 38.923122 -279.225724) (xy 38.934899 -279.17794) (xy 38.95419 -279.132664)
			(xy 38.980493 -279.091068) (xy 39.013128 -279.054231) (xy 39.051249 -279.023106) (xy 39.09387 -278.998499)
			(xy 39.139886 -278.981047) (xy 39.188105 -278.971203) (xy 39.23728 -278.969222) (xy 39.286135 -278.975154)
			(xy 39.333406 -278.988846) (xy 39.377868 -279.009944) (xy 39.418371 -279.0379) (xy 39.453864 -279.071992)
			(xy 39.483429 -279.111336) (xy 39.5063 -279.154913) (xy 39.521884 -279.201594) (xy 39.529779 -279.250171)
			(xy 39.530274 -279.274778) (xy 39.869122 -279.274778) (xy 39.873082 -279.225724) (xy 39.884859 -279.17794)
			(xy 39.90415 -279.132664) (xy 39.930453 -279.091068) (xy 39.963088 -279.054231) (xy 40.001209 -279.023106)
			(xy 40.04383 -278.998499) (xy 40.089846 -278.981047) (xy 40.138065 -278.971203) (xy 40.18724 -278.969222)
			(xy 40.236095 -278.975154) (xy 40.283366 -278.988846) (xy 40.327828 -279.009944) (xy 40.368331 -279.0379)
			(xy 40.403824 -279.071992) (xy 40.433389 -279.111336) (xy 40.45626 -279.154913) (xy 40.471844 -279.201594)
			(xy 40.479739 -279.250171) (xy 40.480234 -279.274778) (xy 40.819082 -279.274778) (xy 40.823042 -279.225724)
			(xy 40.834819 -279.17794) (xy 40.85411 -279.132664) (xy 40.880413 -279.091068) (xy 40.913048 -279.054231)
			(xy 40.951169 -279.023106) (xy 40.99379 -278.998499) (xy 41.039806 -278.981047) (xy 41.088025 -278.971203)
			(xy 41.1372 -278.969222) (xy 41.186055 -278.975154) (xy 41.233326 -278.988846) (xy 41.277788 -279.009944)
			(xy 41.318291 -279.0379) (xy 41.353784 -279.071992) (xy 41.383349 -279.111336) (xy 41.40622 -279.154913)
			(xy 41.421804 -279.201594) (xy 41.429699 -279.250171) (xy 41.430194 -279.274778) (xy 41.429699 -279.299385)
			(xy 41.421804 -279.347962) (xy 41.40622 -279.394643) (xy 41.383349 -279.43822) (xy 41.353784 -279.477564)
			(xy 41.318291 -279.511656) (xy 41.277788 -279.539612) (xy 41.233326 -279.56071) (xy 41.186055 -279.574402)
			(xy 41.1372 -279.580334) (xy 41.088025 -279.578353) (xy 41.039806 -279.568509) (xy 40.99379 -279.551057)
			(xy 40.951169 -279.52645) (xy 40.913048 -279.495325) (xy 40.880413 -279.458488) (xy 40.85411 -279.416892)
			(xy 40.834819 -279.371616) (xy 40.823042 -279.323832) (xy 40.819082 -279.274778) (xy 40.480234 -279.274778)
			(xy 40.479739 -279.299385) (xy 40.471844 -279.347962) (xy 40.45626 -279.394643) (xy 40.433389 -279.43822)
			(xy 40.403824 -279.477564) (xy 40.368331 -279.511656) (xy 40.327828 -279.539612) (xy 40.283366 -279.56071)
			(xy 40.236095 -279.574402) (xy 40.18724 -279.580334) (xy 40.138065 -279.578353) (xy 40.089846 -279.568509)
			(xy 40.04383 -279.551057) (xy 40.001209 -279.52645) (xy 39.963088 -279.495325) (xy 39.930453 -279.458488)
			(xy 39.90415 -279.416892) (xy 39.884859 -279.371616) (xy 39.873082 -279.323832) (xy 39.869122 -279.274778)
			(xy 39.530274 -279.274778) (xy 39.529779 -279.299385) (xy 39.521884 -279.347962) (xy 39.5063 -279.394643)
			(xy 39.483429 -279.43822) (xy 39.453864 -279.477564) (xy 39.418371 -279.511656) (xy 39.377868 -279.539612)
			(xy 39.333406 -279.56071) (xy 39.286135 -279.574402) (xy 39.23728 -279.580334) (xy 39.188105 -279.578353)
			(xy 39.139886 -279.568509) (xy 39.09387 -279.551057) (xy 39.051249 -279.52645) (xy 39.013128 -279.495325)
			(xy 38.980493 -279.458488) (xy 38.95419 -279.416892) (xy 38.934899 -279.371616) (xy 38.923122 -279.323832)
			(xy 38.919162 -279.274778) (xy 38.606298 -279.274778) (xy 38.606299 -279.274785) (xy 38.602443 -279.325202)
			(xy 38.590959 -279.374445) (xy 38.572115 -279.421367) (xy 38.54635 -279.464875) (xy 38.514264 -279.503955)
			(xy 38.495732 -279.521158) (xy 38.487858 -279.52827) (xy 38.477698 -279.550368) (xy 38.47592 -279.566116)
			(xy 38.477698 -279.574498) (xy 38.480877 -279.590631) (xy 38.484316 -279.623335) (xy 38.484556 -279.639776)
			(xy 38.484556 -279.85974) (xy 38.484327 -279.876182) (xy 38.480892 -279.908887) (xy 38.477698 -279.925018)
			(xy 38.47592 -279.9334) (xy 38.477698 -279.949148) (xy 38.487858 -279.971246) (xy 38.495732 -279.978358)
			(xy 38.514239 -279.995584) (xy 38.546319 -280.03466) (xy 38.572079 -280.078163) (xy 38.590919 -280.125079)
			(xy 38.6024 -280.174315) (xy 38.606254 -280.224725) (xy 38.606253 -280.224738) (xy 38.919162 -280.224738)
			(xy 38.923122 -280.175684) (xy 38.934899 -280.1279) (xy 38.95419 -280.082624) (xy 38.980493 -280.041028)
			(xy 39.013128 -280.004191) (xy 39.051249 -279.973066) (xy 39.09387 -279.948459) (xy 39.139886 -279.931007)
			(xy 39.188105 -279.921163) (xy 39.23728 -279.919182) (xy 39.286135 -279.925114) (xy 39.333406 -279.938806)
			(xy 39.377868 -279.959904) (xy 39.418371 -279.98786) (xy 39.453864 -280.021952) (xy 39.483429 -280.061296)
			(xy 39.5063 -280.104873) (xy 39.521884 -280.151554) (xy 39.529779 -280.200131) (xy 39.530274 -280.224738)
			(xy 39.869122 -280.224738) (xy 39.873082 -280.175684) (xy 39.884859 -280.1279) (xy 39.90415 -280.082624)
			(xy 39.930453 -280.041028) (xy 39.963088 -280.004191) (xy 40.001209 -279.973066) (xy 40.04383 -279.948459)
			(xy 40.089846 -279.931007) (xy 40.138065 -279.921163) (xy 40.18724 -279.919182) (xy 40.236095 -279.925114)
			(xy 40.283366 -279.938806) (xy 40.327828 -279.959904) (xy 40.368331 -279.98786) (xy 40.403824 -280.021952)
			(xy 40.433389 -280.061296) (xy 40.45626 -280.104873) (xy 40.471844 -280.151554) (xy 40.479739 -280.200131)
			(xy 40.480234 -280.224738) (xy 40.819082 -280.224738) (xy 40.823042 -280.175684) (xy 40.834819 -280.1279)
			(xy 40.85411 -280.082624) (xy 40.880413 -280.041028) (xy 40.913048 -280.004191) (xy 40.951169 -279.973066)
			(xy 40.99379 -279.948459) (xy 41.039806 -279.931007) (xy 41.088025 -279.921163) (xy 41.1372 -279.919182)
			(xy 41.186055 -279.925114) (xy 41.233326 -279.938806) (xy 41.277788 -279.959904) (xy 41.318291 -279.98786)
			(xy 41.353784 -280.021952) (xy 41.383349 -280.061296) (xy 41.40622 -280.104873) (xy 41.421804 -280.151554)
			(xy 41.429699 -280.200131) (xy 41.430194 -280.224738) (xy 41.429699 -280.249345) (xy 41.421804 -280.297922)
			(xy 41.40622 -280.344603) (xy 41.383349 -280.38818) (xy 41.353784 -280.427524) (xy 41.318291 -280.461616)
			(xy 41.277788 -280.489572) (xy 41.233326 -280.51067) (xy 41.186055 -280.524362) (xy 41.1372 -280.530294)
			(xy 41.088025 -280.528313) (xy 41.039806 -280.518469) (xy 40.99379 -280.501017) (xy 40.951169 -280.47641)
			(xy 40.913048 -280.445285) (xy 40.880413 -280.408448) (xy 40.85411 -280.366852) (xy 40.834819 -280.321576)
			(xy 40.823042 -280.273792) (xy 40.819082 -280.224738) (xy 40.480234 -280.224738) (xy 40.479739 -280.249345)
			(xy 40.471844 -280.297922) (xy 40.45626 -280.344603) (xy 40.433389 -280.38818) (xy 40.403824 -280.427524)
			(xy 40.368331 -280.461616) (xy 40.327828 -280.489572) (xy 40.283366 -280.51067) (xy 40.236095 -280.524362)
			(xy 40.18724 -280.530294) (xy 40.138065 -280.528313) (xy 40.089846 -280.518469) (xy 40.04383 -280.501017)
			(xy 40.001209 -280.47641) (xy 39.963088 -280.445285) (xy 39.930453 -280.408448) (xy 39.90415 -280.366852)
			(xy 39.884859 -280.321576) (xy 39.873082 -280.273792) (xy 39.869122 -280.224738) (xy 39.530274 -280.224738)
			(xy 39.529779 -280.249345) (xy 39.521884 -280.297922) (xy 39.5063 -280.344603) (xy 39.483429 -280.38818)
			(xy 39.453864 -280.427524) (xy 39.418371 -280.461616) (xy 39.377868 -280.489572) (xy 39.333406 -280.51067)
			(xy 39.286135 -280.524362) (xy 39.23728 -280.530294) (xy 39.188105 -280.528313) (xy 39.139886 -280.518469)
			(xy 39.09387 -280.501017) (xy 39.051249 -280.47641) (xy 39.013128 -280.445285) (xy 38.980493 -280.408448)
			(xy 38.95419 -280.366852) (xy 38.934899 -280.321576) (xy 38.923122 -280.273792) (xy 38.919162 -280.224738)
			(xy 38.606253 -280.224738) (xy 38.602392 -280.275135) (xy 38.590903 -280.32437) (xy 38.572056 -280.371283)
			(xy 38.54629 -280.414782) (xy 38.514203 -280.453852) (xy 38.495732 -280.471118) (xy 38.487858 -280.47823)
			(xy 38.477698 -280.500328) (xy 38.47592 -280.516076) (xy 38.477698 -280.524458) (xy 38.480874 -280.540591)
			(xy 38.484306 -280.573295) (xy 38.484556 -280.589736) (xy 38.484556 -280.809954) (xy 38.484326 -280.826396)
			(xy 38.48089 -280.859101) (xy 38.477698 -280.875232) (xy 38.47592 -280.883614) (xy 38.477698 -280.899362)
			(xy 38.487858 -280.92146) (xy 38.495732 -280.928572) (xy 38.514245 -280.945798) (xy 38.546339 -280.984876)
			(xy 38.572111 -281.028382) (xy 38.590963 -281.075304) (xy 38.602455 -281.124549) (xy 38.606317 -281.174952)
			(xy 38.919162 -281.174952) (xy 38.923122 -281.125898) (xy 38.934899 -281.078114) (xy 38.95419 -281.032838)
			(xy 38.980493 -280.991242) (xy 39.013128 -280.954405) (xy 39.051249 -280.92328) (xy 39.09387 -280.898673)
			(xy 39.139886 -280.881221) (xy 39.188105 -280.871377) (xy 39.23728 -280.869396) (xy 39.286135 -280.875328)
			(xy 39.333406 -280.88902) (xy 39.377868 -280.910118) (xy 39.418371 -280.938074) (xy 39.453864 -280.972166)
			(xy 39.483429 -281.01151) (xy 39.5063 -281.055087) (xy 39.521884 -281.101768) (xy 39.529779 -281.150345)
			(xy 39.530274 -281.174952) (xy 39.869122 -281.174952) (xy 39.873082 -281.125898) (xy 39.884859 -281.078114)
			(xy 39.90415 -281.032838) (xy 39.930453 -280.991242) (xy 39.963088 -280.954405) (xy 40.001209 -280.92328)
			(xy 40.04383 -280.898673) (xy 40.089846 -280.881221) (xy 40.138065 -280.871377) (xy 40.18724 -280.869396)
			(xy 40.236095 -280.875328) (xy 40.283366 -280.88902) (xy 40.327828 -280.910118) (xy 40.368331 -280.938074)
			(xy 40.403824 -280.972166) (xy 40.433389 -281.01151) (xy 40.45626 -281.055087) (xy 40.471844 -281.101768)
			(xy 40.479739 -281.150345) (xy 40.480234 -281.174952) (xy 40.819082 -281.174952) (xy 40.823042 -281.125898)
			(xy 40.834819 -281.078114) (xy 40.85411 -281.032838) (xy 40.880413 -280.991242) (xy 40.913048 -280.954405)
			(xy 40.951169 -280.92328) (xy 40.99379 -280.898673) (xy 41.039806 -280.881221) (xy 41.088025 -280.871377)
			(xy 41.1372 -280.869396) (xy 41.186055 -280.875328) (xy 41.233326 -280.88902) (xy 41.277788 -280.910118)
			(xy 41.318291 -280.938074) (xy 41.353784 -280.972166) (xy 41.383349 -281.01151) (xy 41.40622 -281.055087)
			(xy 41.421804 -281.101768) (xy 41.429699 -281.150345) (xy 41.430194 -281.174952) (xy 41.429699 -281.199559)
			(xy 41.421804 -281.248136) (xy 41.40622 -281.294817) (xy 41.383349 -281.338394) (xy 41.353784 -281.377738)
			(xy 41.318291 -281.41183) (xy 41.277788 -281.439786) (xy 41.233326 -281.460884) (xy 41.186055 -281.474576)
			(xy 41.1372 -281.480508) (xy 41.088025 -281.478527) (xy 41.039806 -281.468683) (xy 40.99379 -281.451231)
			(xy 40.951169 -281.426624) (xy 40.913048 -281.395499) (xy 40.880413 -281.358662) (xy 40.85411 -281.317066)
			(xy 40.834819 -281.27179) (xy 40.823042 -281.224006) (xy 40.819082 -281.174952) (xy 40.480234 -281.174952)
			(xy 40.479739 -281.199559) (xy 40.471844 -281.248136) (xy 40.45626 -281.294817) (xy 40.433389 -281.338394)
			(xy 40.403824 -281.377738) (xy 40.368331 -281.41183) (xy 40.327828 -281.439786) (xy 40.283366 -281.460884)
			(xy 40.236095 -281.474576) (xy 40.18724 -281.480508) (xy 40.138065 -281.478527) (xy 40.089846 -281.468683)
			(xy 40.04383 -281.451231) (xy 40.001209 -281.426624) (xy 39.963088 -281.395499) (xy 39.930453 -281.358662)
			(xy 39.90415 -281.317066) (xy 39.884859 -281.27179) (xy 39.873082 -281.224006) (xy 39.869122 -281.174952)
			(xy 39.530274 -281.174952) (xy 39.529779 -281.199559) (xy 39.521884 -281.248136) (xy 39.5063 -281.294817)
			(xy 39.483429 -281.338394) (xy 39.453864 -281.377738) (xy 39.418371 -281.41183) (xy 39.377868 -281.439786)
			(xy 39.333406 -281.460884) (xy 39.286135 -281.474576) (xy 39.23728 -281.480508) (xy 39.188105 -281.478527)
			(xy 39.139886 -281.468683) (xy 39.09387 -281.451231) (xy 39.051249 -281.426624) (xy 39.013128 -281.395499)
			(xy 38.980493 -281.358662) (xy 38.95419 -281.317066) (xy 38.934899 -281.27179) (xy 38.923122 -281.224006)
			(xy 38.919162 -281.174952) (xy 38.606317 -281.174952) (xy 38.606318 -281.174968) (xy 38.602464 -281.225388)
			(xy 38.590982 -281.274634) (xy 38.57214 -281.32156) (xy 38.546376 -281.365071) (xy 38.51429 -281.404155)
			(xy 38.495732 -281.421332) (xy 38.487858 -281.428444) (xy 38.477698 -281.450542) (xy 38.47592 -281.46629)
			(xy 38.477698 -281.474672) (xy 38.480879 -281.490805) (xy 38.48432 -281.523508) (xy 38.484556 -281.53995)
			(xy 38.484556 -281.759914) (xy 38.484329 -281.776356) (xy 38.480896 -281.809062) (xy 38.477698 -281.825192)
			(xy 38.47592 -281.833574) (xy 38.477698 -281.849322) (xy 38.487858 -281.87142) (xy 38.495732 -281.878532)
			(xy 38.514241 -281.895758) (xy 38.546325 -281.934835) (xy 38.572089 -281.978338) (xy 38.590932 -282.025256)
			(xy 38.602416 -282.074495) (xy 38.606273 -282.124908) (xy 38.606273 -282.124912) (xy 38.919162 -282.124912)
			(xy 38.923122 -282.075858) (xy 38.934899 -282.028074) (xy 38.95419 -281.982798) (xy 38.980493 -281.941202)
			(xy 39.013128 -281.904365) (xy 39.051249 -281.87324) (xy 39.09387 -281.848633) (xy 39.139886 -281.831181)
			(xy 39.188105 -281.821337) (xy 39.23728 -281.819356) (xy 39.286135 -281.825288) (xy 39.333406 -281.83898)
			(xy 39.377868 -281.860078) (xy 39.418371 -281.888034) (xy 39.453864 -281.922126) (xy 39.483429 -281.96147)
			(xy 39.5063 -282.005047) (xy 39.521884 -282.051728) (xy 39.529779 -282.100305) (xy 39.530274 -282.124912)
			(xy 39.869122 -282.124912) (xy 39.873082 -282.075858) (xy 39.884859 -282.028074) (xy 39.90415 -281.982798)
			(xy 39.930453 -281.941202) (xy 39.963088 -281.904365) (xy 40.001209 -281.87324) (xy 40.04383 -281.848633)
			(xy 40.089846 -281.831181) (xy 40.138065 -281.821337) (xy 40.18724 -281.819356) (xy 40.236095 -281.825288)
			(xy 40.283366 -281.83898) (xy 40.327828 -281.860078) (xy 40.368331 -281.888034) (xy 40.403824 -281.922126)
			(xy 40.433389 -281.96147) (xy 40.45626 -282.005047) (xy 40.471844 -282.051728) (xy 40.479739 -282.100305)
			(xy 40.480234 -282.124912) (xy 40.819082 -282.124912) (xy 40.823042 -282.075858) (xy 40.834819 -282.028074)
			(xy 40.85411 -281.982798) (xy 40.880413 -281.941202) (xy 40.913048 -281.904365) (xy 40.951169 -281.87324)
			(xy 40.99379 -281.848633) (xy 41.039806 -281.831181) (xy 41.088025 -281.821337) (xy 41.1372 -281.819356)
			(xy 41.186055 -281.825288) (xy 41.233326 -281.83898) (xy 41.277788 -281.860078) (xy 41.318291 -281.888034)
			(xy 41.353784 -281.922126) (xy 41.383349 -281.96147) (xy 41.40622 -282.005047) (xy 41.421804 -282.051728)
			(xy 41.429699 -282.100305) (xy 41.430194 -282.124912) (xy 41.429699 -282.149519) (xy 41.421804 -282.198096)
			(xy 41.40622 -282.244777) (xy 41.383349 -282.288354) (xy 41.353784 -282.327698) (xy 41.318291 -282.36179)
			(xy 41.277788 -282.389746) (xy 41.233326 -282.410844) (xy 41.186055 -282.424536) (xy 41.1372 -282.430468)
			(xy 41.088025 -282.428487) (xy 41.039806 -282.418643) (xy 40.99379 -282.401191) (xy 40.951169 -282.376584)
			(xy 40.913048 -282.345459) (xy 40.880413 -282.308622) (xy 40.85411 -282.267026) (xy 40.834819 -282.22175)
			(xy 40.823042 -282.173966) (xy 40.819082 -282.124912) (xy 40.480234 -282.124912) (xy 40.479739 -282.149519)
			(xy 40.471844 -282.198096) (xy 40.45626 -282.244777) (xy 40.433389 -282.288354) (xy 40.403824 -282.327698)
			(xy 40.368331 -282.36179) (xy 40.327828 -282.389746) (xy 40.283366 -282.410844) (xy 40.236095 -282.424536)
			(xy 40.18724 -282.430468) (xy 40.138065 -282.428487) (xy 40.089846 -282.418643) (xy 40.04383 -282.401191)
			(xy 40.001209 -282.376584) (xy 39.963088 -282.345459) (xy 39.930453 -282.308622) (xy 39.90415 -282.267026)
			(xy 39.884859 -282.22175) (xy 39.873082 -282.173966) (xy 39.869122 -282.124912) (xy 39.530274 -282.124912)
			(xy 39.529779 -282.149519) (xy 39.521884 -282.198096) (xy 39.5063 -282.244777) (xy 39.483429 -282.288354)
			(xy 39.453864 -282.327698) (xy 39.418371 -282.36179) (xy 39.377868 -282.389746) (xy 39.333406 -282.410844)
			(xy 39.286135 -282.424536) (xy 39.23728 -282.430468) (xy 39.188105 -282.428487) (xy 39.139886 -282.418643)
			(xy 39.09387 -282.401191) (xy 39.051249 -282.376584) (xy 39.013128 -282.345459) (xy 38.980493 -282.308622)
			(xy 38.95419 -282.267026) (xy 38.934899 -282.22175) (xy 38.923122 -282.173966) (xy 38.919162 -282.124912)
			(xy 38.606273 -282.124912) (xy 38.602414 -282.175321) (xy 38.590927 -282.224559) (xy 38.572081 -282.271476)
			(xy 38.546315 -282.314978) (xy 38.514229 -282.354053) (xy 38.495732 -282.371292) (xy 38.487858 -282.378404)
			(xy 38.477698 -282.400502) (xy 38.47592 -282.41625) (xy 38.477698 -282.424632) (xy 38.480876 -282.440765)
			(xy 38.48431 -282.473469) (xy 38.484556 -282.48991) (xy 38.484556 -282.709874) (xy 38.484325 -282.726316)
			(xy 38.480887 -282.75902) (xy 38.477698 -282.775152) (xy 38.47592 -282.783534) (xy 38.477698 -282.799282)
			(xy 38.487858 -282.82138) (xy 38.495732 -282.828492) (xy 38.514244 -282.845718) (xy 38.546334 -282.884795)
			(xy 38.572104 -282.928301) (xy 38.590953 -282.975222) (xy 38.602442 -283.024464) (xy 38.606302 -283.074872)
			(xy 38.919162 -283.074872) (xy 38.923122 -283.025818) (xy 38.934899 -282.978034) (xy 38.95419 -282.932758)
			(xy 38.980493 -282.891162) (xy 39.013128 -282.854325) (xy 39.051249 -282.8232) (xy 39.09387 -282.798593)
			(xy 39.139886 -282.781141) (xy 39.188105 -282.771297) (xy 39.23728 -282.769316) (xy 39.286135 -282.775248)
			(xy 39.333406 -282.78894) (xy 39.377868 -282.810038) (xy 39.418371 -282.837994) (xy 39.453864 -282.872086)
			(xy 39.483429 -282.91143) (xy 39.5063 -282.955007) (xy 39.521884 -283.001688) (xy 39.529779 -283.050265)
			(xy 39.530274 -283.074872) (xy 39.869122 -283.074872) (xy 39.873082 -283.025818) (xy 39.884859 -282.978034)
			(xy 39.90415 -282.932758) (xy 39.930453 -282.891162) (xy 39.963088 -282.854325) (xy 40.001209 -282.8232)
			(xy 40.04383 -282.798593) (xy 40.089846 -282.781141) (xy 40.138065 -282.771297) (xy 40.18724 -282.769316)
			(xy 40.236095 -282.775248) (xy 40.283366 -282.78894) (xy 40.327828 -282.810038) (xy 40.368331 -282.837994)
			(xy 40.403824 -282.872086) (xy 40.433389 -282.91143) (xy 40.45626 -282.955007) (xy 40.471844 -283.001688)
			(xy 40.479739 -283.050265) (xy 40.480234 -283.074872) (xy 40.819082 -283.074872) (xy 40.823042 -283.025818)
			(xy 40.834819 -282.978034) (xy 40.85411 -282.932758) (xy 40.880413 -282.891162) (xy 40.913048 -282.854325)
			(xy 40.951169 -282.8232) (xy 40.99379 -282.798593) (xy 41.039806 -282.781141) (xy 41.088025 -282.771297)
			(xy 41.1372 -282.769316) (xy 41.186055 -282.775248) (xy 41.233326 -282.78894) (xy 41.277788 -282.810038)
			(xy 41.318291 -282.837994) (xy 41.353784 -282.872086) (xy 41.383349 -282.91143) (xy 41.40622 -282.955007)
			(xy 41.421804 -283.001688) (xy 41.429699 -283.050265) (xy 41.430194 -283.074872) (xy 41.429699 -283.099479)
			(xy 41.421804 -283.148056) (xy 41.40622 -283.194737) (xy 41.383349 -283.238314) (xy 41.353784 -283.277658)
			(xy 41.318291 -283.31175) (xy 41.277788 -283.339706) (xy 41.233326 -283.360804) (xy 41.186055 -283.374496)
			(xy 41.1372 -283.380428) (xy 41.088025 -283.378447) (xy 41.039806 -283.368603) (xy 40.99379 -283.351151)
			(xy 40.951169 -283.326544) (xy 40.913048 -283.295419) (xy 40.880413 -283.258582) (xy 40.85411 -283.216986)
			(xy 40.834819 -283.17171) (xy 40.823042 -283.123926) (xy 40.819082 -283.074872) (xy 40.480234 -283.074872)
			(xy 40.479739 -283.099479) (xy 40.471844 -283.148056) (xy 40.45626 -283.194737) (xy 40.433389 -283.238314)
			(xy 40.403824 -283.277658) (xy 40.368331 -283.31175) (xy 40.327828 -283.339706) (xy 40.283366 -283.360804)
			(xy 40.236095 -283.374496) (xy 40.18724 -283.380428) (xy 40.138065 -283.378447) (xy 40.089846 -283.368603)
			(xy 40.04383 -283.351151) (xy 40.001209 -283.326544) (xy 39.963088 -283.295419) (xy 39.930453 -283.258582)
			(xy 39.90415 -283.216986) (xy 39.884859 -283.17171) (xy 39.873082 -283.123926) (xy 39.869122 -283.074872)
			(xy 39.530274 -283.074872) (xy 39.529779 -283.099479) (xy 39.521884 -283.148056) (xy 39.5063 -283.194737)
			(xy 39.483429 -283.238314) (xy 39.453864 -283.277658) (xy 39.418371 -283.31175) (xy 39.377868 -283.339706)
			(xy 39.333406 -283.360804) (xy 39.286135 -283.374496) (xy 39.23728 -283.380428) (xy 39.188105 -283.378447)
			(xy 39.139886 -283.368603) (xy 39.09387 -283.351151) (xy 39.051249 -283.326544) (xy 39.013128 -283.295419)
			(xy 38.980493 -283.258582) (xy 38.95419 -283.216986) (xy 38.934899 -283.17171) (xy 38.923122 -283.123926)
			(xy 38.919162 -283.074872) (xy 38.606302 -283.074872) (xy 38.606303 -283.074881) (xy 38.602448 -283.125299)
			(xy 38.590964 -283.174543) (xy 38.57212 -283.221465) (xy 38.546356 -283.264974) (xy 38.51427 -283.304055)
			(xy 38.495732 -283.321252) (xy 38.487858 -283.328364) (xy 38.477698 -283.350462) (xy 38.47592 -283.36621)
			(xy 38.477698 -283.374592) (xy 38.480878 -283.390725) (xy 38.484317 -283.423429) (xy 38.484556 -283.43987)
			(xy 38.484556 -283.659834) (xy 38.484327 -283.676276) (xy 38.480893 -283.708982) (xy 38.477698 -283.725112)
			(xy 38.47592 -283.733494) (xy 38.477698 -283.749242) (xy 38.487858 -283.77134) (xy 38.495732 -283.778452)
			(xy 38.514239 -283.795678) (xy 38.54632 -283.834754) (xy 38.572081 -283.878257) (xy 38.590922 -283.925173)
			(xy 38.602403 -283.97441) (xy 38.606258 -284.024821) (xy 38.606257 -284.024832) (xy 38.919162 -284.024832)
			(xy 38.923122 -283.975778) (xy 38.934899 -283.927994) (xy 38.95419 -283.882718) (xy 38.980493 -283.841122)
			(xy 39.013128 -283.804285) (xy 39.051249 -283.77316) (xy 39.09387 -283.748553) (xy 39.139886 -283.731101)
			(xy 39.188105 -283.721257) (xy 39.23728 -283.719276) (xy 39.286135 -283.725208) (xy 39.333406 -283.7389)
			(xy 39.377868 -283.759998) (xy 39.418371 -283.787954) (xy 39.453864 -283.822046) (xy 39.483429 -283.86139)
			(xy 39.5063 -283.904967) (xy 39.521884 -283.951648) (xy 39.529779 -284.000225) (xy 39.530274 -284.024832)
			(xy 39.869122 -284.024832) (xy 39.873082 -283.975778) (xy 39.884859 -283.927994) (xy 39.90415 -283.882718)
			(xy 39.930453 -283.841122) (xy 39.963088 -283.804285) (xy 40.001209 -283.77316) (xy 40.04383 -283.748553)
			(xy 40.089846 -283.731101) (xy 40.138065 -283.721257) (xy 40.18724 -283.719276) (xy 40.236095 -283.725208)
			(xy 40.283366 -283.7389) (xy 40.327828 -283.759998) (xy 40.368331 -283.787954) (xy 40.403824 -283.822046)
			(xy 40.433389 -283.86139) (xy 40.45626 -283.904967) (xy 40.471844 -283.951648) (xy 40.479739 -284.000225)
			(xy 40.480234 -284.024832) (xy 40.819082 -284.024832) (xy 40.823042 -283.975778) (xy 40.834819 -283.927994)
			(xy 40.85411 -283.882718) (xy 40.880413 -283.841122) (xy 40.913048 -283.804285) (xy 40.951169 -283.77316)
			(xy 40.99379 -283.748553) (xy 41.039806 -283.731101) (xy 41.088025 -283.721257) (xy 41.1372 -283.719276)
			(xy 41.186055 -283.725208) (xy 41.233326 -283.7389) (xy 41.277788 -283.759998) (xy 41.318291 -283.787954)
			(xy 41.353784 -283.822046) (xy 41.383349 -283.86139) (xy 41.40622 -283.904967) (xy 41.421804 -283.951648)
			(xy 41.429699 -284.000225) (xy 41.430194 -284.024832) (xy 41.429699 -284.049439) (xy 41.421804 -284.098016)
			(xy 41.40622 -284.144697) (xy 41.383349 -284.188274) (xy 41.353784 -284.227618) (xy 41.318291 -284.26171)
			(xy 41.277788 -284.289666) (xy 41.233326 -284.310764) (xy 41.186055 -284.324456) (xy 41.1372 -284.330388)
			(xy 41.088025 -284.328407) (xy 41.039806 -284.318563) (xy 40.99379 -284.301111) (xy 40.951169 -284.276504)
			(xy 40.913048 -284.245379) (xy 40.880413 -284.208542) (xy 40.85411 -284.166946) (xy 40.834819 -284.12167)
			(xy 40.823042 -284.073886) (xy 40.819082 -284.024832) (xy 40.480234 -284.024832) (xy 40.479739 -284.049439)
			(xy 40.471844 -284.098016) (xy 40.45626 -284.144697) (xy 40.433389 -284.188274) (xy 40.403824 -284.227618)
			(xy 40.368331 -284.26171) (xy 40.327828 -284.289666) (xy 40.283366 -284.310764) (xy 40.236095 -284.324456)
			(xy 40.18724 -284.330388) (xy 40.138065 -284.328407) (xy 40.089846 -284.318563) (xy 40.04383 -284.301111)
			(xy 40.001209 -284.276504) (xy 39.963088 -284.245379) (xy 39.930453 -284.208542) (xy 39.90415 -284.166946)
			(xy 39.884859 -284.12167) (xy 39.873082 -284.073886) (xy 39.869122 -284.024832) (xy 39.530274 -284.024832)
			(xy 39.529779 -284.049439) (xy 39.521884 -284.098016) (xy 39.5063 -284.144697) (xy 39.483429 -284.188274)
			(xy 39.453864 -284.227618) (xy 39.418371 -284.26171) (xy 39.377868 -284.289666) (xy 39.333406 -284.310764)
			(xy 39.286135 -284.324456) (xy 39.23728 -284.330388) (xy 39.188105 -284.328407) (xy 39.139886 -284.318563)
			(xy 39.09387 -284.301111) (xy 39.051249 -284.276504) (xy 39.013128 -284.245379) (xy 38.980493 -284.208542)
			(xy 38.95419 -284.166946) (xy 38.934899 -284.12167) (xy 38.923122 -284.073886) (xy 38.919162 -284.024832)
			(xy 38.606257 -284.024832) (xy 38.602397 -284.075232) (xy 38.590909 -284.124467) (xy 38.572062 -284.171381)
			(xy 38.546296 -284.214881) (xy 38.514209 -284.253952) (xy 38.495732 -284.271212) (xy 38.487858 -284.278324)
			(xy 38.477698 -284.300422) (xy 38.47592 -284.31617) (xy 38.477698 -284.324552) (xy 38.480875 -284.340685)
			(xy 38.484307 -284.373389) (xy 38.484556 -284.38983) (xy 38.484556 -284.609794) (xy 38.48433 -284.626237)
			(xy 38.480899 -284.658943) (xy 38.477698 -284.675072) (xy 38.47592 -284.683454) (xy 38.477698 -284.699202)
			(xy 38.487858 -284.7213) (xy 38.495732 -284.728412) (xy 38.514242 -284.745638) (xy 38.546329 -284.784715)
			(xy 38.572096 -284.82822) (xy 38.590942 -284.875139) (xy 38.602429 -284.92438) (xy 38.606288 -284.974792)
			(xy 38.919162 -284.974792) (xy 38.923122 -284.925738) (xy 38.934899 -284.877954) (xy 38.95419 -284.832678)
			(xy 38.980493 -284.791082) (xy 39.013128 -284.754245) (xy 39.051249 -284.72312) (xy 39.09387 -284.698513)
			(xy 39.139886 -284.681061) (xy 39.188105 -284.671217) (xy 39.23728 -284.669236) (xy 39.286135 -284.675168)
			(xy 39.333406 -284.68886) (xy 39.377868 -284.709958) (xy 39.418371 -284.737914) (xy 39.453864 -284.772006)
			(xy 39.483429 -284.81135) (xy 39.5063 -284.854927) (xy 39.521884 -284.901608) (xy 39.529779 -284.950185)
			(xy 39.530274 -284.974792) (xy 39.869122 -284.974792) (xy 39.873082 -284.925738) (xy 39.884859 -284.877954)
			(xy 39.90415 -284.832678) (xy 39.930453 -284.791082) (xy 39.963088 -284.754245) (xy 40.001209 -284.72312)
			(xy 40.04383 -284.698513) (xy 40.089846 -284.681061) (xy 40.138065 -284.671217) (xy 40.18724 -284.669236)
			(xy 40.236095 -284.675168) (xy 40.283366 -284.68886) (xy 40.327828 -284.709958) (xy 40.368331 -284.737914)
			(xy 40.403824 -284.772006) (xy 40.433389 -284.81135) (xy 40.45626 -284.854927) (xy 40.471844 -284.901608)
			(xy 40.479739 -284.950185) (xy 40.480234 -284.974792) (xy 40.819082 -284.974792) (xy 40.823042 -284.925738)
			(xy 40.834819 -284.877954) (xy 40.85411 -284.832678) (xy 40.880413 -284.791082) (xy 40.913048 -284.754245)
			(xy 40.951169 -284.72312) (xy 40.99379 -284.698513) (xy 41.039806 -284.681061) (xy 41.088025 -284.671217)
			(xy 41.1372 -284.669236) (xy 41.186055 -284.675168) (xy 41.233326 -284.68886) (xy 41.277788 -284.709958)
			(xy 41.318291 -284.737914) (xy 41.353784 -284.772006) (xy 41.383349 -284.81135) (xy 41.40622 -284.854927)
			(xy 41.421804 -284.901608) (xy 41.429699 -284.950185) (xy 41.430194 -284.974792) (xy 41.429699 -284.999399)
			(xy 41.421804 -285.047976) (xy 41.40622 -285.094657) (xy 41.383349 -285.138234) (xy 41.353784 -285.177578)
			(xy 41.318291 -285.21167) (xy 41.277788 -285.239626) (xy 41.233326 -285.260724) (xy 41.186055 -285.274416)
			(xy 41.1372 -285.280348) (xy 41.088025 -285.278367) (xy 41.039806 -285.268523) (xy 40.99379 -285.251071)
			(xy 40.951169 -285.226464) (xy 40.913048 -285.195339) (xy 40.880413 -285.158502) (xy 40.85411 -285.116906)
			(xy 40.834819 -285.07163) (xy 40.823042 -285.023846) (xy 40.819082 -284.974792) (xy 40.480234 -284.974792)
			(xy 40.479739 -284.999399) (xy 40.471844 -285.047976) (xy 40.45626 -285.094657) (xy 40.433389 -285.138234)
			(xy 40.403824 -285.177578) (xy 40.368331 -285.21167) (xy 40.327828 -285.239626) (xy 40.283366 -285.260724)
			(xy 40.236095 -285.274416) (xy 40.18724 -285.280348) (xy 40.138065 -285.278367) (xy 40.089846 -285.268523)
			(xy 40.04383 -285.251071) (xy 40.001209 -285.226464) (xy 39.963088 -285.195339) (xy 39.930453 -285.158502)
			(xy 39.90415 -285.116906) (xy 39.884859 -285.07163) (xy 39.873082 -285.023846) (xy 39.869122 -284.974792)
			(xy 39.530274 -284.974792) (xy 39.529779 -284.999399) (xy 39.521884 -285.047976) (xy 39.5063 -285.094657)
			(xy 39.483429 -285.138234) (xy 39.453864 -285.177578) (xy 39.418371 -285.21167) (xy 39.377868 -285.239626)
			(xy 39.333406 -285.260724) (xy 39.286135 -285.274416) (xy 39.23728 -285.280348) (xy 39.188105 -285.278367)
			(xy 39.139886 -285.268523) (xy 39.09387 -285.251071) (xy 39.051249 -285.226464) (xy 39.013128 -285.195339)
			(xy 38.980493 -285.158502) (xy 38.95419 -285.116906) (xy 38.934899 -285.07163) (xy 38.923122 -285.023846)
			(xy 38.919162 -284.974792) (xy 38.606288 -284.974792) (xy 38.606288 -284.974795) (xy 38.60243 -285.02521)
			(xy 38.590945 -285.074451) (xy 38.572101 -285.121371) (xy 38.546335 -285.164876) (xy 38.514249 -285.203954)
			(xy 38.495732 -285.221172) (xy 38.487858 -285.228284) (xy 38.477698 -285.250382) (xy 38.47592 -285.26613)
			(xy 38.477698 -285.274512) (xy 38.480877 -285.290645) (xy 38.484313 -285.323349) (xy 38.484556 -285.33979)
			(xy 38.484556 -285.559754) (xy 38.484326 -285.576196) (xy 38.48089 -285.608901) (xy 38.477698 -285.625032)
			(xy 38.47592 -285.633414) (xy 38.477698 -285.649162) (xy 38.487858 -285.67126) (xy 38.495732 -285.678372)
			(xy 38.514245 -285.695598) (xy 38.546339 -285.734676) (xy 38.572111 -285.778182) (xy 38.590963 -285.825104)
			(xy 38.602455 -285.874349) (xy 38.606317 -285.924752) (xy 38.919162 -285.924752) (xy 38.923122 -285.875698)
			(xy 38.934899 -285.827914) (xy 38.95419 -285.782638) (xy 38.980493 -285.741042) (xy 39.013128 -285.704205)
			(xy 39.051249 -285.67308) (xy 39.09387 -285.648473) (xy 39.139886 -285.631021) (xy 39.188105 -285.621177)
			(xy 39.23728 -285.619196) (xy 39.286135 -285.625128) (xy 39.333406 -285.63882) (xy 39.377868 -285.659918)
			(xy 39.418371 -285.687874) (xy 39.453864 -285.721966) (xy 39.483429 -285.76131) (xy 39.5063 -285.804887)
			(xy 39.521884 -285.851568) (xy 39.529779 -285.900145) (xy 39.530274 -285.924752) (xy 39.869122 -285.924752)
			(xy 39.873082 -285.875698) (xy 39.884859 -285.827914) (xy 39.90415 -285.782638) (xy 39.930453 -285.741042)
			(xy 39.963088 -285.704205) (xy 40.001209 -285.67308) (xy 40.04383 -285.648473) (xy 40.089846 -285.631021)
			(xy 40.138065 -285.621177) (xy 40.18724 -285.619196) (xy 40.236095 -285.625128) (xy 40.283366 -285.63882)
			(xy 40.327828 -285.659918) (xy 40.368331 -285.687874) (xy 40.403824 -285.721966) (xy 40.433389 -285.76131)
			(xy 40.45626 -285.804887) (xy 40.471844 -285.851568) (xy 40.479739 -285.900145) (xy 40.480234 -285.924752)
			(xy 40.819082 -285.924752) (xy 40.823042 -285.875698) (xy 40.834819 -285.827914) (xy 40.85411 -285.782638)
			(xy 40.880413 -285.741042) (xy 40.913048 -285.704205) (xy 40.951169 -285.67308) (xy 40.99379 -285.648473)
			(xy 41.039806 -285.631021) (xy 41.088025 -285.621177) (xy 41.1372 -285.619196) (xy 41.186055 -285.625128)
			(xy 41.233326 -285.63882) (xy 41.277788 -285.659918) (xy 41.318291 -285.687874) (xy 41.353784 -285.721966)
			(xy 41.383349 -285.76131) (xy 41.40622 -285.804887) (xy 41.421804 -285.851568) (xy 41.429699 -285.900145)
			(xy 41.430194 -285.924752) (xy 41.429699 -285.949359) (xy 41.421804 -285.997936) (xy 41.40622 -286.044617)
			(xy 41.383349 -286.088194) (xy 41.353784 -286.127538) (xy 41.318291 -286.16163) (xy 41.277788 -286.189586)
			(xy 41.233326 -286.210684) (xy 41.186055 -286.224376) (xy 41.1372 -286.230308) (xy 41.088025 -286.228327)
			(xy 41.039806 -286.218483) (xy 40.99379 -286.201031) (xy 40.951169 -286.176424) (xy 40.913048 -286.145299)
			(xy 40.880413 -286.108462) (xy 40.85411 -286.066866) (xy 40.834819 -286.02159) (xy 40.823042 -285.973806)
			(xy 40.819082 -285.924752) (xy 40.480234 -285.924752) (xy 40.479739 -285.949359) (xy 40.471844 -285.997936)
			(xy 40.45626 -286.044617) (xy 40.433389 -286.088194) (xy 40.403824 -286.127538) (xy 40.368331 -286.16163)
			(xy 40.327828 -286.189586) (xy 40.283366 -286.210684) (xy 40.236095 -286.224376) (xy 40.18724 -286.230308)
			(xy 40.138065 -286.228327) (xy 40.089846 -286.218483) (xy 40.04383 -286.201031) (xy 40.001209 -286.176424)
			(xy 39.963088 -286.145299) (xy 39.930453 -286.108462) (xy 39.90415 -286.066866) (xy 39.884859 -286.02159)
			(xy 39.873082 -285.973806) (xy 39.869122 -285.924752) (xy 39.530274 -285.924752) (xy 39.529779 -285.949359)
			(xy 39.521884 -285.997936) (xy 39.5063 -286.044617) (xy 39.483429 -286.088194) (xy 39.453864 -286.127538)
			(xy 39.418371 -286.16163) (xy 39.377868 -286.189586) (xy 39.333406 -286.210684) (xy 39.286135 -286.224376)
			(xy 39.23728 -286.230308) (xy 39.188105 -286.228327) (xy 39.139886 -286.218483) (xy 39.09387 -286.201031)
			(xy 39.051249 -286.176424) (xy 39.013128 -286.145299) (xy 38.980493 -286.108462) (xy 38.95419 -286.066866)
			(xy 38.934899 -286.02159) (xy 38.923122 -285.973806) (xy 38.919162 -285.924752) (xy 38.606317 -285.924752)
			(xy 38.606318 -285.924768) (xy 38.602464 -285.975188) (xy 38.590982 -286.024434) (xy 38.57214 -286.07136)
			(xy 38.546376 -286.114871) (xy 38.51429 -286.153955) (xy 38.495732 -286.171132) (xy 38.487858 -286.178244)
			(xy 38.477698 -286.200342) (xy 38.47592 -286.21609) (xy 38.477698 -286.224472) (xy 38.480879 -286.240605)
			(xy 38.48432 -286.273308) (xy 38.484556 -286.28975) (xy 38.484556 -286.509968) (xy 38.484326 -286.52641)
			(xy 38.480888 -286.559115) (xy 38.477698 -286.575246) (xy 38.47592 -286.583628) (xy 38.477698 -286.599376)
			(xy 38.487858 -286.621474) (xy 38.495732 -286.628586) (xy 38.516052 -286.647578) (xy 38.550665 -286.691111)
			(xy 38.577515 -286.739817) (xy 38.595849 -286.792325) (xy 38.605149 -286.847158) (xy 38.605714 -286.874966)
			(xy 38.919162 -286.874966) (xy 38.923122 -286.825912) (xy 38.934899 -286.778128) (xy 38.95419 -286.732852)
			(xy 38.980493 -286.691256) (xy 39.013128 -286.654419) (xy 39.051249 -286.623294) (xy 39.09387 -286.598687)
			(xy 39.139886 -286.581235) (xy 39.188105 -286.571391) (xy 39.23728 -286.56941) (xy 39.286135 -286.575342)
			(xy 39.333406 -286.589034) (xy 39.377868 -286.610132) (xy 39.418371 -286.638088) (xy 39.453864 -286.67218)
			(xy 39.483429 -286.711524) (xy 39.5063 -286.755101) (xy 39.521884 -286.801782) (xy 39.529779 -286.850359)
			(xy 39.530274 -286.874966) (xy 39.869122 -286.874966) (xy 39.873082 -286.825912) (xy 39.884859 -286.778128)
			(xy 39.90415 -286.732852) (xy 39.930453 -286.691256) (xy 39.963088 -286.654419) (xy 40.001209 -286.623294)
			(xy 40.04383 -286.598687) (xy 40.089846 -286.581235) (xy 40.138065 -286.571391) (xy 40.18724 -286.56941)
			(xy 40.236095 -286.575342) (xy 40.283366 -286.589034) (xy 40.327828 -286.610132) (xy 40.368331 -286.638088)
			(xy 40.403824 -286.67218) (xy 40.433389 -286.711524) (xy 40.45626 -286.755101) (xy 40.471844 -286.801782)
			(xy 40.479739 -286.850359) (xy 40.480234 -286.874966) (xy 40.819082 -286.874966) (xy 40.823042 -286.825912)
			(xy 40.834819 -286.778128) (xy 40.85411 -286.732852) (xy 40.880413 -286.691256) (xy 40.913048 -286.654419)
			(xy 40.951169 -286.623294) (xy 40.99379 -286.598687) (xy 41.039806 -286.581235) (xy 41.088025 -286.571391)
			(xy 41.1372 -286.56941) (xy 41.186055 -286.575342) (xy 41.233326 -286.589034) (xy 41.277788 -286.610132)
			(xy 41.318291 -286.638088) (xy 41.353784 -286.67218) (xy 41.383349 -286.711524) (xy 41.40622 -286.755101)
			(xy 41.421804 -286.801782) (xy 41.429699 -286.850359) (xy 41.430194 -286.874966) (xy 41.769042 -286.874966)
			(xy 41.773002 -286.825912) (xy 41.784779 -286.778128) (xy 41.80407 -286.732852) (xy 41.830373 -286.691256)
			(xy 41.863008 -286.654419) (xy 41.901129 -286.623294) (xy 41.94375 -286.598687) (xy 41.989766 -286.581235)
			(xy 42.037985 -286.571391) (xy 42.08716 -286.56941) (xy 42.136015 -286.575342) (xy 42.183286 -286.589034)
			(xy 42.227748 -286.610132) (xy 42.268251 -286.638088) (xy 42.303744 -286.67218) (xy 42.333309 -286.711524)
			(xy 42.35618 -286.755101) (xy 42.371764 -286.801782) (xy 42.379659 -286.850359) (xy 42.380149 -286.874712)
			(xy 42.719002 -286.874712) (xy 42.722962 -286.825658) (xy 42.734739 -286.777874) (xy 42.75403 -286.732598)
			(xy 42.780333 -286.691002) (xy 42.812968 -286.654165) (xy 42.851089 -286.62304) (xy 42.89371 -286.598433)
			(xy 42.939726 -286.580981) (xy 42.987945 -286.571137) (xy 43.03712 -286.569156) (xy 43.085975 -286.575088)
			(xy 43.133246 -286.58878) (xy 43.177708 -286.609878) (xy 43.218211 -286.637834) (xy 43.253704 -286.671926)
			(xy 43.283269 -286.71127) (xy 43.30614 -286.754847) (xy 43.321724 -286.801528) (xy 43.329619 -286.850105)
			(xy 43.330114 -286.874712) (xy 43.668962 -286.874712) (xy 43.672922 -286.825658) (xy 43.684699 -286.777874)
			(xy 43.70399 -286.732598) (xy 43.730293 -286.691002) (xy 43.762928 -286.654165) (xy 43.801049 -286.62304)
			(xy 43.84367 -286.598433) (xy 43.889686 -286.580981) (xy 43.937905 -286.571137) (xy 43.98708 -286.569156)
			(xy 44.035935 -286.575088) (xy 44.083206 -286.58878) (xy 44.127668 -286.609878) (xy 44.168171 -286.637834)
			(xy 44.203664 -286.671926) (xy 44.233229 -286.71127) (xy 44.2561 -286.754847) (xy 44.271684 -286.801528)
			(xy 44.279579 -286.850105) (xy 44.280074 -286.874712) (xy 44.279579 -286.899319) (xy 44.271684 -286.947896)
			(xy 44.2561 -286.994577) (xy 44.233229 -287.038154) (xy 44.203664 -287.077498) (xy 44.168171 -287.11159)
			(xy 44.127668 -287.139546) (xy 44.083206 -287.160644) (xy 44.035935 -287.174336) (xy 43.98708 -287.180268)
			(xy 43.937905 -287.178287) (xy 43.889686 -287.168443) (xy 43.84367 -287.150991) (xy 43.801049 -287.126384)
			(xy 43.762928 -287.095259) (xy 43.730293 -287.058422) (xy 43.70399 -287.016826) (xy 43.684699 -286.97155)
			(xy 43.672922 -286.923766) (xy 43.668962 -286.874712) (xy 43.330114 -286.874712) (xy 43.329619 -286.899319)
			(xy 43.321724 -286.947896) (xy 43.30614 -286.994577) (xy 43.283269 -287.038154) (xy 43.253704 -287.077498)
			(xy 43.218211 -287.11159) (xy 43.177708 -287.139546) (xy 43.133246 -287.160644) (xy 43.085975 -287.174336)
			(xy 43.03712 -287.180268) (xy 42.987945 -287.178287) (xy 42.939726 -287.168443) (xy 42.89371 -287.150991)
			(xy 42.851089 -287.126384) (xy 42.812968 -287.095259) (xy 42.780333 -287.058422) (xy 42.75403 -287.016826)
			(xy 42.734739 -286.97155) (xy 42.722962 -286.923766) (xy 42.719002 -286.874712) (xy 42.380149 -286.874712)
			(xy 42.380154 -286.874966) (xy 42.379659 -286.899573) (xy 42.371764 -286.94815) (xy 42.35618 -286.994831)
			(xy 42.333309 -287.038408) (xy 42.303744 -287.077752) (xy 42.268251 -287.111844) (xy 42.227748 -287.1398)
			(xy 42.183286 -287.160898) (xy 42.136015 -287.17459) (xy 42.08716 -287.180522) (xy 42.037985 -287.178541)
			(xy 41.989766 -287.168697) (xy 41.94375 -287.151245) (xy 41.901129 -287.126638) (xy 41.863008 -287.095513)
			(xy 41.830373 -287.058676) (xy 41.80407 -287.01708) (xy 41.784779 -286.971804) (xy 41.773002 -286.92402)
			(xy 41.769042 -286.874966) (xy 41.430194 -286.874966) (xy 41.429699 -286.899573) (xy 41.421804 -286.94815)
			(xy 41.40622 -286.994831) (xy 41.383349 -287.038408) (xy 41.353784 -287.077752) (xy 41.318291 -287.111844)
			(xy 41.277788 -287.1398) (xy 41.233326 -287.160898) (xy 41.186055 -287.17459) (xy 41.1372 -287.180522)
			(xy 41.088025 -287.178541) (xy 41.039806 -287.168697) (xy 40.99379 -287.151245) (xy 40.951169 -287.126638)
			(xy 40.913048 -287.095513) (xy 40.880413 -287.058676) (xy 40.85411 -287.01708) (xy 40.834819 -286.971804)
			(xy 40.823042 -286.92402) (xy 40.819082 -286.874966) (xy 40.480234 -286.874966) (xy 40.479739 -286.899573)
			(xy 40.471844 -286.94815) (xy 40.45626 -286.994831) (xy 40.433389 -287.038408) (xy 40.403824 -287.077752)
			(xy 40.368331 -287.111844) (xy 40.327828 -287.1398) (xy 40.283366 -287.160898) (xy 40.236095 -287.17459)
			(xy 40.18724 -287.180522) (xy 40.138065 -287.178541) (xy 40.089846 -287.168697) (xy 40.04383 -287.151245)
			(xy 40.001209 -287.126638) (xy 39.963088 -287.095513) (xy 39.930453 -287.058676) (xy 39.90415 -287.01708)
			(xy 39.884859 -286.971804) (xy 39.873082 -286.92402) (xy 39.869122 -286.874966) (xy 39.530274 -286.874966)
			(xy 39.529779 -286.899573) (xy 39.521884 -286.94815) (xy 39.5063 -286.994831) (xy 39.483429 -287.038408)
			(xy 39.453864 -287.077752) (xy 39.418371 -287.111844) (xy 39.377868 -287.1398) (xy 39.333406 -287.160898)
			(xy 39.286135 -287.17459) (xy 39.23728 -287.180522) (xy 39.188105 -287.178541) (xy 39.139886 -287.168697)
			(xy 39.09387 -287.151245) (xy 39.051249 -287.126638) (xy 39.013128 -287.095513) (xy 38.980493 -287.058676)
			(xy 38.95419 -287.01708) (xy 38.934899 -286.971804) (xy 38.923122 -286.92402) (xy 38.919162 -286.874966)
			(xy 38.605714 -286.874966) (xy 38.604943 -286.906896) (xy 38.592659 -286.969564) (xy 38.58133 -286.999426)
			(xy 38.577266 -287.009586) (xy 38.574549 -287.016957) (xy 38.573247 -287.032605) (xy 38.574726 -287.04032)
			(xy 38.57498 -287.041082) (xy 38.576788 -287.04792) (xy 38.583611 -287.060302) (xy 38.588442 -287.065466)
			(xy 39.0017 -287.47847) (xy 39.009097 -287.48532) (xy 39.027695 -287.493059) (xy 39.037768 -287.493456)
			(xy 39.224966 -287.493456) (xy 39.250976 -287.493937) (xy 39.302358 -287.50207) (xy 39.351833 -287.518142)
			(xy 39.398186 -287.541756) (xy 39.440273 -287.572332) (xy 39.477058 -287.609115) (xy 39.507635 -287.651201)
			(xy 39.531252 -287.697552) (xy 39.547326 -287.747027) (xy 39.555462 -287.798408) (xy 39.555928 -287.824418)
			(xy 39.555919 -287.824926) (xy 39.869122 -287.824926) (xy 39.873082 -287.775872) (xy 39.884859 -287.728088)
			(xy 39.90415 -287.682812) (xy 39.930453 -287.641216) (xy 39.963088 -287.604379) (xy 40.001209 -287.573254)
			(xy 40.04383 -287.548647) (xy 40.089846 -287.531195) (xy 40.138065 -287.521351) (xy 40.18724 -287.51937)
			(xy 40.236095 -287.525302) (xy 40.283366 -287.538994) (xy 40.327828 -287.560092) (xy 40.368331 -287.588048)
			(xy 40.403824 -287.62214) (xy 40.433389 -287.661484) (xy 40.45626 -287.705061) (xy 40.471844 -287.751742)
			(xy 40.479739 -287.800319) (xy 40.480234 -287.824926) (xy 40.479739 -287.849533) (xy 40.479597 -287.850405)
			(xy 40.794466 -287.850405) (xy 40.794466 -287.798395) (xy 40.802602 -287.747025) (xy 40.818674 -287.697561)
			(xy 40.842285 -287.651219) (xy 40.872855 -287.609142) (xy 40.909631 -287.572364) (xy 40.951707 -287.541792)
			(xy 40.998048 -287.518179) (xy 41.047512 -287.502105) (xy 41.098881 -287.493967) (xy 41.124886 -287.493456)
			(xy 42.074846 -287.493456) (xy 42.100852 -287.493934) (xy 42.152223 -287.502077) (xy 42.201688 -287.518155)
			(xy 42.248029 -287.541773) (xy 42.290106 -287.572348) (xy 42.326882 -287.609129) (xy 42.357451 -287.65121)
			(xy 42.381063 -287.697554) (xy 42.397134 -287.747022) (xy 42.40527 -287.798394) (xy 42.40527 -287.824926)
			(xy 42.719002 -287.824926) (xy 42.722962 -287.775872) (xy 42.734739 -287.728088) (xy 42.75403 -287.682812)
			(xy 42.780333 -287.641216) (xy 42.812968 -287.604379) (xy 42.851089 -287.573254) (xy 42.89371 -287.548647)
			(xy 42.939726 -287.531195) (xy 42.987945 -287.521351) (xy 43.03712 -287.51937) (xy 43.085975 -287.525302)
			(xy 43.133246 -287.538994) (xy 43.177708 -287.560092) (xy 43.218211 -287.588048) (xy 43.253704 -287.62214)
			(xy 43.283269 -287.661484) (xy 43.30614 -287.705061) (xy 43.321724 -287.751742) (xy 43.329619 -287.800319)
			(xy 43.330114 -287.824926) (xy 43.668962 -287.824926) (xy 43.672922 -287.775872) (xy 43.684699 -287.728088)
			(xy 43.70399 -287.682812) (xy 43.730293 -287.641216) (xy 43.762928 -287.604379) (xy 43.801049 -287.573254)
			(xy 43.84367 -287.548647) (xy 43.889686 -287.531195) (xy 43.937905 -287.521351) (xy 43.98708 -287.51937)
			(xy 44.035935 -287.525302) (xy 44.083206 -287.538994) (xy 44.127668 -287.560092) (xy 44.168171 -287.588048)
			(xy 44.203664 -287.62214) (xy 44.233229 -287.661484) (xy 44.2561 -287.705061) (xy 44.271684 -287.751742)
			(xy 44.279579 -287.800319) (xy 44.280074 -287.824926) (xy 44.619176 -287.824926) (xy 44.623136 -287.775872)
			(xy 44.634913 -287.728088) (xy 44.654204 -287.682812) (xy 44.680507 -287.641216) (xy 44.713142 -287.604379)
			(xy 44.751263 -287.573254) (xy 44.793884 -287.548647) (xy 44.8399 -287.531195) (xy 44.888119 -287.521351)
			(xy 44.937294 -287.51937) (xy 44.986149 -287.525302) (xy 45.03342 -287.538994) (xy 45.077882 -287.560092)
			(xy 45.118385 -287.588048) (xy 45.153878 -287.62214) (xy 45.183443 -287.661484) (xy 45.206314 -287.705061)
			(xy 45.221898 -287.751742) (xy 45.229793 -287.800319) (xy 45.230288 -287.824926) (xy 45.229793 -287.849533)
			(xy 45.221898 -287.89811) (xy 45.206314 -287.944791) (xy 45.183443 -287.988368) (xy 45.153878 -288.027712)
			(xy 45.118385 -288.061804) (xy 45.077882 -288.08976) (xy 45.03342 -288.110858) (xy 44.986149 -288.12455)
			(xy 44.937294 -288.130482) (xy 44.888119 -288.128501) (xy 44.8399 -288.118657) (xy 44.793884 -288.101205)
			(xy 44.751263 -288.076598) (xy 44.713142 -288.045473) (xy 44.680507 -288.008636) (xy 44.654204 -287.96704)
			(xy 44.634913 -287.921764) (xy 44.623136 -287.87398) (xy 44.619176 -287.824926) (xy 44.280074 -287.824926)
			(xy 44.279579 -287.849533) (xy 44.271684 -287.89811) (xy 44.2561 -287.944791) (xy 44.233229 -287.988368)
			(xy 44.203664 -288.027712) (xy 44.168171 -288.061804) (xy 44.127668 -288.08976) (xy 44.083206 -288.110858)
			(xy 44.035935 -288.12455) (xy 43.98708 -288.130482) (xy 43.937905 -288.128501) (xy 43.889686 -288.118657)
			(xy 43.84367 -288.101205) (xy 43.801049 -288.076598) (xy 43.762928 -288.045473) (xy 43.730293 -288.008636)
			(xy 43.70399 -287.96704) (xy 43.684699 -287.921764) (xy 43.672922 -287.87398) (xy 43.668962 -287.824926)
			(xy 43.330114 -287.824926) (xy 43.329619 -287.849533) (xy 43.321724 -287.89811) (xy 43.30614 -287.944791)
			(xy 43.283269 -287.988368) (xy 43.253704 -288.027712) (xy 43.218211 -288.061804) (xy 43.177708 -288.08976)
			(xy 43.133246 -288.110858) (xy 43.085975 -288.12455) (xy 43.03712 -288.130482) (xy 42.987945 -288.128501)
			(xy 42.939726 -288.118657) (xy 42.89371 -288.101205) (xy 42.851089 -288.076598) (xy 42.812968 -288.045473)
			(xy 42.780333 -288.008636) (xy 42.75403 -287.96704) (xy 42.734739 -287.921764) (xy 42.722962 -287.87398)
			(xy 42.719002 -287.824926) (xy 42.40527 -287.824926) (xy 42.40527 -287.850406) (xy 42.397134 -287.901778)
			(xy 42.381063 -287.951246) (xy 42.357451 -287.99759) (xy 42.326882 -288.039671) (xy 42.290106 -288.076452)
			(xy 42.248029 -288.107027) (xy 42.201688 -288.130645) (xy 42.152223 -288.146723) (xy 42.100852 -288.154866)
			(xy 42.074846 -288.15538) (xy 41.124886 -288.15538) (xy 41.098881 -288.154833) (xy 41.047512 -288.146695)
			(xy 40.998048 -288.130621) (xy 40.951707 -288.107008) (xy 40.909631 -288.076436) (xy 40.872855 -288.039658)
			(xy 40.842285 -287.997581) (xy 40.818674 -287.951239) (xy 40.802602 -287.901775) (xy 40.794466 -287.850405)
			(xy 40.479597 -287.850405) (xy 40.471844 -287.89811) (xy 40.45626 -287.944791) (xy 40.433389 -287.988368)
			(xy 40.403824 -288.027712) (xy 40.368331 -288.061804) (xy 40.327828 -288.08976) (xy 40.283366 -288.110858)
			(xy 40.236095 -288.12455) (xy 40.18724 -288.130482) (xy 40.138065 -288.128501) (xy 40.089846 -288.118657)
			(xy 40.04383 -288.101205) (xy 40.001209 -288.076598) (xy 39.963088 -288.045473) (xy 39.930453 -288.008636)
			(xy 39.90415 -287.96704) (xy 39.884859 -287.921764) (xy 39.873082 -287.87398) (xy 39.869122 -287.824926)
			(xy 39.555919 -287.824926) (xy 39.555532 -287.847444) (xy 39.549135 -287.893049) (xy 39.536454 -287.937321)
			(xy 39.52748 -287.95853) (xy 39.52113 -287.973008) (xy 39.526718 -288.003742) (xy 39.984426 -288.46145)
			(xy 39.989472 -288.4661) (xy 40.001446 -288.472789) (xy 40.008048 -288.474658) (xy 40.017192 -288.477198)
			(xy 40.033956 -288.475674) (xy 40.04183 -288.472118) (xy 40.062812 -288.463304) (xy 40.106592 -288.450874)
			(xy 40.151663 -288.444572) (xy 40.174418 -288.444178) (xy 40.174926 -288.444178) (xy 40.200912 -288.444689)
			(xy 40.252244 -288.452823) (xy 40.301672 -288.468886) (xy 40.347979 -288.492483) (xy 40.390025 -288.523033)
			(xy 40.426775 -288.559784) (xy 40.457323 -288.601831) (xy 40.480918 -288.648139) (xy 40.49698 -288.697567)
			(xy 40.505111 -288.7489) (xy 40.505634 -288.774886) (xy 41.769042 -288.774886) (xy 41.773002 -288.725832)
			(xy 41.784779 -288.678048) (xy 41.80407 -288.632772) (xy 41.830373 -288.591176) (xy 41.863008 -288.554339)
			(xy 41.901129 -288.523214) (xy 41.94375 -288.498607) (xy 41.989766 -288.481155) (xy 42.037985 -288.471311)
			(xy 42.08716 -288.46933) (xy 42.136015 -288.475262) (xy 42.183286 -288.488954) (xy 42.227748 -288.510052)
			(xy 42.268251 -288.538008) (xy 42.303744 -288.5721) (xy 42.333309 -288.611444) (xy 42.35618 -288.655021)
			(xy 42.371764 -288.701702) (xy 42.379659 -288.750279) (xy 42.380154 -288.774886) (xy 42.379659 -288.799493)
			(xy 42.37951 -288.800411) (xy 42.694299 -288.800411) (xy 42.694299 -288.748389) (xy 42.702438 -288.697007)
			(xy 42.718514 -288.64753) (xy 42.742132 -288.601178) (xy 42.77271 -288.559091) (xy 42.809496 -288.522306)
			(xy 42.851583 -288.491729) (xy 42.897936 -288.468111) (xy 42.947413 -288.452036) (xy 42.998795 -288.443899)
			(xy 43.024806 -288.443416) (xy 43.974766 -288.443416) (xy 44.000775 -288.443941) (xy 44.052154 -288.452074)
			(xy 44.101628 -288.468144) (xy 44.147978 -288.491757) (xy 44.190064 -288.52233) (xy 44.226848 -288.55911)
			(xy 44.257426 -288.601193) (xy 44.281043 -288.647541) (xy 44.297119 -288.697013) (xy 44.305257 -288.748391)
			(xy 44.305257 -288.774886) (xy 44.619176 -288.774886) (xy 44.623136 -288.725832) (xy 44.634913 -288.678048)
			(xy 44.654204 -288.632772) (xy 44.680507 -288.591176) (xy 44.713142 -288.554339) (xy 44.751263 -288.523214)
			(xy 44.793884 -288.498607) (xy 44.8399 -288.481155) (xy 44.888119 -288.471311) (xy 44.937294 -288.46933)
			(xy 44.986149 -288.475262) (xy 45.03342 -288.488954) (xy 45.077882 -288.510052) (xy 45.118385 -288.538008)
			(xy 45.153878 -288.5721) (xy 45.183443 -288.611444) (xy 45.206314 -288.655021) (xy 45.221898 -288.701702)
			(xy 45.229793 -288.750279) (xy 45.230288 -288.774886) (xy 45.569136 -288.774886) (xy 45.573096 -288.725832)
			(xy 45.584873 -288.678048) (xy 45.604164 -288.632772) (xy 45.630467 -288.591176) (xy 45.663102 -288.554339)
			(xy 45.701223 -288.523214) (xy 45.743844 -288.498607) (xy 45.78986 -288.481155) (xy 45.838079 -288.471311)
			(xy 45.887254 -288.46933) (xy 45.936109 -288.475262) (xy 45.98338 -288.488954) (xy 46.027842 -288.510052)
			(xy 46.068345 -288.538008) (xy 46.103838 -288.5721) (xy 46.133403 -288.611444) (xy 46.156274 -288.655021)
			(xy 46.171858 -288.701702) (xy 46.179753 -288.750279) (xy 46.180248 -288.774886) (xy 46.179753 -288.799493)
			(xy 46.171858 -288.84807) (xy 46.156274 -288.894751) (xy 46.133403 -288.938328) (xy 46.103838 -288.977672)
			(xy 46.068345 -289.011764) (xy 46.027842 -289.03972) (xy 45.98338 -289.060818) (xy 45.936109 -289.07451)
			(xy 45.887254 -289.080442) (xy 45.838079 -289.078461) (xy 45.78986 -289.068617) (xy 45.743844 -289.051165)
			(xy 45.701223 -289.026558) (xy 45.663102 -288.995433) (xy 45.630467 -288.958596) (xy 45.604164 -288.917)
			(xy 45.584873 -288.871724) (xy 45.573096 -288.82394) (xy 45.569136 -288.774886) (xy 45.230288 -288.774886)
			(xy 45.229793 -288.799493) (xy 45.221898 -288.84807) (xy 45.206314 -288.894751) (xy 45.183443 -288.938328)
			(xy 45.153878 -288.977672) (xy 45.118385 -289.011764) (xy 45.077882 -289.03972) (xy 45.03342 -289.060818)
			(xy 44.986149 -289.07451) (xy 44.937294 -289.080442) (xy 44.888119 -289.078461) (xy 44.8399 -289.068617)
			(xy 44.793884 -289.051165) (xy 44.751263 -289.026558) (xy 44.713142 -288.995433) (xy 44.680507 -288.958596)
			(xy 44.654204 -288.917) (xy 44.634913 -288.871724) (xy 44.623136 -288.82394) (xy 44.619176 -288.774886)
			(xy 44.305257 -288.774886) (xy 44.305257 -288.800409) (xy 44.297119 -288.851787) (xy 44.281043 -288.901259)
			(xy 44.257426 -288.947607) (xy 44.226848 -288.98969) (xy 44.190064 -289.02647) (xy 44.147978 -289.057043)
			(xy 44.101628 -289.080656) (xy 44.052154 -289.096726) (xy 44.000775 -289.104859) (xy 43.974766 -289.10534)
			(xy 43.024806 -289.10534) (xy 42.998795 -289.104901) (xy 42.947413 -289.096764) (xy 42.897936 -289.080689)
			(xy 42.851583 -289.057071) (xy 42.809496 -289.026494) (xy 42.77271 -288.989709) (xy 42.742132 -288.947622)
			(xy 42.718514 -288.90127) (xy 42.702438 -288.851793) (xy 42.694299 -288.800411) (xy 42.37951 -288.800411)
			(xy 42.371764 -288.84807) (xy 42.35618 -288.894751) (xy 42.333309 -288.938328) (xy 42.303744 -288.977672)
			(xy 42.268251 -289.011764) (xy 42.227748 -289.03972) (xy 42.183286 -289.060818) (xy 42.136015 -289.07451)
			(xy 42.08716 -289.080442) (xy 42.037985 -289.078461) (xy 41.989766 -289.068617) (xy 41.94375 -289.051165)
			(xy 41.901129 -289.026558) (xy 41.863008 -288.995433) (xy 41.830373 -288.958596) (xy 41.80407 -288.917)
			(xy 41.784779 -288.871724) (xy 41.773002 -288.82394) (xy 41.769042 -288.774886) (xy 40.505634 -288.774886)
			(xy 40.504861 -288.806815) (xy 40.492574 -288.869482) (xy 40.48125 -288.899346) (xy 40.477186 -288.909506)
			(xy 40.474471 -288.916877) (xy 40.473175 -288.932524) (xy 40.474646 -288.94024) (xy 40.4749 -288.941002)
			(xy 40.476711 -288.947838) (xy 40.483539 -288.960215) (xy 40.488362 -288.965386) (xy 40.934386 -289.41141)
			(xy 40.939428 -289.416066) (xy 40.951399 -289.42277) (xy 40.958008 -289.424618) (xy 40.967152 -289.427158)
			(xy 40.983916 -289.425634) (xy 40.99179 -289.422078) (xy 41.012773 -289.413269) (xy 41.056553 -289.400848)
			(xy 41.101624 -289.394555) (xy 41.124378 -289.394138) (xy 41.124886 -289.394138) (xy 41.150875 -289.39462)
			(xy 41.202212 -289.40275) (xy 41.251646 -289.418811) (xy 41.297958 -289.442409) (xy 41.340007 -289.472962)
			(xy 41.376759 -289.509717) (xy 41.407308 -289.55177) (xy 41.430901 -289.598084) (xy 41.446958 -289.647519)
			(xy 41.455082 -289.698857) (xy 41.455594 -289.724846) (xy 41.769042 -289.724846) (xy 41.773002 -289.675792)
			(xy 41.784779 -289.628008) (xy 41.80407 -289.582732) (xy 41.830373 -289.541136) (xy 41.863008 -289.504299)
			(xy 41.901129 -289.473174) (xy 41.94375 -289.448567) (xy 41.989766 -289.431115) (xy 42.037985 -289.421271)
			(xy 42.08716 -289.41929) (xy 42.136015 -289.425222) (xy 42.183286 -289.438914) (xy 42.227748 -289.460012)
			(xy 42.268251 -289.487968) (xy 42.303744 -289.52206) (xy 42.333309 -289.561404) (xy 42.35618 -289.604981)
			(xy 42.371764 -289.651662) (xy 42.379659 -289.700239) (xy 42.380154 -289.724846) (xy 42.719002 -289.724846)
			(xy 42.722962 -289.675792) (xy 42.734739 -289.628008) (xy 42.75403 -289.582732) (xy 42.780333 -289.541136)
			(xy 42.812968 -289.504299) (xy 42.851089 -289.473174) (xy 42.89371 -289.448567) (xy 42.939726 -289.431115)
			(xy 42.987945 -289.421271) (xy 43.03712 -289.41929) (xy 43.085975 -289.425222) (xy 43.133246 -289.438914)
			(xy 43.177708 -289.460012) (xy 43.218211 -289.487968) (xy 43.253704 -289.52206) (xy 43.283269 -289.561404)
			(xy 43.30614 -289.604981) (xy 43.321724 -289.651662) (xy 43.329619 -289.700239) (xy 43.330114 -289.724846)
			(xy 43.668962 -289.724846) (xy 43.672922 -289.675792) (xy 43.684699 -289.628008) (xy 43.70399 -289.582732)
			(xy 43.730293 -289.541136) (xy 43.762928 -289.504299) (xy 43.801049 -289.473174) (xy 43.84367 -289.448567)
			(xy 43.889686 -289.431115) (xy 43.937905 -289.421271) (xy 43.98708 -289.41929) (xy 44.035935 -289.425222)
			(xy 44.083206 -289.438914) (xy 44.127668 -289.460012) (xy 44.168171 -289.487968) (xy 44.203664 -289.52206)
			(xy 44.233229 -289.561404) (xy 44.2561 -289.604981) (xy 44.271684 -289.651662) (xy 44.279579 -289.700239)
			(xy 44.280074 -289.724846) (xy 44.619176 -289.724846) (xy 44.623136 -289.675792) (xy 44.634913 -289.628008)
			(xy 44.654204 -289.582732) (xy 44.680507 -289.541136) (xy 44.713142 -289.504299) (xy 44.751263 -289.473174)
			(xy 44.793884 -289.448567) (xy 44.8399 -289.431115) (xy 44.888119 -289.421271) (xy 44.937294 -289.41929)
			(xy 44.986149 -289.425222) (xy 45.03342 -289.438914) (xy 45.077882 -289.460012) (xy 45.118385 -289.487968)
			(xy 45.153878 -289.52206) (xy 45.183443 -289.561404) (xy 45.206314 -289.604981) (xy 45.221898 -289.651662)
			(xy 45.229793 -289.700239) (xy 45.230288 -289.724846) (xy 45.569136 -289.724846) (xy 45.573096 -289.675792)
			(xy 45.584873 -289.628008) (xy 45.604164 -289.582732) (xy 45.630467 -289.541136) (xy 45.663102 -289.504299)
			(xy 45.701223 -289.473174) (xy 45.743844 -289.448567) (xy 45.78986 -289.431115) (xy 45.838079 -289.421271)
			(xy 45.887254 -289.41929) (xy 45.936109 -289.425222) (xy 45.98338 -289.438914) (xy 46.027842 -289.460012)
			(xy 46.068345 -289.487968) (xy 46.103838 -289.52206) (xy 46.133403 -289.561404) (xy 46.156274 -289.604981)
			(xy 46.171858 -289.651662) (xy 46.179753 -289.700239) (xy 46.180248 -289.724846) (xy 46.519096 -289.724846)
			(xy 46.523056 -289.675792) (xy 46.534833 -289.628008) (xy 46.554124 -289.582732) (xy 46.580427 -289.541136)
			(xy 46.613062 -289.504299) (xy 46.651183 -289.473174) (xy 46.693804 -289.448567) (xy 46.73982 -289.431115)
			(xy 46.788039 -289.421271) (xy 46.837214 -289.41929) (xy 46.886069 -289.425222) (xy 46.93334 -289.438914)
			(xy 46.977802 -289.460012) (xy 47.018305 -289.487968) (xy 47.053798 -289.52206) (xy 47.083363 -289.561404)
			(xy 47.106234 -289.604981) (xy 47.121818 -289.651662) (xy 47.129713 -289.700239) (xy 47.130208 -289.724846)
			(xy 47.129713 -289.749453) (xy 47.121818 -289.79803) (xy 47.106234 -289.844711) (xy 47.083363 -289.888288)
			(xy 47.053798 -289.927632) (xy 47.018305 -289.961724) (xy 46.977802 -289.98968) (xy 46.93334 -290.010778)
			(xy 46.886069 -290.02447) (xy 46.837214 -290.030402) (xy 46.788039 -290.028421) (xy 46.73982 -290.018577)
			(xy 46.693804 -290.001125) (xy 46.651183 -289.976518) (xy 46.613062 -289.945393) (xy 46.580427 -289.908556)
			(xy 46.554124 -289.86696) (xy 46.534833 -289.821684) (xy 46.523056 -289.7739) (xy 46.519096 -289.724846)
			(xy 46.180248 -289.724846) (xy 46.179753 -289.749453) (xy 46.171858 -289.79803) (xy 46.156274 -289.844711)
			(xy 46.133403 -289.888288) (xy 46.103838 -289.927632) (xy 46.068345 -289.961724) (xy 46.027842 -289.98968)
			(xy 45.98338 -290.010778) (xy 45.936109 -290.02447) (xy 45.887254 -290.030402) (xy 45.838079 -290.028421)
			(xy 45.78986 -290.018577) (xy 45.743844 -290.001125) (xy 45.701223 -289.976518) (xy 45.663102 -289.945393)
			(xy 45.630467 -289.908556) (xy 45.604164 -289.86696) (xy 45.584873 -289.821684) (xy 45.573096 -289.7739)
			(xy 45.569136 -289.724846) (xy 45.230288 -289.724846) (xy 45.229793 -289.749453) (xy 45.221898 -289.79803)
			(xy 45.206314 -289.844711) (xy 45.183443 -289.888288) (xy 45.153878 -289.927632) (xy 45.118385 -289.961724)
			(xy 45.077882 -289.98968) (xy 45.03342 -290.010778) (xy 44.986149 -290.02447) (xy 44.937294 -290.030402)
			(xy 44.888119 -290.028421) (xy 44.8399 -290.018577) (xy 44.793884 -290.001125) (xy 44.751263 -289.976518)
			(xy 44.713142 -289.945393) (xy 44.680507 -289.908556) (xy 44.654204 -289.86696) (xy 44.634913 -289.821684)
			(xy 44.623136 -289.7739) (xy 44.619176 -289.724846) (xy 44.280074 -289.724846) (xy 44.279579 -289.749453)
			(xy 44.271684 -289.79803) (xy 44.2561 -289.844711) (xy 44.233229 -289.888288) (xy 44.203664 -289.927632)
			(xy 44.168171 -289.961724) (xy 44.127668 -289.98968) (xy 44.083206 -290.010778) (xy 44.035935 -290.02447)
			(xy 43.98708 -290.030402) (xy 43.937905 -290.028421) (xy 43.889686 -290.018577) (xy 43.84367 -290.001125)
			(xy 43.801049 -289.976518) (xy 43.762928 -289.945393) (xy 43.730293 -289.908556) (xy 43.70399 -289.86696)
			(xy 43.684699 -289.821684) (xy 43.672922 -289.7739) (xy 43.668962 -289.724846) (xy 43.330114 -289.724846)
			(xy 43.329619 -289.749453) (xy 43.321724 -289.79803) (xy 43.30614 -289.844711) (xy 43.283269 -289.888288)
			(xy 43.253704 -289.927632) (xy 43.218211 -289.961724) (xy 43.177708 -289.98968) (xy 43.133246 -290.010778)
			(xy 43.085975 -290.02447) (xy 43.03712 -290.030402) (xy 42.987945 -290.028421) (xy 42.939726 -290.018577)
			(xy 42.89371 -290.001125) (xy 42.851089 -289.976518) (xy 42.812968 -289.945393) (xy 42.780333 -289.908556)
			(xy 42.75403 -289.86696) (xy 42.734739 -289.821684) (xy 42.722962 -289.7739) (xy 42.719002 -289.724846)
			(xy 42.380154 -289.724846) (xy 42.379659 -289.749453) (xy 42.371764 -289.79803) (xy 42.35618 -289.844711)
			(xy 42.333309 -289.888288) (xy 42.303744 -289.927632) (xy 42.268251 -289.961724) (xy 42.227748 -289.98968)
			(xy 42.183286 -290.010778) (xy 42.136015 -290.02447) (xy 42.08716 -290.030402) (xy 42.037985 -290.028421)
			(xy 41.989766 -290.018577) (xy 41.94375 -290.001125) (xy 41.901129 -289.976518) (xy 41.863008 -289.945393)
			(xy 41.830373 -289.908556) (xy 41.80407 -289.86696) (xy 41.784779 -289.821684) (xy 41.773002 -289.7739)
			(xy 41.769042 -289.724846) (xy 41.455594 -289.724846) (xy 41.454825 -289.756776) (xy 41.442547 -289.819447)
			(xy 41.43121 -289.849306) (xy 41.427146 -289.859466) (xy 41.424442 -289.866838) (xy 41.423164 -289.88248)
			(xy 41.424606 -289.8902) (xy 41.42486 -289.890962) (xy 41.426676 -289.897795) (xy 41.433511 -289.910165)
			(xy 41.438322 -289.915346) (xy 41.884346 -290.36137) (xy 41.889394 -290.366016) (xy 41.901369 -290.372699)
			(xy 41.907968 -290.374578) (xy 41.917112 -290.377118) (xy 41.933876 -290.375594) (xy 41.94175 -290.372038)
			(xy 41.962732 -290.363225) (xy 42.006512 -290.350796) (xy 42.051584 -290.344497) (xy 42.074338 -290.344098)
			(xy 42.074846 -290.344098) (xy 42.100831 -290.344611) (xy 42.152159 -290.352747) (xy 42.201583 -290.368812)
			(xy 42.247886 -290.392411) (xy 42.289927 -290.422961) (xy 42.326672 -290.459712) (xy 42.357216 -290.501758)
			(xy 42.380808 -290.548065) (xy 42.396865 -290.597491) (xy 42.404993 -290.648821) (xy 42.405554 -290.674806)
			(xy 42.719002 -290.674806) (xy 42.722962 -290.625752) (xy 42.734739 -290.577968) (xy 42.75403 -290.532692)
			(xy 42.780333 -290.491096) (xy 42.812968 -290.454259) (xy 42.851089 -290.423134) (xy 42.89371 -290.398527)
			(xy 42.939726 -290.381075) (xy 42.987945 -290.371231) (xy 43.03712 -290.36925) (xy 43.085975 -290.375182)
			(xy 43.133246 -290.388874) (xy 43.177708 -290.409972) (xy 43.218211 -290.437928) (xy 43.253704 -290.47202)
			(xy 43.283269 -290.511364) (xy 43.30614 -290.554941) (xy 43.321724 -290.601622) (xy 43.329619 -290.650199)
			(xy 43.330114 -290.674806) (xy 43.668962 -290.674806) (xy 43.672922 -290.625752) (xy 43.684699 -290.577968)
			(xy 43.70399 -290.532692) (xy 43.730293 -290.491096) (xy 43.762928 -290.454259) (xy 43.801049 -290.423134)
			(xy 43.84367 -290.398527) (xy 43.889686 -290.381075) (xy 43.937905 -290.371231) (xy 43.98708 -290.36925)
			(xy 44.035935 -290.375182) (xy 44.083206 -290.388874) (xy 44.127668 -290.409972) (xy 44.168171 -290.437928)
			(xy 44.203664 -290.47202) (xy 44.233229 -290.511364) (xy 44.2561 -290.554941) (xy 44.271684 -290.601622)
			(xy 44.279579 -290.650199) (xy 44.280074 -290.674806) (xy 44.619176 -290.674806) (xy 44.623136 -290.625752)
			(xy 44.634913 -290.577968) (xy 44.654204 -290.532692) (xy 44.680507 -290.491096) (xy 44.713142 -290.454259)
			(xy 44.751263 -290.423134) (xy 44.793884 -290.398527) (xy 44.8399 -290.381075) (xy 44.888119 -290.371231)
			(xy 44.937294 -290.36925) (xy 44.986149 -290.375182) (xy 45.03342 -290.388874) (xy 45.077882 -290.409972)
			(xy 45.118385 -290.437928) (xy 45.153878 -290.47202) (xy 45.183443 -290.511364) (xy 45.206314 -290.554941)
			(xy 45.221898 -290.601622) (xy 45.229793 -290.650199) (xy 45.230288 -290.674806) (xy 45.569136 -290.674806)
			(xy 45.573096 -290.625752) (xy 45.584873 -290.577968) (xy 45.604164 -290.532692) (xy 45.630467 -290.491096)
			(xy 45.663102 -290.454259) (xy 45.701223 -290.423134) (xy 45.743844 -290.398527) (xy 45.78986 -290.381075)
			(xy 45.838079 -290.371231) (xy 45.887254 -290.36925) (xy 45.936109 -290.375182) (xy 45.98338 -290.388874)
			(xy 46.027842 -290.409972) (xy 46.068345 -290.437928) (xy 46.103838 -290.47202) (xy 46.133403 -290.511364)
			(xy 46.156274 -290.554941) (xy 46.171858 -290.601622) (xy 46.179753 -290.650199) (xy 46.180248 -290.674806)
			(xy 46.519096 -290.674806) (xy 46.523056 -290.625752) (xy 46.534833 -290.577968) (xy 46.554124 -290.532692)
			(xy 46.580427 -290.491096) (xy 46.613062 -290.454259) (xy 46.651183 -290.423134) (xy 46.693804 -290.398527)
			(xy 46.73982 -290.381075) (xy 46.788039 -290.371231) (xy 46.837214 -290.36925) (xy 46.886069 -290.375182)
			(xy 46.93334 -290.388874) (xy 46.977802 -290.409972) (xy 47.018305 -290.437928) (xy 47.053798 -290.47202)
			(xy 47.083363 -290.511364) (xy 47.106234 -290.554941) (xy 47.121818 -290.601622) (xy 47.129713 -290.650199)
			(xy 47.130208 -290.674806) (xy 47.129713 -290.699413) (xy 47.121818 -290.74799) (xy 47.106234 -290.794671)
			(xy 47.083363 -290.838248) (xy 47.053798 -290.877592) (xy 47.018305 -290.911684) (xy 46.977802 -290.93964)
			(xy 46.93334 -290.960738) (xy 46.886069 -290.97443) (xy 46.837214 -290.980362) (xy 46.788039 -290.978381)
			(xy 46.73982 -290.968537) (xy 46.693804 -290.951085) (xy 46.651183 -290.926478) (xy 46.613062 -290.895353)
			(xy 46.580427 -290.858516) (xy 46.554124 -290.81692) (xy 46.534833 -290.771644) (xy 46.523056 -290.72386)
			(xy 46.519096 -290.674806) (xy 46.180248 -290.674806) (xy 46.179753 -290.699413) (xy 46.171858 -290.74799)
			(xy 46.156274 -290.794671) (xy 46.133403 -290.838248) (xy 46.103838 -290.877592) (xy 46.068345 -290.911684)
			(xy 46.027842 -290.93964) (xy 45.98338 -290.960738) (xy 45.936109 -290.97443) (xy 45.887254 -290.980362)
			(xy 45.838079 -290.978381) (xy 45.78986 -290.968537) (xy 45.743844 -290.951085) (xy 45.701223 -290.926478)
			(xy 45.663102 -290.895353) (xy 45.630467 -290.858516) (xy 45.604164 -290.81692) (xy 45.584873 -290.771644)
			(xy 45.573096 -290.72386) (xy 45.569136 -290.674806) (xy 45.230288 -290.674806) (xy 45.229793 -290.699413)
			(xy 45.221898 -290.74799) (xy 45.206314 -290.794671) (xy 45.183443 -290.838248) (xy 45.153878 -290.877592)
			(xy 45.118385 -290.911684) (xy 45.077882 -290.93964) (xy 45.03342 -290.960738) (xy 44.986149 -290.97443)
			(xy 44.937294 -290.980362) (xy 44.888119 -290.978381) (xy 44.8399 -290.968537) (xy 44.793884 -290.951085)
			(xy 44.751263 -290.926478) (xy 44.713142 -290.895353) (xy 44.680507 -290.858516) (xy 44.654204 -290.81692)
			(xy 44.634913 -290.771644) (xy 44.623136 -290.72386) (xy 44.619176 -290.674806) (xy 44.280074 -290.674806)
			(xy 44.279579 -290.699413) (xy 44.271684 -290.74799) (xy 44.2561 -290.794671) (xy 44.233229 -290.838248)
			(xy 44.203664 -290.877592) (xy 44.168171 -290.911684) (xy 44.127668 -290.93964) (xy 44.083206 -290.960738)
			(xy 44.035935 -290.97443) (xy 43.98708 -290.980362) (xy 43.937905 -290.978381) (xy 43.889686 -290.968537)
			(xy 43.84367 -290.951085) (xy 43.801049 -290.926478) (xy 43.762928 -290.895353) (xy 43.730293 -290.858516)
			(xy 43.70399 -290.81692) (xy 43.684699 -290.771644) (xy 43.672922 -290.72386) (xy 43.668962 -290.674806)
			(xy 43.330114 -290.674806) (xy 43.329619 -290.699413) (xy 43.321724 -290.74799) (xy 43.30614 -290.794671)
			(xy 43.283269 -290.838248) (xy 43.253704 -290.877592) (xy 43.218211 -290.911684) (xy 43.177708 -290.93964)
			(xy 43.133246 -290.960738) (xy 43.085975 -290.97443) (xy 43.03712 -290.980362) (xy 42.987945 -290.978381)
			(xy 42.939726 -290.968537) (xy 42.89371 -290.951085) (xy 42.851089 -290.926478) (xy 42.812968 -290.895353)
			(xy 42.780333 -290.858516) (xy 42.75403 -290.81692) (xy 42.734739 -290.771644) (xy 42.722962 -290.72386)
			(xy 42.719002 -290.674806) (xy 42.405554 -290.674806) (xy 42.404789 -290.706737) (xy 42.392517 -290.76941)
			(xy 42.38117 -290.799266) (xy 42.377106 -290.809426) (xy 42.374393 -290.816797) (xy 42.373102 -290.832443)
			(xy 42.374566 -290.84016) (xy 42.37482 -290.840922) (xy 42.376634 -290.847756) (xy 42.383468 -290.860127)
			(xy 42.388282 -290.865306) (xy 42.834306 -291.31133) (xy 42.83935 -291.315983) (xy 42.851322 -291.32268)
			(xy 42.857928 -291.324538) (xy 42.867072 -291.327078) (xy 42.883836 -291.325554) (xy 42.89171 -291.321998)
			(xy 42.912693 -291.31319) (xy 42.956474 -291.30077) (xy 43.001545 -291.29448) (xy 43.024298 -291.294058)
			(xy 43.024806 -291.294058) (xy 43.050794 -291.294568) (xy 43.10213 -291.302699) (xy 43.151562 -291.31876)
			(xy 43.197873 -291.342356) (xy 43.239923 -291.372905) (xy 43.276677 -291.409656) (xy 43.30723 -291.451703)
			(xy 43.330829 -291.498013) (xy 43.346894 -291.547443) (xy 43.35503 -291.598778) (xy 43.355514 -291.624766)
			(xy 43.668962 -291.624766) (xy 43.672922 -291.575712) (xy 43.684699 -291.527928) (xy 43.70399 -291.482652)
			(xy 43.730293 -291.441056) (xy 43.762928 -291.404219) (xy 43.801049 -291.373094) (xy 43.84367 -291.348487)
			(xy 43.889686 -291.331035) (xy 43.937905 -291.321191) (xy 43.98708 -291.31921) (xy 44.035935 -291.325142)
			(xy 44.083206 -291.338834) (xy 44.127668 -291.359932) (xy 44.168171 -291.387888) (xy 44.203664 -291.42198)
			(xy 44.233229 -291.461324) (xy 44.2561 -291.504901) (xy 44.271684 -291.551582) (xy 44.279579 -291.600159)
			(xy 44.280074 -291.624766) (xy 44.619176 -291.624766) (xy 44.623136 -291.575712) (xy 44.634913 -291.527928)
			(xy 44.654204 -291.482652) (xy 44.680507 -291.441056) (xy 44.713142 -291.404219) (xy 44.751263 -291.373094)
			(xy 44.793884 -291.348487) (xy 44.8399 -291.331035) (xy 44.888119 -291.321191) (xy 44.937294 -291.31921)
			(xy 44.986149 -291.325142) (xy 45.03342 -291.338834) (xy 45.077882 -291.359932) (xy 45.118385 -291.387888)
			(xy 45.153878 -291.42198) (xy 45.183443 -291.461324) (xy 45.206314 -291.504901) (xy 45.221898 -291.551582)
			(xy 45.229793 -291.600159) (xy 45.230288 -291.624766) (xy 45.569136 -291.624766) (xy 45.573096 -291.575712)
			(xy 45.584873 -291.527928) (xy 45.604164 -291.482652) (xy 45.630467 -291.441056) (xy 45.663102 -291.404219)
			(xy 45.701223 -291.373094) (xy 45.743844 -291.348487) (xy 45.78986 -291.331035) (xy 45.838079 -291.321191)
			(xy 45.887254 -291.31921) (xy 45.936109 -291.325142) (xy 45.98338 -291.338834) (xy 46.027842 -291.359932)
			(xy 46.068345 -291.387888) (xy 46.103838 -291.42198) (xy 46.133403 -291.461324) (xy 46.156274 -291.504901)
			(xy 46.171858 -291.551582) (xy 46.179753 -291.600159) (xy 46.180248 -291.624766) (xy 46.179753 -291.649373)
			(xy 46.171858 -291.69795) (xy 46.156274 -291.744631) (xy 46.133403 -291.788208) (xy 46.103838 -291.827552)
			(xy 46.068345 -291.861644) (xy 46.027842 -291.8896) (xy 45.98338 -291.910698) (xy 45.936109 -291.92439)
			(xy 45.887254 -291.930322) (xy 45.838079 -291.928341) (xy 45.78986 -291.918497) (xy 45.743844 -291.901045)
			(xy 45.701223 -291.876438) (xy 45.663102 -291.845313) (xy 45.630467 -291.808476) (xy 45.604164 -291.76688)
			(xy 45.584873 -291.721604) (xy 45.573096 -291.67382) (xy 45.569136 -291.624766) (xy 45.230288 -291.624766)
			(xy 45.229793 -291.649373) (xy 45.221898 -291.69795) (xy 45.206314 -291.744631) (xy 45.183443 -291.788208)
			(xy 45.153878 -291.827552) (xy 45.118385 -291.861644) (xy 45.077882 -291.8896) (xy 45.03342 -291.910698)
			(xy 44.986149 -291.92439) (xy 44.937294 -291.930322) (xy 44.888119 -291.928341) (xy 44.8399 -291.918497)
			(xy 44.793884 -291.901045) (xy 44.751263 -291.876438) (xy 44.713142 -291.845313) (xy 44.680507 -291.808476)
			(xy 44.654204 -291.76688) (xy 44.634913 -291.721604) (xy 44.623136 -291.67382) (xy 44.619176 -291.624766)
			(xy 44.280074 -291.624766) (xy 44.279579 -291.649373) (xy 44.271684 -291.69795) (xy 44.2561 -291.744631)
			(xy 44.233229 -291.788208) (xy 44.203664 -291.827552) (xy 44.168171 -291.861644) (xy 44.127668 -291.8896)
			(xy 44.083206 -291.910698) (xy 44.035935 -291.92439) (xy 43.98708 -291.930322) (xy 43.937905 -291.928341)
			(xy 43.889686 -291.918497) (xy 43.84367 -291.901045) (xy 43.801049 -291.876438) (xy 43.762928 -291.845313)
			(xy 43.730293 -291.808476) (xy 43.70399 -291.76688) (xy 43.684699 -291.721604) (xy 43.672922 -291.67382)
			(xy 43.668962 -291.624766) (xy 43.355514 -291.624766) (xy 43.354743 -291.656696) (xy 43.342459 -291.719364)
			(xy 43.33113 -291.749226) (xy 43.327066 -291.759386) (xy 43.324349 -291.766757) (xy 43.323047 -291.782405)
			(xy 43.324526 -291.79012) (xy 43.32478 -291.790882) (xy 43.326588 -291.79772) (xy 43.333411 -291.810102)
			(xy 43.338242 -291.815266) (xy 43.780456 -292.25748) (xy 43.787857 -292.26432) (xy 43.806455 -292.272037)
			(xy 43.816524 -292.272466) (xy 43.840908 -292.272466) (xy 43.850052 -292.268656) (xy 43.879968 -292.257285)
			(xy 43.94277 -292.245012) (xy 43.974766 -292.244272) (xy 44.000758 -292.244753) (xy 44.052101 -292.252879)
			(xy 44.101542 -292.268938) (xy 44.147861 -292.292534) (xy 44.189919 -292.323085) (xy 44.22668 -292.35984)
			(xy 44.257238 -292.401893) (xy 44.280841 -292.448208) (xy 44.296908 -292.497646) (xy 44.305043 -292.548988)
			(xy 44.305474 -292.57498) (xy 44.619176 -292.57498) (xy 44.623136 -292.525926) (xy 44.634913 -292.478142)
			(xy 44.654204 -292.432866) (xy 44.680507 -292.39127) (xy 44.713142 -292.354433) (xy 44.751263 -292.323308)
			(xy 44.793884 -292.298701) (xy 44.8399 -292.281249) (xy 44.888119 -292.271405) (xy 44.937294 -292.269424)
			(xy 44.986149 -292.275356) (xy 45.03342 -292.289048) (xy 45.077882 -292.310146) (xy 45.118385 -292.338102)
			(xy 45.153878 -292.372194) (xy 45.183443 -292.411538) (xy 45.206314 -292.455115) (xy 45.221898 -292.501796)
			(xy 45.229793 -292.550373) (xy 45.230288 -292.57498) (xy 45.569136 -292.57498) (xy 45.573096 -292.525926)
			(xy 45.584873 -292.478142) (xy 45.604164 -292.432866) (xy 45.630467 -292.39127) (xy 45.663102 -292.354433)
			(xy 45.701223 -292.323308) (xy 45.743844 -292.298701) (xy 45.78986 -292.281249) (xy 45.838079 -292.271405)
			(xy 45.887254 -292.269424) (xy 45.936109 -292.275356) (xy 45.98338 -292.289048) (xy 46.027842 -292.310146)
			(xy 46.068345 -292.338102) (xy 46.103838 -292.372194) (xy 46.133403 -292.411538) (xy 46.156274 -292.455115)
			(xy 46.171858 -292.501796) (xy 46.179753 -292.550373) (xy 46.180248 -292.57498) (xy 46.519096 -292.57498)
			(xy 46.523056 -292.525926) (xy 46.534833 -292.478142) (xy 46.554124 -292.432866) (xy 46.580427 -292.39127)
			(xy 46.613062 -292.354433) (xy 46.651183 -292.323308) (xy 46.693804 -292.298701) (xy 46.73982 -292.281249)
			(xy 46.788039 -292.271405) (xy 46.837214 -292.269424) (xy 46.886069 -292.275356) (xy 46.93334 -292.289048)
			(xy 46.977802 -292.310146) (xy 47.018305 -292.338102) (xy 47.053798 -292.372194) (xy 47.083363 -292.411538)
			(xy 47.106234 -292.455115) (xy 47.121818 -292.501796) (xy 47.129713 -292.550373) (xy 47.130208 -292.57498)
			(xy 47.129713 -292.599587) (xy 47.121818 -292.648164) (xy 47.106234 -292.694845) (xy 47.083363 -292.738422)
			(xy 47.053798 -292.777766) (xy 47.018305 -292.811858) (xy 46.977802 -292.839814) (xy 46.93334 -292.860912)
			(xy 46.886069 -292.874604) (xy 46.837214 -292.880536) (xy 46.788039 -292.878555) (xy 46.73982 -292.868711)
			(xy 46.693804 -292.851259) (xy 46.651183 -292.826652) (xy 46.613062 -292.795527) (xy 46.580427 -292.75869)
			(xy 46.554124 -292.717094) (xy 46.534833 -292.671818) (xy 46.523056 -292.624034) (xy 46.519096 -292.57498)
			(xy 46.180248 -292.57498) (xy 46.179753 -292.599587) (xy 46.171858 -292.648164) (xy 46.156274 -292.694845)
			(xy 46.133403 -292.738422) (xy 46.103838 -292.777766) (xy 46.068345 -292.811858) (xy 46.027842 -292.839814)
			(xy 45.98338 -292.860912) (xy 45.936109 -292.874604) (xy 45.887254 -292.880536) (xy 45.838079 -292.878555)
			(xy 45.78986 -292.868711) (xy 45.743844 -292.851259) (xy 45.701223 -292.826652) (xy 45.663102 -292.795527)
			(xy 45.630467 -292.75869) (xy 45.604164 -292.717094) (xy 45.584873 -292.671818) (xy 45.573096 -292.624034)
			(xy 45.569136 -292.57498) (xy 45.230288 -292.57498) (xy 45.229793 -292.599587) (xy 45.221898 -292.648164)
			(xy 45.206314 -292.694845) (xy 45.183443 -292.738422) (xy 45.153878 -292.777766) (xy 45.118385 -292.811858)
			(xy 45.077882 -292.839814) (xy 45.03342 -292.860912) (xy 44.986149 -292.874604) (xy 44.937294 -292.880536)
			(xy 44.888119 -292.878555) (xy 44.8399 -292.868711) (xy 44.793884 -292.851259) (xy 44.751263 -292.826652)
			(xy 44.713142 -292.795527) (xy 44.680507 -292.75869) (xy 44.654204 -292.717094) (xy 44.634913 -292.671818)
			(xy 44.623136 -292.624034) (xy 44.619176 -292.57498) (xy 44.305474 -292.57498) (xy 44.305066 -292.597869)
			(xy 44.298711 -292.643205) (xy 44.286161 -292.68723) (xy 44.27728 -292.70833) (xy 44.27093 -292.722808)
			(xy 44.276772 -292.753796) (xy 45.351192 -293.828216) (xy 45.358037 -293.835615) (xy 45.365767 -293.854213)
			(xy 45.366178 -293.864284) (xy 45.366178 -293.894002) (xy 45.366601 -293.904073) (xy 45.374313 -293.922679)
			(xy 45.381164 -293.93007) (xy 45.392848 -293.941754) (xy 45.393356 -293.942262) (xy 45.400738 -293.948843)
			(xy 45.419037 -293.956291) (xy 45.428916 -293.95674)
		)
		(stroke
			(width 0)
			(type solid)
		)
		(fill yes)
		(layer "In7.Cu")
		(net "PCEPLL5_VDDA18_PEX0")
	)
	(gr_poly
		(pts
			(xy 277.79599 -293.95674) (xy 277.806087 -293.956252) (xy 277.82469 -293.948378) (xy 277.838834 -293.933955)
			(xy 277.84298 -293.924736) (xy 277.87219 -293.844726) (xy 277.876762 -293.832026) (xy 277.878877 -293.824972)
			(xy 277.879381 -293.810259) (xy 277.877778 -293.80307) (xy 277.875746 -293.795958) (xy 277.867618 -293.783004)
			(xy 277.861268 -293.77767) (xy 277.843273 -293.761865) (xy 277.811576 -293.725962) (xy 277.785378 -293.68587)
			(xy 277.765226 -293.642423) (xy 277.751538 -293.596528) (xy 277.744601 -293.54914) (xy 277.744174 -293.525194)
			(xy 277.744174 -293.52494) (xy 277.744684 -293.498953) (xy 277.752814 -293.447618) (xy 277.768875 -293.398188)
			(xy 277.792471 -293.351878) (xy 277.823021 -293.30983) (xy 277.859772 -293.273079) (xy 277.90182 -293.242529)
			(xy 277.94813 -293.218933) (xy 277.99756 -293.202872) (xy 278.048895 -293.194742) (xy 278.100869 -293.194742)
			(xy 278.152204 -293.202872) (xy 278.201634 -293.218933) (xy 278.247944 -293.242529) (xy 278.289992 -293.273079)
			(xy 278.326743 -293.30983) (xy 278.357293 -293.351878) (xy 278.380889 -293.398188) (xy 278.39695 -293.447618)
			(xy 278.40508 -293.498953) (xy 278.40559 -293.52494) (xy 278.40559 -293.525194) (xy 278.405 -293.553233)
			(xy 278.395542 -293.608509) (xy 278.376897 -293.661397) (xy 278.349598 -293.710383) (xy 278.314428 -293.754063)
			(xy 278.29383 -293.773098) (xy 278.288242 -293.777924) (xy 278.271986 -293.803578) (xy 278.269954 -293.81069)
			(xy 278.270208 -293.81831) (xy 278.27052 -293.822214) (xy 278.272181 -293.829866) (xy 278.27351 -293.83355)
			(xy 278.277574 -293.844726) (xy 278.306784 -293.924736) (xy 278.310924 -293.93396) (xy 278.32506 -293.948391)
			(xy 278.343674 -293.956241) (xy 278.353774 -293.95674) (xy 278.74595 -293.95674) (xy 278.756052 -293.956259)
			(xy 278.774667 -293.948393) (xy 278.788823 -293.933972) (xy 278.79294 -293.924736) (xy 278.82215 -293.844726)
			(xy 278.826722 -293.832026) (xy 278.828835 -293.824971) (xy 278.829338 -293.81026) (xy 278.827738 -293.80307)
			(xy 278.825706 -293.795958) (xy 278.817578 -293.783004) (xy 278.811228 -293.77767) (xy 278.79323 -293.761867)
			(xy 278.761528 -293.725966) (xy 278.735325 -293.685874) (xy 278.715169 -293.642427) (xy 278.701479 -293.596531)
			(xy 278.69454 -293.549141) (xy 278.694134 -293.525194) (xy 278.694134 -293.52494) (xy 278.694644 -293.498953)
			(xy 278.702774 -293.447618) (xy 278.718835 -293.398188) (xy 278.742431 -293.351878) (xy 278.772981 -293.30983)
			(xy 278.809732 -293.273079) (xy 278.85178 -293.242529) (xy 278.89809 -293.218933) (xy 278.94752 -293.202872)
			(xy 278.998855 -293.194742) (xy 279.050829 -293.194742) (xy 279.102164 -293.202872) (xy 279.151594 -293.218933)
			(xy 279.197904 -293.242529) (xy 279.239952 -293.273079) (xy 279.276703 -293.30983) (xy 279.307253 -293.351878)
			(xy 279.330849 -293.398188) (xy 279.34691 -293.447618) (xy 279.35504 -293.498953) (xy 279.35555 -293.52494)
			(xy 279.35555 -293.525194) (xy 279.35496 -293.553234) (xy 279.345504 -293.608511) (xy 279.326861 -293.661402)
			(xy 279.299565 -293.710391) (xy 279.264399 -293.754075) (xy 279.24379 -293.773098) (xy 279.238202 -293.777924)
			(xy 279.221946 -293.803578) (xy 279.219914 -293.81069) (xy 279.220168 -293.81831) (xy 279.220481 -293.822213)
			(xy 279.222144 -293.829865) (xy 279.22347 -293.83355) (xy 279.227534 -293.844726) (xy 279.256744 -293.924736)
			(xy 279.260882 -293.933964) (xy 279.275016 -293.948407) (xy 279.293631 -293.956271) (xy 279.303734 -293.95674)
			(xy 279.918922 -293.95674) (xy 279.92832 -293.955724) (xy 279.928828 -293.955724) (xy 279.935985 -293.954015)
			(xy 279.949005 -293.947176) (xy 279.954482 -293.942262) (xy 280.058114 -293.83863) (xy 280.063956 -293.831772)
			(xy 280.071838 -293.820641) (xy 280.089259 -293.799653) (xy 280.098754 -293.789862) (xy 280.16835 -293.720012)
			(xy 280.2001 -293.688262) (xy 280.202132 -293.685468) (xy 280.203402 -293.684706) (xy 280.208228 -293.679626)
			(xy 280.212134 -293.673795) (xy 280.21653 -293.660475) (xy 280.216864 -293.653464) (xy 280.216864 -292.98138)
			(xy 280.216656 -292.975281) (xy 280.213318 -292.963546) (xy 280.21026 -292.958266) (xy 280.206196 -292.952932)
			(xy 280.205942 -292.952424) (xy 280.200608 -292.94709) (xy 280.199338 -292.946074) (xy 280.196036 -292.943788)
			(xy 280.182574 -292.93439) (xy 280.179272 -292.93185) (xy 280.163778 -292.921182) (xy 280.162762 -292.920674)
			(xy 280.153618 -292.91407) (xy 280.137362 -292.902386) (xy 280.115518 -292.884606) (xy 280.110438 -292.88359)
			(xy 280.098246 -292.882066) (xy 280.09088 -292.884606) (xy 280.062988 -292.894375) (xy 280.004855 -292.904983)
			(xy 279.97531 -292.905688) (xy 279.974802 -292.905688) (xy 279.948814 -292.905205) (xy 279.897478 -292.897075)
			(xy 279.848047 -292.881013) (xy 279.801736 -292.857417) (xy 279.759687 -292.826867) (xy 279.722934 -292.790115)
			(xy 279.692384 -292.748066) (xy 279.668787 -292.701755) (xy 279.652726 -292.652323) (xy 279.644595 -292.600988)
			(xy 279.644595 -292.549012) (xy 279.652726 -292.497677) (xy 279.668787 -292.448245) (xy 279.692384 -292.401934)
			(xy 279.722934 -292.359885) (xy 279.759687 -292.323133) (xy 279.801736 -292.292583) (xy 279.848047 -292.268987)
			(xy 279.897478 -292.252925) (xy 279.948814 -292.244795) (xy 279.974802 -292.244272) (xy 279.97531 -292.244272)
			(xy 280.004857 -292.244966) (xy 280.062993 -292.255566) (xy 280.09088 -292.265354) (xy 280.098246 -292.267894)
			(xy 280.110438 -292.26637) (xy 280.110946 -292.26637) (xy 280.11247 -292.264846) (xy 280.148792 -292.239192)
			(xy 280.149808 -292.238684) (xy 280.199592 -292.20414) (xy 280.203148 -292.200584) (xy 280.203656 -292.200076)
			(xy 280.206704 -292.196774) (xy 280.21091 -292.191293) (xy 280.21609 -292.178493) (xy 280.216864 -292.171628)
			(xy 280.216864 -292.031166) (xy 280.216654 -292.025067) (xy 280.213313 -292.013335) (xy 280.21026 -292.008052)
			(xy 280.206704 -292.003226) (xy 280.199846 -291.996368) (xy 280.199338 -291.99586) (xy 280.196036 -291.993574)
			(xy 280.182574 -291.984176) (xy 280.179272 -291.981636) (xy 280.163778 -291.970968) (xy 280.162762 -291.97046)
			(xy 280.153618 -291.963856) (xy 280.137362 -291.952172) (xy 280.115518 -291.934392) (xy 280.110438 -291.933376)
			(xy 280.098246 -291.931852) (xy 280.09088 -291.934392) (xy 280.062987 -291.944159) (xy 280.004855 -291.954764)
			(xy 279.97531 -291.955474) (xy 279.974802 -291.955474) (xy 279.948815 -291.954991) (xy 279.897482 -291.946861)
			(xy 279.848052 -291.930801) (xy 279.801743 -291.907205) (xy 279.759696 -291.876656) (xy 279.722945 -291.839906)
			(xy 279.692396 -291.797858) (xy 279.6688 -291.75155) (xy 279.652739 -291.70212) (xy 279.644609 -291.650787)
			(xy 279.644609 -291.598813) (xy 279.652739 -291.54748) (xy 279.6688 -291.49805) (xy 279.692396 -291.451742)
			(xy 279.722945 -291.409694) (xy 279.759696 -291.372944) (xy 279.801743 -291.342395) (xy 279.848052 -291.318799)
			(xy 279.897482 -291.302739) (xy 279.948815 -291.294609) (xy 279.974802 -291.294058) (xy 279.97531 -291.294058)
			(xy 280.004857 -291.294752) (xy 280.062993 -291.305351) (xy 280.09088 -291.31514) (xy 280.098246 -291.31768)
			(xy 280.110438 -291.316156) (xy 280.110946 -291.316156) (xy 280.11247 -291.314632) (xy 280.148792 -291.288978)
			(xy 280.149808 -291.28847) (xy 280.199592 -291.253926) (xy 280.203148 -291.25037) (xy 280.203656 -291.249862)
			(xy 280.206704 -291.24656) (xy 280.210908 -291.241078) (xy 280.216084 -291.228278) (xy 280.216864 -291.221414)
			(xy 280.216864 -291.081206) (xy 280.216647 -291.07511) (xy 280.213292 -291.063386) (xy 280.21026 -291.058092)
			(xy 280.206704 -291.053266) (xy 280.199846 -291.046408) (xy 280.199338 -291.0459) (xy 280.196036 -291.043614)
			(xy 280.182574 -291.034216) (xy 280.179272 -291.031676) (xy 280.163778 -291.021008) (xy 280.162762 -291.0205)
			(xy 280.153618 -291.013896) (xy 280.137362 -291.002212) (xy 280.115518 -290.984432) (xy 280.110438 -290.983416)
			(xy 280.098246 -290.981892) (xy 280.09088 -290.984432) (xy 280.062988 -290.9942) (xy 280.004855 -291.004807)
			(xy 279.97531 -291.005514) (xy 279.974802 -291.005514) (xy 279.948812 -291.005031) (xy 279.897472 -290.9969)
			(xy 279.848037 -290.980838) (xy 279.801722 -290.957239) (xy 279.75967 -290.926687) (xy 279.722915 -290.889932)
			(xy 279.692362 -290.847879) (xy 279.668763 -290.801565) (xy 279.652701 -290.75213) (xy 279.644569 -290.70079)
			(xy 279.644569 -290.64881) (xy 279.652701 -290.59747) (xy 279.668763 -290.548035) (xy 279.692362 -290.501721)
			(xy 279.722915 -290.459668) (xy 279.75967 -290.422913) (xy 279.801722 -290.392361) (xy 279.848037 -290.368762)
			(xy 279.897472 -290.3527) (xy 279.948812 -290.344569) (xy 279.974802 -290.344098) (xy 279.97531 -290.344098)
			(xy 280.004857 -290.344792) (xy 280.062993 -290.355393) (xy 280.09088 -290.36518) (xy 280.098246 -290.36772)
			(xy 280.110438 -290.366196) (xy 280.110946 -290.366196) (xy 280.11247 -290.364672) (xy 280.148792 -290.339018)
			(xy 280.149808 -290.33851) (xy 280.199592 -290.303966) (xy 280.203148 -290.30041) (xy 280.203656 -290.299902)
			(xy 280.206704 -290.2966) (xy 280.210913 -290.29112) (xy 280.2161 -290.27832) (xy 280.216864 -290.271454)
			(xy 280.216864 -290.186364) (xy 280.217591 -290.181609) (xy 280.217197 -290.171999) (xy 280.216102 -290.167314)
			(xy 280.215594 -290.165536) (xy 280.21534 -290.165028) (xy 280.214578 -290.161726) (xy 280.214324 -290.161472)
			(xy 280.213816 -290.160202) (xy 280.213308 -290.158424) (xy 280.213054 -290.157916) (xy 280.212546 -290.157154)
			(xy 280.211022 -290.154106) (xy 280.209498 -290.151566) (xy 280.203402 -290.143946) (xy 280.100786 -290.041584)
			(xy 280.100278 -290.04133) (xy 280.091134 -290.039044) (xy 280.077418 -290.039298) (xy 280.070814 -290.04133)
			(xy 280.047434 -290.047975) (xy 279.999358 -290.055116) (xy 279.975056 -290.055554) (xy 279.974802 -290.055554)
			(xy 279.948813 -290.055045) (xy 279.897476 -290.046915) (xy 279.848042 -290.030854) (xy 279.801729 -290.007259)
			(xy 279.759677 -289.97671) (xy 279.722921 -289.93996) (xy 279.692366 -289.897912) (xy 279.668764 -289.851602)
			(xy 279.652697 -289.802171) (xy 279.644559 -289.750835) (xy 279.644094 -289.724846) (xy 279.644094 -289.724592)
			(xy 279.644542 -289.700291) (xy 279.651681 -289.652215) (xy 279.658318 -289.628834) (xy 279.66035 -289.62223)
			(xy 279.660604 -289.608514) (xy 279.658572 -289.600894) (xy 279.656656 -289.594578) (xy 279.650107 -289.583125)
			(xy 279.645618 -289.578288) (xy 279.1714 -289.10407) (xy 279.166582 -289.099553) (xy 279.155126 -289.092993)
			(xy 279.148794 -289.091116) (xy 279.141174 -289.089084) (xy 279.127458 -289.089338) (xy 279.120854 -289.09137)
			(xy 279.097474 -289.098017) (xy 279.049398 -289.105163) (xy 279.025096 -289.105594) (xy 279.024842 -289.105594)
			(xy 278.998851 -289.105114) (xy 278.947508 -289.096988) (xy 278.898069 -289.080929) (xy 278.851751 -289.057333)
			(xy 278.809695 -289.026782) (xy 278.772936 -288.990027) (xy 278.742381 -288.947973) (xy 278.718782 -288.901657)
			(xy 278.702719 -288.852219) (xy 278.694588 -288.800877) (xy 278.694134 -288.774886) (xy 278.694134 -288.774632)
			(xy 278.694586 -288.750332) (xy 278.701732 -288.702258) (xy 278.708358 -288.678874) (xy 278.71039 -288.67227)
			(xy 278.710644 -288.658554) (xy 278.708612 -288.650934) (xy 278.706688 -288.644624) (xy 278.700124 -288.633185)
			(xy 278.695658 -288.628328) (xy 278.22144 -288.15411) (xy 278.216621 -288.149595) (xy 278.205163 -288.143043)
			(xy 278.198834 -288.141156) (xy 278.191214 -288.139124) (xy 278.177498 -288.139378) (xy 278.170894 -288.14141)
			(xy 278.147514 -288.148054) (xy 278.099438 -288.155192) (xy 278.075136 -288.155634) (xy 278.074882 -288.155634)
			(xy 278.048895 -288.155123) (xy 277.997561 -288.14699) (xy 277.948131 -288.130928) (xy 277.901822 -288.107332)
			(xy 277.859775 -288.076782) (xy 277.823023 -288.040031) (xy 277.792472 -287.997984) (xy 277.768875 -287.951676)
			(xy 277.752811 -287.902247) (xy 277.744677 -287.850913) (xy 277.744174 -287.824926) (xy 277.744174 -287.824672)
			(xy 277.744623 -287.800371) (xy 277.751765 -287.752296) (xy 277.758398 -287.728914) (xy 277.76043 -287.72231)
			(xy 277.760684 -287.708594) (xy 277.758652 -287.700974) (xy 277.756734 -287.69466) (xy 277.75018 -287.683211)
			(xy 277.745698 -287.678368) (xy 277.27148 -287.20415) (xy 277.266665 -287.199629) (xy 277.25521 -287.193062)
			(xy 277.248874 -287.191196) (xy 277.241254 -287.189164) (xy 277.227538 -287.189418) (xy 277.220934 -287.19145)
			(xy 277.197554 -287.198096) (xy 277.149478 -287.205239) (xy 277.125176 -287.205674) (xy 277.124922 -287.205674)
			(xy 277.098933 -287.205192) (xy 277.047593 -287.197064) (xy 276.998158 -287.181003) (xy 276.951844 -287.157406)
			(xy 276.909793 -287.126853) (xy 276.873039 -287.090098) (xy 276.842488 -287.048045) (xy 276.818892 -287.001731)
			(xy 276.802833 -286.952295) (xy 276.794707 -286.900955) (xy 276.794214 -286.874966) (xy 276.794214 -286.874712)
			(xy 276.79466 -286.850411) (xy 276.801795 -286.802334) (xy 276.808438 -286.778954) (xy 276.81047 -286.77235)
			(xy 276.810724 -286.758634) (xy 276.808692 -286.751014) (xy 276.806765 -286.744705) (xy 276.800196 -286.733271)
			(xy 276.795738 -286.728408) (xy 275.371306 -285.303976) (xy 275.366489 -285.299458) (xy 275.355033 -285.292895)
			(xy 275.3487 -285.291022) (xy 275.34108 -285.28899) (xy 275.327364 -285.289244) (xy 275.32076 -285.291276)
			(xy 275.297381 -285.297923) (xy 275.249304 -285.30507) (xy 275.225002 -285.3055) (xy 275.224748 -285.3055)
			(xy 275.198756 -285.30502) (xy 275.147413 -285.296895) (xy 275.097972 -285.280837) (xy 275.051653 -285.257242)
			(xy 275.009595 -285.22669) (xy 274.972836 -285.189935) (xy 274.942279 -285.147881) (xy 274.918678 -285.101565)
			(xy 274.902614 -285.052126) (xy 274.894483 -285.000783) (xy 274.89404 -284.974792) (xy 274.89404 -284.974538)
			(xy 274.894492 -284.950238) (xy 274.901637 -284.902164) (xy 274.908264 -284.87878) (xy 274.910296 -284.872176)
			(xy 274.91055 -284.85846) (xy 274.908518 -284.85084) (xy 274.906595 -284.844529) (xy 274.900032 -284.833088)
			(xy 274.895564 -284.828234) (xy 274.421346 -284.354016) (xy 274.416528 -284.3495) (xy 274.40507 -284.342946)
			(xy 274.39874 -284.341062) (xy 274.39112 -284.33903) (xy 274.377404 -284.339284) (xy 274.3708 -284.341316)
			(xy 274.34742 -284.34796) (xy 274.299344 -284.355099) (xy 274.275042 -284.35554) (xy 274.274788 -284.35554)
			(xy 274.248801 -284.35503) (xy 274.197466 -284.346898) (xy 274.148035 -284.330836) (xy 274.101724 -284.30724)
			(xy 274.059675 -284.276691) (xy 274.022922 -284.23994) (xy 273.99237 -284.197893) (xy 273.968772 -284.151584)
			(xy 273.952707 -284.102154) (xy 273.944572 -284.050819) (xy 273.94408 -284.024832) (xy 273.944527 -283.999948)
			(xy 273.951979 -283.950742) (xy 273.966721 -283.903207) (xy 273.988418 -283.858418) (xy 274.016581 -283.817386)
			(xy 274.050574 -283.781037) (xy 274.06981 -283.765244) (xy 274.076668 -283.759656) (xy 274.0914 -283.730192)
			(xy 274.093864 -283.724867) (xy 274.096565 -283.713451) (xy 274.096734 -283.707586) (xy 274.096734 -283.392118)
			(xy 274.096579 -283.386251) (xy 274.093877 -283.374833) (xy 274.0914 -283.369512) (xy 274.076668 -283.340048)
			(xy 274.06981 -283.334206) (xy 274.050598 -283.318433) (xy 274.016676 -283.282103) (xy 273.988573 -283.241104)
			(xy 273.966923 -283.196361) (xy 273.952213 -283.148882) (xy 273.944776 -283.099736) (xy 273.944779 -283.05003)
			(xy 273.952221 -283.000884) (xy 273.966935 -282.953406) (xy 273.98859 -282.908666) (xy 274.016697 -282.86767)
			(xy 274.050624 -282.831343) (xy 274.06981 -282.815538) (xy 274.076668 -282.809696) (xy 274.0914 -282.780232)
			(xy 274.093858 -282.774906) (xy 274.096545 -282.76349) (xy 274.096734 -282.757626) (xy 274.096734 -282.442158)
			(xy 274.096584 -282.43629) (xy 274.093889 -282.424868) (xy 274.0914 -282.419552) (xy 274.076668 -282.390088)
			(xy 274.06981 -282.384246) (xy 274.050595 -282.368473) (xy 274.016667 -282.332142) (xy 273.988558 -282.291141)
			(xy 273.966903 -282.246396) (xy 273.952188 -282.198913) (xy 273.944747 -282.149763) (xy 273.944746 -282.100052)
			(xy 273.952185 -282.050902) (xy 273.966897 -282.003418) (xy 273.98855 -281.958671) (xy 274.016657 -281.91767)
			(xy 274.050584 -281.881337) (xy 274.06981 -281.865578) (xy 274.076668 -281.859736) (xy 274.0914 -281.830272)
			(xy 274.093862 -281.824946) (xy 274.096558 -281.81353) (xy 274.096734 -281.807666) (xy 274.096734 -281.492198)
			(xy 274.096588 -281.486329) (xy 274.093902 -281.474903) (xy 274.0914 -281.469592) (xy 274.076668 -281.440128)
			(xy 274.06981 -281.434286) (xy 274.0506 -281.418513) (xy 274.01668 -281.382183) (xy 273.98858 -281.341186)
			(xy 273.966933 -281.296444) (xy 273.952226 -281.248966) (xy 273.944791 -281.199822) (xy 273.944795 -281.150119)
			(xy 273.952239 -281.100976) (xy 273.966954 -281.053501) (xy 273.98861 -281.008763) (xy 274.016717 -280.96777)
			(xy 274.050644 -280.931446) (xy 274.06981 -280.915618) (xy 274.076668 -280.909776) (xy 274.0914 -280.880312)
			(xy 274.093856 -280.874985) (xy 274.096538 -280.863569) (xy 274.096734 -280.857706) (xy 274.096734 -280.541984)
			(xy 274.096587 -280.536115) (xy 274.093897 -280.524691) (xy 274.0914 -280.519378) (xy 274.076668 -280.489914)
			(xy 274.06981 -280.484072) (xy 274.050593 -280.468299) (xy 274.016661 -280.431967) (xy 273.988548 -280.390966)
			(xy 273.966889 -280.346218) (xy 273.952172 -280.298733) (xy 273.944728 -280.24958) (xy 273.944724 -280.199867)
			(xy 273.952162 -280.150713) (xy 273.966872 -280.103226) (xy 273.988525 -280.058475) (xy 274.016631 -280.01747)
			(xy 274.050559 -279.981133) (xy 274.06981 -279.965404) (xy 274.076668 -279.959562) (xy 274.0914 -279.930098)
			(xy 274.093865 -279.924773) (xy 274.096567 -279.913357) (xy 274.096734 -279.907492) (xy 274.096734 -279.592024)
			(xy 274.09658 -279.586157) (xy 274.093878 -279.574738) (xy 274.0914 -279.569418) (xy 274.076668 -279.539954)
			(xy 274.06981 -279.534112) (xy 274.050598 -279.518339) (xy 274.016674 -279.482009) (xy 273.98857 -279.44101)
			(xy 273.96692 -279.396266) (xy 273.95221 -279.348786) (xy 273.944772 -279.29964) (xy 273.944774 -279.249933)
			(xy 273.952216 -279.200787) (xy 273.96693 -279.153308) (xy 273.988584 -279.108567) (xy 274.016691 -279.06757)
			(xy 274.050618 -279.031242) (xy 274.06981 -279.015444) (xy 274.076668 -279.009602) (xy 274.0914 -278.980138)
			(xy 274.093859 -278.974812) (xy 274.096547 -278.963396) (xy 274.096734 -278.957532) (xy 274.096734 -278.642064)
			(xy 274.096585 -278.636196) (xy 274.093891 -278.624773) (xy 274.0914 -278.619458) (xy 274.076668 -278.589994)
			(xy 274.06981 -278.584152) (xy 274.050595 -278.568379) (xy 274.016665 -278.532048) (xy 273.988556 -278.491047)
			(xy 273.9669 -278.446301) (xy 273.952185 -278.398818) (xy 273.944742 -278.349667) (xy 273.944741 -278.299956)
			(xy 273.95218 -278.250804) (xy 273.966891 -278.20332) (xy 273.988544 -278.158572) (xy 274.016651 -278.11757)
			(xy 274.050579 -278.081236) (xy 274.06981 -278.065484) (xy 274.076668 -278.059642) (xy 274.0914 -278.030178)
			(xy 274.093863 -278.024853) (xy 274.09656 -278.013437) (xy 274.096734 -278.007572) (xy 274.096734 -277.692104)
			(xy 274.096578 -277.686238) (xy 274.093872 -277.674821) (xy 274.0914 -277.669498) (xy 274.076668 -277.640034)
			(xy 274.06981 -277.634192) (xy 274.050599 -277.618419) (xy 274.016679 -277.582089) (xy 273.988578 -277.541091)
			(xy 273.96693 -277.496349) (xy 273.952222 -277.448871) (xy 273.944787 -277.399726) (xy 273.94479 -277.350022)
			(xy 273.952234 -277.300878) (xy 273.966949 -277.253402) (xy 273.988604 -277.208664) (xy 274.016711 -277.16767)
			(xy 274.050638 -277.131345) (xy 274.06981 -277.115524) (xy 274.076668 -277.109682) (xy 274.0914 -277.080218)
			(xy 274.093857 -277.074891) (xy 274.09654 -277.063475) (xy 274.096734 -277.057612) (xy 274.096734 -276.742144)
			(xy 274.096582 -276.736276) (xy 274.093885 -276.724856) (xy 274.0914 -276.719538) (xy 274.076668 -276.690074)
			(xy 274.06981 -276.684232) (xy 274.050596 -276.668459) (xy 274.01667 -276.632128) (xy 273.988563 -276.591128)
			(xy 273.96691 -276.546384) (xy 273.952197 -276.498902) (xy 273.944757 -276.449753) (xy 273.944757 -276.400044)
			(xy 273.952198 -276.350896) (xy 273.96691 -276.303414) (xy 273.988564 -276.258669) (xy 274.016671 -276.21767)
			(xy 274.050598 -276.181339) (xy 274.06981 -276.165564) (xy 274.076668 -276.159722) (xy 274.0914 -276.130258)
			(xy 274.093861 -276.124932) (xy 274.096553 -276.113516) (xy 274.096734 -276.107652) (xy 274.096734 -275.792184)
			(xy 274.096587 -275.786315) (xy 274.093897 -275.774891) (xy 274.0914 -275.769578) (xy 274.076668 -275.740114)
			(xy 274.06981 -275.734272) (xy 274.050593 -275.718499) (xy 274.016661 -275.682167) (xy 273.988548 -275.641166)
			(xy 273.966889 -275.596418) (xy 273.952172 -275.548933) (xy 273.944728 -275.49978) (xy 273.944724 -275.450067)
			(xy 273.952162 -275.400913) (xy 273.966872 -275.353426) (xy 273.988525 -275.308675) (xy 274.016631 -275.26767)
			(xy 274.050559 -275.231333) (xy 274.06981 -275.215604) (xy 274.076668 -275.209762) (xy 274.0914 -275.180298)
			(xy 274.093865 -275.174973) (xy 274.096567 -275.163557) (xy 274.096734 -275.157692) (xy 274.096734 -274.842224)
			(xy 274.09658 -274.836357) (xy 274.093878 -274.824938) (xy 274.0914 -274.819618) (xy 274.076668 -274.790154)
			(xy 274.06981 -274.784312) (xy 274.050598 -274.768539) (xy 274.016674 -274.732209) (xy 273.98857 -274.69121)
			(xy 273.96692 -274.646466) (xy 273.95221 -274.598986) (xy 273.944772 -274.54984) (xy 273.944774 -274.500133)
			(xy 273.952216 -274.450987) (xy 273.96693 -274.403508) (xy 273.988584 -274.358767) (xy 274.016691 -274.31777)
			(xy 274.050618 -274.281442) (xy 274.06981 -274.265644) (xy 274.076668 -274.259802) (xy 274.0914 -274.230338)
			(xy 274.093859 -274.225012) (xy 274.096547 -274.213596) (xy 274.096734 -274.207732) (xy 274.096734 -273.89201)
			(xy 274.096578 -273.886143) (xy 274.093874 -273.874726) (xy 274.0914 -273.869404) (xy 274.076668 -273.83994)
			(xy 274.06981 -273.834098) (xy 274.050599 -273.818325) (xy 274.016677 -273.781995) (xy 273.988576 -273.740997)
			(xy 273.966927 -273.696254) (xy 273.952218 -273.648775) (xy 273.944782 -273.59963) (xy 273.944786 -273.549925)
			(xy 273.952228 -273.500781) (xy 273.966943 -273.453304) (xy 273.988598 -273.408565) (xy 274.016705 -273.36757)
			(xy 274.050632 -273.331244) (xy 274.06981 -273.31543) (xy 274.076668 -273.309588) (xy 274.0914 -273.280124)
			(xy 274.093857 -273.274797) (xy 274.096542 -273.263381) (xy 274.096734 -273.257518) (xy 274.096734 -272.94205)
			(xy 274.096583 -272.936182) (xy 274.093887 -272.924761) (xy 274.0914 -272.919444) (xy 274.076668 -272.88998)
			(xy 274.06981 -272.884138) (xy 274.050596 -272.868365) (xy 274.016668 -272.832034) (xy 273.988561 -272.791034)
			(xy 273.966907 -272.746289) (xy 273.952193 -272.698807) (xy 273.944753 -272.649657) (xy 273.944752 -272.599948)
			(xy 273.952192 -272.550798) (xy 273.966905 -272.503316) (xy 273.988558 -272.45857) (xy 274.016665 -272.41757)
			(xy 274.050592 -272.381238) (xy 274.06981 -272.36547) (xy 274.076668 -272.359628) (xy 274.0914 -272.330164)
			(xy 274.093861 -272.324838) (xy 274.096555 -272.313422) (xy 274.096734 -272.307558) (xy 274.096734 -265.848846)
			(xy 274.096029 -265.836692) (xy 274.084874 -265.815092) (xy 274.075398 -265.807444) (xy 274.05457 -265.792028)
			(xy 274.016873 -265.756476) (xy 273.984333 -265.716149) (xy 273.957548 -265.671792) (xy 273.93701 -265.624218)
			(xy 273.923097 -265.574303) (xy 273.916066 -265.522965) (xy 273.915632 -265.497056) (xy 273.916156 -265.468213)
			(xy 273.924829 -265.411182) (xy 273.941986 -265.356106) (xy 273.967235 -265.304239) (xy 274.000003 -265.256763)
			(xy 274.039542 -265.214759) (xy 274.061936 -265.196574) (xy 274.071842 -265.188954) (xy 274.082256 -265.165078)
			(xy 274.0025 -264.258552) (xy 273.979386 -263.996932) (xy 273.963892 -263.97458) (xy 273.951446 -263.968992)
			(xy 273.926981 -263.95718) (xy 273.881376 -263.92766) (xy 273.840421 -263.891968) (xy 273.804943 -263.850826)
			(xy 273.775661 -263.805068) (xy 273.753168 -263.755617) (xy 273.737918 -263.703476) (xy 273.730219 -263.649699)
			(xy 273.729704 -263.622536) (xy 273.730145 -263.596287) (xy 273.737349 -263.544284) (xy 273.751611 -263.493759)
			(xy 273.772664 -263.445666) (xy 273.800109 -263.400912) (xy 273.833428 -263.360342) (xy 273.871993 -263.32472)
			(xy 273.89328 -263.309354) (xy 273.904456 -263.30148) (xy 273.91614 -263.276842) (xy 273.83613 -262.371332)
			(xy 273.835289 -262.366594) (xy 273.832088 -262.35752) (xy 273.82978 -262.353298) (xy 273.811746 -262.335264)
			(xy 273.806412 -262.332216) (xy 273.7827 -262.317295) (xy 273.739518 -262.281602) (xy 273.702017 -262.239981)
			(xy 273.671003 -262.193325) (xy 273.647141 -262.142637) (xy 273.630944 -262.089006) (xy 273.622759 -262.033584)
			(xy 273.622262 -262.005572) (xy 273.622361 -261.993601) (xy 273.623886 -261.969707) (xy 273.62531 -261.95782)
			(xy 273.62531 -261.957566) (xy 273.625989 -261.948705) (xy 273.621988 -261.931402) (xy 273.612353 -261.916484)
			(xy 273.605498 -261.91083) (xy 273.534886 -261.857744) (xy 273.529326 -261.853845) (xy 273.516713 -261.848823)
			(xy 273.509994 -261.847838) (xy 273.496786 -261.846314) (xy 273.48434 -261.851902) (xy 273.460318 -261.861874)
			(xy 273.410235 -261.875907) (xy 273.358708 -261.88299) (xy 273.332702 -261.883398) (xy 273.33194 -261.883398)
			(xy 273.304686 -261.882937) (xy 273.250732 -261.875185) (xy 273.198431 -261.859833) (xy 273.148847 -261.837193)
			(xy 273.10299 -261.807727) (xy 273.061794 -261.772035) (xy 273.026097 -261.730842) (xy 272.996626 -261.684988)
			(xy 272.973981 -261.635407) (xy 272.958623 -261.583107) (xy 272.950865 -261.529154) (xy 272.950865 -261.474646)
			(xy 272.958623 -261.420693) (xy 272.973981 -261.368393) (xy 272.996626 -261.318812) (xy 273.026097 -261.272958)
			(xy 273.061794 -261.231765) (xy 273.10299 -261.196073) (xy 273.148847 -261.166607) (xy 273.198431 -261.143967)
			(xy 273.250732 -261.128615) (xy 273.304686 -261.120863) (xy 273.33194 -261.120382) (xy 273.332194 -261.120382)
			(xy 273.363136 -261.120977) (xy 273.424208 -261.13096) (xy 273.482865 -261.150682) (xy 273.537563 -261.179624)
			(xy 273.562572 -261.197852) (xy 273.565366 -261.200138) (xy 273.573293 -261.204818) (xy 273.591266 -261.208736)
			(xy 273.609462 -261.206045) (xy 273.61769 -261.201916) (xy 273.69897 -261.156958) (xy 273.707371 -261.151828)
			(xy 273.719785 -261.136573) (xy 273.725551 -261.117771) (xy 273.725132 -261.107936) (xy 273.509232 -258.657852)
			(xy 273.508038 -258.649034) (xy 273.500498 -258.63293) (xy 273.4945 -258.626356) (xy 272.303494 -257.43535)
			(xy 272.298668 -257.430778) (xy 272.29816 -257.43027) (xy 272.296128 -257.428492) (xy 272.289624 -257.422571)
			(xy 272.273622 -257.415299) (xy 272.264886 -257.414268) (xy 272.234152 -257.412236) (xy 272.230596 -257.411982)
			(xy 272.200878 -257.421634) (xy 272.176377 -257.438584) (xy 272.123213 -257.465469) (xy 272.066511 -257.483747)
			(xy 272.007654 -257.492972) (xy 271.977866 -257.493516) (xy 271.977612 -257.493516) (xy 271.950358 -257.493053)
			(xy 271.896406 -257.485298) (xy 271.844106 -257.469943) (xy 271.794524 -257.447301) (xy 271.748669 -257.417834)
			(xy 271.707474 -257.38214) (xy 271.671778 -257.340947) (xy 271.642308 -257.295094) (xy 271.619664 -257.245513)
			(xy 271.604306 -257.193214) (xy 271.596548 -257.139262) (xy 271.596104 -257.112008) (xy 271.596104 -257.111754)
			(xy 271.596516 -257.086138) (xy 271.603375 -257.035366) (xy 271.616975 -256.985972) (xy 271.637073 -256.938846)
			(xy 271.663304 -256.894838) (xy 271.678908 -256.874518) (xy 271.684415 -256.86701) (xy 271.690109 -256.8493)
			(xy 271.689076 -256.830725) (xy 271.681452 -256.813756) (xy 271.675098 -256.806954) (xy 271.419828 -256.551684)
			(xy 271.416976 -256.548979) (xy 271.410598 -256.544387) (xy 271.407128 -256.54254) (xy 271.401701 -256.539958)
			(xy 271.390021 -256.537139) (xy 271.384014 -256.536952) (xy 267.265658 -256.536952) (xy 267.257143 -256.537277)
			(xy 267.241054 -256.542862) (xy 267.234162 -256.547874) (xy 267.231194 -256.550305) (xy 267.225967 -256.55592)
			(xy 267.223748 -256.55905) (xy 267.210894 -256.581631) (xy 267.18 -256.623407) (xy 267.143722 -256.660606)
			(xy 267.102733 -256.692537) (xy 267.05779 -256.718611) (xy 267.009724 -256.738345) (xy 266.959426 -256.751374)
			(xy 266.93368 -256.754884) (xy 266.923266 -256.756154) (xy 266.889484 -256.757678) (xy 266.888976 -256.757678)
			(xy 266.862568 -256.75722) (xy 266.810261 -256.749914) (xy 266.759462 -256.735457) (xy 266.711145 -256.714128)
			(xy 266.666235 -256.686334) (xy 266.645644 -256.669794) (xy 266.638278 -256.663698) (xy 266.620244 -256.657602)
			(xy 266.610846 -256.65811) (xy 266.601541 -256.658984) (xy 266.584462 -256.66653) (xy 266.577572 -256.672842)
			(xy 266.191238 -257.059176) (xy 266.188531 -257.062026) (xy 266.183935 -257.068403) (xy 266.182094 -257.071876)
			(xy 266.179515 -257.077304) (xy 266.176699 -257.088983) (xy 266.176506 -257.09499) (xy 266.176506 -257.137916)
			(xy 268.778988 -257.137916) (xy 268.783059 -257.082294) (xy 268.795185 -257.027857) (xy 268.815108 -256.975766)
			(xy 268.842404 -256.927131) (xy 268.87649 -256.882988) (xy 268.916639 -256.844279) (xy 268.961997 -256.811828)
			(xy 269.011597 -256.786327) (xy 269.064381 -256.76832) (xy 269.119224 -256.75819) (xy 269.174958 -256.756153)
			(xy 269.230395 -256.762253) (xy 269.284352 -256.776359) (xy 269.335681 -256.798171) (xy 269.383287 -256.827225)
			(xy 269.426155 -256.8629) (xy 269.463372 -256.904437) (xy 269.494145 -256.95095) (xy 269.517817 -257.001447)
			(xy 269.533885 -257.054854) (xy 269.542005 -257.11003) (xy 269.542514 -257.137916) (xy 269.542005 -257.165802)
			(xy 269.533885 -257.220978) (xy 269.517817 -257.274385) (xy 269.494145 -257.324882) (xy 269.463372 -257.371395)
			(xy 269.426155 -257.412932) (xy 269.383287 -257.448607) (xy 269.335681 -257.477661) (xy 269.284352 -257.499473)
			(xy 269.230395 -257.513579) (xy 269.174958 -257.519679) (xy 269.119224 -257.517642) (xy 269.064381 -257.507512)
			(xy 269.011597 -257.489505) (xy 268.961997 -257.464004) (xy 268.916639 -257.431553) (xy 268.87649 -257.392844)
			(xy 268.842404 -257.348701) (xy 268.815108 -257.300066) (xy 268.795185 -257.247975) (xy 268.783059 -257.193538)
			(xy 268.778988 -257.137916) (xy 266.176506 -257.137916) (xy 266.176506 -258.691888) (xy 266.177522 -258.701286)
			(xy 266.177522 -258.701794) (xy 266.179228 -258.708952) (xy 266.186065 -258.721974) (xy 266.190984 -258.727448)
			(xy 266.586208 -259.122672) (xy 266.591639 -259.127651) (xy 266.604678 -259.134497) (xy 266.611862 -259.136134)
			(xy 266.61237 -259.136134) (xy 266.621768 -259.13715) (xy 269.292324 -259.13715) (xy 269.302391 -259.137579)
			(xy 269.320985 -259.145305) (xy 269.328392 -259.152136) (xy 270.65478 -260.478524) (xy 270.661625 -260.485923)
			(xy 270.669354 -260.504521) (xy 270.669766 -260.514592) (xy 270.669766 -260.585966) (xy 270.670274 -260.58622)
			(xy 270.670274 -260.596888) (xy 270.670391 -260.601843) (xy 270.672307 -260.611565) (xy 270.674084 -260.616192)
			(xy 270.677894 -260.625336) (xy 270.684752 -260.632194) (xy 270.684752 -262.978138) (xy 270.684616 -262.99038)
			(xy 270.682712 -263.014792) (xy 270.680942 -263.026906) (xy 270.689324 -263.03097) (xy 270.713844 -263.042761)
			(xy 270.75956 -263.072259) (xy 270.800622 -263.107952) (xy 270.836197 -263.149116) (xy 270.865564 -263.194916)
			(xy 270.888127 -263.244423) (xy 270.903429 -263.296634) (xy 270.911159 -263.350488) (xy 270.91116 -263.404895)
			(xy 270.903432 -263.45875) (xy 270.888133 -263.510961) (xy 270.865572 -263.560469) (xy 270.836207 -263.606271)
			(xy 270.800634 -263.647436) (xy 270.759573 -263.683131) (xy 270.713859 -263.712631) (xy 270.689324 -263.72439)
			(xy 270.680942 -263.728454) (xy 270.682718 -263.740568) (xy 270.684628 -263.764979) (xy 270.684752 -263.777222)
			(xy 270.684752 -263.871456) (xy 270.685134 -263.880018) (xy 270.690859 -263.896161) (xy 270.701558 -263.909537)
			(xy 270.708628 -263.914382) (xy 270.793464 -263.96696) (xy 270.819626 -263.96823) (xy 270.831564 -263.962134)
			(xy 270.857988 -263.949622) (xy 270.913719 -263.931957) (xy 270.971496 -263.923021) (xy 271.000728 -263.92251)
			(xy 271.000982 -263.92251) (xy 271.028234 -263.922972) (xy 271.082185 -263.930727) (xy 271.134482 -263.94608)
			(xy 271.184062 -263.968721) (xy 271.229916 -263.998187) (xy 271.271108 -264.033879) (xy 271.306802 -264.07507)
			(xy 271.336271 -264.120922) (xy 271.358913 -264.170501) (xy 271.37427 -264.222798) (xy 271.382027 -264.276748)
			(xy 271.382027 -264.331252) (xy 271.37427 -264.385202) (xy 271.358913 -264.437499) (xy 271.336271 -264.487078)
			(xy 271.329041 -264.498328) (xy 273.06854 -264.498328) (xy 273.072611 -264.442706) (xy 273.084737 -264.388269)
			(xy 273.10466 -264.336178) (xy 273.131956 -264.287543) (xy 273.166042 -264.2434) (xy 273.206191 -264.204691)
			(xy 273.251549 -264.17224) (xy 273.301149 -264.146739) (xy 273.353933 -264.128732) (xy 273.408776 -264.118602)
			(xy 273.46451 -264.116565) (xy 273.519947 -264.122665) (xy 273.573904 -264.136771) (xy 273.625233 -264.158583)
			(xy 273.672839 -264.187637) (xy 273.715707 -264.223312) (xy 273.752924 -264.264849) (xy 273.783697 -264.311362)
			(xy 273.807369 -264.361859) (xy 273.823437 -264.415266) (xy 273.831557 -264.470442) (xy 273.832066 -264.498328)
			(xy 273.831557 -264.526214) (xy 273.823437 -264.58139) (xy 273.807369 -264.634797) (xy 273.783697 -264.685294)
			(xy 273.752924 -264.731807) (xy 273.715707 -264.773344) (xy 273.672839 -264.809019) (xy 273.625233 -264.838073)
			(xy 273.573904 -264.859885) (xy 273.519947 -264.873991) (xy 273.46451 -264.880091) (xy 273.408776 -264.878054)
			(xy 273.353933 -264.867924) (xy 273.301149 -264.849917) (xy 273.251549 -264.824416) (xy 273.206191 -264.791965)
			(xy 273.166042 -264.753256) (xy 273.131956 -264.709113) (xy 273.10466 -264.660478) (xy 273.084737 -264.608387)
			(xy 273.072611 -264.55395) (xy 273.06854 -264.498328) (xy 271.329041 -264.498328) (xy 271.306802 -264.53293)
			(xy 271.271108 -264.574121) (xy 271.229916 -264.609813) (xy 271.184062 -264.639279) (xy 271.134482 -264.66192)
			(xy 271.082185 -264.677273) (xy 271.028234 -264.685028) (xy 271.000982 -264.685526) (xy 271.000728 -264.685526)
			(xy 270.971502 -264.684944) (xy 270.913738 -264.675995) (xy 270.858008 -264.658362) (xy 270.831564 -264.645902)
			(xy 270.819626 -264.639806) (xy 270.793464 -264.641076) (xy 270.708628 -264.693654) (xy 270.701522 -264.698464)
			(xy 270.690782 -264.711832) (xy 270.685086 -264.728006) (xy 270.684752 -264.73658) (xy 270.684752 -266.012422)
			(xy 273.142454 -266.012422) (xy 273.146525 -265.9568) (xy 273.158651 -265.902363) (xy 273.178574 -265.850272)
			(xy 273.20587 -265.801637) (xy 273.239956 -265.757494) (xy 273.280105 -265.718785) (xy 273.325463 -265.686334)
			(xy 273.375063 -265.660833) (xy 273.427847 -265.642826) (xy 273.48269 -265.632696) (xy 273.538424 -265.630659)
			(xy 273.593861 -265.636759) (xy 273.647818 -265.650865) (xy 273.699147 -265.672677) (xy 273.746753 -265.701731)
			(xy 273.789621 -265.737406) (xy 273.826838 -265.778943) (xy 273.857611 -265.825456) (xy 273.881283 -265.875953)
			(xy 273.897351 -265.92936) (xy 273.905471 -265.984536) (xy 273.90598 -266.012422) (xy 273.905471 -266.040308)
			(xy 273.897351 -266.095484) (xy 273.881283 -266.148891) (xy 273.857611 -266.199388) (xy 273.826838 -266.245901)
			(xy 273.789621 -266.287438) (xy 273.746753 -266.323113) (xy 273.699147 -266.352167) (xy 273.647818 -266.373979)
			(xy 273.593861 -266.388085) (xy 273.538424 -266.394185) (xy 273.48269 -266.392148) (xy 273.427847 -266.382018)
			(xy 273.375063 -266.364011) (xy 273.325463 -266.33851) (xy 273.280105 -266.306059) (xy 273.239956 -266.26735)
			(xy 273.20587 -266.223207) (xy 273.178574 -266.174572) (xy 273.158651 -266.122481) (xy 273.146525 -266.068044)
			(xy 273.142454 -266.012422) (xy 270.684752 -266.012422) (xy 270.684752 -266.963398) (xy 270.855946 -266.963398)
			(xy 270.860017 -266.907776) (xy 270.872143 -266.853339) (xy 270.892066 -266.801248) (xy 270.919362 -266.752613)
			(xy 270.953448 -266.70847) (xy 270.993597 -266.669761) (xy 271.038955 -266.63731) (xy 271.088555 -266.611809)
			(xy 271.141339 -266.593802) (xy 271.196182 -266.583672) (xy 271.251916 -266.581635) (xy 271.307353 -266.587735)
			(xy 271.36131 -266.601841) (xy 271.412639 -266.623653) (xy 271.460245 -266.652707) (xy 271.503113 -266.688382)
			(xy 271.54033 -266.729919) (xy 271.571103 -266.776432) (xy 271.594775 -266.826929) (xy 271.595026 -266.827762)
			(xy 271.740374 -266.827762) (xy 271.744445 -266.77214) (xy 271.756571 -266.717703) (xy 271.776494 -266.665612)
			(xy 271.80379 -266.616977) (xy 271.837876 -266.572834) (xy 271.878025 -266.534125) (xy 271.923383 -266.501674)
			(xy 271.972983 -266.476173) (xy 272.025767 -266.458166) (xy 272.08061 -266.448036) (xy 272.136344 -266.445999)
			(xy 272.191781 -266.452099) (xy 272.245738 -266.466205) (xy 272.297067 -266.488017) (xy 272.344673 -266.517071)
			(xy 272.387541 -266.552746) (xy 272.424758 -266.594283) (xy 272.455531 -266.640796) (xy 272.479203 -266.691293)
			(xy 272.495271 -266.7447) (xy 272.503391 -266.799876) (xy 272.5039 -266.827762) (xy 272.503391 -266.855648)
			(xy 272.495271 -266.910824) (xy 272.479203 -266.964231) (xy 272.455531 -267.014728) (xy 272.424758 -267.061241)
			(xy 272.387541 -267.102778) (xy 272.344673 -267.138453) (xy 272.297067 -267.167507) (xy 272.245738 -267.189319)
			(xy 272.191781 -267.203425) (xy 272.136344 -267.209525) (xy 272.08061 -267.207488) (xy 272.025767 -267.197358)
			(xy 271.972983 -267.179351) (xy 271.923383 -267.15385) (xy 271.878025 -267.121399) (xy 271.837876 -267.08269)
			(xy 271.80379 -267.038547) (xy 271.776494 -266.989912) (xy 271.756571 -266.937821) (xy 271.744445 -266.883384)
			(xy 271.740374 -266.827762) (xy 271.595026 -266.827762) (xy 271.610843 -266.880336) (xy 271.618963 -266.935512)
			(xy 271.619472 -266.963398) (xy 271.618963 -266.991284) (xy 271.610843 -267.04646) (xy 271.594775 -267.099867)
			(xy 271.571103 -267.150364) (xy 271.54033 -267.196877) (xy 271.503113 -267.238414) (xy 271.460245 -267.274089)
			(xy 271.412639 -267.303143) (xy 271.36131 -267.324955) (xy 271.307353 -267.339061) (xy 271.251916 -267.345161)
			(xy 271.196182 -267.343124) (xy 271.141339 -267.332994) (xy 271.088555 -267.314987) (xy 271.038955 -267.289486)
			(xy 270.993597 -267.257035) (xy 270.953448 -267.218326) (xy 270.919362 -267.174183) (xy 270.892066 -267.125548)
			(xy 270.872143 -267.073457) (xy 270.860017 -267.01902) (xy 270.855946 -266.963398) (xy 270.684752 -266.963398)
			(xy 270.684752 -268.766658) (xy 271.815721 -268.766658) (xy 271.815721 -268.712146) (xy 271.823479 -268.658189)
			(xy 271.838837 -268.605885) (xy 271.861482 -268.556299) (xy 271.890954 -268.510441) (xy 271.926652 -268.469244)
			(xy 271.96785 -268.433547) (xy 272.01371 -268.404076) (xy 272.063296 -268.381432) (xy 272.1156 -268.366076)
			(xy 272.169558 -268.35832) (xy 272.196814 -268.357858) (xy 272.222265 -268.358291) (xy 272.272712 -268.365091)
			(xy 272.321805 -268.378542) (xy 272.345404 -268.388084) (xy 272.358518 -268.393175) (xy 272.386414 -268.396718)
			(xy 272.414218 -268.392512) (xy 272.439817 -268.380875) (xy 272.461267 -268.362692) (xy 272.476939 -268.339344)
			(xy 272.485642 -268.312605) (xy 272.486715 -268.284505) (xy 272.483834 -268.270736) (xy 272.478981 -268.24896)
			(xy 272.473764 -268.204651) (xy 272.47342 -268.182344) (xy 272.473808 -268.155088) (xy 272.48156 -268.101129)
			(xy 272.496912 -268.048823) (xy 272.519551 -267.999234) (xy 272.549018 -267.953372) (xy 272.584712 -267.91217)
			(xy 272.625906 -267.876468) (xy 272.671761 -267.846991) (xy 272.721345 -267.824341) (xy 272.773648 -267.808977)
			(xy 272.827605 -267.801214) (xy 272.882118 -267.801208) (xy 272.936076 -267.808961) (xy 272.988382 -267.824314)
			(xy 273.037971 -267.846954) (xy 273.083832 -267.876421) (xy 273.125033 -267.912116) (xy 273.160735 -267.95331)
			(xy 273.190211 -267.999166) (xy 273.212861 -268.04875) (xy 273.228224 -268.101053) (xy 273.235987 -268.15501)
			(xy 273.235991 -268.209523) (xy 273.228238 -268.263481) (xy 273.212885 -268.315787) (xy 273.190243 -268.365375)
			(xy 273.160775 -268.411237) (xy 273.125081 -268.452437) (xy 273.083886 -268.488139) (xy 273.038029 -268.517614)
			(xy 272.988445 -268.540263) (xy 272.936141 -268.555625) (xy 272.882184 -268.563387) (xy 272.854928 -268.563852)
			(xy 272.829477 -268.563405) (xy 272.779031 -268.55661) (xy 272.729937 -268.543165) (xy 272.706338 -268.533626)
			(xy 272.693217 -268.528571) (xy 272.665332 -268.525047) (xy 272.637544 -268.529263) (xy 272.611959 -268.540898)
			(xy 272.590519 -268.559071) (xy 272.574848 -268.582403) (xy 272.566135 -268.609124) (xy 272.565041 -268.637209)
			(xy 272.567908 -268.650974) (xy 272.572763 -268.672749) (xy 272.577979 -268.717059) (xy 272.578322 -268.739366)
			(xy 272.577881 -268.766622) (xy 272.570128 -268.82058) (xy 272.554775 -268.872885) (xy 272.532133 -268.922473)
			(xy 272.502665 -268.968334) (xy 272.46697 -269.009534) (xy 272.425775 -269.045234) (xy 272.379919 -269.074708)
			(xy 272.330334 -269.097356) (xy 272.278031 -269.112717) (xy 272.224074 -269.120478) (xy 272.169562 -269.12048)
			(xy 272.115604 -269.112725) (xy 272.0633 -269.097369) (xy 272.013713 -269.074726) (xy 271.967854 -269.045256)
			(xy 271.926655 -269.009559) (xy 271.890956 -268.968362) (xy 271.861484 -268.922505) (xy 271.838838 -268.872919)
			(xy 271.823479 -268.820615) (xy 271.815721 -268.766658) (xy 270.684752 -268.766658) (xy 270.684752 -269.681706)
			(xy 270.685768 -269.682468) (xy 270.684752 -269.683484) (xy 270.684752 -271.808192) (xy 272.605236 -271.808192)
			(xy 272.605236 -271.754856) (xy 272.613186 -271.702115) (xy 272.628907 -271.651148) (xy 272.652049 -271.603093)
			(xy 272.682094 -271.559024) (xy 272.718373 -271.519926) (xy 272.760073 -271.486671) (xy 272.806264 -271.460003)
			(xy 272.855913 -271.440517) (xy 272.907913 -271.428648) (xy 272.9611 -271.424663) (xy 273.014287 -271.428648)
			(xy 273.066287 -271.440517) (xy 273.115936 -271.460003) (xy 273.162127 -271.486671) (xy 273.203827 -271.519926)
			(xy 273.240106 -271.559024) (xy 273.270151 -271.603093) (xy 273.293293 -271.651148) (xy 273.309014 -271.702115)
			(xy 273.316964 -271.754856) (xy 273.317462 -271.781524) (xy 273.316964 -271.808192) (xy 273.309014 -271.860933)
			(xy 273.293293 -271.9119) (xy 273.270151 -271.959955) (xy 273.240106 -272.004024) (xy 273.203827 -272.043122)
			(xy 273.162127 -272.076377) (xy 273.115936 -272.103045) (xy 273.066287 -272.122531) (xy 273.014287 -272.1344)
			(xy 272.9611 -272.138386) (xy 272.907913 -272.1344) (xy 272.855913 -272.122531) (xy 272.806264 -272.103045)
			(xy 272.760073 -272.076377) (xy 272.718373 -272.043122) (xy 272.682094 -272.004024) (xy 272.652049 -271.959955)
			(xy 272.628907 -271.9119) (xy 272.613186 -271.860933) (xy 272.605236 -271.808192) (xy 270.684752 -271.808192)
			(xy 270.684752 -272.259806) (xy 270.684466 -272.276317) (xy 270.680904 -272.30915) (xy 270.67764 -272.325338)
			(xy 270.676624 -272.335498) (xy 270.676745 -272.341145) (xy 270.679177 -272.352172) (xy 270.68145 -272.357342)
			(xy 270.688054 -272.37182) (xy 270.695674 -272.378424) (xy 270.714181 -272.395651) (xy 270.746263 -272.434729)
			(xy 270.772025 -272.478234) (xy 270.790867 -272.525152) (xy 270.80235 -272.57439) (xy 270.806208 -272.624803)
			(xy 270.806208 -272.624804) (xy 271.119104 -272.624804) (xy 271.123064 -272.57575) (xy 271.134841 -272.527966)
			(xy 271.154132 -272.48269) (xy 271.180435 -272.441094) (xy 271.21307 -272.404257) (xy 271.251191 -272.373132)
			(xy 271.293812 -272.348525) (xy 271.339828 -272.331073) (xy 271.388047 -272.321229) (xy 271.437222 -272.319248)
			(xy 271.486077 -272.32518) (xy 271.533348 -272.338872) (xy 271.57781 -272.35997) (xy 271.618313 -272.387926)
			(xy 271.653806 -272.422018) (xy 271.683371 -272.461362) (xy 271.706242 -272.504939) (xy 271.721826 -272.55162)
			(xy 271.729721 -272.600197) (xy 271.730216 -272.624804) (xy 272.069064 -272.624804) (xy 272.073024 -272.57575)
			(xy 272.084801 -272.527966) (xy 272.104092 -272.48269) (xy 272.130395 -272.441094) (xy 272.16303 -272.404257)
			(xy 272.201151 -272.373132) (xy 272.243772 -272.348525) (xy 272.289788 -272.331073) (xy 272.338007 -272.321229)
			(xy 272.387182 -272.319248) (xy 272.436037 -272.32518) (xy 272.483308 -272.338872) (xy 272.52777 -272.35997)
			(xy 272.568273 -272.387926) (xy 272.603766 -272.422018) (xy 272.633331 -272.461362) (xy 272.656202 -272.504939)
			(xy 272.671786 -272.55162) (xy 272.679681 -272.600197) (xy 272.680176 -272.624804) (xy 273.019024 -272.624804)
			(xy 273.022984 -272.57575) (xy 273.034761 -272.527966) (xy 273.054052 -272.48269) (xy 273.080355 -272.441094)
			(xy 273.11299 -272.404257) (xy 273.151111 -272.373132) (xy 273.193732 -272.348525) (xy 273.239748 -272.331073)
			(xy 273.287967 -272.321229) (xy 273.337142 -272.319248) (xy 273.385997 -272.32518) (xy 273.433268 -272.338872)
			(xy 273.47773 -272.35997) (xy 273.518233 -272.387926) (xy 273.553726 -272.422018) (xy 273.583291 -272.461362)
			(xy 273.606162 -272.504939) (xy 273.621746 -272.55162) (xy 273.629641 -272.600197) (xy 273.630136 -272.624804)
			(xy 273.629641 -272.649411) (xy 273.621746 -272.697988) (xy 273.606162 -272.744669) (xy 273.583291 -272.788246)
			(xy 273.553726 -272.82759) (xy 273.518233 -272.861682) (xy 273.47773 -272.889638) (xy 273.433268 -272.910736)
			(xy 273.385997 -272.924428) (xy 273.337142 -272.93036) (xy 273.287967 -272.928379) (xy 273.239748 -272.918535)
			(xy 273.193732 -272.901083) (xy 273.151111 -272.876476) (xy 273.11299 -272.845351) (xy 273.080355 -272.808514)
			(xy 273.054052 -272.766918) (xy 273.034761 -272.721642) (xy 273.022984 -272.673858) (xy 273.019024 -272.624804)
			(xy 272.680176 -272.624804) (xy 272.679681 -272.649411) (xy 272.671786 -272.697988) (xy 272.656202 -272.744669)
			(xy 272.633331 -272.788246) (xy 272.603766 -272.82759) (xy 272.568273 -272.861682) (xy 272.52777 -272.889638)
			(xy 272.483308 -272.910736) (xy 272.436037 -272.924428) (xy 272.387182 -272.93036) (xy 272.338007 -272.928379)
			(xy 272.289788 -272.918535) (xy 272.243772 -272.901083) (xy 272.201151 -272.876476) (xy 272.16303 -272.845351)
			(xy 272.130395 -272.808514) (xy 272.104092 -272.766918) (xy 272.084801 -272.721642) (xy 272.073024 -272.673858)
			(xy 272.069064 -272.624804) (xy 271.730216 -272.624804) (xy 271.729721 -272.649411) (xy 271.721826 -272.697988)
			(xy 271.706242 -272.744669) (xy 271.683371 -272.788246) (xy 271.653806 -272.82759) (xy 271.618313 -272.861682)
			(xy 271.57781 -272.889638) (xy 271.533348 -272.910736) (xy 271.486077 -272.924428) (xy 271.437222 -272.93036)
			(xy 271.388047 -272.928379) (xy 271.339828 -272.918535) (xy 271.293812 -272.901083) (xy 271.251191 -272.876476)
			(xy 271.21307 -272.845351) (xy 271.180435 -272.808514) (xy 271.154132 -272.766918) (xy 271.134841 -272.721642)
			(xy 271.123064 -272.673858) (xy 271.119104 -272.624804) (xy 270.806208 -272.624804) (xy 270.802349 -272.675215)
			(xy 270.790865 -272.724454) (xy 270.772022 -272.771371) (xy 270.74626 -272.814875) (xy 270.714178 -272.853953)
			(xy 270.695674 -272.871184) (xy 270.688054 -272.877788) (xy 270.68145 -272.892266) (xy 270.679191 -272.897441)
			(xy 270.676759 -272.908465) (xy 270.676624 -272.91411) (xy 270.67764 -272.92427) (xy 270.680901 -272.940458)
			(xy 270.684461 -272.973291) (xy 270.684752 -272.989802) (xy 270.684752 -273.209766) (xy 270.684511 -273.22692)
			(xy 270.680817 -273.261029) (xy 270.677386 -273.277838) (xy 270.676116 -273.28876) (xy 270.676342 -273.296031)
			(xy 270.680465 -273.309976) (xy 270.684244 -273.316192) (xy 270.688054 -273.322288) (xy 270.706091 -273.338066)
			(xy 270.737869 -273.373935) (xy 270.764134 -273.414017) (xy 270.784336 -273.457471) (xy 270.79805 -273.503388)
			(xy 270.80499 -273.550804) (xy 270.805402 -273.574764) (xy 271.119104 -273.574764) (xy 271.123064 -273.52571)
			(xy 271.134841 -273.477926) (xy 271.154132 -273.43265) (xy 271.180435 -273.391054) (xy 271.21307 -273.354217)
			(xy 271.251191 -273.323092) (xy 271.293812 -273.298485) (xy 271.339828 -273.281033) (xy 271.388047 -273.271189)
			(xy 271.437222 -273.269208) (xy 271.486077 -273.27514) (xy 271.533348 -273.288832) (xy 271.57781 -273.30993)
			(xy 271.618313 -273.337886) (xy 271.653806 -273.371978) (xy 271.683371 -273.411322) (xy 271.706242 -273.454899)
			(xy 271.721826 -273.50158) (xy 271.729721 -273.550157) (xy 271.730216 -273.574764) (xy 272.069064 -273.574764)
			(xy 272.073024 -273.52571) (xy 272.084801 -273.477926) (xy 272.104092 -273.43265) (xy 272.130395 -273.391054)
			(xy 272.16303 -273.354217) (xy 272.201151 -273.323092) (xy 272.243772 -273.298485) (xy 272.289788 -273.281033)
			(xy 272.338007 -273.271189) (xy 272.387182 -273.269208) (xy 272.436037 -273.27514) (xy 272.483308 -273.288832)
			(xy 272.52777 -273.30993) (xy 272.568273 -273.337886) (xy 272.603766 -273.371978) (xy 272.633331 -273.411322)
			(xy 272.656202 -273.454899) (xy 272.671786 -273.50158) (xy 272.679681 -273.550157) (xy 272.680176 -273.574764)
			(xy 273.019024 -273.574764) (xy 273.022984 -273.52571) (xy 273.034761 -273.477926) (xy 273.054052 -273.43265)
			(xy 273.080355 -273.391054) (xy 273.11299 -273.354217) (xy 273.151111 -273.323092) (xy 273.193732 -273.298485)
			(xy 273.239748 -273.281033) (xy 273.287967 -273.271189) (xy 273.337142 -273.269208) (xy 273.385997 -273.27514)
			(xy 273.433268 -273.288832) (xy 273.47773 -273.30993) (xy 273.518233 -273.337886) (xy 273.553726 -273.371978)
			(xy 273.583291 -273.411322) (xy 273.606162 -273.454899) (xy 273.621746 -273.50158) (xy 273.629641 -273.550157)
			(xy 273.630136 -273.574764) (xy 273.629641 -273.599371) (xy 273.621746 -273.647948) (xy 273.606162 -273.694629)
			(xy 273.583291 -273.738206) (xy 273.553726 -273.77755) (xy 273.518233 -273.811642) (xy 273.47773 -273.839598)
			(xy 273.433268 -273.860696) (xy 273.385997 -273.874388) (xy 273.337142 -273.88032) (xy 273.287967 -273.878339)
			(xy 273.239748 -273.868495) (xy 273.193732 -273.851043) (xy 273.151111 -273.826436) (xy 273.11299 -273.795311)
			(xy 273.080355 -273.758474) (xy 273.054052 -273.716878) (xy 273.034761 -273.671602) (xy 273.022984 -273.623818)
			(xy 273.019024 -273.574764) (xy 272.680176 -273.574764) (xy 272.679681 -273.599371) (xy 272.671786 -273.647948)
			(xy 272.656202 -273.694629) (xy 272.633331 -273.738206) (xy 272.603766 -273.77755) (xy 272.568273 -273.811642)
			(xy 272.52777 -273.839598) (xy 272.483308 -273.860696) (xy 272.436037 -273.874388) (xy 272.387182 -273.88032)
			(xy 272.338007 -273.878339) (xy 272.289788 -273.868495) (xy 272.243772 -273.851043) (xy 272.201151 -273.826436)
			(xy 272.16303 -273.795311) (xy 272.130395 -273.758474) (xy 272.104092 -273.716878) (xy 272.084801 -273.671602)
			(xy 272.073024 -273.623818) (xy 272.069064 -273.574764) (xy 271.730216 -273.574764) (xy 271.729721 -273.599371)
			(xy 271.721826 -273.647948) (xy 271.706242 -273.694629) (xy 271.683371 -273.738206) (xy 271.653806 -273.77755)
			(xy 271.618313 -273.811642) (xy 271.57781 -273.839598) (xy 271.533348 -273.860696) (xy 271.486077 -273.874388)
			(xy 271.437222 -273.88032) (xy 271.388047 -273.878339) (xy 271.339828 -273.868495) (xy 271.293812 -273.851043)
			(xy 271.251191 -273.826436) (xy 271.21307 -273.795311) (xy 271.180435 -273.758474) (xy 271.154132 -273.716878)
			(xy 271.134841 -273.671602) (xy 271.123064 -273.623818) (xy 271.119104 -273.574764) (xy 270.805402 -273.574764)
			(xy 270.804782 -273.602813) (xy 270.795267 -273.658101) (xy 270.776571 -273.710994) (xy 270.749228 -273.75998)
			(xy 270.714022 -273.803657) (xy 270.693388 -273.822668) (xy 270.68399 -273.83359) (xy 270.672306 -273.851878)
			(xy 270.67809 -273.873388) (xy 270.684331 -273.917491) (xy 270.684752 -273.939762) (xy 270.684752 -274.15998)
			(xy 270.684468 -274.176492) (xy 270.680908 -274.209325) (xy 270.67764 -274.225512) (xy 270.676624 -274.235672)
			(xy 270.676753 -274.241317) (xy 270.6792 -274.252337) (xy 270.68145 -274.257516) (xy 270.688054 -274.271994)
			(xy 270.695674 -274.278598) (xy 270.714183 -274.295825) (xy 270.746269 -274.334904) (xy 270.772034 -274.37841)
			(xy 270.79088 -274.425329) (xy 270.802367 -274.47457) (xy 270.806226 -274.524978) (xy 271.119104 -274.524978)
			(xy 271.123064 -274.475924) (xy 271.134841 -274.42814) (xy 271.154132 -274.382864) (xy 271.180435 -274.341268)
			(xy 271.21307 -274.304431) (xy 271.251191 -274.273306) (xy 271.293812 -274.248699) (xy 271.339828 -274.231247)
			(xy 271.388047 -274.221403) (xy 271.437222 -274.219422) (xy 271.486077 -274.225354) (xy 271.533348 -274.239046)
			(xy 271.57781 -274.260144) (xy 271.618313 -274.2881) (xy 271.653806 -274.322192) (xy 271.683371 -274.361536)
			(xy 271.706242 -274.405113) (xy 271.721826 -274.451794) (xy 271.729721 -274.500371) (xy 271.730216 -274.524978)
			(xy 272.069064 -274.524978) (xy 272.073024 -274.475924) (xy 272.084801 -274.42814) (xy 272.104092 -274.382864)
			(xy 272.130395 -274.341268) (xy 272.16303 -274.304431) (xy 272.201151 -274.273306) (xy 272.243772 -274.248699)
			(xy 272.289788 -274.231247) (xy 272.338007 -274.221403) (xy 272.387182 -274.219422) (xy 272.436037 -274.225354)
			(xy 272.483308 -274.239046) (xy 272.52777 -274.260144) (xy 272.568273 -274.2881) (xy 272.603766 -274.322192)
			(xy 272.633331 -274.361536) (xy 272.656202 -274.405113) (xy 272.671786 -274.451794) (xy 272.679681 -274.500371)
			(xy 272.680176 -274.524978) (xy 273.019024 -274.524978) (xy 273.022984 -274.475924) (xy 273.034761 -274.42814)
			(xy 273.054052 -274.382864) (xy 273.080355 -274.341268) (xy 273.11299 -274.304431) (xy 273.151111 -274.273306)
			(xy 273.193732 -274.248699) (xy 273.239748 -274.231247) (xy 273.287967 -274.221403) (xy 273.337142 -274.219422)
			(xy 273.385997 -274.225354) (xy 273.433268 -274.239046) (xy 273.47773 -274.260144) (xy 273.518233 -274.2881)
			(xy 273.553726 -274.322192) (xy 273.583291 -274.361536) (xy 273.606162 -274.405113) (xy 273.621746 -274.451794)
			(xy 273.629641 -274.500371) (xy 273.630136 -274.524978) (xy 273.629641 -274.549585) (xy 273.621746 -274.598162)
			(xy 273.606162 -274.644843) (xy 273.583291 -274.68842) (xy 273.553726 -274.727764) (xy 273.518233 -274.761856)
			(xy 273.47773 -274.789812) (xy 273.433268 -274.81091) (xy 273.385997 -274.824602) (xy 273.337142 -274.830534)
			(xy 273.287967 -274.828553) (xy 273.239748 -274.818709) (xy 273.193732 -274.801257) (xy 273.151111 -274.77665)
			(xy 273.11299 -274.745525) (xy 273.080355 -274.708688) (xy 273.054052 -274.667092) (xy 273.034761 -274.621816)
			(xy 273.022984 -274.574032) (xy 273.019024 -274.524978) (xy 272.680176 -274.524978) (xy 272.679681 -274.549585)
			(xy 272.671786 -274.598162) (xy 272.656202 -274.644843) (xy 272.633331 -274.68842) (xy 272.603766 -274.727764)
			(xy 272.568273 -274.761856) (xy 272.52777 -274.789812) (xy 272.483308 -274.81091) (xy 272.436037 -274.824602)
			(xy 272.387182 -274.830534) (xy 272.338007 -274.828553) (xy 272.289788 -274.818709) (xy 272.243772 -274.801257)
			(xy 272.201151 -274.77665) (xy 272.16303 -274.745525) (xy 272.130395 -274.708688) (xy 272.104092 -274.667092)
			(xy 272.084801 -274.621816) (xy 272.073024 -274.574032) (xy 272.069064 -274.524978) (xy 271.730216 -274.524978)
			(xy 271.729721 -274.549585) (xy 271.721826 -274.598162) (xy 271.706242 -274.644843) (xy 271.683371 -274.68842)
			(xy 271.653806 -274.727764) (xy 271.618313 -274.761856) (xy 271.57781 -274.789812) (xy 271.533348 -274.81091)
			(xy 271.486077 -274.824602) (xy 271.437222 -274.830534) (xy 271.388047 -274.828553) (xy 271.339828 -274.818709)
			(xy 271.293812 -274.801257) (xy 271.251191 -274.77665) (xy 271.21307 -274.745525) (xy 271.180435 -274.708688)
			(xy 271.154132 -274.667092) (xy 271.134841 -274.621816) (xy 271.123064 -274.574032) (xy 271.119104 -274.524978)
			(xy 270.806226 -274.524978) (xy 270.806227 -274.524985) (xy 270.802371 -274.575401) (xy 270.790889 -274.624643)
			(xy 270.772047 -274.671564) (xy 270.746286 -274.715072) (xy 270.714204 -274.754153) (xy 270.695674 -274.771358)
			(xy 270.688054 -274.777962) (xy 270.68145 -274.79244) (xy 270.679188 -274.797614) (xy 270.676751 -274.808638)
			(xy 270.676624 -274.814284) (xy 270.67764 -274.824444) (xy 270.680903 -274.840632) (xy 270.684465 -274.873465)
			(xy 270.684752 -274.889976) (xy 270.684752 -275.10994) (xy 270.684465 -275.126451) (xy 270.680899 -275.159283)
			(xy 270.67764 -275.175472) (xy 270.676624 -275.185632) (xy 270.676749 -275.191278) (xy 270.679187 -275.202302)
			(xy 270.68145 -275.207476) (xy 270.688054 -275.221954) (xy 270.695674 -275.228558) (xy 270.714179 -275.245786)
			(xy 270.746255 -275.284863) (xy 270.772012 -275.328366) (xy 270.790849 -275.375281) (xy 270.802328 -275.424517)
			(xy 270.806182 -275.474925) (xy 270.806181 -275.474938) (xy 271.119104 -275.474938) (xy 271.123064 -275.425884)
			(xy 271.134841 -275.3781) (xy 271.154132 -275.332824) (xy 271.180435 -275.291228) (xy 271.21307 -275.254391)
			(xy 271.251191 -275.223266) (xy 271.293812 -275.198659) (xy 271.339828 -275.181207) (xy 271.388047 -275.171363)
			(xy 271.437222 -275.169382) (xy 271.486077 -275.175314) (xy 271.533348 -275.189006) (xy 271.57781 -275.210104)
			(xy 271.618313 -275.23806) (xy 271.653806 -275.272152) (xy 271.683371 -275.311496) (xy 271.706242 -275.355073)
			(xy 271.721826 -275.401754) (xy 271.729721 -275.450331) (xy 271.730216 -275.474938) (xy 272.069064 -275.474938)
			(xy 272.073024 -275.425884) (xy 272.084801 -275.3781) (xy 272.104092 -275.332824) (xy 272.130395 -275.291228)
			(xy 272.16303 -275.254391) (xy 272.201151 -275.223266) (xy 272.243772 -275.198659) (xy 272.289788 -275.181207)
			(xy 272.338007 -275.171363) (xy 272.387182 -275.169382) (xy 272.436037 -275.175314) (xy 272.483308 -275.189006)
			(xy 272.52777 -275.210104) (xy 272.568273 -275.23806) (xy 272.603766 -275.272152) (xy 272.633331 -275.311496)
			(xy 272.656202 -275.355073) (xy 272.671786 -275.401754) (xy 272.679681 -275.450331) (xy 272.680176 -275.474938)
			(xy 273.019024 -275.474938) (xy 273.022984 -275.425884) (xy 273.034761 -275.3781) (xy 273.054052 -275.332824)
			(xy 273.080355 -275.291228) (xy 273.11299 -275.254391) (xy 273.151111 -275.223266) (xy 273.193732 -275.198659)
			(xy 273.239748 -275.181207) (xy 273.287967 -275.171363) (xy 273.337142 -275.169382) (xy 273.385997 -275.175314)
			(xy 273.433268 -275.189006) (xy 273.47773 -275.210104) (xy 273.518233 -275.23806) (xy 273.553726 -275.272152)
			(xy 273.583291 -275.311496) (xy 273.606162 -275.355073) (xy 273.621746 -275.401754) (xy 273.629641 -275.450331)
			(xy 273.630136 -275.474938) (xy 273.629641 -275.499545) (xy 273.621746 -275.548122) (xy 273.606162 -275.594803)
			(xy 273.583291 -275.63838) (xy 273.553726 -275.677724) (xy 273.518233 -275.711816) (xy 273.47773 -275.739772)
			(xy 273.433268 -275.76087) (xy 273.385997 -275.774562) (xy 273.337142 -275.780494) (xy 273.287967 -275.778513)
			(xy 273.239748 -275.768669) (xy 273.193732 -275.751217) (xy 273.151111 -275.72661) (xy 273.11299 -275.695485)
			(xy 273.080355 -275.658648) (xy 273.054052 -275.617052) (xy 273.034761 -275.571776) (xy 273.022984 -275.523992)
			(xy 273.019024 -275.474938) (xy 272.680176 -275.474938) (xy 272.679681 -275.499545) (xy 272.671786 -275.548122)
			(xy 272.656202 -275.594803) (xy 272.633331 -275.63838) (xy 272.603766 -275.677724) (xy 272.568273 -275.711816)
			(xy 272.52777 -275.739772) (xy 272.483308 -275.76087) (xy 272.436037 -275.774562) (xy 272.387182 -275.780494)
			(xy 272.338007 -275.778513) (xy 272.289788 -275.768669) (xy 272.243772 -275.751217) (xy 272.201151 -275.72661)
			(xy 272.16303 -275.695485) (xy 272.130395 -275.658648) (xy 272.104092 -275.617052) (xy 272.084801 -275.571776)
			(xy 272.073024 -275.523992) (xy 272.069064 -275.474938) (xy 271.730216 -275.474938) (xy 271.729721 -275.499545)
			(xy 271.721826 -275.548122) (xy 271.706242 -275.594803) (xy 271.683371 -275.63838) (xy 271.653806 -275.677724)
			(xy 271.618313 -275.711816) (xy 271.57781 -275.739772) (xy 271.533348 -275.76087) (xy 271.486077 -275.774562)
			(xy 271.437222 -275.780494) (xy 271.388047 -275.778513) (xy 271.339828 -275.768669) (xy 271.293812 -275.751217)
			(xy 271.251191 -275.72661) (xy 271.21307 -275.695485) (xy 271.180435 -275.658648) (xy 271.154132 -275.617052)
			(xy 271.134841 -275.571776) (xy 271.123064 -275.523992) (xy 271.119104 -275.474938) (xy 270.806181 -275.474938)
			(xy 270.80232 -275.525334) (xy 270.790834 -275.574567) (xy 270.771989 -275.62148) (xy 270.746226 -275.664979)
			(xy 270.714143 -275.704051) (xy 270.695674 -275.721318) (xy 270.688054 -275.727922) (xy 270.68145 -275.7424)
			(xy 270.679184 -275.747574) (xy 270.676738 -275.758598) (xy 270.676624 -275.764244) (xy 270.67764 -275.774404)
			(xy 270.680905 -275.790592) (xy 270.684471 -275.823424) (xy 270.684752 -275.839936) (xy 270.684752 -276.0599)
			(xy 270.684467 -276.076411) (xy 270.680905 -276.109244) (xy 270.67764 -276.125432) (xy 270.676624 -276.135592)
			(xy 270.676745 -276.141239) (xy 270.679175 -276.152266) (xy 270.68145 -276.157436) (xy 270.688054 -276.171914)
			(xy 270.695674 -276.178518) (xy 270.714182 -276.195745) (xy 270.746264 -276.234823) (xy 270.772027 -276.278328)
			(xy 270.79087 -276.325246) (xy 270.802354 -276.374485) (xy 270.806212 -276.424898) (xy 271.119104 -276.424898)
			(xy 271.123064 -276.375844) (xy 271.134841 -276.32806) (xy 271.154132 -276.282784) (xy 271.180435 -276.241188)
			(xy 271.21307 -276.204351) (xy 271.251191 -276.173226) (xy 271.293812 -276.148619) (xy 271.339828 -276.131167)
			(xy 271.388047 -276.121323) (xy 271.437222 -276.119342) (xy 271.486077 -276.125274) (xy 271.533348 -276.138966)
			(xy 271.57781 -276.160064) (xy 271.618313 -276.18802) (xy 271.653806 -276.222112) (xy 271.683371 -276.261456)
			(xy 271.706242 -276.305033) (xy 271.721826 -276.351714) (xy 271.729721 -276.400291) (xy 271.730216 -276.424898)
			(xy 272.069064 -276.424898) (xy 272.073024 -276.375844) (xy 272.084801 -276.32806) (xy 272.104092 -276.282784)
			(xy 272.130395 -276.241188) (xy 272.16303 -276.204351) (xy 272.201151 -276.173226) (xy 272.243772 -276.148619)
			(xy 272.289788 -276.131167) (xy 272.338007 -276.121323) (xy 272.387182 -276.119342) (xy 272.436037 -276.125274)
			(xy 272.483308 -276.138966) (xy 272.52777 -276.160064) (xy 272.568273 -276.18802) (xy 272.603766 -276.222112)
			(xy 272.633331 -276.261456) (xy 272.656202 -276.305033) (xy 272.671786 -276.351714) (xy 272.679681 -276.400291)
			(xy 272.680176 -276.424898) (xy 273.019024 -276.424898) (xy 273.022984 -276.375844) (xy 273.034761 -276.32806)
			(xy 273.054052 -276.282784) (xy 273.080355 -276.241188) (xy 273.11299 -276.204351) (xy 273.151111 -276.173226)
			(xy 273.193732 -276.148619) (xy 273.239748 -276.131167) (xy 273.287967 -276.121323) (xy 273.337142 -276.119342)
			(xy 273.385997 -276.125274) (xy 273.433268 -276.138966) (xy 273.47773 -276.160064) (xy 273.518233 -276.18802)
			(xy 273.553726 -276.222112) (xy 273.583291 -276.261456) (xy 273.606162 -276.305033) (xy 273.621746 -276.351714)
			(xy 273.629641 -276.400291) (xy 273.630136 -276.424898) (xy 273.629641 -276.449505) (xy 273.621746 -276.498082)
			(xy 273.606162 -276.544763) (xy 273.583291 -276.58834) (xy 273.553726 -276.627684) (xy 273.518233 -276.661776)
			(xy 273.47773 -276.689732) (xy 273.433268 -276.71083) (xy 273.385997 -276.724522) (xy 273.337142 -276.730454)
			(xy 273.287967 -276.728473) (xy 273.239748 -276.718629) (xy 273.193732 -276.701177) (xy 273.151111 -276.67657)
			(xy 273.11299 -276.645445) (xy 273.080355 -276.608608) (xy 273.054052 -276.567012) (xy 273.034761 -276.521736)
			(xy 273.022984 -276.473952) (xy 273.019024 -276.424898) (xy 272.680176 -276.424898) (xy 272.679681 -276.449505)
			(xy 272.671786 -276.498082) (xy 272.656202 -276.544763) (xy 272.633331 -276.58834) (xy 272.603766 -276.627684)
			(xy 272.568273 -276.661776) (xy 272.52777 -276.689732) (xy 272.483308 -276.71083) (xy 272.436037 -276.724522)
			(xy 272.387182 -276.730454) (xy 272.338007 -276.728473) (xy 272.289788 -276.718629) (xy 272.243772 -276.701177)
			(xy 272.201151 -276.67657) (xy 272.16303 -276.645445) (xy 272.130395 -276.608608) (xy 272.104092 -276.567012)
			(xy 272.084801 -276.521736) (xy 272.073024 -276.473952) (xy 272.069064 -276.424898) (xy 271.730216 -276.424898)
			(xy 271.729721 -276.449505) (xy 271.721826 -276.498082) (xy 271.706242 -276.544763) (xy 271.683371 -276.58834)
			(xy 271.653806 -276.627684) (xy 271.618313 -276.661776) (xy 271.57781 -276.689732) (xy 271.533348 -276.71083)
			(xy 271.486077 -276.724522) (xy 271.437222 -276.730454) (xy 271.388047 -276.728473) (xy 271.339828 -276.718629)
			(xy 271.293812 -276.701177) (xy 271.251191 -276.67657) (xy 271.21307 -276.645445) (xy 271.180435 -276.608608)
			(xy 271.154132 -276.567012) (xy 271.134841 -276.521736) (xy 271.123064 -276.473952) (xy 271.119104 -276.424898)
			(xy 270.806212 -276.424898) (xy 270.806212 -276.424899) (xy 270.802354 -276.475312) (xy 270.790871 -276.524551)
			(xy 270.772028 -276.571469) (xy 270.746266 -276.614974) (xy 270.714184 -276.654053) (xy 270.695674 -276.671278)
			(xy 270.688054 -276.677882) (xy 270.68145 -276.69236) (xy 270.67919 -276.697535) (xy 270.676757 -276.708559)
			(xy 270.676624 -276.714204) (xy 270.67764 -276.724364) (xy 270.680901 -276.740552) (xy 270.684462 -276.773385)
			(xy 270.684752 -276.789896) (xy 270.684752 -277.00986) (xy 270.684464 -277.026371) (xy 270.680896 -277.059202)
			(xy 270.67764 -277.075392) (xy 270.676624 -277.085552) (xy 270.676751 -277.091197) (xy 270.679194 -277.102219)
			(xy 270.68145 -277.107396) (xy 270.688054 -277.121874) (xy 270.695674 -277.128478) (xy 270.714185 -277.145705)
			(xy 270.746273 -277.184784) (xy 270.772042 -277.228291) (xy 270.79089 -277.275212) (xy 270.802379 -277.324455)
			(xy 270.806241 -277.374858) (xy 271.119104 -277.374858) (xy 271.123064 -277.325804) (xy 271.134841 -277.27802)
			(xy 271.154132 -277.232744) (xy 271.180435 -277.191148) (xy 271.21307 -277.154311) (xy 271.251191 -277.123186)
			(xy 271.293812 -277.098579) (xy 271.339828 -277.081127) (xy 271.388047 -277.071283) (xy 271.437222 -277.069302)
			(xy 271.486077 -277.075234) (xy 271.533348 -277.088926) (xy 271.57781 -277.110024) (xy 271.618313 -277.13798)
			(xy 271.653806 -277.172072) (xy 271.683371 -277.211416) (xy 271.706242 -277.254993) (xy 271.721826 -277.301674)
			(xy 271.729721 -277.350251) (xy 271.730216 -277.374858) (xy 272.069064 -277.374858) (xy 272.073024 -277.325804)
			(xy 272.084801 -277.27802) (xy 272.104092 -277.232744) (xy 272.130395 -277.191148) (xy 272.16303 -277.154311)
			(xy 272.201151 -277.123186) (xy 272.243772 -277.098579) (xy 272.289788 -277.081127) (xy 272.338007 -277.071283)
			(xy 272.387182 -277.069302) (xy 272.436037 -277.075234) (xy 272.483308 -277.088926) (xy 272.52777 -277.110024)
			(xy 272.568273 -277.13798) (xy 272.603766 -277.172072) (xy 272.633331 -277.211416) (xy 272.656202 -277.254993)
			(xy 272.671786 -277.301674) (xy 272.679681 -277.350251) (xy 272.680176 -277.374858) (xy 273.019024 -277.374858)
			(xy 273.022984 -277.325804) (xy 273.034761 -277.27802) (xy 273.054052 -277.232744) (xy 273.080355 -277.191148)
			(xy 273.11299 -277.154311) (xy 273.151111 -277.123186) (xy 273.193732 -277.098579) (xy 273.239748 -277.081127)
			(xy 273.287967 -277.071283) (xy 273.337142 -277.069302) (xy 273.385997 -277.075234) (xy 273.433268 -277.088926)
			(xy 273.47773 -277.110024) (xy 273.518233 -277.13798) (xy 273.553726 -277.172072) (xy 273.583291 -277.211416)
			(xy 273.606162 -277.254993) (xy 273.621746 -277.301674) (xy 273.629641 -277.350251) (xy 273.630136 -277.374858)
			(xy 273.629641 -277.399465) (xy 273.621746 -277.448042) (xy 273.606162 -277.494723) (xy 273.583291 -277.5383)
			(xy 273.553726 -277.577644) (xy 273.518233 -277.611736) (xy 273.47773 -277.639692) (xy 273.433268 -277.66079)
			(xy 273.385997 -277.674482) (xy 273.337142 -277.680414) (xy 273.287967 -277.678433) (xy 273.239748 -277.668589)
			(xy 273.193732 -277.651137) (xy 273.151111 -277.62653) (xy 273.11299 -277.595405) (xy 273.080355 -277.558568)
			(xy 273.054052 -277.516972) (xy 273.034761 -277.471696) (xy 273.022984 -277.423912) (xy 273.019024 -277.374858)
			(xy 272.680176 -277.374858) (xy 272.679681 -277.399465) (xy 272.671786 -277.448042) (xy 272.656202 -277.494723)
			(xy 272.633331 -277.5383) (xy 272.603766 -277.577644) (xy 272.568273 -277.611736) (xy 272.52777 -277.639692)
			(xy 272.483308 -277.66079) (xy 272.436037 -277.674482) (xy 272.387182 -277.680414) (xy 272.338007 -277.678433)
			(xy 272.289788 -277.668589) (xy 272.243772 -277.651137) (xy 272.201151 -277.62653) (xy 272.16303 -277.595405)
			(xy 272.130395 -277.558568) (xy 272.104092 -277.516972) (xy 272.084801 -277.471696) (xy 272.073024 -277.423912)
			(xy 272.069064 -277.374858) (xy 271.730216 -277.374858) (xy 271.729721 -277.399465) (xy 271.721826 -277.448042)
			(xy 271.706242 -277.494723) (xy 271.683371 -277.5383) (xy 271.653806 -277.577644) (xy 271.618313 -277.611736)
			(xy 271.57781 -277.639692) (xy 271.533348 -277.66079) (xy 271.486077 -277.674482) (xy 271.437222 -277.680414)
			(xy 271.388047 -277.678433) (xy 271.339828 -277.668589) (xy 271.293812 -277.651137) (xy 271.251191 -277.62653)
			(xy 271.21307 -277.595405) (xy 271.180435 -277.558568) (xy 271.154132 -277.516972) (xy 271.134841 -277.471696)
			(xy 271.123064 -277.423912) (xy 271.119104 -277.374858) (xy 270.806241 -277.374858) (xy 270.806242 -277.374872)
			(xy 270.802388 -277.42529) (xy 270.790907 -277.474535) (xy 270.772067 -277.521459) (xy 270.746306 -277.56497)
			(xy 270.714224 -277.604054) (xy 270.695674 -277.621238) (xy 270.688054 -277.627842) (xy 270.68145 -277.64232)
			(xy 270.679186 -277.647494) (xy 270.676744 -277.658518) (xy 270.676624 -277.664164) (xy 270.67764 -277.674324)
			(xy 270.680904 -277.690512) (xy 270.684468 -277.723345) (xy 270.684752 -277.739856) (xy 270.684752 -277.95982)
			(xy 270.684466 -277.976331) (xy 270.680902 -278.009164) (xy 270.67764 -278.025352) (xy 270.676624 -278.035512)
			(xy 270.676747 -278.041158) (xy 270.679181 -278.052184) (xy 270.68145 -278.057356) (xy 270.688054 -278.071834)
			(xy 270.695674 -278.078438) (xy 270.71418 -278.095665) (xy 270.74626 -278.134743) (xy 270.772019 -278.178247)
			(xy 270.79086 -278.225164) (xy 270.802341 -278.274401) (xy 270.806197 -278.324812) (xy 270.806197 -278.324818)
			(xy 271.119104 -278.324818) (xy 271.123064 -278.275764) (xy 271.134841 -278.22798) (xy 271.154132 -278.182704)
			(xy 271.180435 -278.141108) (xy 271.21307 -278.104271) (xy 271.251191 -278.073146) (xy 271.293812 -278.048539)
			(xy 271.339828 -278.031087) (xy 271.388047 -278.021243) (xy 271.437222 -278.019262) (xy 271.486077 -278.025194)
			(xy 271.533348 -278.038886) (xy 271.57781 -278.059984) (xy 271.618313 -278.08794) (xy 271.653806 -278.122032)
			(xy 271.683371 -278.161376) (xy 271.706242 -278.204953) (xy 271.721826 -278.251634) (xy 271.729721 -278.300211)
			(xy 271.730216 -278.324818) (xy 272.069064 -278.324818) (xy 272.073024 -278.275764) (xy 272.084801 -278.22798)
			(xy 272.104092 -278.182704) (xy 272.130395 -278.141108) (xy 272.16303 -278.104271) (xy 272.201151 -278.073146)
			(xy 272.243772 -278.048539) (xy 272.289788 -278.031087) (xy 272.338007 -278.021243) (xy 272.387182 -278.019262)
			(xy 272.436037 -278.025194) (xy 272.483308 -278.038886) (xy 272.52777 -278.059984) (xy 272.568273 -278.08794)
			(xy 272.603766 -278.122032) (xy 272.633331 -278.161376) (xy 272.656202 -278.204953) (xy 272.671786 -278.251634)
			(xy 272.679681 -278.300211) (xy 272.680176 -278.324818) (xy 273.019024 -278.324818) (xy 273.022984 -278.275764)
			(xy 273.034761 -278.22798) (xy 273.054052 -278.182704) (xy 273.080355 -278.141108) (xy 273.11299 -278.104271)
			(xy 273.151111 -278.073146) (xy 273.193732 -278.048539) (xy 273.239748 -278.031087) (xy 273.287967 -278.021243)
			(xy 273.337142 -278.019262) (xy 273.385997 -278.025194) (xy 273.433268 -278.038886) (xy 273.47773 -278.059984)
			(xy 273.518233 -278.08794) (xy 273.553726 -278.122032) (xy 273.583291 -278.161376) (xy 273.606162 -278.204953)
			(xy 273.621746 -278.251634) (xy 273.629641 -278.300211) (xy 273.630136 -278.324818) (xy 273.629641 -278.349425)
			(xy 273.621746 -278.398002) (xy 273.606162 -278.444683) (xy 273.583291 -278.48826) (xy 273.553726 -278.527604)
			(xy 273.518233 -278.561696) (xy 273.47773 -278.589652) (xy 273.433268 -278.61075) (xy 273.385997 -278.624442)
			(xy 273.337142 -278.630374) (xy 273.287967 -278.628393) (xy 273.239748 -278.618549) (xy 273.193732 -278.601097)
			(xy 273.151111 -278.57649) (xy 273.11299 -278.545365) (xy 273.080355 -278.508528) (xy 273.054052 -278.466932)
			(xy 273.034761 -278.421656) (xy 273.022984 -278.373872) (xy 273.019024 -278.324818) (xy 272.680176 -278.324818)
			(xy 272.679681 -278.349425) (xy 272.671786 -278.398002) (xy 272.656202 -278.444683) (xy 272.633331 -278.48826)
			(xy 272.603766 -278.527604) (xy 272.568273 -278.561696) (xy 272.52777 -278.589652) (xy 272.483308 -278.61075)
			(xy 272.436037 -278.624442) (xy 272.387182 -278.630374) (xy 272.338007 -278.628393) (xy 272.289788 -278.618549)
			(xy 272.243772 -278.601097) (xy 272.201151 -278.57649) (xy 272.16303 -278.545365) (xy 272.130395 -278.508528)
			(xy 272.104092 -278.466932) (xy 272.084801 -278.421656) (xy 272.073024 -278.373872) (xy 272.069064 -278.324818)
			(xy 271.730216 -278.324818) (xy 271.729721 -278.349425) (xy 271.721826 -278.398002) (xy 271.706242 -278.444683)
			(xy 271.683371 -278.48826) (xy 271.653806 -278.527604) (xy 271.618313 -278.561696) (xy 271.57781 -278.589652)
			(xy 271.533348 -278.61075) (xy 271.486077 -278.624442) (xy 271.437222 -278.630374) (xy 271.388047 -278.628393)
			(xy 271.339828 -278.618549) (xy 271.293812 -278.601097) (xy 271.251191 -278.57649) (xy 271.21307 -278.545365)
			(xy 271.180435 -278.508528) (xy 271.154132 -278.466932) (xy 271.134841 -278.421656) (xy 271.123064 -278.373872)
			(xy 271.119104 -278.324818) (xy 270.806197 -278.324818) (xy 270.802338 -278.375223) (xy 270.790852 -278.424459)
			(xy 270.772009 -278.471375) (xy 270.746246 -278.514877) (xy 270.714164 -278.553952) (xy 270.695674 -278.571198)
			(xy 270.688054 -278.577802) (xy 270.68145 -278.59228) (xy 270.679193 -278.597455) (xy 270.676764 -278.608479)
			(xy 270.676624 -278.614124) (xy 270.67764 -278.624284) (xy 270.6809 -278.640473) (xy 270.684459 -278.673305)
			(xy 270.684752 -278.689816) (xy 270.684752 -278.90978) (xy 270.684468 -278.926292) (xy 270.680908 -278.959125)
			(xy 270.67764 -278.975312) (xy 270.676624 -278.985472) (xy 270.676753 -278.991117) (xy 270.6792 -279.002137)
			(xy 270.68145 -279.007316) (xy 270.688054 -279.021794) (xy 270.695674 -279.028398) (xy 270.714183 -279.045625)
			(xy 270.746269 -279.084704) (xy 270.772034 -279.12821) (xy 270.79088 -279.175129) (xy 270.802367 -279.22437)
			(xy 270.806226 -279.274778) (xy 271.119104 -279.274778) (xy 271.123064 -279.225724) (xy 271.134841 -279.17794)
			(xy 271.154132 -279.132664) (xy 271.180435 -279.091068) (xy 271.21307 -279.054231) (xy 271.251191 -279.023106)
			(xy 271.293812 -278.998499) (xy 271.339828 -278.981047) (xy 271.388047 -278.971203) (xy 271.437222 -278.969222)
			(xy 271.486077 -278.975154) (xy 271.533348 -278.988846) (xy 271.57781 -279.009944) (xy 271.618313 -279.0379)
			(xy 271.653806 -279.071992) (xy 271.683371 -279.111336) (xy 271.706242 -279.154913) (xy 271.721826 -279.201594)
			(xy 271.729721 -279.250171) (xy 271.730216 -279.274778) (xy 272.069064 -279.274778) (xy 272.073024 -279.225724)
			(xy 272.084801 -279.17794) (xy 272.104092 -279.132664) (xy 272.130395 -279.091068) (xy 272.16303 -279.054231)
			(xy 272.201151 -279.023106) (xy 272.243772 -278.998499) (xy 272.289788 -278.981047) (xy 272.338007 -278.971203)
			(xy 272.387182 -278.969222) (xy 272.436037 -278.975154) (xy 272.483308 -278.988846) (xy 272.52777 -279.009944)
			(xy 272.568273 -279.0379) (xy 272.603766 -279.071992) (xy 272.633331 -279.111336) (xy 272.656202 -279.154913)
			(xy 272.671786 -279.201594) (xy 272.679681 -279.250171) (xy 272.680176 -279.274778) (xy 273.019024 -279.274778)
			(xy 273.022984 -279.225724) (xy 273.034761 -279.17794) (xy 273.054052 -279.132664) (xy 273.080355 -279.091068)
			(xy 273.11299 -279.054231) (xy 273.151111 -279.023106) (xy 273.193732 -278.998499) (xy 273.239748 -278.981047)
			(xy 273.287967 -278.971203) (xy 273.337142 -278.969222) (xy 273.385997 -278.975154) (xy 273.433268 -278.988846)
			(xy 273.47773 -279.009944) (xy 273.518233 -279.0379) (xy 273.553726 -279.071992) (xy 273.583291 -279.111336)
			(xy 273.606162 -279.154913) (xy 273.621746 -279.201594) (xy 273.629641 -279.250171) (xy 273.630136 -279.274778)
			(xy 273.629641 -279.299385) (xy 273.621746 -279.347962) (xy 273.606162 -279.394643) (xy 273.583291 -279.43822)
			(xy 273.553726 -279.477564) (xy 273.518233 -279.511656) (xy 273.47773 -279.539612) (xy 273.433268 -279.56071)
			(xy 273.385997 -279.574402) (xy 273.337142 -279.580334) (xy 273.287967 -279.578353) (xy 273.239748 -279.568509)
			(xy 273.193732 -279.551057) (xy 273.151111 -279.52645) (xy 273.11299 -279.495325) (xy 273.080355 -279.458488)
			(xy 273.054052 -279.416892) (xy 273.034761 -279.371616) (xy 273.022984 -279.323832) (xy 273.019024 -279.274778)
			(xy 272.680176 -279.274778) (xy 272.679681 -279.299385) (xy 272.671786 -279.347962) (xy 272.656202 -279.394643)
			(xy 272.633331 -279.43822) (xy 272.603766 -279.477564) (xy 272.568273 -279.511656) (xy 272.52777 -279.539612)
			(xy 272.483308 -279.56071) (xy 272.436037 -279.574402) (xy 272.387182 -279.580334) (xy 272.338007 -279.578353)
			(xy 272.289788 -279.568509) (xy 272.243772 -279.551057) (xy 272.201151 -279.52645) (xy 272.16303 -279.495325)
			(xy 272.130395 -279.458488) (xy 272.104092 -279.416892) (xy 272.084801 -279.371616) (xy 272.073024 -279.323832)
			(xy 272.069064 -279.274778) (xy 271.730216 -279.274778) (xy 271.729721 -279.299385) (xy 271.721826 -279.347962)
			(xy 271.706242 -279.394643) (xy 271.683371 -279.43822) (xy 271.653806 -279.477564) (xy 271.618313 -279.511656)
			(xy 271.57781 -279.539612) (xy 271.533348 -279.56071) (xy 271.486077 -279.574402) (xy 271.437222 -279.580334)
			(xy 271.388047 -279.578353) (xy 271.339828 -279.568509) (xy 271.293812 -279.551057) (xy 271.251191 -279.52645)
			(xy 271.21307 -279.495325) (xy 271.180435 -279.458488) (xy 271.154132 -279.416892) (xy 271.134841 -279.371616)
			(xy 271.123064 -279.323832) (xy 271.119104 -279.274778) (xy 270.806226 -279.274778) (xy 270.806227 -279.274785)
			(xy 270.802371 -279.325201) (xy 270.790889 -279.374443) (xy 270.772047 -279.421364) (xy 270.746286 -279.464872)
			(xy 270.714204 -279.503953) (xy 270.695674 -279.521158) (xy 270.688054 -279.527762) (xy 270.68145 -279.54224)
			(xy 270.679188 -279.547414) (xy 270.676751 -279.558438) (xy 270.676624 -279.564084) (xy 270.67764 -279.574244)
			(xy 270.680903 -279.590432) (xy 270.684465 -279.623265) (xy 270.684752 -279.639776) (xy 270.684752 -279.85974)
			(xy 270.684465 -279.876251) (xy 270.680899 -279.909083) (xy 270.67764 -279.925272) (xy 270.676624 -279.935432)
			(xy 270.676749 -279.941078) (xy 270.679187 -279.952102) (xy 270.68145 -279.957276) (xy 270.688054 -279.971754)
			(xy 270.695674 -279.978358) (xy 270.714179 -279.995586) (xy 270.746255 -280.034663) (xy 270.772012 -280.078166)
			(xy 270.790849 -280.125081) (xy 270.802328 -280.174317) (xy 270.806182 -280.224725) (xy 270.806181 -280.224738)
			(xy 271.119104 -280.224738) (xy 271.123064 -280.175684) (xy 271.134841 -280.1279) (xy 271.154132 -280.082624)
			(xy 271.180435 -280.041028) (xy 271.21307 -280.004191) (xy 271.251191 -279.973066) (xy 271.293812 -279.948459)
			(xy 271.339828 -279.931007) (xy 271.388047 -279.921163) (xy 271.437222 -279.919182) (xy 271.486077 -279.925114)
			(xy 271.533348 -279.938806) (xy 271.57781 -279.959904) (xy 271.618313 -279.98786) (xy 271.653806 -280.021952)
			(xy 271.683371 -280.061296) (xy 271.706242 -280.104873) (xy 271.721826 -280.151554) (xy 271.729721 -280.200131)
			(xy 271.730216 -280.224738) (xy 272.069064 -280.224738) (xy 272.073024 -280.175684) (xy 272.084801 -280.1279)
			(xy 272.104092 -280.082624) (xy 272.130395 -280.041028) (xy 272.16303 -280.004191) (xy 272.201151 -279.973066)
			(xy 272.243772 -279.948459) (xy 272.289788 -279.931007) (xy 272.338007 -279.921163) (xy 272.387182 -279.919182)
			(xy 272.436037 -279.925114) (xy 272.483308 -279.938806) (xy 272.52777 -279.959904) (xy 272.568273 -279.98786)
			(xy 272.603766 -280.021952) (xy 272.633331 -280.061296) (xy 272.656202 -280.104873) (xy 272.671786 -280.151554)
			(xy 272.679681 -280.200131) (xy 272.680176 -280.224738) (xy 273.019024 -280.224738) (xy 273.022984 -280.175684)
			(xy 273.034761 -280.1279) (xy 273.054052 -280.082624) (xy 273.080355 -280.041028) (xy 273.11299 -280.004191)
			(xy 273.151111 -279.973066) (xy 273.193732 -279.948459) (xy 273.239748 -279.931007) (xy 273.287967 -279.921163)
			(xy 273.337142 -279.919182) (xy 273.385997 -279.925114) (xy 273.433268 -279.938806) (xy 273.47773 -279.959904)
			(xy 273.518233 -279.98786) (xy 273.553726 -280.021952) (xy 273.583291 -280.061296) (xy 273.606162 -280.104873)
			(xy 273.621746 -280.151554) (xy 273.629641 -280.200131) (xy 273.630136 -280.224738) (xy 273.629641 -280.249345)
			(xy 273.621746 -280.297922) (xy 273.606162 -280.344603) (xy 273.583291 -280.38818) (xy 273.553726 -280.427524)
			(xy 273.518233 -280.461616) (xy 273.47773 -280.489572) (xy 273.433268 -280.51067) (xy 273.385997 -280.524362)
			(xy 273.337142 -280.530294) (xy 273.287967 -280.528313) (xy 273.239748 -280.518469) (xy 273.193732 -280.501017)
			(xy 273.151111 -280.47641) (xy 273.11299 -280.445285) (xy 273.080355 -280.408448) (xy 273.054052 -280.366852)
			(xy 273.034761 -280.321576) (xy 273.022984 -280.273792) (xy 273.019024 -280.224738) (xy 272.680176 -280.224738)
			(xy 272.679681 -280.249345) (xy 272.671786 -280.297922) (xy 272.656202 -280.344603) (xy 272.633331 -280.38818)
			(xy 272.603766 -280.427524) (xy 272.568273 -280.461616) (xy 272.52777 -280.489572) (xy 272.483308 -280.51067)
			(xy 272.436037 -280.524362) (xy 272.387182 -280.530294) (xy 272.338007 -280.528313) (xy 272.289788 -280.518469)
			(xy 272.243772 -280.501017) (xy 272.201151 -280.47641) (xy 272.16303 -280.445285) (xy 272.130395 -280.408448)
			(xy 272.104092 -280.366852) (xy 272.084801 -280.321576) (xy 272.073024 -280.273792) (xy 272.069064 -280.224738)
			(xy 271.730216 -280.224738) (xy 271.729721 -280.249345) (xy 271.721826 -280.297922) (xy 271.706242 -280.344603)
			(xy 271.683371 -280.38818) (xy 271.653806 -280.427524) (xy 271.618313 -280.461616) (xy 271.57781 -280.489572)
			(xy 271.533348 -280.51067) (xy 271.486077 -280.524362) (xy 271.437222 -280.530294) (xy 271.388047 -280.528313)
			(xy 271.339828 -280.518469) (xy 271.293812 -280.501017) (xy 271.251191 -280.47641) (xy 271.21307 -280.445285)
			(xy 271.180435 -280.408448) (xy 271.154132 -280.366852) (xy 271.134841 -280.321576) (xy 271.123064 -280.273792)
			(xy 271.119104 -280.224738) (xy 270.806181 -280.224738) (xy 270.80232 -280.275134) (xy 270.790834 -280.324367)
			(xy 270.771989 -280.37128) (xy 270.746226 -280.414779) (xy 270.714143 -280.453851) (xy 270.695674 -280.471118)
			(xy 270.688054 -280.477722) (xy 270.68145 -280.4922) (xy 270.679184 -280.497374) (xy 270.676738 -280.508398)
			(xy 270.676624 -280.514044) (xy 270.67764 -280.524204) (xy 270.680905 -280.540392) (xy 270.684471 -280.573224)
			(xy 270.684752 -280.589736) (xy 270.684752 -280.809954) (xy 270.684464 -280.826465) (xy 270.680897 -280.859297)
			(xy 270.67764 -280.875486) (xy 270.676624 -280.885646) (xy 270.676751 -280.891291) (xy 270.679192 -280.902314)
			(xy 270.68145 -280.90749) (xy 270.688054 -280.921968) (xy 270.695674 -280.928572) (xy 270.714185 -280.945799)
			(xy 270.746275 -280.984879) (xy 270.772044 -281.028385) (xy 270.790893 -281.075307) (xy 270.802383 -281.12455)
			(xy 270.806245 -281.174952) (xy 271.119104 -281.174952) (xy 271.123064 -281.125898) (xy 271.134841 -281.078114)
			(xy 271.154132 -281.032838) (xy 271.180435 -280.991242) (xy 271.21307 -280.954405) (xy 271.251191 -280.92328)
			(xy 271.293812 -280.898673) (xy 271.339828 -280.881221) (xy 271.388047 -280.871377) (xy 271.437222 -280.869396)
			(xy 271.486077 -280.875328) (xy 271.533348 -280.88902) (xy 271.57781 -280.910118) (xy 271.618313 -280.938074)
			(xy 271.653806 -280.972166) (xy 271.683371 -281.01151) (xy 271.706242 -281.055087) (xy 271.721826 -281.101768)
			(xy 271.729721 -281.150345) (xy 271.730216 -281.174952) (xy 272.069064 -281.174952) (xy 272.073024 -281.125898)
			(xy 272.084801 -281.078114) (xy 272.104092 -281.032838) (xy 272.130395 -280.991242) (xy 272.16303 -280.954405)
			(xy 272.201151 -280.92328) (xy 272.243772 -280.898673) (xy 272.289788 -280.881221) (xy 272.338007 -280.871377)
			(xy 272.387182 -280.869396) (xy 272.436037 -280.875328) (xy 272.483308 -280.88902) (xy 272.52777 -280.910118)
			(xy 272.568273 -280.938074) (xy 272.603766 -280.972166) (xy 272.633331 -281.01151) (xy 272.656202 -281.055087)
			(xy 272.671786 -281.101768) (xy 272.679681 -281.150345) (xy 272.680176 -281.174952) (xy 273.019024 -281.174952)
			(xy 273.022984 -281.125898) (xy 273.034761 -281.078114) (xy 273.054052 -281.032838) (xy 273.080355 -280.991242)
			(xy 273.11299 -280.954405) (xy 273.151111 -280.92328) (xy 273.193732 -280.898673) (xy 273.239748 -280.881221)
			(xy 273.287967 -280.871377) (xy 273.337142 -280.869396) (xy 273.385997 -280.875328) (xy 273.433268 -280.88902)
			(xy 273.47773 -280.910118) (xy 273.518233 -280.938074) (xy 273.553726 -280.972166) (xy 273.583291 -281.01151)
			(xy 273.606162 -281.055087) (xy 273.621746 -281.101768) (xy 273.629641 -281.150345) (xy 273.630136 -281.174952)
			(xy 273.629641 -281.199559) (xy 273.621746 -281.248136) (xy 273.606162 -281.294817) (xy 273.583291 -281.338394)
			(xy 273.553726 -281.377738) (xy 273.518233 -281.41183) (xy 273.47773 -281.439786) (xy 273.433268 -281.460884)
			(xy 273.385997 -281.474576) (xy 273.337142 -281.480508) (xy 273.287967 -281.478527) (xy 273.239748 -281.468683)
			(xy 273.193732 -281.451231) (xy 273.151111 -281.426624) (xy 273.11299 -281.395499) (xy 273.080355 -281.358662)
			(xy 273.054052 -281.317066) (xy 273.034761 -281.27179) (xy 273.022984 -281.224006) (xy 273.019024 -281.174952)
			(xy 272.680176 -281.174952) (xy 272.679681 -281.199559) (xy 272.671786 -281.248136) (xy 272.656202 -281.294817)
			(xy 272.633331 -281.338394) (xy 272.603766 -281.377738) (xy 272.568273 -281.41183) (xy 272.52777 -281.439786)
			(xy 272.483308 -281.460884) (xy 272.436037 -281.474576) (xy 272.387182 -281.480508) (xy 272.338007 -281.478527)
			(xy 272.289788 -281.468683) (xy 272.243772 -281.451231) (xy 272.201151 -281.426624) (xy 272.16303 -281.395499)
			(xy 272.130395 -281.358662) (xy 272.104092 -281.317066) (xy 272.084801 -281.27179) (xy 272.073024 -281.224006)
			(xy 272.069064 -281.174952) (xy 271.730216 -281.174952) (xy 271.729721 -281.199559) (xy 271.721826 -281.248136)
			(xy 271.706242 -281.294817) (xy 271.683371 -281.338394) (xy 271.653806 -281.377738) (xy 271.618313 -281.41183)
			(xy 271.57781 -281.439786) (xy 271.533348 -281.460884) (xy 271.486077 -281.474576) (xy 271.437222 -281.480508)
			(xy 271.388047 -281.478527) (xy 271.339828 -281.468683) (xy 271.293812 -281.451231) (xy 271.251191 -281.426624)
			(xy 271.21307 -281.395499) (xy 271.180435 -281.358662) (xy 271.154132 -281.317066) (xy 271.134841 -281.27179)
			(xy 271.123064 -281.224006) (xy 271.119104 -281.174952) (xy 270.806245 -281.174952) (xy 270.806246 -281.174968)
			(xy 270.802393 -281.225387) (xy 270.790912 -281.274632) (xy 270.772072 -281.321557) (xy 270.746312 -281.365069)
			(xy 270.71423 -281.404154) (xy 270.695674 -281.421332) (xy 270.688054 -281.427936) (xy 270.68145 -281.442414)
			(xy 270.679186 -281.447588) (xy 270.676743 -281.458612) (xy 270.676624 -281.464258) (xy 270.67764 -281.474418)
			(xy 270.680904 -281.490606) (xy 270.684469 -281.523439) (xy 270.684752 -281.53995) (xy 270.684752 -281.759914)
			(xy 270.684466 -281.776425) (xy 270.680903 -281.809258) (xy 270.67764 -281.825446) (xy 270.676624 -281.835606)
			(xy 270.676746 -281.841253) (xy 270.67918 -281.852279) (xy 270.68145 -281.85745) (xy 270.688054 -281.871928)
			(xy 270.695674 -281.878532) (xy 270.714181 -281.895759) (xy 270.746261 -281.934837) (xy 270.772022 -281.978341)
			(xy 270.790863 -282.025258) (xy 270.802345 -282.074496) (xy 270.806202 -282.124908) (xy 270.806202 -282.124912)
			(xy 271.119104 -282.124912) (xy 271.123064 -282.075858) (xy 271.134841 -282.028074) (xy 271.154132 -281.982798)
			(xy 271.180435 -281.941202) (xy 271.21307 -281.904365) (xy 271.251191 -281.87324) (xy 271.293812 -281.848633)
			(xy 271.339828 -281.831181) (xy 271.388047 -281.821337) (xy 271.437222 -281.819356) (xy 271.486077 -281.825288)
			(xy 271.533348 -281.83898) (xy 271.57781 -281.860078) (xy 271.618313 -281.888034) (xy 271.653806 -281.922126)
			(xy 271.683371 -281.96147) (xy 271.706242 -282.005047) (xy 271.721826 -282.051728) (xy 271.729721 -282.100305)
			(xy 271.730216 -282.124912) (xy 272.069064 -282.124912) (xy 272.073024 -282.075858) (xy 272.084801 -282.028074)
			(xy 272.104092 -281.982798) (xy 272.130395 -281.941202) (xy 272.16303 -281.904365) (xy 272.201151 -281.87324)
			(xy 272.243772 -281.848633) (xy 272.289788 -281.831181) (xy 272.338007 -281.821337) (xy 272.387182 -281.819356)
			(xy 272.436037 -281.825288) (xy 272.483308 -281.83898) (xy 272.52777 -281.860078) (xy 272.568273 -281.888034)
			(xy 272.603766 -281.922126) (xy 272.633331 -281.96147) (xy 272.656202 -282.005047) (xy 272.671786 -282.051728)
			(xy 272.679681 -282.100305) (xy 272.680176 -282.124912) (xy 273.019024 -282.124912) (xy 273.022984 -282.075858)
			(xy 273.034761 -282.028074) (xy 273.054052 -281.982798) (xy 273.080355 -281.941202) (xy 273.11299 -281.904365)
			(xy 273.151111 -281.87324) (xy 273.193732 -281.848633) (xy 273.239748 -281.831181) (xy 273.287967 -281.821337)
			(xy 273.337142 -281.819356) (xy 273.385997 -281.825288) (xy 273.433268 -281.83898) (xy 273.47773 -281.860078)
			(xy 273.518233 -281.888034) (xy 273.553726 -281.922126) (xy 273.583291 -281.96147) (xy 273.606162 -282.005047)
			(xy 273.621746 -282.051728) (xy 273.629641 -282.100305) (xy 273.630136 -282.124912) (xy 273.629641 -282.149519)
			(xy 273.621746 -282.198096) (xy 273.606162 -282.244777) (xy 273.583291 -282.288354) (xy 273.553726 -282.327698)
			(xy 273.518233 -282.36179) (xy 273.47773 -282.389746) (xy 273.433268 -282.410844) (xy 273.385997 -282.424536)
			(xy 273.337142 -282.430468) (xy 273.287967 -282.428487) (xy 273.239748 -282.418643) (xy 273.193732 -282.401191)
			(xy 273.151111 -282.376584) (xy 273.11299 -282.345459) (xy 273.080355 -282.308622) (xy 273.054052 -282.267026)
			(xy 273.034761 -282.22175) (xy 273.022984 -282.173966) (xy 273.019024 -282.124912) (xy 272.680176 -282.124912)
			(xy 272.679681 -282.149519) (xy 272.671786 -282.198096) (xy 272.656202 -282.244777) (xy 272.633331 -282.288354)
			(xy 272.603766 -282.327698) (xy 272.568273 -282.36179) (xy 272.52777 -282.389746) (xy 272.483308 -282.410844)
			(xy 272.436037 -282.424536) (xy 272.387182 -282.430468) (xy 272.338007 -282.428487) (xy 272.289788 -282.418643)
			(xy 272.243772 -282.401191) (xy 272.201151 -282.376584) (xy 272.16303 -282.345459) (xy 272.130395 -282.308622)
			(xy 272.104092 -282.267026) (xy 272.084801 -282.22175) (xy 272.073024 -282.173966) (xy 272.069064 -282.124912)
			(xy 271.730216 -282.124912) (xy 271.729721 -282.149519) (xy 271.721826 -282.198096) (xy 271.706242 -282.244777)
			(xy 271.683371 -282.288354) (xy 271.653806 -282.327698) (xy 271.618313 -282.36179) (xy 271.57781 -282.389746)
			(xy 271.533348 -282.410844) (xy 271.486077 -282.424536) (xy 271.437222 -282.430468) (xy 271.388047 -282.428487)
			(xy 271.339828 -282.418643) (xy 271.293812 -282.401191) (xy 271.251191 -282.376584) (xy 271.21307 -282.345459)
			(xy 271.180435 -282.308622) (xy 271.154132 -282.267026) (xy 271.134841 -282.22175) (xy 271.123064 -282.173966)
			(xy 271.119104 -282.124912) (xy 270.806202 -282.124912) (xy 270.802343 -282.17532) (xy 270.790858 -282.224557)
			(xy 270.772015 -282.271473) (xy 270.746252 -282.314976) (xy 270.71417 -282.354052) (xy 270.695674 -282.371292)
			(xy 270.688054 -282.377896) (xy 270.68145 -282.392374) (xy 270.679192 -282.397549) (xy 270.676762 -282.408573)
			(xy 270.676624 -282.414218) (xy 270.67764 -282.424378) (xy 270.680901 -282.440567) (xy 270.68446 -282.473399)
			(xy 270.684752 -282.48991) (xy 270.684752 -282.709874) (xy 270.684468 -282.726386) (xy 270.680909 -282.759219)
			(xy 270.67764 -282.775406) (xy 270.676624 -282.785566) (xy 270.676753 -282.791211) (xy 270.679198 -282.802232)
			(xy 270.68145 -282.80741) (xy 270.688054 -282.821888) (xy 270.695674 -282.828492) (xy 270.714184 -282.845719)
			(xy 270.74627 -282.884798) (xy 270.772037 -282.928304) (xy 270.790883 -282.975224) (xy 270.80237 -283.024465)
			(xy 270.80623 -283.074872) (xy 271.119104 -283.074872) (xy 271.123064 -283.025818) (xy 271.134841 -282.978034)
			(xy 271.154132 -282.932758) (xy 271.180435 -282.891162) (xy 271.21307 -282.854325) (xy 271.251191 -282.8232)
			(xy 271.293812 -282.798593) (xy 271.339828 -282.781141) (xy 271.388047 -282.771297) (xy 271.437222 -282.769316)
			(xy 271.486077 -282.775248) (xy 271.533348 -282.78894) (xy 271.57781 -282.810038) (xy 271.618313 -282.837994)
			(xy 271.653806 -282.872086) (xy 271.683371 -282.91143) (xy 271.706242 -282.955007) (xy 271.721826 -283.001688)
			(xy 271.729721 -283.050265) (xy 271.730216 -283.074872) (xy 272.069064 -283.074872) (xy 272.073024 -283.025818)
			(xy 272.084801 -282.978034) (xy 272.104092 -282.932758) (xy 272.130395 -282.891162) (xy 272.16303 -282.854325)
			(xy 272.201151 -282.8232) (xy 272.243772 -282.798593) (xy 272.289788 -282.781141) (xy 272.338007 -282.771297)
			(xy 272.387182 -282.769316) (xy 272.436037 -282.775248) (xy 272.483308 -282.78894) (xy 272.52777 -282.810038)
			(xy 272.568273 -282.837994) (xy 272.603766 -282.872086) (xy 272.633331 -282.91143) (xy 272.656202 -282.955007)
			(xy 272.671786 -283.001688) (xy 272.679681 -283.050265) (xy 272.680176 -283.074872) (xy 273.019024 -283.074872)
			(xy 273.022984 -283.025818) (xy 273.034761 -282.978034) (xy 273.054052 -282.932758) (xy 273.080355 -282.891162)
			(xy 273.11299 -282.854325) (xy 273.151111 -282.8232) (xy 273.193732 -282.798593) (xy 273.239748 -282.781141)
			(xy 273.287967 -282.771297) (xy 273.337142 -282.769316) (xy 273.385997 -282.775248) (xy 273.433268 -282.78894)
			(xy 273.47773 -282.810038) (xy 273.518233 -282.837994) (xy 273.553726 -282.872086) (xy 273.583291 -282.91143)
			(xy 273.606162 -282.955007) (xy 273.621746 -283.001688) (xy 273.629641 -283.050265) (xy 273.630136 -283.074872)
			(xy 273.629641 -283.099479) (xy 273.621746 -283.148056) (xy 273.606162 -283.194737) (xy 273.583291 -283.238314)
			(xy 273.553726 -283.277658) (xy 273.518233 -283.31175) (xy 273.47773 -283.339706) (xy 273.433268 -283.360804)
			(xy 273.385997 -283.374496) (xy 273.337142 -283.380428) (xy 273.287967 -283.378447) (xy 273.239748 -283.368603)
			(xy 273.193732 -283.351151) (xy 273.151111 -283.326544) (xy 273.11299 -283.295419) (xy 273.080355 -283.258582)
			(xy 273.054052 -283.216986) (xy 273.034761 -283.17171) (xy 273.022984 -283.123926) (xy 273.019024 -283.074872)
			(xy 272.680176 -283.074872) (xy 272.679681 -283.099479) (xy 272.671786 -283.148056) (xy 272.656202 -283.194737)
			(xy 272.633331 -283.238314) (xy 272.603766 -283.277658) (xy 272.568273 -283.31175) (xy 272.52777 -283.339706)
			(xy 272.483308 -283.360804) (xy 272.436037 -283.374496) (xy 272.387182 -283.380428) (xy 272.338007 -283.378447)
			(xy 272.289788 -283.368603) (xy 272.243772 -283.351151) (xy 272.201151 -283.326544) (xy 272.16303 -283.295419)
			(xy 272.130395 -283.258582) (xy 272.104092 -283.216986) (xy 272.084801 -283.17171) (xy 272.073024 -283.123926)
			(xy 272.069064 -283.074872) (xy 271.730216 -283.074872) (xy 271.729721 -283.099479) (xy 271.721826 -283.148056)
			(xy 271.706242 -283.194737) (xy 271.683371 -283.238314) (xy 271.653806 -283.277658) (xy 271.618313 -283.31175)
			(xy 271.57781 -283.339706) (xy 271.533348 -283.360804) (xy 271.486077 -283.374496) (xy 271.437222 -283.380428)
			(xy 271.388047 -283.378447) (xy 271.339828 -283.368603) (xy 271.293812 -283.351151) (xy 271.251191 -283.326544)
			(xy 271.21307 -283.295419) (xy 271.180435 -283.258582) (xy 271.154132 -283.216986) (xy 271.134841 -283.17171)
			(xy 271.123064 -283.123926) (xy 271.119104 -283.074872) (xy 270.80623 -283.074872) (xy 270.806231 -283.074881)
			(xy 270.802376 -283.125298) (xy 270.790894 -283.17454) (xy 270.772053 -283.221462) (xy 270.746292 -283.264971)
			(xy 270.71421 -283.304054) (xy 270.695674 -283.321252) (xy 270.688054 -283.327856) (xy 270.68145 -283.342334)
			(xy 270.679188 -283.347508) (xy 270.676749 -283.358532) (xy 270.676624 -283.364178) (xy 270.67764 -283.374338)
			(xy 270.680903 -283.390526) (xy 270.684466 -283.423359) (xy 270.684752 -283.43987) (xy 270.684752 -283.659834)
			(xy 270.684465 -283.676345) (xy 270.6809 -283.709177) (xy 270.67764 -283.725366) (xy 270.676624 -283.735526)
			(xy 270.676748 -283.741172) (xy 270.679186 -283.752196) (xy 270.68145 -283.75737) (xy 270.688054 -283.771848)
			(xy 270.695674 -283.778452) (xy 270.714179 -283.79568) (xy 270.746256 -283.834757) (xy 270.772014 -283.87826)
			(xy 270.790852 -283.925176) (xy 270.802332 -283.974412) (xy 270.806186 -284.024821) (xy 270.806185 -284.024832)
			(xy 271.119104 -284.024832) (xy 271.123064 -283.975778) (xy 271.134841 -283.927994) (xy 271.154132 -283.882718)
			(xy 271.180435 -283.841122) (xy 271.21307 -283.804285) (xy 271.251191 -283.77316) (xy 271.293812 -283.748553)
			(xy 271.339828 -283.731101) (xy 271.388047 -283.721257) (xy 271.437222 -283.719276) (xy 271.486077 -283.725208)
			(xy 271.533348 -283.7389) (xy 271.57781 -283.759998) (xy 271.618313 -283.787954) (xy 271.653806 -283.822046)
			(xy 271.683371 -283.86139) (xy 271.706242 -283.904967) (xy 271.721826 -283.951648) (xy 271.729721 -284.000225)
			(xy 271.730216 -284.024832) (xy 272.069064 -284.024832) (xy 272.073024 -283.975778) (xy 272.084801 -283.927994)
			(xy 272.104092 -283.882718) (xy 272.130395 -283.841122) (xy 272.16303 -283.804285) (xy 272.201151 -283.77316)
			(xy 272.243772 -283.748553) (xy 272.289788 -283.731101) (xy 272.338007 -283.721257) (xy 272.387182 -283.719276)
			(xy 272.436037 -283.725208) (xy 272.483308 -283.7389) (xy 272.52777 -283.759998) (xy 272.568273 -283.787954)
			(xy 272.603766 -283.822046) (xy 272.633331 -283.86139) (xy 272.656202 -283.904967) (xy 272.671786 -283.951648)
			(xy 272.679681 -284.000225) (xy 272.680176 -284.024832) (xy 273.019024 -284.024832) (xy 273.022984 -283.975778)
			(xy 273.034761 -283.927994) (xy 273.054052 -283.882718) (xy 273.080355 -283.841122) (xy 273.11299 -283.804285)
			(xy 273.151111 -283.77316) (xy 273.193732 -283.748553) (xy 273.239748 -283.731101) (xy 273.287967 -283.721257)
			(xy 273.337142 -283.719276) (xy 273.385997 -283.725208) (xy 273.433268 -283.7389) (xy 273.47773 -283.759998)
			(xy 273.518233 -283.787954) (xy 273.553726 -283.822046) (xy 273.583291 -283.86139) (xy 273.606162 -283.904967)
			(xy 273.621746 -283.951648) (xy 273.629641 -284.000225) (xy 273.630136 -284.024832) (xy 273.629641 -284.049439)
			(xy 273.621746 -284.098016) (xy 273.606162 -284.144697) (xy 273.583291 -284.188274) (xy 273.553726 -284.227618)
			(xy 273.518233 -284.26171) (xy 273.47773 -284.289666) (xy 273.433268 -284.310764) (xy 273.385997 -284.324456)
			(xy 273.337142 -284.330388) (xy 273.287967 -284.328407) (xy 273.239748 -284.318563) (xy 273.193732 -284.301111)
			(xy 273.151111 -284.276504) (xy 273.11299 -284.245379) (xy 273.080355 -284.208542) (xy 273.054052 -284.166946)
			(xy 273.034761 -284.12167) (xy 273.022984 -284.073886) (xy 273.019024 -284.024832) (xy 272.680176 -284.024832)
			(xy 272.679681 -284.049439) (xy 272.671786 -284.098016) (xy 272.656202 -284.144697) (xy 272.633331 -284.188274)
			(xy 272.603766 -284.227618) (xy 272.568273 -284.26171) (xy 272.52777 -284.289666) (xy 272.483308 -284.310764)
			(xy 272.436037 -284.324456) (xy 272.387182 -284.330388) (xy 272.338007 -284.328407) (xy 272.289788 -284.318563)
			(xy 272.243772 -284.301111) (xy 272.201151 -284.276504) (xy 272.16303 -284.245379) (xy 272.130395 -284.208542)
			(xy 272.104092 -284.166946) (xy 272.084801 -284.12167) (xy 272.073024 -284.073886) (xy 272.069064 -284.024832)
			(xy 271.730216 -284.024832) (xy 271.729721 -284.049439) (xy 271.721826 -284.098016) (xy 271.706242 -284.144697)
			(xy 271.683371 -284.188274) (xy 271.653806 -284.227618) (xy 271.618313 -284.26171) (xy 271.57781 -284.289666)
			(xy 271.533348 -284.310764) (xy 271.486077 -284.324456) (xy 271.437222 -284.330388) (xy 271.388047 -284.328407)
			(xy 271.339828 -284.318563) (xy 271.293812 -284.301111) (xy 271.251191 -284.276504) (xy 271.21307 -284.245379)
			(xy 271.180435 -284.208542) (xy 271.154132 -284.166946) (xy 271.134841 -284.12167) (xy 271.123064 -284.073886)
			(xy 271.119104 -284.024832) (xy 270.806185 -284.024832) (xy 270.802325 -284.07523) (xy 270.790839 -284.124465)
			(xy 270.771995 -284.171378) (xy 270.746232 -284.214878) (xy 270.714149 -284.253951) (xy 270.695674 -284.271212)
			(xy 270.688054 -284.277816) (xy 270.68145 -284.292294) (xy 270.679194 -284.29747) (xy 270.676768 -284.308493)
			(xy 270.676624 -284.314138) (xy 270.67764 -284.324298) (xy 270.680905 -284.340486) (xy 270.684472 -284.373318)
			(xy 270.684752 -284.38983) (xy 270.684752 -284.609794) (xy 270.684467 -284.626306) (xy 270.680906 -284.659138)
			(xy 270.67764 -284.675326) (xy 270.676624 -284.685486) (xy 270.676744 -284.691133) (xy 270.679173 -284.702161)
			(xy 270.68145 -284.70733) (xy 270.688054 -284.721808) (xy 270.695674 -284.728412) (xy 270.714182 -284.745639)
			(xy 270.746266 -284.784718) (xy 270.772029 -284.828223) (xy 270.790873 -284.875141) (xy 270.802358 -284.924381)
			(xy 270.806217 -284.974792) (xy 271.119104 -284.974792) (xy 271.123064 -284.925738) (xy 271.134841 -284.877954)
			(xy 271.154132 -284.832678) (xy 271.180435 -284.791082) (xy 271.21307 -284.754245) (xy 271.251191 -284.72312)
			(xy 271.293812 -284.698513) (xy 271.339828 -284.681061) (xy 271.388047 -284.671217) (xy 271.437222 -284.669236)
			(xy 271.486077 -284.675168) (xy 271.533348 -284.68886) (xy 271.57781 -284.709958) (xy 271.618313 -284.737914)
			(xy 271.653806 -284.772006) (xy 271.683371 -284.81135) (xy 271.706242 -284.854927) (xy 271.721826 -284.901608)
			(xy 271.729721 -284.950185) (xy 271.730216 -284.974792) (xy 272.069064 -284.974792) (xy 272.073024 -284.925738)
			(xy 272.084801 -284.877954) (xy 272.104092 -284.832678) (xy 272.130395 -284.791082) (xy 272.16303 -284.754245)
			(xy 272.201151 -284.72312) (xy 272.243772 -284.698513) (xy 272.289788 -284.681061) (xy 272.338007 -284.671217)
			(xy 272.387182 -284.669236) (xy 272.436037 -284.675168) (xy 272.483308 -284.68886) (xy 272.52777 -284.709958)
			(xy 272.568273 -284.737914) (xy 272.603766 -284.772006) (xy 272.633331 -284.81135) (xy 272.656202 -284.854927)
			(xy 272.671786 -284.901608) (xy 272.679681 -284.950185) (xy 272.680176 -284.974792) (xy 273.019024 -284.974792)
			(xy 273.022984 -284.925738) (xy 273.034761 -284.877954) (xy 273.054052 -284.832678) (xy 273.080355 -284.791082)
			(xy 273.11299 -284.754245) (xy 273.151111 -284.72312) (xy 273.193732 -284.698513) (xy 273.239748 -284.681061)
			(xy 273.287967 -284.671217) (xy 273.337142 -284.669236) (xy 273.385997 -284.675168) (xy 273.433268 -284.68886)
			(xy 273.47773 -284.709958) (xy 273.518233 -284.737914) (xy 273.553726 -284.772006) (xy 273.583291 -284.81135)
			(xy 273.606162 -284.854927) (xy 273.621746 -284.901608) (xy 273.629641 -284.950185) (xy 273.630136 -284.974792)
			(xy 273.629641 -284.999399) (xy 273.621746 -285.047976) (xy 273.606162 -285.094657) (xy 273.583291 -285.138234)
			(xy 273.553726 -285.177578) (xy 273.518233 -285.21167) (xy 273.47773 -285.239626) (xy 273.433268 -285.260724)
			(xy 273.385997 -285.274416) (xy 273.337142 -285.280348) (xy 273.287967 -285.278367) (xy 273.239748 -285.268523)
			(xy 273.193732 -285.251071) (xy 273.151111 -285.226464) (xy 273.11299 -285.195339) (xy 273.080355 -285.158502)
			(xy 273.054052 -285.116906) (xy 273.034761 -285.07163) (xy 273.022984 -285.023846) (xy 273.019024 -284.974792)
			(xy 272.680176 -284.974792) (xy 272.679681 -284.999399) (xy 272.671786 -285.047976) (xy 272.656202 -285.094657)
			(xy 272.633331 -285.138234) (xy 272.603766 -285.177578) (xy 272.568273 -285.21167) (xy 272.52777 -285.239626)
			(xy 272.483308 -285.260724) (xy 272.436037 -285.274416) (xy 272.387182 -285.280348) (xy 272.338007 -285.278367)
			(xy 272.289788 -285.268523) (xy 272.243772 -285.251071) (xy 272.201151 -285.226464) (xy 272.16303 -285.195339)
			(xy 272.130395 -285.158502) (xy 272.104092 -285.116906) (xy 272.084801 -285.07163) (xy 272.073024 -285.023846)
			(xy 272.069064 -284.974792) (xy 271.730216 -284.974792) (xy 271.729721 -284.999399) (xy 271.721826 -285.047976)
			(xy 271.706242 -285.094657) (xy 271.683371 -285.138234) (xy 271.653806 -285.177578) (xy 271.618313 -285.21167)
			(xy 271.57781 -285.239626) (xy 271.533348 -285.260724) (xy 271.486077 -285.274416) (xy 271.437222 -285.280348)
			(xy 271.388047 -285.278367) (xy 271.339828 -285.268523) (xy 271.293812 -285.251071) (xy 271.251191 -285.226464)
			(xy 271.21307 -285.195339) (xy 271.180435 -285.158502) (xy 271.154132 -285.116906) (xy 271.134841 -285.07163)
			(xy 271.123064 -285.023846) (xy 271.119104 -284.974792) (xy 270.806217 -284.974792) (xy 270.806217 -284.974795)
			(xy 270.802359 -285.025209) (xy 270.790876 -285.074449) (xy 270.772034 -285.121368) (xy 270.746272 -285.164874)
			(xy 270.71419 -285.203953) (xy 270.695674 -285.221172) (xy 270.688054 -285.227776) (xy 270.68145 -285.242254)
			(xy 270.67919 -285.247429) (xy 270.676755 -285.258453) (xy 270.676624 -285.264098) (xy 270.67764 -285.274258)
			(xy 270.680902 -285.290446) (xy 270.684463 -285.323279) (xy 270.684752 -285.33979) (xy 270.684752 -285.559754)
			(xy 270.684464 -285.576265) (xy 270.680897 -285.609097) (xy 270.67764 -285.625286) (xy 270.676624 -285.635446)
			(xy 270.676751 -285.641091) (xy 270.679192 -285.652114) (xy 270.68145 -285.65729) (xy 270.688054 -285.671768)
			(xy 270.695674 -285.678372) (xy 270.714185 -285.695599) (xy 270.746275 -285.734679) (xy 270.772044 -285.778185)
			(xy 270.790893 -285.825107) (xy 270.802383 -285.87435) (xy 270.806245 -285.924752) (xy 271.119104 -285.924752)
			(xy 271.123064 -285.875698) (xy 271.134841 -285.827914) (xy 271.154132 -285.782638) (xy 271.180435 -285.741042)
			(xy 271.21307 -285.704205) (xy 271.251191 -285.67308) (xy 271.293812 -285.648473) (xy 271.339828 -285.631021)
			(xy 271.388047 -285.621177) (xy 271.437222 -285.619196) (xy 271.486077 -285.625128) (xy 271.533348 -285.63882)
			(xy 271.57781 -285.659918) (xy 271.618313 -285.687874) (xy 271.653806 -285.721966) (xy 271.683371 -285.76131)
			(xy 271.706242 -285.804887) (xy 271.721826 -285.851568) (xy 271.729721 -285.900145) (xy 271.730216 -285.924752)
			(xy 272.069064 -285.924752) (xy 272.073024 -285.875698) (xy 272.084801 -285.827914) (xy 272.104092 -285.782638)
			(xy 272.130395 -285.741042) (xy 272.16303 -285.704205) (xy 272.201151 -285.67308) (xy 272.243772 -285.648473)
			(xy 272.289788 -285.631021) (xy 272.338007 -285.621177) (xy 272.387182 -285.619196) (xy 272.436037 -285.625128)
			(xy 272.483308 -285.63882) (xy 272.52777 -285.659918) (xy 272.568273 -285.687874) (xy 272.603766 -285.721966)
			(xy 272.633331 -285.76131) (xy 272.656202 -285.804887) (xy 272.671786 -285.851568) (xy 272.679681 -285.900145)
			(xy 272.680176 -285.924752) (xy 273.019024 -285.924752) (xy 273.022984 -285.875698) (xy 273.034761 -285.827914)
			(xy 273.054052 -285.782638) (xy 273.080355 -285.741042) (xy 273.11299 -285.704205) (xy 273.151111 -285.67308)
			(xy 273.193732 -285.648473) (xy 273.239748 -285.631021) (xy 273.287967 -285.621177) (xy 273.337142 -285.619196)
			(xy 273.385997 -285.625128) (xy 273.433268 -285.63882) (xy 273.47773 -285.659918) (xy 273.518233 -285.687874)
			(xy 273.553726 -285.721966) (xy 273.583291 -285.76131) (xy 273.606162 -285.804887) (xy 273.621746 -285.851568)
			(xy 273.629641 -285.900145) (xy 273.630136 -285.924752) (xy 273.629641 -285.949359) (xy 273.621746 -285.997936)
			(xy 273.606162 -286.044617) (xy 273.583291 -286.088194) (xy 273.553726 -286.127538) (xy 273.518233 -286.16163)
			(xy 273.47773 -286.189586) (xy 273.433268 -286.210684) (xy 273.385997 -286.224376) (xy 273.337142 -286.230308)
			(xy 273.287967 -286.228327) (xy 273.239748 -286.218483) (xy 273.193732 -286.201031) (xy 273.151111 -286.176424)
			(xy 273.11299 -286.145299) (xy 273.080355 -286.108462) (xy 273.054052 -286.066866) (xy 273.034761 -286.02159)
			(xy 273.022984 -285.973806) (xy 273.019024 -285.924752) (xy 272.680176 -285.924752) (xy 272.679681 -285.949359)
			(xy 272.671786 -285.997936) (xy 272.656202 -286.044617) (xy 272.633331 -286.088194) (xy 272.603766 -286.127538)
			(xy 272.568273 -286.16163) (xy 272.52777 -286.189586) (xy 272.483308 -286.210684) (xy 272.436037 -286.224376)
			(xy 272.387182 -286.230308) (xy 272.338007 -286.228327) (xy 272.289788 -286.218483) (xy 272.243772 -286.201031)
			(xy 272.201151 -286.176424) (xy 272.16303 -286.145299) (xy 272.130395 -286.108462) (xy 272.104092 -286.066866)
			(xy 272.084801 -286.02159) (xy 272.073024 -285.973806) (xy 272.069064 -285.924752) (xy 271.730216 -285.924752)
			(xy 271.729721 -285.949359) (xy 271.721826 -285.997936) (xy 271.706242 -286.044617) (xy 271.683371 -286.088194)
			(xy 271.653806 -286.127538) (xy 271.618313 -286.16163) (xy 271.57781 -286.189586) (xy 271.533348 -286.210684)
			(xy 271.486077 -286.224376) (xy 271.437222 -286.230308) (xy 271.388047 -286.228327) (xy 271.339828 -286.218483)
			(xy 271.293812 -286.201031) (xy 271.251191 -286.176424) (xy 271.21307 -286.145299) (xy 271.180435 -286.108462)
			(xy 271.154132 -286.066866) (xy 271.134841 -286.02159) (xy 271.123064 -285.973806) (xy 271.119104 -285.924752)
			(xy 270.806245 -285.924752) (xy 270.806246 -285.924768) (xy 270.802393 -285.975187) (xy 270.790912 -286.024432)
			(xy 270.772072 -286.071357) (xy 270.746312 -286.114869) (xy 270.71423 -286.153954) (xy 270.695674 -286.171132)
			(xy 270.688054 -286.177736) (xy 270.68145 -286.192214) (xy 270.679186 -286.197388) (xy 270.676743 -286.208412)
			(xy 270.676624 -286.214058) (xy 270.67764 -286.224218) (xy 270.680904 -286.240406) (xy 270.684469 -286.273239)
			(xy 270.684752 -286.28975) (xy 270.684752 -286.509968) (xy 270.684468 -286.52648) (xy 270.68091 -286.559313)
			(xy 270.67764 -286.5755) (xy 270.676624 -286.58566) (xy 270.676752 -286.591305) (xy 270.679196 -286.602326)
			(xy 270.68145 -286.607504) (xy 270.688054 -286.621982) (xy 270.695674 -286.628586) (xy 270.715997 -286.647576)
			(xy 270.750616 -286.691108) (xy 270.777471 -286.739813) (xy 270.795808 -286.792322) (xy 270.80511 -286.847157)
			(xy 270.805656 -286.874966) (xy 271.119104 -286.874966) (xy 271.123064 -286.825912) (xy 271.134841 -286.778128)
			(xy 271.154132 -286.732852) (xy 271.180435 -286.691256) (xy 271.21307 -286.654419) (xy 271.251191 -286.623294)
			(xy 271.293812 -286.598687) (xy 271.339828 -286.581235) (xy 271.388047 -286.571391) (xy 271.437222 -286.56941)
			(xy 271.486077 -286.575342) (xy 271.533348 -286.589034) (xy 271.57781 -286.610132) (xy 271.618313 -286.638088)
			(xy 271.653806 -286.67218) (xy 271.683371 -286.711524) (xy 271.706242 -286.755101) (xy 271.721826 -286.801782)
			(xy 271.729721 -286.850359) (xy 271.730216 -286.874966) (xy 272.069064 -286.874966) (xy 272.073024 -286.825912)
			(xy 272.084801 -286.778128) (xy 272.104092 -286.732852) (xy 272.130395 -286.691256) (xy 272.16303 -286.654419)
			(xy 272.201151 -286.623294) (xy 272.243772 -286.598687) (xy 272.289788 -286.581235) (xy 272.338007 -286.571391)
			(xy 272.387182 -286.56941) (xy 272.436037 -286.575342) (xy 272.483308 -286.589034) (xy 272.52777 -286.610132)
			(xy 272.568273 -286.638088) (xy 272.603766 -286.67218) (xy 272.633331 -286.711524) (xy 272.656202 -286.755101)
			(xy 272.671786 -286.801782) (xy 272.679681 -286.850359) (xy 272.680176 -286.874966) (xy 273.019024 -286.874966)
			(xy 273.022984 -286.825912) (xy 273.034761 -286.778128) (xy 273.054052 -286.732852) (xy 273.080355 -286.691256)
			(xy 273.11299 -286.654419) (xy 273.151111 -286.623294) (xy 273.193732 -286.598687) (xy 273.239748 -286.581235)
			(xy 273.287967 -286.571391) (xy 273.337142 -286.56941) (xy 273.385997 -286.575342) (xy 273.433268 -286.589034)
			(xy 273.47773 -286.610132) (xy 273.518233 -286.638088) (xy 273.553726 -286.67218) (xy 273.583291 -286.711524)
			(xy 273.606162 -286.755101) (xy 273.621746 -286.801782) (xy 273.629641 -286.850359) (xy 273.630136 -286.874966)
			(xy 273.968984 -286.874966) (xy 273.972944 -286.825912) (xy 273.984721 -286.778128) (xy 274.004012 -286.732852)
			(xy 274.030315 -286.691256) (xy 274.06295 -286.654419) (xy 274.101071 -286.623294) (xy 274.143692 -286.598687)
			(xy 274.189708 -286.581235) (xy 274.237927 -286.571391) (xy 274.287102 -286.56941) (xy 274.335957 -286.575342)
			(xy 274.383228 -286.589034) (xy 274.42769 -286.610132) (xy 274.468193 -286.638088) (xy 274.503686 -286.67218)
			(xy 274.533251 -286.711524) (xy 274.556122 -286.755101) (xy 274.571706 -286.801782) (xy 274.579601 -286.850359)
			(xy 274.580091 -286.874712) (xy 274.918944 -286.874712) (xy 274.922904 -286.825658) (xy 274.934681 -286.777874)
			(xy 274.953972 -286.732598) (xy 274.980275 -286.691002) (xy 275.01291 -286.654165) (xy 275.051031 -286.62304)
			(xy 275.093652 -286.598433) (xy 275.139668 -286.580981) (xy 275.187887 -286.571137) (xy 275.237062 -286.569156)
			(xy 275.285917 -286.575088) (xy 275.333188 -286.58878) (xy 275.37765 -286.609878) (xy 275.418153 -286.637834)
			(xy 275.453646 -286.671926) (xy 275.483211 -286.71127) (xy 275.506082 -286.754847) (xy 275.521666 -286.801528)
			(xy 275.529561 -286.850105) (xy 275.530056 -286.874712) (xy 275.868904 -286.874712) (xy 275.872864 -286.825658)
			(xy 275.884641 -286.777874) (xy 275.903932 -286.732598) (xy 275.930235 -286.691002) (xy 275.96287 -286.654165)
			(xy 276.000991 -286.62304) (xy 276.043612 -286.598433) (xy 276.089628 -286.580981) (xy 276.137847 -286.571137)
			(xy 276.187022 -286.569156) (xy 276.235877 -286.575088) (xy 276.283148 -286.58878) (xy 276.32761 -286.609878)
			(xy 276.368113 -286.637834) (xy 276.403606 -286.671926) (xy 276.433171 -286.71127) (xy 276.456042 -286.754847)
			(xy 276.471626 -286.801528) (xy 276.479521 -286.850105) (xy 276.480016 -286.874712) (xy 276.479521 -286.899319)
			(xy 276.471626 -286.947896) (xy 276.456042 -286.994577) (xy 276.433171 -287.038154) (xy 276.403606 -287.077498)
			(xy 276.368113 -287.11159) (xy 276.32761 -287.139546) (xy 276.283148 -287.160644) (xy 276.235877 -287.174336)
			(xy 276.187022 -287.180268) (xy 276.137847 -287.178287) (xy 276.089628 -287.168443) (xy 276.043612 -287.150991)
			(xy 276.000991 -287.126384) (xy 275.96287 -287.095259) (xy 275.930235 -287.058422) (xy 275.903932 -287.016826)
			(xy 275.884641 -286.97155) (xy 275.872864 -286.923766) (xy 275.868904 -286.874712) (xy 275.530056 -286.874712)
			(xy 275.529561 -286.899319) (xy 275.521666 -286.947896) (xy 275.506082 -286.994577) (xy 275.483211 -287.038154)
			(xy 275.453646 -287.077498) (xy 275.418153 -287.11159) (xy 275.37765 -287.139546) (xy 275.333188 -287.160644)
			(xy 275.285917 -287.174336) (xy 275.237062 -287.180268) (xy 275.187887 -287.178287) (xy 275.139668 -287.168443)
			(xy 275.093652 -287.150991) (xy 275.051031 -287.126384) (xy 275.01291 -287.095259) (xy 274.980275 -287.058422)
			(xy 274.953972 -287.016826) (xy 274.934681 -286.97155) (xy 274.922904 -286.923766) (xy 274.918944 -286.874712)
			(xy 274.580091 -286.874712) (xy 274.580096 -286.874966) (xy 274.579601 -286.899573) (xy 274.571706 -286.94815)
			(xy 274.556122 -286.994831) (xy 274.533251 -287.038408) (xy 274.503686 -287.077752) (xy 274.468193 -287.111844)
			(xy 274.42769 -287.1398) (xy 274.383228 -287.160898) (xy 274.335957 -287.17459) (xy 274.287102 -287.180522)
			(xy 274.237927 -287.178541) (xy 274.189708 -287.168697) (xy 274.143692 -287.151245) (xy 274.101071 -287.126638)
			(xy 274.06295 -287.095513) (xy 274.030315 -287.058676) (xy 274.004012 -287.01708) (xy 273.984721 -286.971804)
			(xy 273.972944 -286.92402) (xy 273.968984 -286.874966) (xy 273.630136 -286.874966) (xy 273.629641 -286.899573)
			(xy 273.621746 -286.94815) (xy 273.606162 -286.994831) (xy 273.583291 -287.038408) (xy 273.553726 -287.077752)
			(xy 273.518233 -287.111844) (xy 273.47773 -287.1398) (xy 273.433268 -287.160898) (xy 273.385997 -287.17459)
			(xy 273.337142 -287.180522) (xy 273.287967 -287.178541) (xy 273.239748 -287.168697) (xy 273.193732 -287.151245)
			(xy 273.151111 -287.126638) (xy 273.11299 -287.095513) (xy 273.080355 -287.058676) (xy 273.054052 -287.01708)
			(xy 273.034761 -286.971804) (xy 273.022984 -286.92402) (xy 273.019024 -286.874966) (xy 272.680176 -286.874966)
			(xy 272.679681 -286.899573) (xy 272.671786 -286.94815) (xy 272.656202 -286.994831) (xy 272.633331 -287.038408)
			(xy 272.603766 -287.077752) (xy 272.568273 -287.111844) (xy 272.52777 -287.1398) (xy 272.483308 -287.160898)
			(xy 272.436037 -287.17459) (xy 272.387182 -287.180522) (xy 272.338007 -287.178541) (xy 272.289788 -287.168697)
			(xy 272.243772 -287.151245) (xy 272.201151 -287.126638) (xy 272.16303 -287.095513) (xy 272.130395 -287.058676)
			(xy 272.104092 -287.01708) (xy 272.084801 -286.971804) (xy 272.073024 -286.92402) (xy 272.069064 -286.874966)
			(xy 271.730216 -286.874966) (xy 271.729721 -286.899573) (xy 271.721826 -286.94815) (xy 271.706242 -286.994831)
			(xy 271.683371 -287.038408) (xy 271.653806 -287.077752) (xy 271.618313 -287.111844) (xy 271.57781 -287.1398)
			(xy 271.533348 -287.160898) (xy 271.486077 -287.17459) (xy 271.437222 -287.180522) (xy 271.388047 -287.178541)
			(xy 271.339828 -287.168697) (xy 271.293812 -287.151245) (xy 271.251191 -287.126638) (xy 271.21307 -287.095513)
			(xy 271.180435 -287.058676) (xy 271.154132 -287.01708) (xy 271.134841 -286.971804) (xy 271.123064 -286.92402)
			(xy 271.119104 -286.874966) (xy 270.805656 -286.874966) (xy 270.804885 -286.906896) (xy 270.792602 -286.969564)
			(xy 270.781272 -286.999426) (xy 270.777462 -287.00857) (xy 270.777462 -287.008824) (xy 270.775176 -287.014158)
			(xy 270.77289 -287.025842) (xy 270.773652 -287.036002) (xy 270.774668 -287.041082) (xy 270.77649 -287.047856)
			(xy 270.783325 -287.0601) (xy 270.78813 -287.065212) (xy 271.547844 -287.824926) (xy 273.019024 -287.824926)
			(xy 273.022984 -287.775872) (xy 273.034761 -287.728088) (xy 273.054052 -287.682812) (xy 273.080355 -287.641216)
			(xy 273.11299 -287.604379) (xy 273.151111 -287.573254) (xy 273.193732 -287.548647) (xy 273.239748 -287.531195)
			(xy 273.287967 -287.521351) (xy 273.337142 -287.51937) (xy 273.385997 -287.525302) (xy 273.433268 -287.538994)
			(xy 273.47773 -287.560092) (xy 273.518233 -287.588048) (xy 273.553726 -287.62214) (xy 273.583291 -287.661484)
			(xy 273.606162 -287.705061) (xy 273.621746 -287.751742) (xy 273.629641 -287.800319) (xy 273.630136 -287.824926)
			(xy 276.819118 -287.824926) (xy 276.823078 -287.775872) (xy 276.834855 -287.728088) (xy 276.854146 -287.682812)
			(xy 276.880449 -287.641216) (xy 276.913084 -287.604379) (xy 276.951205 -287.573254) (xy 276.993826 -287.548647)
			(xy 277.039842 -287.531195) (xy 277.088061 -287.521351) (xy 277.137236 -287.51937) (xy 277.186091 -287.525302)
			(xy 277.233362 -287.538994) (xy 277.277824 -287.560092) (xy 277.318327 -287.588048) (xy 277.35382 -287.62214)
			(xy 277.383385 -287.661484) (xy 277.406256 -287.705061) (xy 277.42184 -287.751742) (xy 277.429735 -287.800319)
			(xy 277.43023 -287.824926) (xy 277.429735 -287.849533) (xy 277.42184 -287.89811) (xy 277.406256 -287.944791)
			(xy 277.383385 -287.988368) (xy 277.35382 -288.027712) (xy 277.318327 -288.061804) (xy 277.277824 -288.08976)
			(xy 277.233362 -288.110858) (xy 277.186091 -288.12455) (xy 277.137236 -288.130482) (xy 277.088061 -288.128501)
			(xy 277.039842 -288.118657) (xy 276.993826 -288.101205) (xy 276.951205 -288.076598) (xy 276.913084 -288.045473)
			(xy 276.880449 -288.008636) (xy 276.854146 -287.96704) (xy 276.834855 -287.921764) (xy 276.823078 -287.87398)
			(xy 276.819118 -287.824926) (xy 273.630136 -287.824926) (xy 273.629641 -287.849533) (xy 273.621746 -287.89811)
			(xy 273.606162 -287.944791) (xy 273.583291 -287.988368) (xy 273.553726 -288.027712) (xy 273.518233 -288.061804)
			(xy 273.47773 -288.08976) (xy 273.433268 -288.110858) (xy 273.385997 -288.12455) (xy 273.337142 -288.130482)
			(xy 273.287967 -288.128501) (xy 273.239748 -288.118657) (xy 273.193732 -288.101205) (xy 273.151111 -288.076598)
			(xy 273.11299 -288.045473) (xy 273.080355 -288.008636) (xy 273.054052 -287.96704) (xy 273.034761 -287.921764)
			(xy 273.022984 -287.87398) (xy 273.019024 -287.824926) (xy 271.547844 -287.824926) (xy 272.184622 -288.461704)
			(xy 272.190258 -288.466892) (xy 272.203818 -288.473999) (xy 272.211292 -288.475674) (xy 272.213578 -288.476182)
			(xy 272.230342 -288.477198) (xy 272.23466 -288.47542) (xy 272.256634 -288.465613) (xy 272.302707 -288.451734)
			(xy 272.350302 -288.444659) (xy 272.37436 -288.444178) (xy 272.374868 -288.444178) (xy 272.400859 -288.444659)
			(xy 272.452203 -288.452786) (xy 272.501642 -288.468845) (xy 272.547961 -288.492441) (xy 272.590018 -288.522992)
			(xy 272.626778 -288.559747) (xy 272.657335 -288.6018) (xy 272.680937 -288.648115) (xy 272.697003 -288.697553)
			(xy 272.705138 -288.748895) (xy 272.705576 -288.774886) (xy 273.019024 -288.774886) (xy 273.022984 -288.725832)
			(xy 273.034761 -288.678048) (xy 273.054052 -288.632772) (xy 273.080355 -288.591176) (xy 273.11299 -288.554339)
			(xy 273.151111 -288.523214) (xy 273.193732 -288.498607) (xy 273.239748 -288.481155) (xy 273.287967 -288.471311)
			(xy 273.337142 -288.46933) (xy 273.385997 -288.475262) (xy 273.433268 -288.488954) (xy 273.47773 -288.510052)
			(xy 273.518233 -288.538008) (xy 273.553726 -288.5721) (xy 273.583291 -288.611444) (xy 273.606162 -288.655021)
			(xy 273.621746 -288.701702) (xy 273.629641 -288.750279) (xy 273.630136 -288.774886) (xy 273.968984 -288.774886)
			(xy 273.972944 -288.725832) (xy 273.984721 -288.678048) (xy 274.004012 -288.632772) (xy 274.030315 -288.591176)
			(xy 274.06295 -288.554339) (xy 274.101071 -288.523214) (xy 274.143692 -288.498607) (xy 274.189708 -288.481155)
			(xy 274.237927 -288.471311) (xy 274.287102 -288.46933) (xy 274.335957 -288.475262) (xy 274.383228 -288.488954)
			(xy 274.42769 -288.510052) (xy 274.468193 -288.538008) (xy 274.503686 -288.5721) (xy 274.533251 -288.611444)
			(xy 274.556122 -288.655021) (xy 274.571706 -288.701702) (xy 274.579601 -288.750279) (xy 274.580096 -288.774886)
			(xy 274.918944 -288.774886) (xy 274.922904 -288.725832) (xy 274.934681 -288.678048) (xy 274.953972 -288.632772)
			(xy 274.980275 -288.591176) (xy 275.01291 -288.554339) (xy 275.051031 -288.523214) (xy 275.093652 -288.498607)
			(xy 275.139668 -288.481155) (xy 275.187887 -288.471311) (xy 275.237062 -288.46933) (xy 275.285917 -288.475262)
			(xy 275.333188 -288.488954) (xy 275.37765 -288.510052) (xy 275.418153 -288.538008) (xy 275.453646 -288.5721)
			(xy 275.483211 -288.611444) (xy 275.506082 -288.655021) (xy 275.521666 -288.701702) (xy 275.529561 -288.750279)
			(xy 275.530056 -288.774886) (xy 275.868904 -288.774886) (xy 275.872864 -288.725832) (xy 275.884641 -288.678048)
			(xy 275.903932 -288.632772) (xy 275.930235 -288.591176) (xy 275.96287 -288.554339) (xy 276.000991 -288.523214)
			(xy 276.043612 -288.498607) (xy 276.089628 -288.481155) (xy 276.137847 -288.471311) (xy 276.187022 -288.46933)
			(xy 276.235877 -288.475262) (xy 276.283148 -288.488954) (xy 276.32761 -288.510052) (xy 276.368113 -288.538008)
			(xy 276.403606 -288.5721) (xy 276.433171 -288.611444) (xy 276.456042 -288.655021) (xy 276.471626 -288.701702)
			(xy 276.479521 -288.750279) (xy 276.480016 -288.774886) (xy 276.819118 -288.774886) (xy 276.823078 -288.725832)
			(xy 276.834855 -288.678048) (xy 276.854146 -288.632772) (xy 276.880449 -288.591176) (xy 276.913084 -288.554339)
			(xy 276.951205 -288.523214) (xy 276.993826 -288.498607) (xy 277.039842 -288.481155) (xy 277.088061 -288.471311)
			(xy 277.137236 -288.46933) (xy 277.186091 -288.475262) (xy 277.233362 -288.488954) (xy 277.277824 -288.510052)
			(xy 277.318327 -288.538008) (xy 277.35382 -288.5721) (xy 277.383385 -288.611444) (xy 277.406256 -288.655021)
			(xy 277.42184 -288.701702) (xy 277.429735 -288.750279) (xy 277.43023 -288.774886) (xy 277.769078 -288.774886)
			(xy 277.773038 -288.725832) (xy 277.784815 -288.678048) (xy 277.804106 -288.632772) (xy 277.830409 -288.591176)
			(xy 277.863044 -288.554339) (xy 277.901165 -288.523214) (xy 277.943786 -288.498607) (xy 277.989802 -288.481155)
			(xy 278.038021 -288.471311) (xy 278.087196 -288.46933) (xy 278.136051 -288.475262) (xy 278.183322 -288.488954)
			(xy 278.227784 -288.510052) (xy 278.268287 -288.538008) (xy 278.30378 -288.5721) (xy 278.333345 -288.611444)
			(xy 278.356216 -288.655021) (xy 278.3718 -288.701702) (xy 278.379695 -288.750279) (xy 278.38019 -288.774886)
			(xy 278.379695 -288.799493) (xy 278.3718 -288.84807) (xy 278.356216 -288.894751) (xy 278.333345 -288.938328)
			(xy 278.30378 -288.977672) (xy 278.268287 -289.011764) (xy 278.227784 -289.03972) (xy 278.183322 -289.060818)
			(xy 278.136051 -289.07451) (xy 278.087196 -289.080442) (xy 278.038021 -289.078461) (xy 277.989802 -289.068617)
			(xy 277.943786 -289.051165) (xy 277.901165 -289.026558) (xy 277.863044 -288.995433) (xy 277.830409 -288.958596)
			(xy 277.804106 -288.917) (xy 277.784815 -288.871724) (xy 277.773038 -288.82394) (xy 277.769078 -288.774886)
			(xy 277.43023 -288.774886) (xy 277.429735 -288.799493) (xy 277.42184 -288.84807) (xy 277.406256 -288.894751)
			(xy 277.383385 -288.938328) (xy 277.35382 -288.977672) (xy 277.318327 -289.011764) (xy 277.277824 -289.03972)
			(xy 277.233362 -289.060818) (xy 277.186091 -289.07451) (xy 277.137236 -289.080442) (xy 277.088061 -289.078461)
			(xy 277.039842 -289.068617) (xy 276.993826 -289.051165) (xy 276.951205 -289.026558) (xy 276.913084 -288.995433)
			(xy 276.880449 -288.958596) (xy 276.854146 -288.917) (xy 276.834855 -288.871724) (xy 276.823078 -288.82394)
			(xy 276.819118 -288.774886) (xy 276.480016 -288.774886) (xy 276.479521 -288.799493) (xy 276.471626 -288.84807)
			(xy 276.456042 -288.894751) (xy 276.433171 -288.938328) (xy 276.403606 -288.977672) (xy 276.368113 -289.011764)
			(xy 276.32761 -289.03972) (xy 276.283148 -289.060818) (xy 276.235877 -289.07451) (xy 276.187022 -289.080442)
			(xy 276.137847 -289.078461) (xy 276.089628 -289.068617) (xy 276.043612 -289.051165) (xy 276.000991 -289.026558)
			(xy 275.96287 -288.995433) (xy 275.930235 -288.958596) (xy 275.903932 -288.917) (xy 275.884641 -288.871724)
			(xy 275.872864 -288.82394) (xy 275.868904 -288.774886) (xy 275.530056 -288.774886) (xy 275.529561 -288.799493)
			(xy 275.521666 -288.84807) (xy 275.506082 -288.894751) (xy 275.483211 -288.938328) (xy 275.453646 -288.977672)
			(xy 275.418153 -289.011764) (xy 275.37765 -289.03972) (xy 275.333188 -289.060818) (xy 275.285917 -289.07451)
			(xy 275.237062 -289.080442) (xy 275.187887 -289.078461) (xy 275.139668 -289.068617) (xy 275.093652 -289.051165)
			(xy 275.051031 -289.026558) (xy 275.01291 -288.995433) (xy 274.980275 -288.958596) (xy 274.953972 -288.917)
			(xy 274.934681 -288.871724) (xy 274.922904 -288.82394) (xy 274.918944 -288.774886) (xy 274.580096 -288.774886)
			(xy 274.579601 -288.799493) (xy 274.571706 -288.84807) (xy 274.556122 -288.894751) (xy 274.533251 -288.938328)
			(xy 274.503686 -288.977672) (xy 274.468193 -289.011764) (xy 274.42769 -289.03972) (xy 274.383228 -289.060818)
			(xy 274.335957 -289.07451) (xy 274.287102 -289.080442) (xy 274.237927 -289.078461) (xy 274.189708 -289.068617)
			(xy 274.143692 -289.051165) (xy 274.101071 -289.026558) (xy 274.06295 -288.995433) (xy 274.030315 -288.958596)
			(xy 274.004012 -288.917) (xy 273.984721 -288.871724) (xy 273.972944 -288.82394) (xy 273.968984 -288.774886)
			(xy 273.630136 -288.774886) (xy 273.629641 -288.799493) (xy 273.621746 -288.84807) (xy 273.606162 -288.894751)
			(xy 273.583291 -288.938328) (xy 273.553726 -288.977672) (xy 273.518233 -289.011764) (xy 273.47773 -289.03972)
			(xy 273.433268 -289.060818) (xy 273.385997 -289.07451) (xy 273.337142 -289.080442) (xy 273.287967 -289.078461)
			(xy 273.239748 -289.068617) (xy 273.193732 -289.051165) (xy 273.151111 -289.026558) (xy 273.11299 -288.995433)
			(xy 273.080355 -288.958596) (xy 273.054052 -288.917) (xy 273.034761 -288.871724) (xy 273.022984 -288.82394)
			(xy 273.019024 -288.774886) (xy 272.705576 -288.774886) (xy 272.704804 -288.806815) (xy 272.692518 -288.869483)
			(xy 272.681192 -288.899346) (xy 272.677382 -288.90849) (xy 272.677382 -288.908744) (xy 272.675096 -288.914078)
			(xy 272.67281 -288.925762) (xy 272.673572 -288.935922) (xy 272.674588 -288.941002) (xy 272.67641 -288.947777)
			(xy 272.68324 -288.960025) (xy 272.68805 -288.965132) (xy 273.134582 -289.411664) (xy 273.140218 -289.416851)
			(xy 273.153777 -289.423961) (xy 273.161252 -289.425634) (xy 273.163538 -289.426142) (xy 273.180302 -289.427158)
			(xy 273.18462 -289.42538) (xy 273.206595 -289.415578) (xy 273.252669 -289.401709) (xy 273.300263 -289.394644)
			(xy 273.32432 -289.394138) (xy 273.324828 -289.394138) (xy 273.350815 -289.394623) (xy 273.402147 -289.402758)
			(xy 273.451575 -289.418824) (xy 273.497881 -289.442424) (xy 273.539925 -289.472977) (xy 273.576671 -289.509732)
			(xy 273.607215 -289.551782) (xy 273.630805 -289.598094) (xy 273.646859 -289.647525) (xy 273.654983 -289.698859)
			(xy 273.655536 -289.724846) (xy 273.968984 -289.724846) (xy 273.972944 -289.675792) (xy 273.984721 -289.628008)
			(xy 274.004012 -289.582732) (xy 274.030315 -289.541136) (xy 274.06295 -289.504299) (xy 274.101071 -289.473174)
			(xy 274.143692 -289.448567) (xy 274.189708 -289.431115) (xy 274.237927 -289.421271) (xy 274.287102 -289.41929)
			(xy 274.335957 -289.425222) (xy 274.383228 -289.438914) (xy 274.42769 -289.460012) (xy 274.468193 -289.487968)
			(xy 274.503686 -289.52206) (xy 274.533251 -289.561404) (xy 274.556122 -289.604981) (xy 274.571706 -289.651662)
			(xy 274.579601 -289.700239) (xy 274.580096 -289.724846) (xy 274.918944 -289.724846) (xy 274.922904 -289.675792)
			(xy 274.934681 -289.628008) (xy 274.953972 -289.582732) (xy 274.980275 -289.541136) (xy 275.01291 -289.504299)
			(xy 275.051031 -289.473174) (xy 275.093652 -289.448567) (xy 275.139668 -289.431115) (xy 275.187887 -289.421271)
			(xy 275.237062 -289.41929) (xy 275.285917 -289.425222) (xy 275.333188 -289.438914) (xy 275.37765 -289.460012)
			(xy 275.418153 -289.487968) (xy 275.453646 -289.52206) (xy 275.483211 -289.561404) (xy 275.506082 -289.604981)
			(xy 275.521666 -289.651662) (xy 275.529561 -289.700239) (xy 275.530056 -289.724846) (xy 275.868904 -289.724846)
			(xy 275.872864 -289.675792) (xy 275.884641 -289.628008) (xy 275.903932 -289.582732) (xy 275.930235 -289.541136)
			(xy 275.96287 -289.504299) (xy 276.000991 -289.473174) (xy 276.043612 -289.448567) (xy 276.089628 -289.431115)
			(xy 276.137847 -289.421271) (xy 276.187022 -289.41929) (xy 276.235877 -289.425222) (xy 276.283148 -289.438914)
			(xy 276.32761 -289.460012) (xy 276.368113 -289.487968) (xy 276.403606 -289.52206) (xy 276.433171 -289.561404)
			(xy 276.456042 -289.604981) (xy 276.471626 -289.651662) (xy 276.479521 -289.700239) (xy 276.480016 -289.724846)
			(xy 276.819118 -289.724846) (xy 276.823078 -289.675792) (xy 276.834855 -289.628008) (xy 276.854146 -289.582732)
			(xy 276.880449 -289.541136) (xy 276.913084 -289.504299) (xy 276.951205 -289.473174) (xy 276.993826 -289.448567)
			(xy 277.039842 -289.431115) (xy 277.088061 -289.421271) (xy 277.137236 -289.41929) (xy 277.186091 -289.425222)
			(xy 277.233362 -289.438914) (xy 277.277824 -289.460012) (xy 277.318327 -289.487968) (xy 277.35382 -289.52206)
			(xy 277.383385 -289.561404) (xy 277.406256 -289.604981) (xy 277.42184 -289.651662) (xy 277.429735 -289.700239)
			(xy 277.43023 -289.724846) (xy 277.769078 -289.724846) (xy 277.773038 -289.675792) (xy 277.784815 -289.628008)
			(xy 277.804106 -289.582732) (xy 277.830409 -289.541136) (xy 277.863044 -289.504299) (xy 277.901165 -289.473174)
			(xy 277.943786 -289.448567) (xy 277.989802 -289.431115) (xy 278.038021 -289.421271) (xy 278.087196 -289.41929)
			(xy 278.136051 -289.425222) (xy 278.183322 -289.438914) (xy 278.227784 -289.460012) (xy 278.268287 -289.487968)
			(xy 278.30378 -289.52206) (xy 278.333345 -289.561404) (xy 278.356216 -289.604981) (xy 278.3718 -289.651662)
			(xy 278.379695 -289.700239) (xy 278.38019 -289.724846) (xy 278.719038 -289.724846) (xy 278.722998 -289.675792)
			(xy 278.734775 -289.628008) (xy 278.754066 -289.582732) (xy 278.780369 -289.541136) (xy 278.813004 -289.504299)
			(xy 278.851125 -289.473174) (xy 278.893746 -289.448567) (xy 278.939762 -289.431115) (xy 278.987981 -289.421271)
			(xy 279.037156 -289.41929) (xy 279.086011 -289.425222) (xy 279.133282 -289.438914) (xy 279.177744 -289.460012)
			(xy 279.218247 -289.487968) (xy 279.25374 -289.52206) (xy 279.283305 -289.561404) (xy 279.306176 -289.604981)
			(xy 279.32176 -289.651662) (xy 279.329655 -289.700239) (xy 279.33015 -289.724846) (xy 279.329655 -289.749453)
			(xy 279.32176 -289.79803) (xy 279.306176 -289.844711) (xy 279.283305 -289.888288) (xy 279.25374 -289.927632)
			(xy 279.218247 -289.961724) (xy 279.177744 -289.98968) (xy 279.133282 -290.010778) (xy 279.086011 -290.02447)
			(xy 279.037156 -290.030402) (xy 278.987981 -290.028421) (xy 278.939762 -290.018577) (xy 278.893746 -290.001125)
			(xy 278.851125 -289.976518) (xy 278.813004 -289.945393) (xy 278.780369 -289.908556) (xy 278.754066 -289.86696)
			(xy 278.734775 -289.821684) (xy 278.722998 -289.7739) (xy 278.719038 -289.724846) (xy 278.38019 -289.724846)
			(xy 278.379695 -289.749453) (xy 278.3718 -289.79803) (xy 278.356216 -289.844711) (xy 278.333345 -289.888288)
			(xy 278.30378 -289.927632) (xy 278.268287 -289.961724) (xy 278.227784 -289.98968) (xy 278.183322 -290.010778)
			(xy 278.136051 -290.02447) (xy 278.087196 -290.030402) (xy 278.038021 -290.028421) (xy 277.989802 -290.018577)
			(xy 277.943786 -290.001125) (xy 277.901165 -289.976518) (xy 277.863044 -289.945393) (xy 277.830409 -289.908556)
			(xy 277.804106 -289.86696) (xy 277.784815 -289.821684) (xy 277.773038 -289.7739) (xy 277.769078 -289.724846)
			(xy 277.43023 -289.724846) (xy 277.429735 -289.749453) (xy 277.42184 -289.79803) (xy 277.406256 -289.844711)
			(xy 277.383385 -289.888288) (xy 277.35382 -289.927632) (xy 277.318327 -289.961724) (xy 277.277824 -289.98968)
			(xy 277.233362 -290.010778) (xy 277.186091 -290.02447) (xy 277.137236 -290.030402) (xy 277.088061 -290.028421)
			(xy 277.039842 -290.018577) (xy 276.993826 -290.001125) (xy 276.951205 -289.976518) (xy 276.913084 -289.945393)
			(xy 276.880449 -289.908556) (xy 276.854146 -289.86696) (xy 276.834855 -289.821684) (xy 276.823078 -289.7739)
			(xy 276.819118 -289.724846) (xy 276.480016 -289.724846) (xy 276.479521 -289.749453) (xy 276.471626 -289.79803)
			(xy 276.456042 -289.844711) (xy 276.433171 -289.888288) (xy 276.403606 -289.927632) (xy 276.368113 -289.961724)
			(xy 276.32761 -289.98968) (xy 276.283148 -290.010778) (xy 276.235877 -290.02447) (xy 276.187022 -290.030402)
			(xy 276.137847 -290.028421) (xy 276.089628 -290.018577) (xy 276.043612 -290.001125) (xy 276.000991 -289.976518)
			(xy 275.96287 -289.945393) (xy 275.930235 -289.908556) (xy 275.903932 -289.86696) (xy 275.884641 -289.821684)
			(xy 275.872864 -289.7739) (xy 275.868904 -289.724846) (xy 275.530056 -289.724846) (xy 275.529561 -289.749453)
			(xy 275.521666 -289.79803) (xy 275.506082 -289.844711) (xy 275.483211 -289.888288) (xy 275.453646 -289.927632)
			(xy 275.418153 -289.961724) (xy 275.37765 -289.98968) (xy 275.333188 -290.010778) (xy 275.285917 -290.02447)
			(xy 275.237062 -290.030402) (xy 275.187887 -290.028421) (xy 275.139668 -290.018577) (xy 275.093652 -290.001125)
			(xy 275.051031 -289.976518) (xy 275.01291 -289.945393) (xy 274.980275 -289.908556) (xy 274.953972 -289.86696)
			(xy 274.934681 -289.821684) (xy 274.922904 -289.7739) (xy 274.918944 -289.724846) (xy 274.580096 -289.724846)
			(xy 274.579601 -289.749453) (xy 274.571706 -289.79803) (xy 274.556122 -289.844711) (xy 274.533251 -289.888288)
			(xy 274.503686 -289.927632) (xy 274.468193 -289.961724) (xy 274.42769 -289.98968) (xy 274.383228 -290.010778)
			(xy 274.335957 -290.02447) (xy 274.287102 -290.030402) (xy 274.237927 -290.028421) (xy 274.189708 -290.018577)
			(xy 274.143692 -290.001125) (xy 274.101071 -289.976518) (xy 274.06295 -289.945393) (xy 274.030315 -289.908556)
			(xy 274.004012 -289.86696) (xy 273.984721 -289.821684) (xy 273.972944 -289.7739) (xy 273.968984 -289.724846)
			(xy 273.655536 -289.724846) (xy 273.654767 -289.756776) (xy 273.642487 -289.819446) (xy 273.631152 -289.849306)
			(xy 273.627342 -289.85845) (xy 273.627342 -289.858704) (xy 273.625056 -289.864038) (xy 273.62277 -289.875722)
			(xy 273.623532 -289.885882) (xy 273.624548 -289.890962) (xy 273.626367 -289.897738) (xy 273.633197 -289.909988)
			(xy 273.63801 -289.915092) (xy 274.084542 -290.361624) (xy 274.09018 -290.366808) (xy 274.103741 -290.373907)
			(xy 274.111212 -290.375594) (xy 274.113498 -290.376102) (xy 274.130262 -290.377118) (xy 274.13458 -290.37534)
			(xy 274.156554 -290.365534) (xy 274.202627 -290.351657) (xy 274.250222 -290.344585) (xy 274.27428 -290.344098)
			(xy 274.274788 -290.344098) (xy 274.300778 -290.34458) (xy 274.352117 -290.35271) (xy 274.401553 -290.368771)
			(xy 274.447868 -290.392368) (xy 274.48992 -290.422921) (xy 274.526676 -290.459675) (xy 274.557228 -290.501727)
			(xy 274.580826 -290.548041) (xy 274.596889 -290.597477) (xy 274.605019 -290.648816) (xy 274.605496 -290.674806)
			(xy 274.918944 -290.674806) (xy 274.922904 -290.625752) (xy 274.934681 -290.577968) (xy 274.953972 -290.532692)
			(xy 274.980275 -290.491096) (xy 275.01291 -290.454259) (xy 275.051031 -290.423134) (xy 275.093652 -290.398527)
			(xy 275.139668 -290.381075) (xy 275.187887 -290.371231) (xy 275.237062 -290.36925) (xy 275.285917 -290.375182)
			(xy 275.333188 -290.388874) (xy 275.37765 -290.409972) (xy 275.418153 -290.437928) (xy 275.453646 -290.47202)
			(xy 275.483211 -290.511364) (xy 275.506082 -290.554941) (xy 275.521666 -290.601622) (xy 275.529561 -290.650199)
			(xy 275.530056 -290.674806) (xy 275.868904 -290.674806) (xy 275.872864 -290.625752) (xy 275.884641 -290.577968)
			(xy 275.903932 -290.532692) (xy 275.930235 -290.491096) (xy 275.96287 -290.454259) (xy 276.000991 -290.423134)
			(xy 276.043612 -290.398527) (xy 276.089628 -290.381075) (xy 276.137847 -290.371231) (xy 276.187022 -290.36925)
			(xy 276.235877 -290.375182) (xy 276.283148 -290.388874) (xy 276.32761 -290.409972) (xy 276.368113 -290.437928)
			(xy 276.403606 -290.47202) (xy 276.433171 -290.511364) (xy 276.456042 -290.554941) (xy 276.471626 -290.601622)
			(xy 276.479521 -290.650199) (xy 276.480016 -290.674806) (xy 276.819118 -290.674806) (xy 276.823078 -290.625752)
			(xy 276.834855 -290.577968) (xy 276.854146 -290.532692) (xy 276.880449 -290.491096) (xy 276.913084 -290.454259)
			(xy 276.951205 -290.423134) (xy 276.993826 -290.398527) (xy 277.039842 -290.381075) (xy 277.088061 -290.371231)
			(xy 277.137236 -290.36925) (xy 277.186091 -290.375182) (xy 277.233362 -290.388874) (xy 277.277824 -290.409972)
			(xy 277.318327 -290.437928) (xy 277.35382 -290.47202) (xy 277.383385 -290.511364) (xy 277.406256 -290.554941)
			(xy 277.42184 -290.601622) (xy 277.429735 -290.650199) (xy 277.43023 -290.674806) (xy 277.769078 -290.674806)
			(xy 277.773038 -290.625752) (xy 277.784815 -290.577968) (xy 277.804106 -290.532692) (xy 277.830409 -290.491096)
			(xy 277.863044 -290.454259) (xy 277.901165 -290.423134) (xy 277.943786 -290.398527) (xy 277.989802 -290.381075)
			(xy 278.038021 -290.371231) (xy 278.087196 -290.36925) (xy 278.136051 -290.375182) (xy 278.183322 -290.388874)
			(xy 278.227784 -290.409972) (xy 278.268287 -290.437928) (xy 278.30378 -290.47202) (xy 278.333345 -290.511364)
			(xy 278.356216 -290.554941) (xy 278.3718 -290.601622) (xy 278.379695 -290.650199) (xy 278.38019 -290.674806)
			(xy 278.719038 -290.674806) (xy 278.722998 -290.625752) (xy 278.734775 -290.577968) (xy 278.754066 -290.532692)
			(xy 278.780369 -290.491096) (xy 278.813004 -290.454259) (xy 278.851125 -290.423134) (xy 278.893746 -290.398527)
			(xy 278.939762 -290.381075) (xy 278.987981 -290.371231) (xy 279.037156 -290.36925) (xy 279.086011 -290.375182)
			(xy 279.133282 -290.388874) (xy 279.177744 -290.409972) (xy 279.218247 -290.437928) (xy 279.25374 -290.47202)
			(xy 279.283305 -290.511364) (xy 279.306176 -290.554941) (xy 279.32176 -290.601622) (xy 279.329655 -290.650199)
			(xy 279.33015 -290.674806) (xy 279.329655 -290.699413) (xy 279.32176 -290.74799) (xy 279.306176 -290.794671)
			(xy 279.283305 -290.838248) (xy 279.25374 -290.877592) (xy 279.218247 -290.911684) (xy 279.177744 -290.93964)
			(xy 279.133282 -290.960738) (xy 279.086011 -290.97443) (xy 279.037156 -290.980362) (xy 278.987981 -290.978381)
			(xy 278.939762 -290.968537) (xy 278.893746 -290.951085) (xy 278.851125 -290.926478) (xy 278.813004 -290.895353)
			(xy 278.780369 -290.858516) (xy 278.754066 -290.81692) (xy 278.734775 -290.771644) (xy 278.722998 -290.72386)
			(xy 278.719038 -290.674806) (xy 278.38019 -290.674806) (xy 278.379695 -290.699413) (xy 278.3718 -290.74799)
			(xy 278.356216 -290.794671) (xy 278.333345 -290.838248) (xy 278.30378 -290.877592) (xy 278.268287 -290.911684)
			(xy 278.227784 -290.93964) (xy 278.183322 -290.960738) (xy 278.136051 -290.97443) (xy 278.087196 -290.980362)
			(xy 278.038021 -290.978381) (xy 277.989802 -290.968537) (xy 277.943786 -290.951085) (xy 277.901165 -290.926478)
			(xy 277.863044 -290.895353) (xy 277.830409 -290.858516) (xy 277.804106 -290.81692) (xy 277.784815 -290.771644)
			(xy 277.773038 -290.72386) (xy 277.769078 -290.674806) (xy 277.43023 -290.674806) (xy 277.429735 -290.699413)
			(xy 277.42184 -290.74799) (xy 277.406256 -290.794671) (xy 277.383385 -290.838248) (xy 277.35382 -290.877592)
			(xy 277.318327 -290.911684) (xy 277.277824 -290.93964) (xy 277.233362 -290.960738) (xy 277.186091 -290.97443)
			(xy 277.137236 -290.980362) (xy 277.088061 -290.978381) (xy 277.039842 -290.968537) (xy 276.993826 -290.951085)
			(xy 276.951205 -290.926478) (xy 276.913084 -290.895353) (xy 276.880449 -290.858516) (xy 276.854146 -290.81692)
			(xy 276.834855 -290.771644) (xy 276.823078 -290.72386) (xy 276.819118 -290.674806) (xy 276.480016 -290.674806)
			(xy 276.479521 -290.699413) (xy 276.471626 -290.74799) (xy 276.456042 -290.794671) (xy 276.433171 -290.838248)
			(xy 276.403606 -290.877592) (xy 276.368113 -290.911684) (xy 276.32761 -290.93964) (xy 276.283148 -290.960738)
			(xy 276.235877 -290.97443) (xy 276.187022 -290.980362) (xy 276.137847 -290.978381) (xy 276.089628 -290.968537)
			(xy 276.043612 -290.951085) (xy 276.000991 -290.926478) (xy 275.96287 -290.895353) (xy 275.930235 -290.858516)
			(xy 275.903932 -290.81692) (xy 275.884641 -290.771644) (xy 275.872864 -290.72386) (xy 275.868904 -290.674806)
			(xy 275.530056 -290.674806) (xy 275.529561 -290.699413) (xy 275.521666 -290.74799) (xy 275.506082 -290.794671)
			(xy 275.483211 -290.838248) (xy 275.453646 -290.877592) (xy 275.418153 -290.911684) (xy 275.37765 -290.93964)
			(xy 275.333188 -290.960738) (xy 275.285917 -290.97443) (xy 275.237062 -290.980362) (xy 275.187887 -290.978381)
			(xy 275.139668 -290.968537) (xy 275.093652 -290.951085) (xy 275.051031 -290.926478) (xy 275.01291 -290.895353)
			(xy 274.980275 -290.858516) (xy 274.953972 -290.81692) (xy 274.934681 -290.771644) (xy 274.922904 -290.72386)
			(xy 274.918944 -290.674806) (xy 274.605496 -290.674806) (xy 274.604731 -290.706737) (xy 274.59246 -290.76941)
			(xy 274.581112 -290.799266) (xy 274.577302 -290.80841) (xy 274.577302 -290.808664) (xy 274.575016 -290.813998)
			(xy 274.57273 -290.825682) (xy 274.573492 -290.835842) (xy 274.574508 -290.840922) (xy 274.576333 -290.847695)
			(xy 274.583168 -290.859938) (xy 274.58797 -290.865052) (xy 275.034502 -291.311584) (xy 275.040136 -291.316776)
			(xy 275.053694 -291.323891) (xy 275.061172 -291.325554) (xy 275.063458 -291.326062) (xy 275.080222 -291.327078)
			(xy 275.08454 -291.3253) (xy 275.106514 -291.315492) (xy 275.152587 -291.301611) (xy 275.200182 -291.294534)
			(xy 275.22424 -291.294058) (xy 275.224748 -291.294058) (xy 275.250734 -291.294571) (xy 275.302064 -291.302707)
			(xy 275.351491 -291.318772) (xy 275.397796 -291.34237) (xy 275.43984 -291.37292) (xy 275.476589 -291.40967)
			(xy 275.507137 -291.451716) (xy 275.530733 -291.498022) (xy 275.546796 -291.547449) (xy 275.55493 -291.59878)
			(xy 275.555456 -291.624766) (xy 275.868904 -291.624766) (xy 275.872864 -291.575712) (xy 275.884641 -291.527928)
			(xy 275.903932 -291.482652) (xy 275.930235 -291.441056) (xy 275.96287 -291.404219) (xy 276.000991 -291.373094)
			(xy 276.043612 -291.348487) (xy 276.089628 -291.331035) (xy 276.137847 -291.321191) (xy 276.187022 -291.31921)
			(xy 276.235877 -291.325142) (xy 276.283148 -291.338834) (xy 276.32761 -291.359932) (xy 276.368113 -291.387888)
			(xy 276.403606 -291.42198) (xy 276.433171 -291.461324) (xy 276.456042 -291.504901) (xy 276.471626 -291.551582)
			(xy 276.479521 -291.600159) (xy 276.480016 -291.624766) (xy 276.819118 -291.624766) (xy 276.823078 -291.575712)
			(xy 276.834855 -291.527928) (xy 276.854146 -291.482652) (xy 276.880449 -291.441056) (xy 276.913084 -291.404219)
			(xy 276.951205 -291.373094) (xy 276.993826 -291.348487) (xy 277.039842 -291.331035) (xy 277.088061 -291.321191)
			(xy 277.137236 -291.31921) (xy 277.186091 -291.325142) (xy 277.233362 -291.338834) (xy 277.277824 -291.359932)
			(xy 277.318327 -291.387888) (xy 277.35382 -291.42198) (xy 277.383385 -291.461324) (xy 277.406256 -291.504901)
			(xy 277.42184 -291.551582) (xy 277.429735 -291.600159) (xy 277.43023 -291.624766) (xy 277.769078 -291.624766)
			(xy 277.773038 -291.575712) (xy 277.784815 -291.527928) (xy 277.804106 -291.482652) (xy 277.830409 -291.441056)
			(xy 277.863044 -291.404219) (xy 277.901165 -291.373094) (xy 277.943786 -291.348487) (xy 277.989802 -291.331035)
			(xy 278.038021 -291.321191) (xy 278.087196 -291.31921) (xy 278.136051 -291.325142) (xy 278.183322 -291.338834)
			(xy 278.227784 -291.359932) (xy 278.268287 -291.387888) (xy 278.30378 -291.42198) (xy 278.333345 -291.461324)
			(xy 278.356216 -291.504901) (xy 278.3718 -291.551582) (xy 278.379695 -291.600159) (xy 278.38019 -291.624766)
			(xy 278.719038 -291.624766) (xy 278.722998 -291.575712) (xy 278.734775 -291.527928) (xy 278.754066 -291.482652)
			(xy 278.780369 -291.441056) (xy 278.813004 -291.404219) (xy 278.851125 -291.373094) (xy 278.893746 -291.348487)
			(xy 278.939762 -291.331035) (xy 278.987981 -291.321191) (xy 279.037156 -291.31921) (xy 279.086011 -291.325142)
			(xy 279.133282 -291.338834) (xy 279.177744 -291.359932) (xy 279.218247 -291.387888) (xy 279.25374 -291.42198)
			(xy 279.283305 -291.461324) (xy 279.306176 -291.504901) (xy 279.32176 -291.551582) (xy 279.329655 -291.600159)
			(xy 279.33015 -291.624766) (xy 279.329655 -291.649373) (xy 279.32176 -291.69795) (xy 279.306176 -291.744631)
			(xy 279.283305 -291.788208) (xy 279.25374 -291.827552) (xy 279.218247 -291.861644) (xy 279.177744 -291.8896)
			(xy 279.133282 -291.910698) (xy 279.086011 -291.92439) (xy 279.037156 -291.930322) (xy 278.987981 -291.928341)
			(xy 278.939762 -291.918497) (xy 278.893746 -291.901045) (xy 278.851125 -291.876438) (xy 278.813004 -291.845313)
			(xy 278.780369 -291.808476) (xy 278.754066 -291.76688) (xy 278.734775 -291.721604) (xy 278.722998 -291.67382)
			(xy 278.719038 -291.624766) (xy 278.38019 -291.624766) (xy 278.379695 -291.649373) (xy 278.3718 -291.69795)
			(xy 278.356216 -291.744631) (xy 278.333345 -291.788208) (xy 278.30378 -291.827552) (xy 278.268287 -291.861644)
			(xy 278.227784 -291.8896) (xy 278.183322 -291.910698) (xy 278.136051 -291.92439) (xy 278.087196 -291.930322)
			(xy 278.038021 -291.928341) (xy 277.989802 -291.918497) (xy 277.943786 -291.901045) (xy 277.901165 -291.876438)
			(xy 277.863044 -291.845313) (xy 277.830409 -291.808476) (xy 277.804106 -291.76688) (xy 277.784815 -291.721604)
			(xy 277.773038 -291.67382) (xy 277.769078 -291.624766) (xy 277.43023 -291.624766) (xy 277.429735 -291.649373)
			(xy 277.42184 -291.69795) (xy 277.406256 -291.744631) (xy 277.383385 -291.788208) (xy 277.35382 -291.827552)
			(xy 277.318327 -291.861644) (xy 277.277824 -291.8896) (xy 277.233362 -291.910698) (xy 277.186091 -291.92439)
			(xy 277.137236 -291.930322) (xy 277.088061 -291.928341) (xy 277.039842 -291.918497) (xy 276.993826 -291.901045)
			(xy 276.951205 -291.876438) (xy 276.913084 -291.845313) (xy 276.880449 -291.808476) (xy 276.854146 -291.76688)
			(xy 276.834855 -291.721604) (xy 276.823078 -291.67382) (xy 276.819118 -291.624766) (xy 276.480016 -291.624766)
			(xy 276.479521 -291.649373) (xy 276.471626 -291.69795) (xy 276.456042 -291.744631) (xy 276.433171 -291.788208)
			(xy 276.403606 -291.827552) (xy 276.368113 -291.861644) (xy 276.32761 -291.8896) (xy 276.283148 -291.910698)
			(xy 276.235877 -291.92439) (xy 276.187022 -291.930322) (xy 276.137847 -291.928341) (xy 276.089628 -291.918497)
			(xy 276.043612 -291.901045) (xy 276.000991 -291.876438) (xy 275.96287 -291.845313) (xy 275.930235 -291.808476)
			(xy 275.903932 -291.76688) (xy 275.884641 -291.721604) (xy 275.872864 -291.67382) (xy 275.868904 -291.624766)
			(xy 275.555456 -291.624766) (xy 275.554685 -291.656696) (xy 275.542402 -291.719364) (xy 275.531072 -291.749226)
			(xy 275.527262 -291.75837) (xy 275.527262 -291.758624) (xy 275.524976 -291.763958) (xy 275.52269 -291.775642)
			(xy 275.523452 -291.785802) (xy 275.524468 -291.790882) (xy 275.52629 -291.797656) (xy 275.533125 -291.8099)
			(xy 275.53793 -291.815012) (xy 275.98497 -292.262052) (xy 275.987715 -292.264663) (xy 275.993833 -292.269134)
			(xy 275.997162 -292.270942) (xy 276.000529 -292.272691) (xy 276.007673 -292.275244) (xy 276.011386 -292.276022)
			(xy 276.019006 -292.277292) (xy 276.033484 -292.275768) (xy 276.041104 -292.272466) (xy 276.06224 -292.263563)
			(xy 276.106353 -292.251015) (xy 276.151777 -292.24468) (xy 276.174708 -292.244272) (xy 276.200695 -292.244782)
			(xy 276.25203 -292.252914) (xy 276.301461 -292.268975) (xy 276.347771 -292.292571) (xy 276.389819 -292.323121)
			(xy 276.426572 -292.359872) (xy 276.457123 -292.401919) (xy 276.48072 -292.448228) (xy 276.496784 -292.497658)
			(xy 276.504917 -292.548993) (xy 276.505416 -292.57498) (xy 276.819118 -292.57498) (xy 276.823078 -292.525926)
			(xy 276.834855 -292.478142) (xy 276.854146 -292.432866) (xy 276.880449 -292.39127) (xy 276.913084 -292.354433)
			(xy 276.951205 -292.323308) (xy 276.993826 -292.298701) (xy 277.039842 -292.281249) (xy 277.088061 -292.271405)
			(xy 277.137236 -292.269424) (xy 277.186091 -292.275356) (xy 277.233362 -292.289048) (xy 277.277824 -292.310146)
			(xy 277.318327 -292.338102) (xy 277.35382 -292.372194) (xy 277.383385 -292.411538) (xy 277.406256 -292.455115)
			(xy 277.42184 -292.501796) (xy 277.429735 -292.550373) (xy 277.43023 -292.57498) (xy 277.769078 -292.57498)
			(xy 277.773038 -292.525926) (xy 277.784815 -292.478142) (xy 277.804106 -292.432866) (xy 277.830409 -292.39127)
			(xy 277.863044 -292.354433) (xy 277.901165 -292.323308) (xy 277.943786 -292.298701) (xy 277.989802 -292.281249)
			(xy 278.038021 -292.271405) (xy 278.087196 -292.269424) (xy 278.136051 -292.275356) (xy 278.183322 -292.289048)
			(xy 278.227784 -292.310146) (xy 278.268287 -292.338102) (xy 278.30378 -292.372194) (xy 278.333345 -292.411538)
			(xy 278.356216 -292.455115) (xy 278.3718 -292.501796) (xy 278.379695 -292.550373) (xy 278.38019 -292.57498)
			(xy 278.719038 -292.57498) (xy 278.722998 -292.525926) (xy 278.734775 -292.478142) (xy 278.754066 -292.432866)
			(xy 278.780369 -292.39127) (xy 278.813004 -292.354433) (xy 278.851125 -292.323308) (xy 278.893746 -292.298701)
			(xy 278.939762 -292.281249) (xy 278.987981 -292.271405) (xy 279.037156 -292.269424) (xy 279.086011 -292.275356)
			(xy 279.133282 -292.289048) (xy 279.177744 -292.310146) (xy 279.218247 -292.338102) (xy 279.25374 -292.372194)
			(xy 279.283305 -292.411538) (xy 279.306176 -292.455115) (xy 279.32176 -292.501796) (xy 279.329655 -292.550373)
			(xy 279.33015 -292.57498) (xy 279.329655 -292.599587) (xy 279.32176 -292.648164) (xy 279.306176 -292.694845)
			(xy 279.283305 -292.738422) (xy 279.25374 -292.777766) (xy 279.218247 -292.811858) (xy 279.177744 -292.839814)
			(xy 279.133282 -292.860912) (xy 279.086011 -292.874604) (xy 279.037156 -292.880536) (xy 278.987981 -292.878555)
			(xy 278.939762 -292.868711) (xy 278.893746 -292.851259) (xy 278.851125 -292.826652) (xy 278.813004 -292.795527)
			(xy 278.780369 -292.75869) (xy 278.754066 -292.717094) (xy 278.734775 -292.671818) (xy 278.722998 -292.624034)
			(xy 278.719038 -292.57498) (xy 278.38019 -292.57498) (xy 278.379695 -292.599587) (xy 278.3718 -292.648164)
			(xy 278.356216 -292.694845) (xy 278.333345 -292.738422) (xy 278.30378 -292.777766) (xy 278.268287 -292.811858)
			(xy 278.227784 -292.839814) (xy 278.183322 -292.860912) (xy 278.136051 -292.874604) (xy 278.087196 -292.880536)
			(xy 278.038021 -292.878555) (xy 277.989802 -292.868711) (xy 277.943786 -292.851259) (xy 277.901165 -292.826652)
			(xy 277.863044 -292.795527) (xy 277.830409 -292.75869) (xy 277.804106 -292.717094) (xy 277.784815 -292.671818)
			(xy 277.773038 -292.624034) (xy 277.769078 -292.57498) (xy 277.43023 -292.57498) (xy 277.429735 -292.599587)
			(xy 277.42184 -292.648164) (xy 277.406256 -292.694845) (xy 277.383385 -292.738422) (xy 277.35382 -292.777766)
			(xy 277.318327 -292.811858) (xy 277.277824 -292.839814) (xy 277.233362 -292.860912) (xy 277.186091 -292.874604)
			(xy 277.137236 -292.880536) (xy 277.088061 -292.878555) (xy 277.039842 -292.868711) (xy 276.993826 -292.851259)
			(xy 276.951205 -292.826652) (xy 276.913084 -292.795527) (xy 276.880449 -292.75869) (xy 276.854146 -292.717094)
			(xy 276.834855 -292.671818) (xy 276.823078 -292.624034) (xy 276.819118 -292.57498) (xy 276.505416 -292.57498)
			(xy 276.505026 -292.597912) (xy 276.498689 -292.643337) (xy 276.486134 -292.687451) (xy 276.477222 -292.708584)
			(xy 276.47392 -292.716204) (xy 276.472396 -292.730682) (xy 276.473666 -292.738302) (xy 276.474479 -292.742005)
			(xy 276.477027 -292.749147) (xy 276.478746 -292.752526) (xy 276.480551 -292.755858) (xy 276.485015 -292.761981)
			(xy 276.487636 -292.764718) (xy 277.551134 -293.828216) (xy 277.557985 -293.835612) (xy 277.565724 -293.854211)
			(xy 277.56612 -293.864284) (xy 277.56612 -293.894002) (xy 277.567136 -293.903654) (xy 277.568764 -293.910898)
			(xy 277.575606 -293.924066) (xy 277.580598 -293.929562) (xy 277.59279 -293.941754) (xy 277.600186 -293.948607)
			(xy 277.618784 -293.956352) (xy 277.628858 -293.95674)
		)
		(stroke
			(width 0)
			(type solid)
		)
		(fill yes)
		(layer "In7.Cu")
		(net "PCEPLL5_VDDA18_PEX2")
	)
	(gr_poly
		(pts
			(xy 218.042998 -139.983464) (xy 218.05041 -139.990148) (xy 218.068843 -139.997745) (xy 218.088781 -139.997745)
			(xy 218.107214 -139.990148) (xy 218.114626 -139.983464) (xy 220.00718 -138.09091) (xy 220.030745 -138.068015)
			(xy 220.082131 -138.027067) (xy 220.137774 -137.992125) (xy 220.196978 -137.963627) (xy 220.258998 -137.941932)
			(xy 220.323056 -137.927311) (xy 220.388347 -137.919949) (xy 220.4212 -137.91946) (xy 222.161354 -137.91946)
			(xy 222.196434 -137.919994) (xy 222.26609 -137.928403) (xy 222.300292 -137.936224) (xy 222.300546 -137.936224)
			(xy 222.311858 -137.938411) (xy 222.334349 -137.933521) (xy 222.343726 -137.926826) (xy 222.406718 -137.87755)
			(xy 222.41551 -137.870011) (xy 222.425698 -137.849239) (xy 222.426276 -137.837672) (xy 222.426276 -136.016746)
			(xy 222.426734 -135.983891) (xy 222.434085 -135.918594) (xy 222.448701 -135.854531) (xy 222.470398 -135.792507)
			(xy 222.498902 -135.733302) (xy 222.533855 -135.67766) (xy 222.574819 -135.626282) (xy 222.597726 -135.602726)
			(xy 232.376726 -125.823726) (xy 232.40029 -125.800828) (xy 232.451674 -125.759874) (xy 232.507317 -125.724926)
			(xy 232.56652 -125.696422) (xy 232.62854 -125.674721) (xy 232.692599 -125.660094) (xy 232.757892 -125.652726)
			(xy 232.790746 -125.652276) (xy 234.375706 -125.652276) (xy 234.385775 -125.651851) (xy 234.404376 -125.644133)
			(xy 234.411774 -125.63729) (xy 241.277648 -118.771162) (xy 241.278156 -118.76405) (xy 241.278156 -118.49227)
			(xy 241.277861 -118.484603) (xy 241.273209 -118.469991) (xy 241.269012 -118.463568) (xy 241.249962 -118.435882)
			(xy 241.238532 -118.426484) (xy 241.232182 -118.423944) (xy 241.206713 -118.412696) (xy 241.159064 -118.383901)
			(xy 241.116108 -118.348483) (xy 241.078758 -118.307197) (xy 241.047806 -118.260919) (xy 241.023912 -118.210633)
			(xy 241.015266 -118.184168) (xy 241.007418 -118.156832) (xy 240.998976 -118.100591) (xy 240.998983 -118.043721)
			(xy 241.007437 -117.987482) (xy 241.015266 -117.96014) (xy 241.02392 -117.933677) (xy 241.04782 -117.883394)
			(xy 241.078771 -117.837115) (xy 241.116116 -117.795824) (xy 241.159063 -117.760395) (xy 241.2067 -117.73158)
			(xy 241.232182 -117.720364) (xy 241.238532 -117.717824) (xy 241.249962 -117.708426) (xy 241.269012 -117.68074)
			(xy 241.273141 -117.674284) (xy 241.277796 -117.659692) (xy 241.278156 -117.652038) (xy 241.278156 -102.549706)
			(xy 241.277648 -102.542594) (xy 237.056422 -98.321114) (xy 237.04902 -98.314278) (xy 237.030422 -98.30657)
			(xy 237.020354 -98.306128) (xy 236.921548 -98.306128) (xy 236.917476 -98.306182) (xy 236.909434 -98.307459)
			(xy 236.905546 -98.308668) (xy 236.904276 -98.309176) (xy 236.897694 -98.311589) (xy 236.886093 -98.319449)
			(xy 236.881416 -98.32467) (xy 236.876844 -98.330258) (xy 236.871002 -98.343212) (xy 236.869986 -98.350324)
			(xy 236.865652 -98.377239) (xy 236.850299 -98.429549) (xy 236.827656 -98.479141) (xy 236.798184 -98.525004)
			(xy 236.762483 -98.566204) (xy 236.72128 -98.601902) (xy 236.675414 -98.631371) (xy 236.625821 -98.65401)
			(xy 236.57351 -98.669359) (xy 236.519546 -98.677104) (xy 236.492288 -98.677476) (xy 236.465012 -98.677011)
			(xy 236.411015 -98.66924) (xy 236.358675 -98.653859) (xy 236.30906 -98.631181) (xy 236.263179 -98.601668)
			(xy 236.22197 -98.565922) (xy 236.186271 -98.524671) (xy 236.15681 -98.478757) (xy 236.134189 -98.429116)
			(xy 236.118867 -98.376758) (xy 236.11459 -98.349816) (xy 236.11205 -98.33102) (xy 236.083348 -98.306128)
			(xy 235.904278 -98.306128) (xy 235.89517 -98.306509) (xy 235.878108 -98.312893) (xy 235.864361 -98.324846)
			(xy 235.855667 -98.340854) (xy 235.853986 -98.349816) (xy 235.849676 -98.376754) (xy 235.834363 -98.429112)
			(xy 235.811748 -98.478756) (xy 235.782293 -98.524673) (xy 235.746598 -98.565926) (xy 235.705392 -98.601675)
			(xy 235.659513 -98.63119) (xy 235.609899 -98.653869) (xy 235.55756 -98.669251) (xy 235.503564 -98.677021)
			(xy 235.449012 -98.677021) (xy 235.395016 -98.669251) (xy 235.342677 -98.653869) (xy 235.293063 -98.63119)
			(xy 235.247184 -98.601675) (xy 235.205978 -98.565926) (xy 235.170283 -98.524673) (xy 235.140828 -98.478756)
			(xy 235.118213 -98.429112) (xy 235.1029 -98.376754) (xy 235.09859 -98.349816) (xy 235.096945 -98.340844)
			(xy 235.088244 -98.324828) (xy 235.074485 -98.312872) (xy 235.057412 -98.30649) (xy 235.048298 -98.306128)
			(xy 234.888278 -98.306128) (xy 234.87917 -98.306509) (xy 234.862108 -98.312893) (xy 234.848361 -98.324846)
			(xy 234.839667 -98.340854) (xy 234.837986 -98.349816) (xy 234.833676 -98.376754) (xy 234.818363 -98.429112)
			(xy 234.795748 -98.478756) (xy 234.766293 -98.524673) (xy 234.730598 -98.565926) (xy 234.689392 -98.601675)
			(xy 234.643513 -98.63119) (xy 234.593899 -98.653869) (xy 234.54156 -98.669251) (xy 234.487564 -98.677021)
			(xy 234.433012 -98.677021) (xy 234.379016 -98.669251) (xy 234.326677 -98.653869) (xy 234.277063 -98.63119)
			(xy 234.231184 -98.601675) (xy 234.189978 -98.565926) (xy 234.154283 -98.524673) (xy 234.124828 -98.478756)
			(xy 234.102213 -98.429112) (xy 234.0869 -98.376754) (xy 234.08259 -98.349816) (xy 234.080945 -98.340844)
			(xy 234.072244 -98.324828) (xy 234.058485 -98.312872) (xy 234.041412 -98.30649) (xy 234.032298 -98.306128)
			(xy 233.872278 -98.306128) (xy 233.86317 -98.306509) (xy 233.846108 -98.312893) (xy 233.832361 -98.324846)
			(xy 233.823667 -98.340854) (xy 233.821986 -98.349816) (xy 233.817676 -98.376754) (xy 233.802363 -98.429112)
			(xy 233.779748 -98.478756) (xy 233.750293 -98.524673) (xy 233.714598 -98.565926) (xy 233.673392 -98.601675)
			(xy 233.627513 -98.63119) (xy 233.577899 -98.653869) (xy 233.52556 -98.669251) (xy 233.471564 -98.677021)
			(xy 233.417012 -98.677021) (xy 233.363016 -98.669251) (xy 233.310677 -98.653869) (xy 233.261063 -98.63119)
			(xy 233.215184 -98.601675) (xy 233.173978 -98.565926) (xy 233.138283 -98.524673) (xy 233.108828 -98.478756)
			(xy 233.086213 -98.429112) (xy 233.0709 -98.376754) (xy 233.06659 -98.349816) (xy 233.064945 -98.340844)
			(xy 233.056244 -98.324828) (xy 233.042485 -98.312872) (xy 233.025412 -98.30649) (xy 233.016298 -98.306128)
			(xy 232.837228 -98.306128) (xy 232.808526 -98.33102) (xy 232.805986 -98.349816) (xy 232.801676 -98.376754)
			(xy 232.786363 -98.429112) (xy 232.763748 -98.478756) (xy 232.734293 -98.524673) (xy 232.698598 -98.565926)
			(xy 232.657392 -98.601675) (xy 232.611513 -98.63119) (xy 232.561899 -98.653869) (xy 232.50956 -98.669251)
			(xy 232.455564 -98.677021) (xy 232.401012 -98.677021) (xy 232.347016 -98.669251) (xy 232.294677 -98.653869)
			(xy 232.245063 -98.63119) (xy 232.199184 -98.601675) (xy 232.157978 -98.565926) (xy 232.122283 -98.524673)
			(xy 232.092828 -98.478756) (xy 232.070213 -98.429112) (xy 232.0549 -98.376754) (xy 232.05059 -98.349816)
			(xy 232.04805 -98.33102) (xy 232.019348 -98.306128) (xy 231.821228 -98.306128) (xy 231.792526 -98.33102)
			(xy 231.789986 -98.349816) (xy 231.785678 -98.376755) (xy 231.770367 -98.429116) (xy 231.747755 -98.478763)
			(xy 231.718301 -98.524683) (xy 231.682606 -98.565938) (xy 231.641399 -98.601689) (xy 231.59552 -98.631206)
			(xy 231.545904 -98.653886) (xy 231.493563 -98.669267) (xy 231.439565 -98.677037) (xy 231.412288 -98.677476)
			(xy 231.385493 -98.677014) (xy 231.332431 -98.669498) (xy 231.280944 -98.654629) (xy 231.232045 -98.632701)
			(xy 231.186695 -98.604145) (xy 231.145789 -98.569522) (xy 231.110132 -98.529516) (xy 231.080424 -98.484912)
			(xy 231.057252 -98.43659) (xy 231.041071 -98.3855) (xy 231.032199 -98.332648) (xy 231.031034 -98.305874)
			(xy 231.009698 -98.306128) (xy 231.00919 -98.306128) (xy 230.976334 -98.305673) (xy 230.911035 -98.298326)
			(xy 230.846969 -98.283714) (xy 230.784942 -98.262021) (xy 230.725733 -98.23352) (xy 230.670088 -98.198569)
			(xy 230.618705 -98.157608) (xy 230.59517 -98.134678) (xy 228.495098 -96.034606) (xy 228.472201 -96.011042)
			(xy 228.431248 -95.959659) (xy 228.396302 -95.904016) (xy 228.367801 -95.844812) (xy 228.346104 -95.782791)
			(xy 228.331483 -95.718732) (xy 228.324121 -95.653439) (xy 228.323648 -95.620586) (xy 228.323648 -89.633298)
			(xy 228.323212 -89.623875) (xy 228.316445 -89.606283) (xy 228.31044 -89.599008) (xy 228.29012 -89.57691)
			(xy 228.283965 -89.570682) (xy 228.268506 -89.562488) (xy 228.259894 -89.560908) (xy 228.232888 -89.556661)
			(xy 228.18038 -89.541447) (xy 228.130581 -89.518895) (xy 228.08451 -89.489467) (xy 228.04311 -89.453765)
			(xy 228.007228 -89.412521) (xy 227.9776 -89.366578) (xy 227.954832 -89.316877) (xy 227.939389 -89.264436)
			(xy 227.931589 -89.210328) (xy 227.931589 -89.15566) (xy 227.939392 -89.101552) (xy 227.954836 -89.049111)
			(xy 227.977606 -88.999411) (xy 228.007236 -88.953469) (xy 228.043118 -88.912226) (xy 228.084519 -88.876526)
			(xy 228.130591 -88.847099) (xy 228.180391 -88.824549) (xy 228.2329 -88.809336) (xy 228.259894 -88.805004)
			(xy 228.268491 -88.80338) (xy 228.283944 -88.795199) (xy 228.29012 -88.789002) (xy 228.31044 -88.766904)
			(xy 228.316537 -88.759681) (xy 228.323341 -88.74206) (xy 228.323648 -88.732614) (xy 228.323648 -88.056212)
			(xy 228.324108 -88.023358) (xy 228.331462 -87.958062) (xy 228.346081 -87.894001) (xy 228.367779 -87.831979)
			(xy 228.396285 -87.772775) (xy 228.431239 -87.717136) (xy 228.472202 -87.665759) (xy 228.495098 -87.642192)
			(xy 228.722682 -87.414608) (xy 228.729532 -87.407211) (xy 228.737272 -87.388613) (xy 228.737668 -87.37854)
			(xy 228.737668 -87.008208) (xy 228.737249 -86.998188) (xy 228.72958 -86.979674) (xy 228.715406 -86.965507)
			(xy 228.696888 -86.957846) (xy 228.686868 -86.957408) (xy 228.253036 -86.957408) (xy 228.242971 -86.957843)
			(xy 228.224384 -86.965575) (xy 228.216968 -86.972394) (xy 225.179636 -90.009726) (xy 227.35235 -90.009726)
			(xy 227.356421 -89.954104) (xy 227.368547 -89.899667) (xy 227.38847 -89.847576) (xy 227.415766 -89.798941)
			(xy 227.449852 -89.754798) (xy 227.490001 -89.716089) (xy 227.535359 -89.683638) (xy 227.584959 -89.658137)
			(xy 227.637743 -89.64013) (xy 227.692586 -89.63) (xy 227.74832 -89.627963) (xy 227.803757 -89.634063)
			(xy 227.857714 -89.648169) (xy 227.909043 -89.669981) (xy 227.956649 -89.699035) (xy 227.999517 -89.73471)
			(xy 228.036734 -89.776247) (xy 228.067507 -89.82276) (xy 228.091179 -89.873257) (xy 228.107247 -89.926664)
			(xy 228.115367 -89.98184) (xy 228.115876 -90.009726) (xy 228.115367 -90.037612) (xy 228.107247 -90.092788)
			(xy 228.091179 -90.146195) (xy 228.067507 -90.196692) (xy 228.036734 -90.243205) (xy 227.999517 -90.284742)
			(xy 227.956649 -90.320417) (xy 227.909043 -90.349471) (xy 227.857714 -90.371283) (xy 227.803757 -90.385389)
			(xy 227.74832 -90.391489) (xy 227.692586 -90.389452) (xy 227.637743 -90.379322) (xy 227.584959 -90.361315)
			(xy 227.535359 -90.335814) (xy 227.490001 -90.303363) (xy 227.449852 -90.264654) (xy 227.415766 -90.220511)
			(xy 227.38847 -90.171876) (xy 227.368547 -90.119785) (xy 227.356421 -90.065348) (xy 227.35235 -90.009726)
			(xy 225.179636 -90.009726) (xy 224.733866 -90.455496) (xy 224.727763 -90.462138) (xy 224.720274 -90.478533)
			(xy 224.718954 -90.49651) (xy 224.723967 -90.513824) (xy 224.72904 -90.521282) (xy 224.72904 -90.521536)
			(xy 224.746612 -90.546285) (xy 224.77451 -90.600187) (xy 224.79351 -90.657831) (xy 224.803131 -90.717757)
			(xy 224.803716 -90.748104) (xy 224.803281 -90.772488) (xy 225.37623 -90.772488) (xy 225.380301 -90.716866)
			(xy 225.392427 -90.662429) (xy 225.41235 -90.610338) (xy 225.439646 -90.561703) (xy 225.473732 -90.51756)
			(xy 225.513881 -90.478851) (xy 225.559239 -90.4464) (xy 225.608839 -90.420899) (xy 225.661623 -90.402892)
			(xy 225.716466 -90.392762) (xy 225.7722 -90.390725) (xy 225.827637 -90.396825) (xy 225.881594 -90.410931)
			(xy 225.932923 -90.432743) (xy 225.980529 -90.461797) (xy 226.023397 -90.497472) (xy 226.060614 -90.539009)
			(xy 226.091387 -90.585522) (xy 226.115059 -90.636019) (xy 226.131127 -90.689426) (xy 226.139247 -90.744602)
			(xy 226.139756 -90.772488) (xy 226.139247 -90.800374) (xy 226.131127 -90.85555) (xy 226.115059 -90.908957)
			(xy 226.091387 -90.959454) (xy 226.060614 -91.005967) (xy 226.04291 -91.025726) (xy 227.35235 -91.025726)
			(xy 227.356421 -90.970104) (xy 227.368547 -90.915667) (xy 227.38847 -90.863576) (xy 227.415766 -90.814941)
			(xy 227.449852 -90.770798) (xy 227.490001 -90.732089) (xy 227.535359 -90.699638) (xy 227.584959 -90.674137)
			(xy 227.637743 -90.65613) (xy 227.692586 -90.646) (xy 227.74832 -90.643963) (xy 227.803757 -90.650063)
			(xy 227.857714 -90.664169) (xy 227.909043 -90.685981) (xy 227.956649 -90.715035) (xy 227.999517 -90.75071)
			(xy 228.036734 -90.792247) (xy 228.067507 -90.83876) (xy 228.091179 -90.889257) (xy 228.107247 -90.942664)
			(xy 228.115367 -90.99784) (xy 228.115876 -91.025726) (xy 228.115367 -91.053612) (xy 228.107247 -91.108788)
			(xy 228.091179 -91.162195) (xy 228.067507 -91.212692) (xy 228.036734 -91.259205) (xy 227.999517 -91.300742)
			(xy 227.956649 -91.336417) (xy 227.909043 -91.365471) (xy 227.857714 -91.387283) (xy 227.803757 -91.401389)
			(xy 227.74832 -91.407489) (xy 227.692586 -91.405452) (xy 227.637743 -91.395322) (xy 227.584959 -91.377315)
			(xy 227.535359 -91.351814) (xy 227.490001 -91.319363) (xy 227.449852 -91.280654) (xy 227.415766 -91.236511)
			(xy 227.38847 -91.187876) (xy 227.368547 -91.135785) (xy 227.356421 -91.081348) (xy 227.35235 -91.025726)
			(xy 226.04291 -91.025726) (xy 226.023397 -91.047504) (xy 225.980529 -91.083179) (xy 225.932923 -91.112233)
			(xy 225.881594 -91.134045) (xy 225.827637 -91.148151) (xy 225.7722 -91.154251) (xy 225.716466 -91.152214)
			(xy 225.661623 -91.142084) (xy 225.608839 -91.124077) (xy 225.559239 -91.098576) (xy 225.513881 -91.066125)
			(xy 225.473732 -91.027416) (xy 225.439646 -90.983273) (xy 225.41235 -90.934638) (xy 225.392427 -90.882547)
			(xy 225.380301 -90.82811) (xy 225.37623 -90.772488) (xy 224.803281 -90.772488) (xy 224.80323 -90.775355)
			(xy 224.795473 -90.829303) (xy 224.780118 -90.881598) (xy 224.757476 -90.931175) (xy 224.72801 -90.977025)
			(xy 224.692319 -91.018216) (xy 224.651129 -91.053908) (xy 224.605278 -91.083374) (xy 224.555701 -91.106016)
			(xy 224.503407 -91.121372) (xy 224.449459 -91.12913) (xy 224.422208 -91.129612) (xy 224.391866 -91.128998)
			(xy 224.331952 -91.119344) (xy 224.274318 -91.100342) (xy 224.220412 -91.072469) (xy 224.19564 -91.054936)
			(xy 224.195386 -91.054936) (xy 224.18791 -91.049908) (xy 224.170601 -91.044946) (xy 224.152643 -91.046254)
			(xy 224.136237 -91.053671) (xy 224.1296 -91.059762) (xy 221.234254 -93.955108) (xy 221.210699 -93.978054)
			(xy 221.1593 -94.019073) (xy 221.103628 -94.054076) (xy 221.044386 -94.082622) (xy 220.982319 -94.104351)
			(xy 220.918208 -94.118991) (xy 220.852861 -94.126356) (xy 220.81998 -94.126812) (xy 219.22232 -94.126812)
			(xy 219.216478 -94.131638) (xy 218.438984 -94.909132) (xy 218.433737 -94.914799) (xy 218.426628 -94.928503)
			(xy 218.425014 -94.936056) (xy 218.42349 -94.943676) (xy 218.425522 -94.958662) (xy 218.42857 -94.965774)
			(xy 218.428824 -94.966282) (xy 218.43936 -94.990788) (xy 218.454247 -95.042009) (xy 218.461843 -95.094807)
			(xy 218.462352 -95.121476) (xy 218.462352 -95.123) (xy 218.841826 -95.123) (xy 218.845897 -95.067378)
			(xy 218.858023 -95.012941) (xy 218.877946 -94.96085) (xy 218.905242 -94.912215) (xy 218.939328 -94.868072)
			(xy 218.979477 -94.829363) (xy 219.024835 -94.796912) (xy 219.074435 -94.771411) (xy 219.127219 -94.753404)
			(xy 219.182062 -94.743274) (xy 219.237796 -94.741237) (xy 219.293233 -94.747337) (xy 219.34719 -94.761443)
			(xy 219.398519 -94.783255) (xy 219.446125 -94.812309) (xy 219.488993 -94.847984) (xy 219.52621 -94.889521)
			(xy 219.554645 -94.9325) (xy 220.111826 -94.9325) (xy 220.115897 -94.876878) (xy 220.128023 -94.822441)
			(xy 220.147946 -94.77035) (xy 220.175242 -94.721715) (xy 220.209328 -94.677572) (xy 220.249477 -94.638863)
			(xy 220.294835 -94.606412) (xy 220.344435 -94.580911) (xy 220.397219 -94.562904) (xy 220.452062 -94.552774)
			(xy 220.507796 -94.550737) (xy 220.563233 -94.556837) (xy 220.61719 -94.570943) (xy 220.668519 -94.592755)
			(xy 220.716125 -94.621809) (xy 220.758993 -94.657484) (xy 220.79621 -94.699021) (xy 220.826983 -94.745534)
			(xy 220.850655 -94.796031) (xy 220.866723 -94.849438) (xy 220.874843 -94.904614) (xy 220.875352 -94.9325)
			(xy 220.874843 -94.960386) (xy 220.866723 -95.015562) (xy 220.850655 -95.068969) (xy 220.840925 -95.089726)
			(xy 227.35235 -95.089726) (xy 227.356421 -95.034104) (xy 227.368547 -94.979667) (xy 227.38847 -94.927576)
			(xy 227.415766 -94.878941) (xy 227.449852 -94.834798) (xy 227.490001 -94.796089) (xy 227.535359 -94.763638)
			(xy 227.584959 -94.738137) (xy 227.637743 -94.72013) (xy 227.692586 -94.71) (xy 227.74832 -94.707963)
			(xy 227.803757 -94.714063) (xy 227.857714 -94.728169) (xy 227.909043 -94.749981) (xy 227.956649 -94.779035)
			(xy 227.999517 -94.81471) (xy 228.036734 -94.856247) (xy 228.067507 -94.90276) (xy 228.091179 -94.953257)
			(xy 228.107247 -95.006664) (xy 228.115367 -95.06184) (xy 228.115876 -95.089726) (xy 228.115367 -95.117612)
			(xy 228.107247 -95.172788) (xy 228.091179 -95.226195) (xy 228.067507 -95.276692) (xy 228.036734 -95.323205)
			(xy 227.999517 -95.364742) (xy 227.956649 -95.400417) (xy 227.909043 -95.429471) (xy 227.857714 -95.451283)
			(xy 227.803757 -95.465389) (xy 227.74832 -95.471489) (xy 227.692586 -95.469452) (xy 227.637743 -95.459322)
			(xy 227.584959 -95.441315) (xy 227.535359 -95.415814) (xy 227.490001 -95.383363) (xy 227.449852 -95.344654)
			(xy 227.415766 -95.300511) (xy 227.38847 -95.251876) (xy 227.368547 -95.199785) (xy 227.356421 -95.145348)
			(xy 227.35235 -95.089726) (xy 220.840925 -95.089726) (xy 220.826983 -95.119466) (xy 220.79621 -95.165979)
			(xy 220.758993 -95.207516) (xy 220.716125 -95.243191) (xy 220.668519 -95.272245) (xy 220.61719 -95.294057)
			(xy 220.563233 -95.308163) (xy 220.507796 -95.314263) (xy 220.452062 -95.312226) (xy 220.397219 -95.302096)
			(xy 220.344435 -95.284089) (xy 220.294835 -95.258588) (xy 220.249477 -95.226137) (xy 220.209328 -95.187428)
			(xy 220.175242 -95.143285) (xy 220.147946 -95.09465) (xy 220.128023 -95.042559) (xy 220.115897 -94.988122)
			(xy 220.111826 -94.9325) (xy 219.554645 -94.9325) (xy 219.556983 -94.936034) (xy 219.580655 -94.986531)
			(xy 219.596723 -95.039938) (xy 219.604843 -95.095114) (xy 219.605352 -95.123) (xy 219.604843 -95.150886)
			(xy 219.596723 -95.206062) (xy 219.580655 -95.259469) (xy 219.556983 -95.309966) (xy 219.52621 -95.356479)
			(xy 219.488993 -95.398016) (xy 219.446125 -95.433691) (xy 219.398519 -95.462745) (xy 219.34719 -95.484557)
			(xy 219.293233 -95.498663) (xy 219.237796 -95.504763) (xy 219.182062 -95.502726) (xy 219.127219 -95.492596)
			(xy 219.074435 -95.474589) (xy 219.024835 -95.449088) (xy 218.979477 -95.416637) (xy 218.939328 -95.377928)
			(xy 218.905242 -95.333785) (xy 218.877946 -95.28515) (xy 218.858023 -95.233059) (xy 218.845897 -95.178622)
			(xy 218.841826 -95.123) (xy 218.462352 -95.123) (xy 218.462352 -95.12808) (xy 218.461311 -95.159924)
			(xy 218.449954 -95.222613) (xy 218.439746 -95.252794) (xy 218.43033 -95.277431) (xy 218.405683 -95.324059)
			(xy 218.374852 -95.366852) (xy 218.338426 -95.404995) (xy 218.297098 -95.437762) (xy 218.251653 -95.46453)
			(xy 218.202956 -95.484788) (xy 218.151935 -95.498152) (xy 218.125802 -95.501714) (xy 218.116917 -95.50314)
			(xy 218.100912 -95.511342) (xy 218.09456 -95.517716) (xy 218.07424 -95.53956) (xy 218.067949 -95.546848)
			(xy 218.060881 -95.564739) (xy 218.060524 -95.574358) (xy 218.060524 -97.282) (xy 218.206826 -97.282)
			(xy 218.210897 -97.226378) (xy 218.223023 -97.171941) (xy 218.242946 -97.11985) (xy 218.270242 -97.071215)
			(xy 218.304328 -97.027072) (xy 218.344477 -96.988363) (xy 218.389835 -96.955912) (xy 218.439435 -96.930411)
			(xy 218.492219 -96.912404) (xy 218.547062 -96.902274) (xy 218.602796 -96.900237) (xy 218.658233 -96.906337)
			(xy 218.71219 -96.920443) (xy 218.763519 -96.942255) (xy 218.811125 -96.971309) (xy 218.853993 -97.006984)
			(xy 218.89121 -97.048521) (xy 218.921983 -97.095034) (xy 218.945655 -97.145531) (xy 218.961723 -97.198938)
			(xy 218.969843 -97.254114) (xy 218.970352 -97.282) (xy 218.969843 -97.309886) (xy 218.961723 -97.365062)
			(xy 218.945655 -97.418469) (xy 218.921983 -97.468966) (xy 218.89121 -97.515479) (xy 218.872823 -97.536)
			(xy 219.095826 -97.536) (xy 219.099897 -97.480378) (xy 219.112023 -97.425941) (xy 219.131946 -97.37385)
			(xy 219.159242 -97.325215) (xy 219.193328 -97.281072) (xy 219.233477 -97.242363) (xy 219.278835 -97.209912)
			(xy 219.328435 -97.184411) (xy 219.381219 -97.166404) (xy 219.436062 -97.156274) (xy 219.491796 -97.154237)
			(xy 219.547233 -97.160337) (xy 219.60119 -97.174443) (xy 219.652519 -97.196255) (xy 219.700125 -97.225309)
			(xy 219.742993 -97.260984) (xy 219.78021 -97.302521) (xy 219.787639 -97.31375) (xy 222.308926 -97.31375)
			(xy 222.312997 -97.258128) (xy 222.325123 -97.203691) (xy 222.345046 -97.1516) (xy 222.372342 -97.102965)
			(xy 222.406428 -97.058822) (xy 222.446577 -97.020113) (xy 222.491935 -96.987662) (xy 222.541535 -96.962161)
			(xy 222.594319 -96.944154) (xy 222.649162 -96.934024) (xy 222.704896 -96.931987) (xy 222.760333 -96.938087)
			(xy 222.81429 -96.952193) (xy 222.865619 -96.974005) (xy 222.913225 -97.003059) (xy 222.956093 -97.038734)
			(xy 222.99331 -97.080271) (xy 223.024083 -97.126784) (xy 223.047755 -97.177281) (xy 223.063823 -97.230688)
			(xy 223.071943 -97.285864) (xy 223.072452 -97.31375) (xy 223.324926 -97.31375) (xy 223.328997 -97.258128)
			(xy 223.341123 -97.203691) (xy 223.361046 -97.1516) (xy 223.388342 -97.102965) (xy 223.422428 -97.058822)
			(xy 223.462577 -97.020113) (xy 223.507935 -96.987662) (xy 223.557535 -96.962161) (xy 223.610319 -96.944154)
			(xy 223.665162 -96.934024) (xy 223.720896 -96.931987) (xy 223.776333 -96.938087) (xy 223.83029 -96.952193)
			(xy 223.881619 -96.974005) (xy 223.929225 -97.003059) (xy 223.972093 -97.038734) (xy 224.00931 -97.080271)
			(xy 224.040083 -97.126784) (xy 224.063755 -97.177281) (xy 224.079823 -97.230688) (xy 224.087943 -97.285864)
			(xy 224.088452 -97.31375) (xy 227.642926 -97.31375) (xy 227.646997 -97.258128) (xy 227.659123 -97.203691)
			(xy 227.679046 -97.1516) (xy 227.706342 -97.102965) (xy 227.740428 -97.058822) (xy 227.780577 -97.020113)
			(xy 227.825935 -96.987662) (xy 227.875535 -96.962161) (xy 227.928319 -96.944154) (xy 227.983162 -96.934024)
			(xy 228.038896 -96.931987) (xy 228.094333 -96.938087) (xy 228.14829 -96.952193) (xy 228.199619 -96.974005)
			(xy 228.247225 -97.003059) (xy 228.290093 -97.038734) (xy 228.32731 -97.080271) (xy 228.358083 -97.126784)
			(xy 228.381755 -97.177281) (xy 228.397823 -97.230688) (xy 228.405943 -97.285864) (xy 228.406452 -97.31375)
			(xy 228.405943 -97.341636) (xy 228.397823 -97.396812) (xy 228.381755 -97.450219) (xy 228.358083 -97.500716)
			(xy 228.32731 -97.547229) (xy 228.290093 -97.588766) (xy 228.247225 -97.624441) (xy 228.199619 -97.653495)
			(xy 228.14829 -97.675307) (xy 228.094333 -97.689413) (xy 228.038896 -97.695513) (xy 227.983162 -97.693476)
			(xy 227.928319 -97.683346) (xy 227.875535 -97.665339) (xy 227.825935 -97.639838) (xy 227.780577 -97.607387)
			(xy 227.740428 -97.568678) (xy 227.706342 -97.524535) (xy 227.679046 -97.4759) (xy 227.659123 -97.423809)
			(xy 227.646997 -97.369372) (xy 227.642926 -97.31375) (xy 224.088452 -97.31375) (xy 224.087943 -97.341636)
			(xy 224.079823 -97.396812) (xy 224.063755 -97.450219) (xy 224.040083 -97.500716) (xy 224.00931 -97.547229)
			(xy 223.972093 -97.588766) (xy 223.929225 -97.624441) (xy 223.881619 -97.653495) (xy 223.83029 -97.675307)
			(xy 223.776333 -97.689413) (xy 223.720896 -97.695513) (xy 223.665162 -97.693476) (xy 223.610319 -97.683346)
			(xy 223.557535 -97.665339) (xy 223.507935 -97.639838) (xy 223.462577 -97.607387) (xy 223.422428 -97.568678)
			(xy 223.388342 -97.524535) (xy 223.361046 -97.4759) (xy 223.341123 -97.423809) (xy 223.328997 -97.369372)
			(xy 223.324926 -97.31375) (xy 223.072452 -97.31375) (xy 223.071943 -97.341636) (xy 223.063823 -97.396812)
			(xy 223.047755 -97.450219) (xy 223.024083 -97.500716) (xy 222.99331 -97.547229) (xy 222.956093 -97.588766)
			(xy 222.913225 -97.624441) (xy 222.865619 -97.653495) (xy 222.81429 -97.675307) (xy 222.760333 -97.689413)
			(xy 222.704896 -97.695513) (xy 222.649162 -97.693476) (xy 222.594319 -97.683346) (xy 222.541535 -97.665339)
			(xy 222.491935 -97.639838) (xy 222.446577 -97.607387) (xy 222.406428 -97.568678) (xy 222.372342 -97.524535)
			(xy 222.345046 -97.4759) (xy 222.325123 -97.423809) (xy 222.312997 -97.369372) (xy 222.308926 -97.31375)
			(xy 219.787639 -97.31375) (xy 219.810983 -97.349034) (xy 219.834655 -97.399531) (xy 219.850723 -97.452938)
			(xy 219.858843 -97.508114) (xy 219.859352 -97.536) (xy 219.858843 -97.563886) (xy 219.850723 -97.619062)
			(xy 219.834655 -97.672469) (xy 219.810983 -97.722966) (xy 219.78021 -97.769479) (xy 219.761823 -97.79)
			(xy 219.984826 -97.79) (xy 219.988897 -97.734378) (xy 220.001023 -97.679941) (xy 220.020946 -97.62785)
			(xy 220.048242 -97.579215) (xy 220.082328 -97.535072) (xy 220.122477 -97.496363) (xy 220.167835 -97.463912)
			(xy 220.217435 -97.438411) (xy 220.270219 -97.420404) (xy 220.325062 -97.410274) (xy 220.380796 -97.408237)
			(xy 220.436233 -97.414337) (xy 220.49019 -97.428443) (xy 220.541519 -97.450255) (xy 220.589125 -97.479309)
			(xy 220.631993 -97.514984) (xy 220.66921 -97.556521) (xy 220.699983 -97.603034) (xy 220.723655 -97.653531)
			(xy 220.739723 -97.706938) (xy 220.747843 -97.762114) (xy 220.748352 -97.79) (xy 220.747843 -97.817886)
			(xy 220.739723 -97.873062) (xy 220.723655 -97.926469) (xy 220.699983 -97.976966) (xy 220.66921 -98.023479)
			(xy 220.631993 -98.065016) (xy 220.589125 -98.100691) (xy 220.541519 -98.129745) (xy 220.49019 -98.151557)
			(xy 220.436233 -98.165663) (xy 220.380796 -98.171763) (xy 220.325062 -98.169726) (xy 220.270219 -98.159596)
			(xy 220.217435 -98.141589) (xy 220.167835 -98.116088) (xy 220.122477 -98.083637) (xy 220.082328 -98.044928)
			(xy 220.048242 -98.000785) (xy 220.020946 -97.95215) (xy 220.001023 -97.900059) (xy 219.988897 -97.845622)
			(xy 219.984826 -97.79) (xy 219.761823 -97.79) (xy 219.742993 -97.811016) (xy 219.700125 -97.846691)
			(xy 219.652519 -97.875745) (xy 219.60119 -97.897557) (xy 219.547233 -97.911663) (xy 219.491796 -97.917763)
			(xy 219.436062 -97.915726) (xy 219.381219 -97.905596) (xy 219.328435 -97.887589) (xy 219.278835 -97.862088)
			(xy 219.233477 -97.829637) (xy 219.193328 -97.790928) (xy 219.159242 -97.746785) (xy 219.131946 -97.69815)
			(xy 219.112023 -97.646059) (xy 219.099897 -97.591622) (xy 219.095826 -97.536) (xy 218.872823 -97.536)
			(xy 218.853993 -97.557016) (xy 218.811125 -97.592691) (xy 218.763519 -97.621745) (xy 218.71219 -97.643557)
			(xy 218.658233 -97.657663) (xy 218.602796 -97.663763) (xy 218.547062 -97.661726) (xy 218.492219 -97.651596)
			(xy 218.439435 -97.633589) (xy 218.389835 -97.608088) (xy 218.344477 -97.575637) (xy 218.304328 -97.536928)
			(xy 218.270242 -97.492785) (xy 218.242946 -97.44415) (xy 218.223023 -97.392059) (xy 218.210897 -97.337622)
			(xy 218.206826 -97.282) (xy 218.060524 -97.282) (xy 218.060524 -98.420936) (xy 225.995736 -98.420936)
			(xy 225.999807 -98.365314) (xy 226.011933 -98.310877) (xy 226.031856 -98.258786) (xy 226.059152 -98.210151)
			(xy 226.093238 -98.166008) (xy 226.133387 -98.127299) (xy 226.178745 -98.094848) (xy 226.228345 -98.069347)
			(xy 226.281129 -98.05134) (xy 226.335972 -98.04121) (xy 226.391706 -98.039173) (xy 226.447143 -98.045273)
			(xy 226.5011 -98.059379) (xy 226.552429 -98.081191) (xy 226.600035 -98.110245) (xy 226.642903 -98.14592)
			(xy 226.68012 -98.187457) (xy 226.710893 -98.23397) (xy 226.734565 -98.284467) (xy 226.750633 -98.337874)
			(xy 226.758753 -98.39305) (xy 226.759262 -98.420936) (xy 226.758753 -98.448822) (xy 226.750633 -98.503998)
			(xy 226.734565 -98.557405) (xy 226.710893 -98.607902) (xy 226.68012 -98.654415) (xy 226.642903 -98.695952)
			(xy 226.600035 -98.731627) (xy 226.552429 -98.760681) (xy 226.5011 -98.782493) (xy 226.447143 -98.796599)
			(xy 226.391706 -98.802699) (xy 226.335972 -98.800662) (xy 226.281129 -98.790532) (xy 226.228345 -98.772525)
			(xy 226.178745 -98.747024) (xy 226.133387 -98.714573) (xy 226.093238 -98.675864) (xy 226.059152 -98.631721)
			(xy 226.031856 -98.583086) (xy 226.011933 -98.530995) (xy 225.999807 -98.476558) (xy 225.995736 -98.420936)
			(xy 218.060524 -98.420936) (xy 218.060524 -100.076) (xy 218.371672 -100.076) (xy 218.375743 -100.020378)
			(xy 218.387869 -99.965941) (xy 218.407792 -99.91385) (xy 218.435088 -99.865215) (xy 218.469174 -99.821072)
			(xy 218.509323 -99.782363) (xy 218.554681 -99.749912) (xy 218.604281 -99.724411) (xy 218.657065 -99.706404)
			(xy 218.711908 -99.696274) (xy 218.767642 -99.694237) (xy 218.823079 -99.700337) (xy 218.877036 -99.714443)
			(xy 218.928365 -99.736255) (xy 218.975971 -99.765309) (xy 219.018839 -99.800984) (xy 219.037669 -99.822)
			(xy 219.984826 -99.822) (xy 219.988897 -99.766378) (xy 220.001023 -99.711941) (xy 220.020946 -99.65985)
			(xy 220.048242 -99.611215) (xy 220.082328 -99.567072) (xy 220.122477 -99.528363) (xy 220.167835 -99.495912)
			(xy 220.217435 -99.470411) (xy 220.270219 -99.452404) (xy 220.325062 -99.442274) (xy 220.380796 -99.440237)
			(xy 220.436233 -99.446337) (xy 220.49019 -99.460443) (xy 220.541519 -99.482255) (xy 220.579633 -99.505516)
			(xy 221.292926 -99.505516) (xy 221.296997 -99.449894) (xy 221.309123 -99.395457) (xy 221.329046 -99.343366)
			(xy 221.356342 -99.294731) (xy 221.390428 -99.250588) (xy 221.430577 -99.211879) (xy 221.475935 -99.179428)
			(xy 221.525535 -99.153927) (xy 221.578319 -99.13592) (xy 221.633162 -99.12579) (xy 221.688896 -99.123753)
			(xy 221.744333 -99.129853) (xy 221.79829 -99.143959) (xy 221.849619 -99.165771) (xy 221.897225 -99.194825)
			(xy 221.940093 -99.2305) (xy 221.97731 -99.272037) (xy 222.008083 -99.31855) (xy 222.031755 -99.369047)
			(xy 222.047823 -99.422454) (xy 222.055943 -99.47763) (xy 222.056345 -99.499674) (xy 222.606868 -99.499674)
			(xy 222.610939 -99.444052) (xy 222.623065 -99.389615) (xy 222.642988 -99.337524) (xy 222.670284 -99.288889)
			(xy 222.70437 -99.244746) (xy 222.744519 -99.206037) (xy 222.789877 -99.173586) (xy 222.839477 -99.148085)
			(xy 222.892261 -99.130078) (xy 222.947104 -99.119948) (xy 223.002838 -99.117911) (xy 223.058275 -99.124011)
			(xy 223.112232 -99.138117) (xy 223.163561 -99.159929) (xy 223.211167 -99.188983) (xy 223.254035 -99.224658)
			(xy 223.291252 -99.266195) (xy 223.322025 -99.312708) (xy 223.334419 -99.339146) (xy 223.880932 -99.339146)
			(xy 223.885003 -99.283524) (xy 223.897129 -99.229087) (xy 223.917052 -99.176996) (xy 223.944348 -99.128361)
			(xy 223.978434 -99.084218) (xy 224.018583 -99.045509) (xy 224.063941 -99.013058) (xy 224.113541 -98.987557)
			(xy 224.166325 -98.96955) (xy 224.221168 -98.95942) (xy 224.276902 -98.957383) (xy 224.332339 -98.963483)
			(xy 224.386296 -98.977589) (xy 224.437625 -98.999401) (xy 224.485231 -99.028455) (xy 224.528099 -99.06413)
			(xy 224.565316 -99.105667) (xy 224.596089 -99.15218) (xy 224.619761 -99.202677) (xy 224.635829 -99.256084)
			(xy 224.643949 -99.31126) (xy 224.644458 -99.339146) (xy 224.643949 -99.367032) (xy 224.635829 -99.422208)
			(xy 224.619761 -99.475615) (xy 224.596089 -99.526112) (xy 224.565316 -99.572625) (xy 224.560812 -99.577652)
			(xy 225.818444 -99.577652) (xy 225.822515 -99.52203) (xy 225.834641 -99.467593) (xy 225.854564 -99.415502)
			(xy 225.88186 -99.366867) (xy 225.915946 -99.322724) (xy 225.956095 -99.284015) (xy 226.001453 -99.251564)
			(xy 226.051053 -99.226063) (xy 226.103837 -99.208056) (xy 226.15868 -99.197926) (xy 226.214414 -99.195889)
			(xy 226.269851 -99.201989) (xy 226.323808 -99.216095) (xy 226.375137 -99.237907) (xy 226.422743 -99.266961)
			(xy 226.465611 -99.302636) (xy 226.502828 -99.344173) (xy 226.533601 -99.390686) (xy 226.557273 -99.441183)
			(xy 226.573341 -99.49459) (xy 226.581461 -99.549766) (xy 226.58197 -99.577652) (xy 226.581461 -99.605538)
			(xy 226.573341 -99.660714) (xy 226.557273 -99.714121) (xy 226.533601 -99.764618) (xy 226.502828 -99.811131)
			(xy 226.465611 -99.852668) (xy 226.422743 -99.888343) (xy 226.375137 -99.917397) (xy 226.323808 -99.939209)
			(xy 226.269851 -99.953315) (xy 226.214414 -99.959415) (xy 226.15868 -99.957378) (xy 226.103837 -99.947248)
			(xy 226.051053 -99.929241) (xy 226.001453 -99.90374) (xy 225.956095 -99.871289) (xy 225.915946 -99.83258)
			(xy 225.88186 -99.788437) (xy 225.854564 -99.739802) (xy 225.834641 -99.687711) (xy 225.822515 -99.633274)
			(xy 225.818444 -99.577652) (xy 224.560812 -99.577652) (xy 224.528099 -99.614162) (xy 224.485231 -99.649837)
			(xy 224.437625 -99.678891) (xy 224.386296 -99.700703) (xy 224.332339 -99.714809) (xy 224.276902 -99.720909)
			(xy 224.221168 -99.718872) (xy 224.166325 -99.708742) (xy 224.113541 -99.690735) (xy 224.063941 -99.665234)
			(xy 224.018583 -99.632783) (xy 223.978434 -99.594074) (xy 223.944348 -99.549931) (xy 223.917052 -99.501296)
			(xy 223.897129 -99.449205) (xy 223.885003 -99.394768) (xy 223.880932 -99.339146) (xy 223.334419 -99.339146)
			(xy 223.345697 -99.363205) (xy 223.361765 -99.416612) (xy 223.369885 -99.471788) (xy 223.370394 -99.499674)
			(xy 223.369885 -99.52756) (xy 223.361765 -99.582736) (xy 223.345697 -99.636143) (xy 223.322025 -99.68664)
			(xy 223.291252 -99.733153) (xy 223.254035 -99.77469) (xy 223.211167 -99.810365) (xy 223.163561 -99.839419)
			(xy 223.112232 -99.861231) (xy 223.058275 -99.875337) (xy 223.002838 -99.881437) (xy 222.947104 -99.8794)
			(xy 222.892261 -99.86927) (xy 222.839477 -99.851263) (xy 222.789877 -99.825762) (xy 222.744519 -99.793311)
			(xy 222.70437 -99.754602) (xy 222.670284 -99.710459) (xy 222.642988 -99.661824) (xy 222.623065 -99.609733)
			(xy 222.610939 -99.555296) (xy 222.606868 -99.499674) (xy 222.056345 -99.499674) (xy 222.056452 -99.505516)
			(xy 222.055943 -99.533402) (xy 222.047823 -99.588578) (xy 222.031755 -99.641985) (xy 222.008083 -99.692482)
			(xy 221.97731 -99.738995) (xy 221.940093 -99.780532) (xy 221.897225 -99.816207) (xy 221.849619 -99.845261)
			(xy 221.79829 -99.867073) (xy 221.744333 -99.881179) (xy 221.688896 -99.887279) (xy 221.633162 -99.885242)
			(xy 221.578319 -99.875112) (xy 221.525535 -99.857105) (xy 221.475935 -99.831604) (xy 221.430577 -99.799153)
			(xy 221.390428 -99.760444) (xy 221.356342 -99.716301) (xy 221.329046 -99.667666) (xy 221.309123 -99.615575)
			(xy 221.296997 -99.561138) (xy 221.292926 -99.505516) (xy 220.579633 -99.505516) (xy 220.589125 -99.511309)
			(xy 220.631993 -99.546984) (xy 220.66921 -99.588521) (xy 220.699983 -99.635034) (xy 220.723655 -99.685531)
			(xy 220.739723 -99.738938) (xy 220.747843 -99.794114) (xy 220.748352 -99.822) (xy 220.747843 -99.849886)
			(xy 220.739723 -99.905062) (xy 220.723655 -99.958469) (xy 220.699983 -100.008966) (xy 220.66921 -100.055479)
			(xy 220.631993 -100.097016) (xy 220.589125 -100.132691) (xy 220.541519 -100.161745) (xy 220.49019 -100.183557)
			(xy 220.436233 -100.197663) (xy 220.380796 -100.203763) (xy 220.325062 -100.201726) (xy 220.270219 -100.191596)
			(xy 220.217435 -100.173589) (xy 220.167835 -100.148088) (xy 220.122477 -100.115637) (xy 220.082328 -100.076928)
			(xy 220.048242 -100.032785) (xy 220.020946 -99.98415) (xy 220.001023 -99.932059) (xy 219.988897 -99.877622)
			(xy 219.984826 -99.822) (xy 219.037669 -99.822) (xy 219.056056 -99.842521) (xy 219.086829 -99.889034)
			(xy 219.110501 -99.939531) (xy 219.126569 -99.992938) (xy 219.134689 -100.048114) (xy 219.135198 -100.076)
			(xy 219.134689 -100.103886) (xy 219.126569 -100.159062) (xy 219.110501 -100.212469) (xy 219.086829 -100.262966)
			(xy 219.056056 -100.309479) (xy 219.018839 -100.351016) (xy 218.975971 -100.386691) (xy 218.928365 -100.415745)
			(xy 218.877036 -100.437557) (xy 218.823079 -100.451663) (xy 218.767642 -100.457763) (xy 218.711908 -100.455726)
			(xy 218.657065 -100.445596) (xy 218.604281 -100.427589) (xy 218.554681 -100.402088) (xy 218.509323 -100.369637)
			(xy 218.469174 -100.330928) (xy 218.435088 -100.286785) (xy 218.407792 -100.23815) (xy 218.387869 -100.186059)
			(xy 218.375743 -100.131622) (xy 218.371672 -100.076) (xy 218.060524 -100.076) (xy 218.060524 -101.219)
			(xy 220.238826 -101.219) (xy 220.242897 -101.163378) (xy 220.255023 -101.108941) (xy 220.274946 -101.05685)
			(xy 220.302242 -101.008215) (xy 220.336328 -100.964072) (xy 220.376477 -100.925363) (xy 220.421835 -100.892912)
			(xy 220.471435 -100.867411) (xy 220.524219 -100.849404) (xy 220.579062 -100.839274) (xy 220.634796 -100.837237)
			(xy 220.690233 -100.843337) (xy 220.74419 -100.857443) (xy 220.795519 -100.879255) (xy 220.843125 -100.908309)
			(xy 220.885993 -100.943984) (xy 220.92321 -100.985521) (xy 220.953983 -101.032034) (xy 220.977655 -101.082531)
			(xy 220.993723 -101.135938) (xy 221.001843 -101.191114) (xy 221.002352 -101.219) (xy 221.001843 -101.246886)
			(xy 220.993723 -101.302062) (xy 220.977655 -101.355469) (xy 220.953983 -101.405966) (xy 220.92321 -101.452479)
			(xy 220.885993 -101.494016) (xy 220.843125 -101.529691) (xy 220.795519 -101.558745) (xy 220.74419 -101.580557)
			(xy 220.690233 -101.594663) (xy 220.634796 -101.600763) (xy 220.579062 -101.598726) (xy 220.524219 -101.588596)
			(xy 220.471435 -101.570589) (xy 220.421835 -101.545088) (xy 220.376477 -101.512637) (xy 220.336328 -101.473928)
			(xy 220.302242 -101.429785) (xy 220.274946 -101.38115) (xy 220.255023 -101.329059) (xy 220.242897 -101.274622)
			(xy 220.238826 -101.219) (xy 218.060524 -101.219) (xy 218.060524 -101.276404) (xy 218.07551 -101.300788)
			(xy 218.083892 -101.305106) (xy 218.110707 -101.319127) (xy 218.159914 -101.35434) (xy 218.20295 -101.396874)
			(xy 218.221306 -101.42093) (xy 218.237188 -101.443385) (xy 218.263027 -101.491936) (xy 218.281631 -101.543692)
			(xy 218.292617 -101.597583) (xy 218.295756 -101.652492) (xy 218.290983 -101.707283) (xy 218.278398 -101.760823)
			(xy 218.258261 -101.812002) (xy 218.230988 -101.859763) (xy 218.197144 -101.903116) (xy 218.15743 -101.941164)
			(xy 218.112667 -101.973119) (xy 218.063783 -101.998321) (xy 218.037918 -102.00767) (xy 218.030552 -102.01021)
			(xy 218.01836 -102.0191) (xy 217.997532 -102.047294) (xy 217.992892 -102.053978) (xy 217.987706 -102.069391)
			(xy 217.987372 -102.07752) (xy 217.987372 -102.118414) (xy 217.986935 -102.150726) (xy 217.979697 -102.214944)
			(xy 217.965315 -102.277948) (xy 217.943968 -102.338945) (xy 217.915925 -102.397168) (xy 217.88154 -102.451885)
			(xy 217.841244 -102.502407) (xy 217.818716 -102.525576) (xy 217.43416 -102.910132) (xy 224.984056 -102.910132)
			(xy 224.984527 -102.882762) (xy 224.992342 -102.828582) (xy 225.007829 -102.776079) (xy 225.03067 -102.726332)
			(xy 225.060394 -102.680365) (xy 225.078036 -102.659434) (xy 225.07829 -102.65918) (xy 225.08389 -102.652103)
			(xy 225.090129 -102.635179) (xy 225.090482 -102.62616) (xy 225.090482 -102.559104) (xy 225.090127 -102.550087)
			(xy 225.083879 -102.53317) (xy 225.07829 -102.526084) (xy 225.078036 -102.526084) (xy 225.078036 -102.52583)
			(xy 225.060426 -102.504872) (xy 225.0307 -102.458909) (xy 225.007852 -102.409167) (xy 224.992353 -102.356669)
			(xy 224.984521 -102.302493) (xy 224.984517 -102.247755) (xy 224.992342 -102.193579) (xy 225.007835 -102.141078)
			(xy 225.030676 -102.091333) (xy 225.060397 -102.045367) (xy 225.078036 -102.024434) (xy 225.07829 -102.02418)
			(xy 225.08389 -102.017103) (xy 225.090129 -102.000179) (xy 225.090482 -101.99116) (xy 225.090482 -101.924104)
			(xy 225.090127 -101.915087) (xy 225.083879 -101.89817) (xy 225.07829 -101.891084) (xy 225.078036 -101.891084)
			(xy 225.078036 -101.89083) (xy 225.060403 -101.869893) (xy 225.030689 -101.823922) (xy 225.007851 -101.774176)
			(xy 224.992359 -101.721676) (xy 224.98453 -101.667501) (xy 224.984056 -101.640132) (xy 224.984542 -101.612881)
			(xy 224.992298 -101.558933) (xy 225.007653 -101.506638) (xy 225.030295 -101.457061) (xy 225.059761 -101.411211)
			(xy 225.095452 -101.37002) (xy 225.136643 -101.334329) (xy 225.182493 -101.304863) (xy 225.23207 -101.282221)
			(xy 225.284365 -101.266866) (xy 225.338313 -101.25911) (xy 225.392815 -101.25911) (xy 225.446763 -101.266866)
			(xy 225.499058 -101.282221) (xy 225.548635 -101.304863) (xy 225.594485 -101.334329) (xy 225.635676 -101.37002)
			(xy 225.671367 -101.411211) (xy 225.700833 -101.457061) (xy 225.723475 -101.506638) (xy 225.73883 -101.558933)
			(xy 225.746586 -101.612881) (xy 225.747072 -101.640132) (xy 225.746632 -101.667503) (xy 225.738809 -101.721684)
			(xy 225.723314 -101.774187) (xy 225.700466 -101.823934) (xy 225.670736 -101.869899) (xy 225.653092 -101.89083)
			(xy 225.652838 -101.891084) (xy 225.647245 -101.898166) (xy 225.641004 -101.915086) (xy 225.640646 -101.924104)
			(xy 225.640646 -101.99116) (xy 225.641012 -102.000176) (xy 225.647252 -102.017094) (xy 225.652838 -102.02418)
			(xy 225.653092 -102.02418) (xy 225.653092 -102.024434) (xy 225.670763 -102.045342) (xy 225.700485 -102.091314)
			(xy 225.723328 -102.141065) (xy 225.738821 -102.193571) (xy 225.746646 -102.247752) (xy 225.746642 -102.302496)
			(xy 225.73881 -102.356677) (xy 225.723311 -102.40918) (xy 225.700462 -102.458928) (xy 225.670734 -102.504897)
			(xy 225.653092 -102.52583) (xy 225.652838 -102.526084) (xy 225.647245 -102.533166) (xy 225.641004 -102.550086)
			(xy 225.640646 -102.559104) (xy 225.640646 -102.62616) (xy 225.641012 -102.635176) (xy 225.647252 -102.652094)
			(xy 225.648871 -102.654148) (xy 226.6389 -102.654148) (xy 226.6389 -102.599652) (xy 226.646655 -102.54571)
			(xy 226.662008 -102.493421) (xy 226.684645 -102.443849) (xy 226.714107 -102.398003) (xy 226.749792 -102.356816)
			(xy 226.790976 -102.321127) (xy 226.836819 -102.291661) (xy 226.886389 -102.26902) (xy 226.938677 -102.253663)
			(xy 226.992618 -102.245903) (xy 227.019866 -102.245414) (xy 227.046182 -102.245833) (xy 227.098312 -102.253077)
			(xy 227.148956 -102.267405) (xy 227.197155 -102.288547) (xy 227.241997 -102.316102) (xy 227.282635 -102.349549)
			(xy 227.30079 -102.368604) (xy 227.308313 -102.376004) (xy 227.327592 -102.384529) (xy 227.338128 -102.385114)
			(xy 227.412804 -102.385114) (xy 227.423355 -102.384596) (xy 227.44265 -102.376053) (xy 227.450142 -102.368604)
			(xy 227.468285 -102.349536) (xy 227.508917 -102.31608) (xy 227.55376 -102.288522) (xy 227.601963 -102.267386)
			(xy 227.652613 -102.253072) (xy 227.704749 -102.24585) (xy 227.731066 -102.245414) (xy 227.758322 -102.245831)
			(xy 227.81228 -102.253584) (xy 227.864585 -102.268938) (xy 227.914172 -102.29158) (xy 227.960032 -102.321049)
			(xy 228.001231 -102.356745) (xy 228.036931 -102.397941) (xy 228.066404 -102.443798) (xy 228.08612 -102.486968)
			(xy 228.66223 -102.486968) (xy 228.66267 -102.459597) (xy 228.670493 -102.405416) (xy 228.685988 -102.352913)
			(xy 228.708835 -102.303166) (xy 228.738566 -102.257201) (xy 228.75621 -102.23627) (xy 228.756464 -102.236016)
			(xy 228.762058 -102.228935) (xy 228.768298 -102.212014) (xy 228.768656 -102.202996) (xy 228.768656 -102.13594)
			(xy 228.768289 -102.126924) (xy 228.76205 -102.110006) (xy 228.756464 -102.10292) (xy 228.75621 -102.10292)
			(xy 228.75621 -102.102666) (xy 228.738539 -102.081758) (xy 228.708816 -102.035786) (xy 228.685974 -101.986035)
			(xy 228.670481 -101.93353) (xy 228.662656 -101.879348) (xy 228.662659 -101.824604) (xy 228.670491 -101.770423)
			(xy 228.685991 -101.71792) (xy 228.70884 -101.668172) (xy 228.738568 -101.622203) (xy 228.75621 -101.60127)
			(xy 228.756464 -101.601016) (xy 228.762058 -101.593935) (xy 228.768298 -101.577014) (xy 228.768656 -101.567996)
			(xy 228.768656 -101.50094) (xy 228.768289 -101.491924) (xy 228.76205 -101.475006) (xy 228.756464 -101.46792)
			(xy 228.75621 -101.46792) (xy 228.75621 -101.467666) (xy 228.73859 -101.446719) (xy 228.708875 -101.40075)
			(xy 228.686035 -101.351007) (xy 228.67054 -101.298509) (xy 228.662707 -101.244336) (xy 228.66223 -101.216968)
			(xy 228.662716 -101.189717) (xy 228.670472 -101.135769) (xy 228.685827 -101.083474) (xy 228.708469 -101.033897)
			(xy 228.737935 -100.988047) (xy 228.773626 -100.946856) (xy 228.814817 -100.911165) (xy 228.860667 -100.881699)
			(xy 228.910244 -100.859057) (xy 228.962539 -100.843702) (xy 229.016487 -100.835946) (xy 229.070989 -100.835946)
			(xy 229.124937 -100.843702) (xy 229.177232 -100.859057) (xy 229.226809 -100.881699) (xy 229.272659 -100.911165)
			(xy 229.31385 -100.946856) (xy 229.349541 -100.988047) (xy 229.379007 -101.033897) (xy 229.401649 -101.083474)
			(xy 229.417004 -101.135769) (xy 229.42476 -101.189717) (xy 229.425246 -101.216968) (xy 229.424774 -101.244338)
			(xy 229.41696 -101.298518) (xy 229.401473 -101.351021) (xy 229.378632 -101.400768) (xy 229.348907 -101.446735)
			(xy 229.331266 -101.467666) (xy 229.331012 -101.46792) (xy 229.325412 -101.474998) (xy 229.319173 -101.491921)
			(xy 229.31882 -101.50094) (xy 229.31882 -101.567996) (xy 229.319174 -101.577013) (xy 229.325423 -101.59393)
			(xy 229.331012 -101.601016) (xy 229.331266 -101.601016) (xy 229.331266 -101.60127) (xy 229.348876 -101.622228)
			(xy 229.378602 -101.668191) (xy 229.40145 -101.717933) (xy 229.416949 -101.770432) (xy 229.424781 -101.824607)
			(xy 229.424784 -101.879345) (xy 229.416959 -101.933521) (xy 229.401467 -101.986022) (xy 229.378625 -102.035766)
			(xy 229.348905 -102.081733) (xy 229.331266 -102.102666) (xy 229.331012 -102.10292) (xy 229.325412 -102.109998)
			(xy 229.319173 -102.126921) (xy 229.31882 -102.13594) (xy 229.31882 -102.202996) (xy 229.319174 -102.212013)
			(xy 229.325423 -102.22893) (xy 229.331012 -102.236016) (xy 229.331266 -102.236016) (xy 229.331266 -102.23627)
			(xy 229.348899 -102.257207) (xy 229.378613 -102.303178) (xy 229.401451 -102.352924) (xy 229.416943 -102.405424)
			(xy 229.424772 -102.459599) (xy 229.425246 -102.486968) (xy 229.424979 -102.501954) (xy 231.856534 -102.501954)
			(xy 231.857023 -102.474585) (xy 231.864834 -102.420406) (xy 231.880318 -102.367903) (xy 231.903154 -102.318156)
			(xy 231.932875 -102.272188) (xy 231.950514 -102.251256) (xy 231.950768 -102.251002) (xy 231.956368 -102.243925)
			(xy 231.962605 -102.227001) (xy 231.96296 -102.217982) (xy 231.96296 -102.150926) (xy 231.962599 -102.141909)
			(xy 231.956355 -102.124992) (xy 231.950768 -102.117906) (xy 231.950514 -102.117906) (xy 231.950514 -102.117652)
			(xy 231.932829 -102.096755) (xy 231.903107 -102.050781) (xy 231.880265 -102.001029) (xy 231.864773 -101.948521)
			(xy 231.856949 -101.894338) (xy 231.856954 -101.839593) (xy 231.864788 -101.785411) (xy 231.880289 -101.732906)
			(xy 231.90314 -101.683158) (xy 231.932871 -101.637189) (xy 231.950514 -101.616256) (xy 231.950768 -101.616002)
			(xy 231.956368 -101.608925) (xy 231.962605 -101.592001) (xy 231.96296 -101.582982) (xy 231.96296 -101.515926)
			(xy 231.962599 -101.506909) (xy 231.956355 -101.489992) (xy 231.950768 -101.482906) (xy 231.950514 -101.482906)
			(xy 231.950514 -101.482652) (xy 231.932888 -101.461709) (xy 231.903174 -101.41574) (xy 231.880335 -101.365995)
			(xy 231.864841 -101.313496) (xy 231.85701 -101.259322) (xy 231.856534 -101.231954) (xy 231.85702 -101.204703)
			(xy 231.864776 -101.150755) (xy 231.880131 -101.09846) (xy 231.902773 -101.048883) (xy 231.932239 -101.003033)
			(xy 231.96793 -100.961842) (xy 232.009121 -100.926151) (xy 232.054971 -100.896685) (xy 232.104548 -100.874043)
			(xy 232.156843 -100.858688) (xy 232.210791 -100.850932) (xy 232.265293 -100.850932) (xy 232.319241 -100.858688)
			(xy 232.371536 -100.874043) (xy 232.421113 -100.896685) (xy 232.466963 -100.926151) (xy 232.508154 -100.961842)
			(xy 232.543845 -101.003033) (xy 232.573311 -101.048883) (xy 232.595953 -101.09846) (xy 232.611308 -101.150755)
			(xy 232.619064 -101.204703) (xy 232.61955 -101.231954) (xy 232.619069 -101.259324) (xy 232.611257 -101.313503)
			(xy 232.595772 -101.366006) (xy 232.572933 -101.415753) (xy 232.543211 -101.46172) (xy 232.52557 -101.482652)
			(xy 232.525316 -101.482906) (xy 232.519723 -101.489988) (xy 232.513479 -101.506908) (xy 232.513124 -101.515926)
			(xy 232.513124 -101.582982) (xy 232.513485 -101.591999) (xy 232.519729 -101.608916) (xy 232.525316 -101.616002)
			(xy 232.52557 -101.616002) (xy 232.52557 -101.616256) (xy 232.543166 -101.637225) (xy 232.572893 -101.683187)
			(xy 232.595741 -101.732927) (xy 232.611241 -101.785423) (xy 232.619074 -101.839597) (xy 232.619079 -101.894334)
			(xy 232.611256 -101.948509) (xy 232.595765 -102.001008) (xy 232.572926 -102.050753) (xy 232.543208 -102.096719)
			(xy 232.52557 -102.117652) (xy 232.525316 -102.117906) (xy 232.519723 -102.124988) (xy 232.513479 -102.141908)
			(xy 232.513124 -102.150926) (xy 232.513124 -102.217982) (xy 232.513485 -102.226999) (xy 232.519729 -102.243916)
			(xy 232.525316 -102.251002) (xy 232.52557 -102.251002) (xy 232.52557 -102.251256) (xy 232.543197 -102.272198)
			(xy 232.572912 -102.318167) (xy 232.595751 -102.367912) (xy 232.611244 -102.420411) (xy 232.619075 -102.474585)
			(xy 232.61955 -102.501954) (xy 232.619064 -102.529205) (xy 232.611308 -102.583153) (xy 232.595953 -102.635448)
			(xy 232.573311 -102.685025) (xy 232.543845 -102.730875) (xy 232.508154 -102.772066) (xy 232.466963 -102.807757)
			(xy 232.421113 -102.837223) (xy 232.371536 -102.859865) (xy 232.319241 -102.87522) (xy 232.265293 -102.882976)
			(xy 232.210791 -102.882976) (xy 232.156843 -102.87522) (xy 232.104548 -102.859865) (xy 232.054971 -102.837223)
			(xy 232.009121 -102.807757) (xy 231.96793 -102.772066) (xy 231.932239 -102.730875) (xy 231.902773 -102.685025)
			(xy 231.880131 -102.635448) (xy 231.864776 -102.583153) (xy 231.85702 -102.529205) (xy 231.856534 -102.501954)
			(xy 229.424979 -102.501954) (xy 229.42476 -102.514219) (xy 229.417004 -102.568167) (xy 229.401649 -102.620462)
			(xy 229.379007 -102.670039) (xy 229.349541 -102.715889) (xy 229.31385 -102.75708) (xy 229.272659 -102.792771)
			(xy 229.226809 -102.822237) (xy 229.177232 -102.844879) (xy 229.124937 -102.860234) (xy 229.070989 -102.86799)
			(xy 229.016487 -102.86799) (xy 228.962539 -102.860234) (xy 228.910244 -102.844879) (xy 228.860667 -102.822237)
			(xy 228.814817 -102.792771) (xy 228.773626 -102.75708) (xy 228.737935 -102.715889) (xy 228.708469 -102.670039)
			(xy 228.685827 -102.620462) (xy 228.670472 -102.568167) (xy 228.662716 -102.514219) (xy 228.66223 -102.486968)
			(xy 228.08612 -102.486968) (xy 228.08905 -102.493383) (xy 228.104409 -102.545687) (xy 228.112167 -102.599644)
			(xy 228.112167 -102.654156) (xy 228.104409 -102.708113) (xy 228.08905 -102.760417) (xy 228.066404 -102.810002)
			(xy 228.036931 -102.855859) (xy 228.001231 -102.897055) (xy 227.960032 -102.932751) (xy 227.914172 -102.96222)
			(xy 227.864585 -102.984862) (xy 227.81228 -103.000216) (xy 227.758322 -103.007969) (xy 227.731066 -103.00843)
			(xy 227.704752 -103.007976) (xy 227.652623 -103.000737) (xy 227.60198 -102.986414) (xy 227.553782 -102.96528)
			(xy 227.508938 -102.937732) (xy 227.468299 -102.904292) (xy 227.450142 -102.88524) (xy 227.442601 -102.877861)
			(xy 227.423336 -102.869322) (xy 227.412804 -102.86873) (xy 227.338128 -102.86873) (xy 227.327577 -102.869252)
			(xy 227.308281 -102.877791) (xy 227.30079 -102.88524) (xy 227.28264 -102.904301) (xy 227.242008 -102.937756)
			(xy 227.197167 -102.965313) (xy 227.148965 -102.986451) (xy 227.098317 -103.000767) (xy 227.046182 -103.007991)
			(xy 227.019866 -103.00843) (xy 226.992618 -103.007897) (xy 226.938677 -103.000137) (xy 226.886389 -102.98478)
			(xy 226.836819 -102.962139) (xy 226.790976 -102.932673) (xy 226.749792 -102.896984) (xy 226.714107 -102.855797)
			(xy 226.684645 -102.809951) (xy 226.662008 -102.760379) (xy 226.646655 -102.70809) (xy 226.6389 -102.654148)
			(xy 225.648871 -102.654148) (xy 225.652838 -102.65918) (xy 225.653092 -102.659688) (xy 225.664036 -102.672422)
			(xy 225.683877 -102.699514) (xy 225.692716 -102.71379) (xy 225.69805 -102.72268) (xy 225.715068 -102.734872)
			(xy 225.808286 -102.755192) (xy 225.82886 -102.750874) (xy 225.837496 -102.745032) (xy 225.861562 -102.729035)
			(xy 225.913492 -102.703691) (xy 225.96865 -102.686464) (xy 226.025774 -102.677749) (xy 226.054666 -102.677214)
			(xy 226.081922 -102.677631) (xy 226.13588 -102.685384) (xy 226.188185 -102.700738) (xy 226.237772 -102.72338)
			(xy 226.283632 -102.752849) (xy 226.324831 -102.788545) (xy 226.360531 -102.829741) (xy 226.390004 -102.875598)
			(xy 226.41265 -102.925183) (xy 226.428009 -102.977487) (xy 226.435767 -103.031444) (xy 226.435767 -103.085956)
			(xy 226.428009 -103.139913) (xy 226.41265 -103.192217) (xy 226.390004 -103.241802) (xy 226.360531 -103.287659)
			(xy 226.324831 -103.328855) (xy 226.283632 -103.364551) (xy 226.237772 -103.39402) (xy 226.188185 -103.416662)
			(xy 226.13588 -103.432016) (xy 226.081922 -103.439769) (xy 226.054666 -103.44023) (xy 226.026574 -103.439756)
			(xy 225.970996 -103.431525) (xy 225.917227 -103.415229) (xy 225.866429 -103.391223) (xy 225.819703 -103.360025)
			(xy 225.778058 -103.322311) (xy 225.742396 -103.278895) (xy 225.727514 -103.255064) (xy 225.72218 -103.246174)
			(xy 225.705162 -103.233982) (xy 225.611944 -103.213662) (xy 225.59137 -103.21798) (xy 225.582734 -103.223822)
			(xy 225.558664 -103.239812) (xy 225.506735 -103.265157) (xy 225.451579 -103.282385) (xy 225.394456 -103.291103)
			(xy 225.365564 -103.29164) (xy 225.338313 -103.291156) (xy 225.284367 -103.283395) (xy 225.232074 -103.268037)
			(xy 225.182499 -103.245394) (xy 225.13665 -103.215927) (xy 225.095462 -103.180236) (xy 225.059771 -103.139046)
			(xy 225.030304 -103.093197) (xy 225.007661 -103.043622) (xy 224.992304 -102.991329) (xy 224.984544 -102.937383)
			(xy 224.984056 -102.910132) (xy 217.43416 -102.910132) (xy 217.401902 -102.94239) (xy 217.399362 -102.9462)
			(xy 217.384247 -102.967416) (xy 217.350798 -103.007356) (xy 217.33256 -103.025956) (xy 216.821258 -103.537258)
			(xy 220.43085 -103.537258) (xy 220.434921 -103.481636) (xy 220.447047 -103.427199) (xy 220.46697 -103.375108)
			(xy 220.494266 -103.326473) (xy 220.528352 -103.28233) (xy 220.568501 -103.243621) (xy 220.613859 -103.21117)
			(xy 220.663459 -103.185669) (xy 220.716243 -103.167662) (xy 220.771086 -103.157532) (xy 220.82682 -103.155495)
			(xy 220.882257 -103.161595) (xy 220.936214 -103.175701) (xy 220.987543 -103.197513) (xy 221.035149 -103.226567)
			(xy 221.078017 -103.262242) (xy 221.115234 -103.303779) (xy 221.146007 -103.350292) (xy 221.169679 -103.400789)
			(xy 221.185747 -103.454196) (xy 221.193867 -103.509372) (xy 221.194376 -103.537258) (xy 221.193867 -103.565144)
			(xy 221.185747 -103.62032) (xy 221.169679 -103.673727) (xy 221.146007 -103.724224) (xy 221.115234 -103.770737)
			(xy 221.078017 -103.812274) (xy 221.035149 -103.847949) (xy 220.987543 -103.877003) (xy 220.936214 -103.898815)
			(xy 220.882257 -103.912921) (xy 220.82682 -103.919021) (xy 220.771086 -103.916984) (xy 220.716243 -103.906854)
			(xy 220.663459 -103.888847) (xy 220.613859 -103.863346) (xy 220.568501 -103.830895) (xy 220.528352 -103.792186)
			(xy 220.494266 -103.748043) (xy 220.46697 -103.699408) (xy 220.447047 -103.647317) (xy 220.434921 -103.59288)
			(xy 220.43085 -103.537258) (xy 216.821258 -103.537258) (xy 216.121234 -104.237282) (xy 216.115397 -104.243641)
			(xy 216.107994 -104.25922) (xy 216.106756 -104.267762) (xy 216.106502 -104.269032) (xy 216.116662 -104.285542)
			(xy 216.11717 -104.28605) (xy 216.131469 -104.309246) (xy 216.154065 -104.358828) (xy 216.169389 -104.411118)
			(xy 216.17713 -104.465054) (xy 216.177622 -104.492298) (xy 216.177622 -104.506268) (xy 216.176218 -104.53275)
			(xy 216.167 -104.584973) (xy 216.150642 -104.635417) (xy 216.148353 -104.640126) (xy 216.7923 -104.640126)
			(xy 216.796371 -104.584504) (xy 216.808497 -104.530067) (xy 216.82842 -104.477976) (xy 216.855716 -104.429341)
			(xy 216.889802 -104.385198) (xy 216.929951 -104.346489) (xy 216.975309 -104.314038) (xy 217.024909 -104.288537)
			(xy 217.077693 -104.27053) (xy 217.132536 -104.2604) (xy 217.18827 -104.258363) (xy 217.243707 -104.264463)
			(xy 217.297664 -104.278569) (xy 217.348993 -104.300381) (xy 217.396599 -104.329435) (xy 217.439467 -104.36511)
			(xy 217.476684 -104.406647) (xy 217.507457 -104.45316) (xy 217.531129 -104.503657) (xy 217.547197 -104.557064)
			(xy 217.550344 -104.578448) (xy 222.806304 -104.578448) (xy 222.806304 -104.523952) (xy 222.814059 -104.470012)
			(xy 222.829411 -104.417724) (xy 222.852048 -104.368153) (xy 222.881508 -104.322308) (xy 222.917193 -104.281121)
			(xy 222.958376 -104.245432) (xy 223.004218 -104.215967) (xy 223.053787 -104.193325) (xy 223.106073 -104.177968)
			(xy 223.160013 -104.170207) (xy 223.18726 -104.169718) (xy 223.21463 -104.170203) (xy 223.268808 -104.178016)
			(xy 223.321311 -104.1935) (xy 223.371058 -104.216338) (xy 223.417026 -104.246058) (xy 223.437958 -104.263698)
			(xy 223.438212 -104.263952) (xy 223.445286 -104.269556) (xy 223.462213 -104.275791) (xy 223.471232 -104.276144)
			(xy 223.538288 -104.276144) (xy 223.547306 -104.275793) (xy 223.564223 -104.269543) (xy 223.571308 -104.263952)
			(xy 223.571308 -104.263698) (xy 223.571562 -104.263698) (xy 223.592497 -104.246063) (xy 223.638469 -104.216351)
			(xy 223.688216 -104.193514) (xy 223.740716 -104.178022) (xy 223.794891 -104.170193) (xy 223.82226 -104.169718)
			(xy 223.849517 -104.170126) (xy 223.903476 -104.177879) (xy 223.955782 -104.193233) (xy 224.00537 -104.215874)
			(xy 224.051232 -104.245343) (xy 224.092432 -104.28104) (xy 224.128133 -104.322236) (xy 224.157606 -104.368094)
			(xy 224.180253 -104.417681) (xy 224.195612 -104.469985) (xy 224.203371 -104.523943) (xy 224.203371 -104.578457)
			(xy 224.195612 -104.632415) (xy 224.180253 -104.684719) (xy 224.157606 -104.734306) (xy 224.128133 -104.780164)
			(xy 224.092432 -104.82136) (xy 224.051232 -104.857057) (xy 224.00537 -104.886526) (xy 223.955782 -104.909167)
			(xy 223.903476 -104.924521) (xy 223.849517 -104.932274) (xy 223.82226 -104.932734) (xy 223.79489 -104.932249)
			(xy 223.740711 -104.924438) (xy 223.688208 -104.908954) (xy 223.638461 -104.886116) (xy 223.592494 -104.856394)
			(xy 223.571562 -104.838754) (xy 223.571308 -104.8385) (xy 223.564223 -104.832911) (xy 223.547305 -104.826666)
			(xy 223.538288 -104.826308) (xy 223.471232 -104.826308) (xy 223.462216 -104.826678) (xy 223.445299 -104.832916)
			(xy 223.438212 -104.8385) (xy 223.438212 -104.838754) (xy 223.437958 -104.838754) (xy 223.417009 -104.856372)
			(xy 223.371042 -104.886089) (xy 223.321298 -104.908929) (xy 223.268801 -104.924425) (xy 223.214628 -104.932258)
			(xy 223.18726 -104.932734) (xy 223.160013 -104.932193) (xy 223.106073 -104.924432) (xy 223.053787 -104.909075)
			(xy 223.004218 -104.886433) (xy 222.958376 -104.856968) (xy 222.917193 -104.821279) (xy 222.881508 -104.780092)
			(xy 222.852048 -104.734247) (xy 222.829411 -104.684676) (xy 222.814059 -104.632388) (xy 222.806304 -104.578448)
			(xy 217.550344 -104.578448) (xy 217.555317 -104.61224) (xy 217.555826 -104.640126) (xy 217.555317 -104.668012)
			(xy 217.547197 -104.723188) (xy 217.531129 -104.776595) (xy 217.507457 -104.827092) (xy 217.476684 -104.873605)
			(xy 217.439467 -104.915142) (xy 217.396599 -104.950817) (xy 217.348993 -104.979871) (xy 217.297664 -105.001683)
			(xy 217.243707 -105.015789) (xy 217.18827 -105.021889) (xy 217.132536 -105.019852) (xy 217.077693 -105.009722)
			(xy 217.024909 -104.991715) (xy 216.975309 -104.966214) (xy 216.929951 -104.933763) (xy 216.889802 -104.895054)
			(xy 216.855716 -104.850911) (xy 216.82842 -104.802276) (xy 216.808497 -104.750185) (xy 216.796371 -104.695748)
			(xy 216.7923 -104.640126) (xy 216.148353 -104.640126) (xy 216.127457 -104.68311) (xy 216.097893 -104.727135)
			(xy 216.06252 -104.766643) (xy 216.022017 -104.800873) (xy 215.999822 -104.815386) (xy 215.994488 -104.818688)
			(xy 215.98636 -104.827324) (xy 215.971374 -104.853486) (xy 215.968235 -104.859364) (xy 215.964771 -104.872227)
			(xy 215.964516 -104.878886) (xy 215.964516 -105.12806) (xy 217.654632 -105.12806) (xy 217.655118 -105.100809)
			(xy 217.662874 -105.046861) (xy 217.678229 -104.994566) (xy 217.700871 -104.944989) (xy 217.730337 -104.899139)
			(xy 217.766028 -104.857948) (xy 217.807219 -104.822257) (xy 217.853069 -104.792791) (xy 217.902646 -104.770149)
			(xy 217.954941 -104.754794) (xy 218.008889 -104.747038) (xy 218.063391 -104.747038) (xy 218.117339 -104.754794)
			(xy 218.169634 -104.770149) (xy 218.219211 -104.792791) (xy 218.265061 -104.822257) (xy 218.306252 -104.857948)
			(xy 218.341943 -104.899139) (xy 218.371409 -104.944989) (xy 218.394051 -104.994566) (xy 218.409406 -105.046861)
			(xy 218.417162 -105.100809) (xy 218.417648 -105.12806) (xy 218.417163 -105.155052) (xy 218.409562 -105.208499)
			(xy 218.394508 -105.260343) (xy 218.372299 -105.309548) (xy 218.34338 -105.355133) (xy 218.326208 -105.375964)
			(xy 218.319096 -105.384092) (xy 218.313 -105.404666) (xy 218.323922 -105.49001) (xy 218.32568 -105.500559)
			(xy 218.336746 -105.51884) (xy 218.337029 -105.519055) (xy 222.355843 -105.519055) (xy 222.355843 -105.464545)
			(xy 222.363601 -105.410591) (xy 222.378958 -105.35829) (xy 222.401603 -105.308707) (xy 222.431073 -105.262852)
			(xy 222.46677 -105.221657) (xy 222.507966 -105.185962) (xy 222.553823 -105.156494) (xy 222.603407 -105.133852)
			(xy 222.655709 -105.118497) (xy 222.709663 -105.110742) (xy 222.736918 -105.11028) (xy 222.76429 -105.110716)
			(xy 222.818471 -105.118538) (xy 222.870975 -105.134033) (xy 222.920721 -105.156882) (xy 222.966686 -105.186615)
			(xy 222.987616 -105.20426) (xy 222.98787 -105.204514) (xy 222.99496 -105.210096) (xy 223.011874 -105.216345)
			(xy 223.02089 -105.216706) (xy 223.087946 -105.216706) (xy 223.09696 -105.216322) (xy 223.113877 -105.210093)
			(xy 223.120966 -105.204514) (xy 223.120966 -105.20426) (xy 223.12122 -105.20426) (xy 223.142166 -105.186638)
			(xy 223.188136 -105.156925) (xy 223.23788 -105.134086) (xy 223.290377 -105.118591) (xy 223.34455 -105.110757)
			(xy 223.371918 -105.11028) (xy 223.399168 -105.110791) (xy 223.453112 -105.11855) (xy 223.505402 -105.133906)
			(xy 223.554976 -105.156547) (xy 223.600822 -105.186013) (xy 223.642009 -105.221704) (xy 223.677698 -105.262892)
			(xy 223.707161 -105.30874) (xy 223.7298 -105.358314) (xy 223.745154 -105.410606) (xy 223.75291 -105.46455)
			(xy 223.75291 -105.51905) (xy 223.745154 -105.572994) (xy 223.7298 -105.625286) (xy 223.707161 -105.67486)
			(xy 223.677698 -105.720708) (xy 223.642009 -105.761896) (xy 223.600822 -105.797587) (xy 223.554976 -105.827053)
			(xy 223.505402 -105.849694) (xy 223.453112 -105.86505) (xy 223.399168 -105.872809) (xy 223.371918 -105.873296)
			(xy 223.344548 -105.87282) (xy 223.290369 -105.865005) (xy 223.237866 -105.849518) (xy 223.188119 -105.826679)
			(xy 223.142152 -105.796956) (xy 223.12122 -105.779316) (xy 223.120966 -105.779062) (xy 223.113868 -105.773493)
			(xy 223.09696 -105.767237) (xy 223.087946 -105.76687) (xy 223.02089 -105.76687) (xy 223.011873 -105.767229)
			(xy 222.994957 -105.773476) (xy 222.98787 -105.779062) (xy 222.98787 -105.779316) (xy 222.987616 -105.779316)
			(xy 222.966691 -105.796964) (xy 222.920716 -105.826674) (xy 222.870967 -105.849508) (xy 222.818464 -105.864997)
			(xy 222.764288 -105.872823) (xy 222.736918 -105.873296) (xy 222.709663 -105.872858) (xy 222.655709 -105.865103)
			(xy 222.603407 -105.849748) (xy 222.553823 -105.827106) (xy 222.507966 -105.797638) (xy 222.46677 -105.761943)
			(xy 222.431073 -105.720748) (xy 222.401603 -105.674893) (xy 222.378958 -105.62531) (xy 222.363601 -105.573009)
			(xy 222.355843 -105.519055) (xy 218.337029 -105.519055) (xy 218.345258 -105.525316) (xy 218.369563 -105.542923)
			(xy 218.41282 -105.584522) (xy 218.431364 -105.60812) (xy 218.437206 -105.615994) (xy 218.454732 -105.626408)
			(xy 218.545156 -105.639616) (xy 218.56446 -105.63479) (xy 218.572334 -105.628948) (xy 218.572588 -105.628948)
			(xy 218.597318 -105.611424) (xy 218.651176 -105.583625) (xy 218.708752 -105.564695) (xy 218.768598 -105.555109)
			(xy 218.798902 -105.554526) (xy 218.826156 -105.554954) (xy 218.88011 -105.562712) (xy 218.932411 -105.57807)
			(xy 218.981993 -105.600715) (xy 219.027848 -105.630186) (xy 219.069042 -105.665884) (xy 219.104735 -105.707081)
			(xy 219.134202 -105.752938) (xy 219.156843 -105.802523) (xy 219.172196 -105.854825) (xy 219.179949 -105.90878)
			(xy 219.18041 -105.936034) (xy 219.179985 -105.962068) (xy 219.172893 -106.013652) (xy 219.158859 -106.063794)
			(xy 219.138143 -106.111565) (xy 219.111129 -106.156079) (xy 219.095066 -106.176572) (xy 219.089322 -106.184327)
			(xy 219.083584 -106.202739) (xy 219.08389 -106.212386) (xy 219.09024 -106.292142) (xy 219.098876 -106.309922)
			(xy 219.106242 -106.316272) (xy 219.125887 -106.334454) (xy 219.160411 -106.37536) (xy 219.188882 -106.420688)
			(xy 219.21074 -106.46955) (xy 219.225557 -106.520986) (xy 219.233042 -106.573988) (xy 219.233496 -106.600752)
			(xy 219.233 -106.628004) (xy 219.225249 -106.681955) (xy 219.209899 -106.734253) (xy 219.187261 -106.783833)
			(xy 219.157797 -106.829687) (xy 219.122106 -106.870881) (xy 219.080916 -106.906575) (xy 219.035065 -106.936044)
			(xy 218.985486 -106.958686) (xy 218.93319 -106.974042) (xy 218.87924 -106.981797) (xy 218.851988 -106.98226)
			(xy 218.823214 -106.981747) (xy 218.76632 -106.973091) (xy 218.71137 -106.955991) (xy 218.65961 -106.930835)
			(xy 218.612213 -106.898194) (xy 218.590876 -106.878882) (xy 218.583002 -106.871516) (xy 218.56319 -106.864404)
			(xy 218.466924 -106.87177) (xy 218.448128 -106.881676) (xy 218.441524 -106.890058) (xy 218.42332 -106.91226)
			(xy 218.381381 -106.95147) (xy 218.334041 -106.983954) (xy 218.282369 -107.00898) (xy 218.227531 -107.025982)
			(xy 218.170765 -107.034577) (xy 218.142058 -107.035092) (xy 218.114805 -107.034661) (xy 218.060854 -107.026899)
			(xy 218.008558 -107.011537) (xy 217.958979 -106.98889) (xy 217.913128 -106.959418) (xy 217.871938 -106.923721)
			(xy 217.836247 -106.882525) (xy 217.806782 -106.83667) (xy 217.784142 -106.787088) (xy 217.768789 -106.734789)
			(xy 217.761035 -106.680837) (xy 217.76055 -106.653584) (xy 217.761021 -106.626682) (xy 217.768594 -106.573413)
			(xy 217.783573 -106.521736) (xy 217.805662 -106.472675) (xy 217.834423 -106.427203) (xy 217.869285 -106.386221)
			(xy 217.909558 -106.350541) (xy 217.931746 -106.335322) (xy 217.942668 -106.32821) (xy 217.954606 -106.30535)
			(xy 217.952574 -106.193082) (xy 217.93962 -106.17073) (xy 217.928444 -106.163872) (xy 217.904851 -106.148937)
			(xy 217.861897 -106.113262) (xy 217.824601 -106.071707) (xy 217.793762 -106.02516) (xy 217.770037 -105.974614)
			(xy 217.753934 -105.921149) (xy 217.745796 -105.865908) (xy 217.74531 -105.83799) (xy 217.745776 -105.810997)
			(xy 217.753383 -105.75755) (xy 217.768442 -105.705707) (xy 217.790655 -105.656502) (xy 217.819577 -105.610917)
			(xy 217.83675 -105.590086) (xy 217.843862 -105.581958) (xy 217.849958 -105.561384) (xy 217.839036 -105.47604)
			(xy 217.837233 -105.465503) (xy 217.826198 -105.447218) (xy 217.8177 -105.440734) (xy 217.79648 -105.425367)
			(xy 217.758029 -105.38978) (xy 217.724811 -105.349265) (xy 217.697452 -105.304585) (xy 217.676467 -105.256579)
			(xy 217.66225 -105.206153) (xy 217.65507 -105.154256) (xy 217.654632 -105.12806) (xy 215.964516 -105.12806)
			(xy 215.964516 -107.41152) (xy 221.678754 -107.41152) (xy 221.679217 -107.385206) (xy 221.686451 -107.333076)
			(xy 221.700769 -107.282433) (xy 221.721902 -107.234233) (xy 221.74945 -107.18939) (xy 221.782891 -107.148752)
			(xy 221.801944 -107.130596) (xy 221.809341 -107.12307) (xy 221.81787 -107.103794) (xy 221.818454 -107.093258)
			(xy 221.818454 -107.018582) (xy 221.817907 -107.008034) (xy 221.809386 -106.988738) (xy 221.801944 -106.981244)
			(xy 221.782858 -106.96312) (xy 221.749405 -106.922482) (xy 221.721852 -106.877635) (xy 221.700719 -106.829428)
			(xy 221.686408 -106.778776) (xy 221.679189 -106.726638) (xy 221.678754 -106.70032) (xy 221.679297 -106.673071)
			(xy 221.68705 -106.619127) (xy 221.7024 -106.566836) (xy 221.725036 -106.517261) (xy 221.754497 -106.471413)
			(xy 221.790182 -106.430223) (xy 221.831366 -106.394532) (xy 221.877211 -106.365064) (xy 221.926782 -106.34242)
			(xy 221.979071 -106.327062) (xy 222.033013 -106.319301) (xy 222.060262 -106.318812) (xy 222.087926 -106.319348)
			(xy 222.142675 -106.327343) (xy 222.195696 -106.343155) (xy 222.24588 -106.366454) (xy 222.292176 -106.396751)
			(xy 222.333615 -106.433413) (xy 222.369328 -106.475672) (xy 222.384366 -106.498898) (xy 222.391031 -106.508552)
			(xy 222.410871 -106.52101) (xy 222.422466 -106.522774) (xy 222.502476 -106.530648) (xy 222.514114 -106.531258)
			(xy 222.53595 -106.523193) (xy 222.544386 -106.515154) (xy 222.54464 -106.5149) (xy 222.562719 -106.496317)
			(xy 222.603052 -106.463739) (xy 222.647426 -106.436926) (xy 222.695025 -106.416374) (xy 222.74497 -106.402461)
			(xy 222.796339 -106.395444) (xy 222.822262 -106.395012) (xy 222.849515 -106.395491) (xy 222.903466 -106.403243)
			(xy 222.955765 -106.418595) (xy 223.005346 -106.441235) (xy 223.051201 -106.470701) (xy 223.092394 -106.506393)
			(xy 223.128089 -106.547585) (xy 223.157557 -106.593438) (xy 223.180198 -106.643018) (xy 223.195553 -106.695316)
			(xy 223.203308 -106.749267) (xy 223.20377 -106.77652) (xy 223.203323 -106.803891) (xy 223.195502 -106.858071)
			(xy 223.180009 -106.910575) (xy 223.157162 -106.960321) (xy 223.127433 -107.006287) (xy 223.10979 -107.027218)
			(xy 223.109536 -107.027472) (xy 223.103947 -107.034557) (xy 223.097704 -107.051475) (xy 223.097344 -107.060492)
			(xy 223.097344 -107.127548) (xy 223.097716 -107.136564) (xy 223.103952 -107.153481) (xy 223.109536 -107.160568)
			(xy 223.10979 -107.160568) (xy 223.10979 -107.160822) (xy 223.127404 -107.181774) (xy 223.15712 -107.227741)
			(xy 223.179961 -107.277484) (xy 223.195458 -107.32998) (xy 223.203293 -107.384152) (xy 223.20377 -107.41152)
			(xy 223.203364 -107.438775) (xy 223.195603 -107.49273) (xy 223.180242 -107.545031) (xy 223.157595 -107.594614)
			(xy 223.128121 -107.640469) (xy 223.092421 -107.681663) (xy 223.051223 -107.717356) (xy 223.005363 -107.746823)
			(xy 222.955777 -107.769463) (xy 222.903473 -107.784815) (xy 222.849517 -107.792568) (xy 222.822262 -107.793028)
			(xy 222.793345 -107.792492) (xy 222.736174 -107.783771) (xy 222.680974 -107.766518) (xy 222.629012 -107.74113)
			(xy 222.581478 -107.708188) (xy 222.539462 -107.668447) (xy 222.521272 -107.645962) (xy 222.513674 -107.637146)
			(xy 222.492766 -107.626969) (xy 222.48114 -107.626404) (xy 222.401384 -107.626404) (xy 222.389753 -107.626947)
			(xy 222.368843 -107.637133) (xy 222.361252 -107.645962) (xy 222.343022 -107.668413) (xy 222.301012 -107.708152)
			(xy 222.253485 -107.741096) (xy 222.201531 -107.76649) (xy 222.14634 -107.783753) (xy 222.089176 -107.792489)
			(xy 222.060262 -107.793028) (xy 222.033011 -107.792558) (xy 221.979063 -107.784796) (xy 221.92677 -107.769437)
			(xy 221.877194 -107.746793) (xy 221.831344 -107.717325) (xy 221.790155 -107.681632) (xy 221.754464 -107.640441)
			(xy 221.724998 -107.594591) (xy 221.702356 -107.545013) (xy 221.687 -107.492719) (xy 221.679241 -107.438771)
			(xy 221.678754 -107.41152) (xy 215.964516 -107.41152) (xy 215.964516 -107.836251) (xy 233.797585 -107.836251)
			(xy 233.797585 -107.781749) (xy 233.805342 -107.727802) (xy 233.820697 -107.675508) (xy 233.843337 -107.625932)
			(xy 233.872803 -107.580082) (xy 233.908494 -107.538893) (xy 233.949684 -107.503202) (xy 233.995534 -107.473737)
			(xy 234.04511 -107.451096) (xy 234.097404 -107.435741) (xy 234.151351 -107.427985) (xy 234.178602 -107.427522)
			(xy 234.204916 -107.427981) (xy 234.257045 -107.435217) (xy 234.307689 -107.449537) (xy 234.355888 -107.470671)
			(xy 234.400731 -107.498219) (xy 234.44137 -107.531659) (xy 234.459526 -107.550712) (xy 234.467034 -107.558129)
			(xy 234.486325 -107.566644) (xy 234.496864 -107.567222) (xy 234.57154 -107.567222) (xy 234.582087 -107.566667)
			(xy 234.601382 -107.558149) (xy 234.608878 -107.550712) (xy 234.628698 -107.529924) (xy 234.67347 -107.493949)
			(xy 234.723128 -107.465089) (xy 234.77655 -107.443996) (xy 234.832529 -107.431147) (xy 234.889802 -107.426832)
			(xy 234.947075 -107.431147) (xy 235.003054 -107.443996) (xy 235.056476 -107.465089) (xy 235.106134 -107.493949)
			(xy 235.150906 -107.529924) (xy 235.170726 -107.550712) (xy 235.178234 -107.558129) (xy 235.197525 -107.566644)
			(xy 235.208064 -107.567222) (xy 235.28274 -107.567222) (xy 235.293287 -107.566667) (xy 235.312582 -107.558149)
			(xy 235.320078 -107.550712) (xy 235.338254 -107.531676) (xy 235.378879 -107.498217) (xy 235.423715 -107.470655)
			(xy 235.471912 -107.449513) (xy 235.522556 -107.435192) (xy 235.574687 -107.427963) (xy 235.601002 -107.427522)
			(xy 235.628255 -107.427948) (xy 235.682207 -107.435705) (xy 235.734506 -107.451062) (xy 235.784087 -107.473705)
			(xy 235.82994 -107.503174) (xy 235.871134 -107.538868) (xy 235.906828 -107.580061) (xy 235.936296 -107.625915)
			(xy 235.958939 -107.675496) (xy 235.974295 -107.727795) (xy 235.982052 -107.781747) (xy 235.982052 -107.836253)
			(xy 235.974295 -107.890205) (xy 235.958939 -107.942504) (xy 235.936296 -107.992085) (xy 235.906828 -108.037939)
			(xy 235.871134 -108.079132) (xy 235.82994 -108.114826) (xy 235.784087 -108.144295) (xy 235.734506 -108.166938)
			(xy 235.682207 -108.182295) (xy 235.628255 -108.190052) (xy 235.601002 -108.190538) (xy 235.574687 -108.190089)
			(xy 235.522557 -108.182853) (xy 235.471913 -108.168532) (xy 235.423714 -108.147396) (xy 235.378871 -108.119846)
			(xy 235.338233 -108.086402) (xy 235.320078 -108.067348) (xy 235.31256 -108.059942) (xy 235.293278 -108.051419)
			(xy 235.28274 -108.050838) (xy 235.208064 -108.050838) (xy 235.197515 -108.051377) (xy 235.178219 -108.059904)
			(xy 235.170726 -108.067348) (xy 235.150906 -108.088136) (xy 235.106134 -108.124111) (xy 235.056476 -108.152971)
			(xy 235.003054 -108.174064) (xy 234.947075 -108.186913) (xy 234.889802 -108.191228) (xy 234.832529 -108.186913)
			(xy 234.77655 -108.174064) (xy 234.723128 -108.152971) (xy 234.67347 -108.124111) (xy 234.628698 -108.088136)
			(xy 234.608878 -108.067348) (xy 234.60136 -108.059942) (xy 234.582078 -108.051419) (xy 234.57154 -108.050838)
			(xy 234.496864 -108.050838) (xy 234.486315 -108.051377) (xy 234.467019 -108.059904) (xy 234.459526 -108.067348)
			(xy 234.44136 -108.086393) (xy 234.400732 -108.119849) (xy 234.355893 -108.147409) (xy 234.307695 -108.168548)
			(xy 234.257049 -108.182868) (xy 234.204917 -108.190097) (xy 234.178602 -108.190538) (xy 234.151351 -108.190015)
			(xy 234.097404 -108.182259) (xy 234.04511 -108.166904) (xy 233.995534 -108.144263) (xy 233.949684 -108.114798)
			(xy 233.908494 -108.079107) (xy 233.872803 -108.037918) (xy 233.843337 -107.992068) (xy 233.820697 -107.942492)
			(xy 233.805342 -107.890198) (xy 233.797585 -107.836251) (xy 215.964516 -107.836251) (xy 215.964516 -108.473054)
			(xy 221.556763 -108.473054) (xy 221.556763 -108.418546) (xy 221.564521 -108.364593) (xy 221.579879 -108.312294)
			(xy 221.602523 -108.262713) (xy 221.631994 -108.216859) (xy 221.66769 -108.175666) (xy 221.708886 -108.139973)
			(xy 221.754742 -108.110507) (xy 221.804326 -108.087867) (xy 221.856627 -108.072514) (xy 221.91058 -108.064761)
			(xy 221.937834 -108.0643) (xy 221.965205 -108.064746) (xy 222.019385 -108.072569) (xy 222.071888 -108.088063)
			(xy 222.121635 -108.110909) (xy 222.167601 -108.140637) (xy 222.188532 -108.15828) (xy 222.188786 -108.158534)
			(xy 222.19587 -108.164125) (xy 222.212789 -108.170368) (xy 222.221806 -108.170726) (xy 222.288862 -108.170726)
			(xy 222.297876 -108.170345) (xy 222.314793 -108.164114) (xy 222.321882 -108.158534) (xy 222.321882 -108.15828)
			(xy 222.322136 -108.15828) (xy 222.343069 -108.140639) (xy 222.389037 -108.110915) (xy 222.438783 -108.088069)
			(xy 222.491285 -108.072573) (xy 222.545463 -108.064744) (xy 222.600205 -108.064744) (xy 222.654383 -108.072573)
			(xy 222.706885 -108.088069) (xy 222.756631 -108.110915) (xy 222.802599 -108.140639) (xy 222.823532 -108.15828)
			(xy 222.823786 -108.158534) (xy 222.83087 -108.164125) (xy 222.847789 -108.170368) (xy 222.856806 -108.170726)
			(xy 222.923862 -108.170726) (xy 222.932876 -108.170345) (xy 222.949793 -108.164114) (xy 222.956882 -108.158534)
			(xy 222.956882 -108.15828) (xy 222.957136 -108.15828) (xy 222.978069 -108.140639) (xy 223.024037 -108.110915)
			(xy 223.073783 -108.088069) (xy 223.126285 -108.072573) (xy 223.180463 -108.064744) (xy 223.235205 -108.064744)
			(xy 223.289383 -108.072573) (xy 223.341885 -108.088069) (xy 223.391631 -108.110915) (xy 223.437599 -108.140639)
			(xy 223.458532 -108.15828) (xy 223.458786 -108.158534) (xy 223.46587 -108.164125) (xy 223.482789 -108.170368)
			(xy 223.491806 -108.170726) (xy 223.558862 -108.170726) (xy 223.567876 -108.170345) (xy 223.584793 -108.164114)
			(xy 223.591882 -108.158534) (xy 223.591882 -108.15828) (xy 223.592136 -108.15828) (xy 223.613079 -108.140654)
			(xy 223.659049 -108.110941) (xy 223.708794 -108.088103) (xy 223.761292 -108.072609) (xy 223.815466 -108.064776)
			(xy 223.842834 -108.0643) (xy 223.870084 -108.064772) (xy 223.924029 -108.072533) (xy 223.976321 -108.087891)
			(xy 224.025895 -108.110535) (xy 224.071742 -108.140002) (xy 224.112929 -108.175695) (xy 224.148618 -108.216885)
			(xy 224.178082 -108.262735) (xy 224.200721 -108.312311) (xy 224.216075 -108.364604) (xy 224.22383 -108.41855)
			(xy 224.22383 -108.47305) (xy 224.216075 -108.526996) (xy 224.200721 -108.579289) (xy 224.178082 -108.628865)
			(xy 224.148618 -108.674715) (xy 224.112929 -108.715905) (xy 224.071742 -108.751598) (xy 224.025895 -108.781065)
			(xy 223.976321 -108.803709) (xy 223.924029 -108.819067) (xy 223.870084 -108.826828) (xy 223.842834 -108.827316)
			(xy 223.815464 -108.82685) (xy 223.761284 -108.819036) (xy 223.70878 -108.803548) (xy 223.659033 -108.780705)
			(xy 223.613067 -108.750979) (xy 223.592136 -108.733336) (xy 223.591882 -108.733082) (xy 223.584806 -108.72748)
			(xy 223.567881 -108.721243) (xy 223.558862 -108.72089) (xy 223.491806 -108.72089) (xy 223.48279 -108.721252)
			(xy 223.465873 -108.727496) (xy 223.458786 -108.733082) (xy 223.458532 -108.733336) (xy 223.437599 -108.750977)
			(xy 223.391631 -108.780701) (xy 223.341885 -108.803547) (xy 223.289383 -108.819043) (xy 223.235205 -108.826872)
			(xy 223.180463 -108.826872) (xy 223.126285 -108.819043) (xy 223.073783 -108.803547) (xy 223.024037 -108.780701)
			(xy 222.978069 -108.750977) (xy 222.957136 -108.733336) (xy 222.956882 -108.733082) (xy 222.949806 -108.72748)
			(xy 222.932881 -108.721243) (xy 222.923862 -108.72089) (xy 222.856806 -108.72089) (xy 222.84779 -108.721252)
			(xy 222.830873 -108.727496) (xy 222.823786 -108.733082) (xy 222.823786 -108.733336) (xy 222.823532 -108.733336)
			(xy 222.802599 -108.750977) (xy 222.756631 -108.780701) (xy 222.706885 -108.803547) (xy 222.654383 -108.819043)
			(xy 222.600205 -108.826872) (xy 222.545463 -108.826872) (xy 222.491285 -108.819043) (xy 222.438783 -108.803547)
			(xy 222.389037 -108.780701) (xy 222.343069 -108.750977) (xy 222.322136 -108.733336) (xy 222.321882 -108.733082)
			(xy 222.314806 -108.72748) (xy 222.297881 -108.721243) (xy 222.288862 -108.72089) (xy 222.221806 -108.72089)
			(xy 222.21279 -108.721252) (xy 222.195873 -108.727496) (xy 222.188786 -108.733082) (xy 222.188786 -108.733336)
			(xy 222.188532 -108.733336) (xy 222.167603 -108.750979) (xy 222.121629 -108.780689) (xy 222.071881 -108.803524)
			(xy 222.019379 -108.819014) (xy 221.965203 -108.826842) (xy 221.937834 -108.827316) (xy 221.91058 -108.826839)
			(xy 221.856627 -108.819086) (xy 221.804326 -108.803733) (xy 221.754742 -108.781093) (xy 221.708886 -108.751627)
			(xy 221.66769 -108.715934) (xy 221.631994 -108.674741) (xy 221.602523 -108.628887) (xy 221.579879 -108.579306)
			(xy 221.564521 -108.527007) (xy 221.556763 -108.473054) (xy 215.964516 -108.473054) (xy 215.964516 -111.128853)
			(xy 221.497087 -111.128853) (xy 221.497087 -111.074347) (xy 221.504845 -111.020397) (xy 221.520202 -110.9681)
			(xy 221.542846 -110.918521) (xy 221.572315 -110.87267) (xy 221.608011 -110.83148) (xy 221.649205 -110.795789)
			(xy 221.69506 -110.766325) (xy 221.744641 -110.743686) (xy 221.79694 -110.728335) (xy 221.850891 -110.720584)
			(xy 221.878144 -110.720124) (xy 221.905513 -110.720617) (xy 221.959691 -110.728427) (xy 222.012195 -110.74391)
			(xy 222.061942 -110.766746) (xy 222.10791 -110.796465) (xy 222.128842 -110.814104) (xy 222.129096 -110.814358)
			(xy 222.136175 -110.819956) (xy 222.153098 -110.826194) (xy 222.162116 -110.82655) (xy 222.229172 -110.82655)
			(xy 222.238189 -110.82619) (xy 222.255106 -110.819946) (xy 222.262192 -110.814358) (xy 222.262192 -110.814104)
			(xy 222.262446 -110.814104) (xy 222.283379 -110.796463) (xy 222.329347 -110.766739) (xy 222.379093 -110.743893)
			(xy 222.431595 -110.728397) (xy 222.485773 -110.720568) (xy 222.540515 -110.720568) (xy 222.594693 -110.728397)
			(xy 222.647195 -110.743893) (xy 222.696941 -110.766739) (xy 222.742909 -110.796463) (xy 222.763842 -110.814104)
			(xy 222.764096 -110.814358) (xy 222.771175 -110.819956) (xy 222.788098 -110.826194) (xy 222.797116 -110.82655)
			(xy 222.864172 -110.82655) (xy 222.873189 -110.82619) (xy 222.890106 -110.819946) (xy 222.897192 -110.814358)
			(xy 222.897192 -110.814104) (xy 222.897446 -110.814104) (xy 222.918379 -110.796463) (xy 222.964347 -110.766739)
			(xy 223.014093 -110.743893) (xy 223.066595 -110.728397) (xy 223.120773 -110.720568) (xy 223.175515 -110.720568)
			(xy 223.229693 -110.728397) (xy 223.282195 -110.743893) (xy 223.331941 -110.766739) (xy 223.377909 -110.796463)
			(xy 223.398842 -110.814104) (xy 223.399096 -110.814358) (xy 223.406175 -110.819956) (xy 223.423098 -110.826194)
			(xy 223.432116 -110.82655) (xy 223.499172 -110.82655) (xy 223.508189 -110.82619) (xy 223.525106 -110.819946)
			(xy 223.532192 -110.814358) (xy 223.532192 -110.814104) (xy 223.532446 -110.814104) (xy 223.553388 -110.796477)
			(xy 223.599358 -110.766764) (xy 223.649103 -110.743925) (xy 223.701602 -110.728431) (xy 223.755776 -110.7206)
			(xy 223.783144 -110.720124) (xy 223.810395 -110.720549) (xy 223.864343 -110.728311) (xy 223.916637 -110.743671)
			(xy 223.966213 -110.766317) (xy 224.012061 -110.795787) (xy 224.05325 -110.831481) (xy 224.08894 -110.872674)
			(xy 224.118404 -110.918526) (xy 224.134218 -110.953156) (xy 233.725619 -110.953156) (xy 233.725619 -110.898644)
			(xy 233.733377 -110.844686) (xy 233.748736 -110.792381) (xy 233.771382 -110.742795) (xy 233.800855 -110.696937)
			(xy 233.836554 -110.65574) (xy 233.877753 -110.620043) (xy 233.923613 -110.590572) (xy 233.9732 -110.567929)
			(xy 234.025505 -110.552573) (xy 234.079464 -110.544818) (xy 234.10672 -110.544356) (xy 234.133035 -110.544792)
			(xy 234.185166 -110.552031) (xy 234.23581 -110.566355) (xy 234.284009 -110.587493) (xy 234.328852 -110.615046)
			(xy 234.369489 -110.648491) (xy 234.387644 -110.667546) (xy 234.395155 -110.674961) (xy 234.414443 -110.68348)
			(xy 234.424982 -110.684056) (xy 234.499658 -110.684056) (xy 234.510208 -110.683531) (xy 234.529505 -110.674994)
			(xy 234.536996 -110.667546) (xy 234.556816 -110.646758) (xy 234.601588 -110.610783) (xy 234.651246 -110.581923)
			(xy 234.704668 -110.56083) (xy 234.760647 -110.547981) (xy 234.81792 -110.543666) (xy 234.875193 -110.547981)
			(xy 234.931172 -110.56083) (xy 234.984594 -110.581923) (xy 235.034252 -110.610783) (xy 235.079024 -110.646758)
			(xy 235.098844 -110.667546) (xy 235.106355 -110.674961) (xy 235.125643 -110.68348) (xy 235.136182 -110.684056)
			(xy 235.210858 -110.684056) (xy 235.221408 -110.683531) (xy 235.240705 -110.674994) (xy 235.248196 -110.667546)
			(xy 235.26635 -110.648489) (xy 235.306981 -110.615034) (xy 235.351822 -110.587477) (xy 235.400023 -110.566339)
			(xy 235.45067 -110.552021) (xy 235.502804 -110.544795) (xy 235.52912 -110.544356) (xy 235.556368 -110.544916)
			(xy 235.610308 -110.552674) (xy 235.662595 -110.568029) (xy 235.712165 -110.590669) (xy 235.758009 -110.620133)
			(xy 235.799193 -110.655821) (xy 235.834879 -110.697007) (xy 235.86434 -110.742852) (xy 235.886978 -110.792423)
			(xy 235.902331 -110.844711) (xy 235.910086 -110.898652) (xy 235.910086 -110.953148) (xy 235.902331 -111.007089)
			(xy 235.886978 -111.059377) (xy 235.86434 -111.108948) (xy 235.834879 -111.154793) (xy 235.799193 -111.195979)
			(xy 235.758009 -111.231667) (xy 235.712165 -111.261131) (xy 235.662595 -111.283771) (xy 235.610308 -111.299126)
			(xy 235.556368 -111.306884) (xy 235.52912 -111.307372) (xy 235.502806 -111.3069) (xy 235.450677 -111.299667)
			(xy 235.400034 -111.28535) (xy 235.351835 -111.264218) (xy 235.306992 -111.236673) (xy 235.266352 -111.203234)
			(xy 235.248196 -111.184182) (xy 235.24068 -111.176774) (xy 235.221396 -111.168254) (xy 235.210858 -111.167672)
			(xy 235.136182 -111.167672) (xy 235.125637 -111.16824) (xy 235.106342 -111.176749) (xy 235.098844 -111.184182)
			(xy 235.079024 -111.20497) (xy 235.034252 -111.240945) (xy 234.984594 -111.269805) (xy 234.931172 -111.290898)
			(xy 234.875193 -111.303747) (xy 234.81792 -111.308062) (xy 234.760647 -111.303747) (xy 234.704668 -111.290898)
			(xy 234.651246 -111.269805) (xy 234.601588 -111.240945) (xy 234.556816 -111.20497) (xy 234.536996 -111.184182)
			(xy 234.52948 -111.176774) (xy 234.510196 -111.168254) (xy 234.499658 -111.167672) (xy 234.424982 -111.167672)
			(xy 234.414437 -111.16824) (xy 234.395142 -111.176749) (xy 234.387644 -111.184182) (xy 234.369505 -111.203254)
			(xy 234.328872 -111.236711) (xy 234.284029 -111.264268) (xy 234.235824 -111.285404) (xy 234.185174 -111.299717)
			(xy 234.133037 -111.306936) (xy 234.10672 -111.307372) (xy 234.079464 -111.306982) (xy 234.025505 -111.299227)
			(xy 233.9732 -111.283871) (xy 233.923613 -111.261228) (xy 233.877753 -111.231757) (xy 233.836554 -111.19606)
			(xy 233.800855 -111.154863) (xy 233.771382 -111.109005) (xy 233.748736 -111.059419) (xy 233.733377 -111.007114)
			(xy 233.725619 -110.953156) (xy 224.134218 -110.953156) (xy 224.141044 -110.968104) (xy 224.156398 -111.0204)
			(xy 224.164154 -111.074348) (xy 224.164154 -111.128852) (xy 224.156398 -111.1828) (xy 224.141044 -111.235096)
			(xy 224.118404 -111.284674) (xy 224.08894 -111.330526) (xy 224.05325 -111.371719) (xy 224.012061 -111.407413)
			(xy 223.966213 -111.436883) (xy 223.916637 -111.459529) (xy 223.864343 -111.474889) (xy 223.810395 -111.482651)
			(xy 223.783144 -111.48314) (xy 223.755774 -111.482663) (xy 223.701595 -111.47485) (xy 223.649091 -111.459364)
			(xy 223.599344 -111.436525) (xy 223.553377 -111.406801) (xy 223.532446 -111.38916) (xy 223.532192 -111.388906)
			(xy 223.525111 -111.383311) (xy 223.50819 -111.377069) (xy 223.499172 -111.376714) (xy 223.432116 -111.376714)
			(xy 223.4231 -111.377075) (xy 223.406182 -111.38332) (xy 223.399096 -111.388906) (xy 223.398842 -111.38916)
			(xy 223.377909 -111.406801) (xy 223.331941 -111.436525) (xy 223.282195 -111.459371) (xy 223.229693 -111.474867)
			(xy 223.175515 -111.482696) (xy 223.120773 -111.482696) (xy 223.066595 -111.474867) (xy 223.014093 -111.459371)
			(xy 222.964347 -111.436525) (xy 222.918379 -111.406801) (xy 222.897446 -111.38916) (xy 222.897192 -111.388906)
			(xy 222.890111 -111.383311) (xy 222.87319 -111.377069) (xy 222.864172 -111.376714) (xy 222.797116 -111.376714)
			(xy 222.7881 -111.377075) (xy 222.771182 -111.38332) (xy 222.764096 -111.388906) (xy 222.764096 -111.38916)
			(xy 222.763842 -111.38916) (xy 222.742909 -111.406801) (xy 222.696941 -111.436525) (xy 222.647195 -111.459371)
			(xy 222.594693 -111.474867) (xy 222.540515 -111.482696) (xy 222.485773 -111.482696) (xy 222.431595 -111.474867)
			(xy 222.379093 -111.459371) (xy 222.329347 -111.436525) (xy 222.283379 -111.406801) (xy 222.262446 -111.38916)
			(xy 222.262192 -111.388906) (xy 222.255111 -111.383311) (xy 222.23819 -111.377069) (xy 222.229172 -111.376714)
			(xy 222.162116 -111.376714) (xy 222.1531 -111.377075) (xy 222.136182 -111.38332) (xy 222.129096 -111.388906)
			(xy 222.129096 -111.38916) (xy 222.128842 -111.38916) (xy 222.1079 -111.406787) (xy 222.06193 -111.436502)
			(xy 222.012186 -111.459341) (xy 221.959687 -111.474835) (xy 221.905513 -111.482665) (xy 221.878144 -111.48314)
			(xy 221.850891 -111.482616) (xy 221.79694 -111.474865) (xy 221.744641 -111.459514) (xy 221.69506 -111.436875)
			(xy 221.649205 -111.407411) (xy 221.608011 -111.37172) (xy 221.572315 -111.33053) (xy 221.542846 -111.284679)
			(xy 221.520202 -111.2351) (xy 221.504845 -111.182803) (xy 221.497087 -111.128853) (xy 215.964516 -111.128853)
			(xy 215.964516 -112.72012) (xy 232.673906 -112.72012) (xy 232.674382 -112.69275) (xy 232.682197 -112.638571)
			(xy 232.697684 -112.586068) (xy 232.720524 -112.536321) (xy 232.750246 -112.490354) (xy 232.767886 -112.469422)
			(xy 232.76814 -112.469168) (xy 232.773709 -112.46207) (xy 232.779965 -112.445162) (xy 232.780332 -112.436148)
			(xy 232.780332 -112.369092) (xy 232.779972 -112.360076) (xy 232.773726 -112.343159) (xy 232.76814 -112.336072)
			(xy 232.767886 -112.336072) (xy 232.767886 -112.335818) (xy 232.75024 -112.314892) (xy 232.720529 -112.268917)
			(xy 232.697695 -112.219168) (xy 232.682206 -112.166666) (xy 232.674379 -112.11249) (xy 232.673906 -112.08512)
			(xy 232.674392 -112.057869) (xy 232.682148 -112.003921) (xy 232.697503 -111.951626) (xy 232.720145 -111.902049)
			(xy 232.749611 -111.856199) (xy 232.785302 -111.815008) (xy 232.826493 -111.779317) (xy 232.872343 -111.749851)
			(xy 232.92192 -111.727209) (xy 232.974215 -111.711854) (xy 233.028163 -111.704098) (xy 233.082665 -111.704098)
			(xy 233.136613 -111.711854) (xy 233.188908 -111.727209) (xy 233.238485 -111.749851) (xy 233.284335 -111.779317)
			(xy 233.325526 -111.815008) (xy 233.361217 -111.856199) (xy 233.390683 -111.902049) (xy 233.413325 -111.951626)
			(xy 233.427314 -111.999268) (xy 238.85347 -111.999268) (xy 238.857541 -111.943646) (xy 238.869667 -111.889209)
			(xy 238.88959 -111.837118) (xy 238.916886 -111.788483) (xy 238.950972 -111.74434) (xy 238.991121 -111.705631)
			(xy 239.036479 -111.67318) (xy 239.086079 -111.647679) (xy 239.138863 -111.629672) (xy 239.193706 -111.619542)
			(xy 239.24944 -111.617505) (xy 239.304877 -111.623605) (xy 239.358834 -111.637711) (xy 239.410163 -111.659523)
			(xy 239.457769 -111.688577) (xy 239.500637 -111.724252) (xy 239.537854 -111.765789) (xy 239.568627 -111.812302)
			(xy 239.592299 -111.862799) (xy 239.608367 -111.916206) (xy 239.616487 -111.971382) (xy 239.616996 -111.999268)
			(xy 239.616487 -112.027154) (xy 239.608367 -112.08233) (xy 239.592299 -112.135737) (xy 239.568627 -112.186234)
			(xy 239.537854 -112.232747) (xy 239.500637 -112.274284) (xy 239.457769 -112.309959) (xy 239.410163 -112.339013)
			(xy 239.358834 -112.360825) (xy 239.304877 -112.374931) (xy 239.24944 -112.381031) (xy 239.193706 -112.378994)
			(xy 239.138863 -112.368864) (xy 239.086079 -112.350857) (xy 239.036479 -112.325356) (xy 238.991121 -112.292905)
			(xy 238.950972 -112.254196) (xy 238.916886 -112.210053) (xy 238.88959 -112.161418) (xy 238.869667 -112.109327)
			(xy 238.857541 -112.05489) (xy 238.85347 -111.999268) (xy 233.427314 -111.999268) (xy 233.42868 -112.003921)
			(xy 233.436436 -112.057869) (xy 233.436922 -112.08512) (xy 233.436487 -112.112492) (xy 233.428664 -112.166673)
			(xy 233.413169 -112.219177) (xy 233.39032 -112.268923) (xy 233.360587 -112.314888) (xy 233.342942 -112.335818)
			(xy 233.342688 -112.336072) (xy 233.337106 -112.343161) (xy 233.330857 -112.360076) (xy 233.330496 -112.369092)
			(xy 233.330496 -112.436148) (xy 233.330879 -112.445162) (xy 233.337109 -112.462079) (xy 233.342688 -112.469168)
			(xy 233.342942 -112.469168) (xy 233.342942 -112.469422) (xy 233.360565 -112.490367) (xy 233.390278 -112.536337)
			(xy 233.413116 -112.586081) (xy 233.428611 -112.638579) (xy 233.436445 -112.692752) (xy 233.436922 -112.72012)
			(xy 233.436436 -112.747371) (xy 233.42868 -112.801319) (xy 233.413325 -112.853614) (xy 233.390683 -112.903191)
			(xy 233.361217 -112.949041) (xy 233.325526 -112.990232) (xy 233.284335 -113.025923) (xy 233.238485 -113.055389)
			(xy 233.188908 -113.078031) (xy 233.136613 -113.093386) (xy 233.082665 -113.101142) (xy 233.028163 -113.101142)
			(xy 232.974215 -113.093386) (xy 232.92192 -113.078031) (xy 232.872343 -113.055389) (xy 232.826493 -113.025923)
			(xy 232.785302 -112.990232) (xy 232.749611 -112.949041) (xy 232.720145 -112.903191) (xy 232.697503 -112.853614)
			(xy 232.682148 -112.801319) (xy 232.674392 -112.747371) (xy 232.673906 -112.72012) (xy 215.964516 -112.72012)
			(xy 215.964516 -113.653062) (xy 235.227366 -113.653062) (xy 235.231437 -113.59744) (xy 235.243563 -113.543003)
			(xy 235.263486 -113.490912) (xy 235.290782 -113.442277) (xy 235.324868 -113.398134) (xy 235.365017 -113.359425)
			(xy 235.410375 -113.326974) (xy 235.459975 -113.301473) (xy 235.512759 -113.283466) (xy 235.567602 -113.273336)
			(xy 235.623336 -113.271299) (xy 235.678773 -113.277399) (xy 235.73273 -113.291505) (xy 235.784059 -113.313317)
			(xy 235.831665 -113.342371) (xy 235.874533 -113.378046) (xy 235.91175 -113.419583) (xy 235.942523 -113.466096)
			(xy 235.966195 -113.516593) (xy 235.982263 -113.57) (xy 235.990383 -113.625176) (xy 235.990892 -113.653062)
			(xy 235.990383 -113.680948) (xy 235.982263 -113.736124) (xy 235.966195 -113.789531) (xy 235.942523 -113.840028)
			(xy 235.91175 -113.886541) (xy 235.874533 -113.928078) (xy 235.831665 -113.963753) (xy 235.784059 -113.992807)
			(xy 235.73273 -114.014619) (xy 235.678773 -114.028725) (xy 235.623336 -114.034825) (xy 235.567602 -114.032788)
			(xy 235.512759 -114.022658) (xy 235.459975 -114.004651) (xy 235.410375 -113.97915) (xy 235.365017 -113.946699)
			(xy 235.324868 -113.90799) (xy 235.290782 -113.863847) (xy 235.263486 -113.815212) (xy 235.243563 -113.763121)
			(xy 235.231437 -113.708684) (xy 235.227366 -113.653062) (xy 215.964516 -113.653062) (xy 215.964516 -116.188224)
			(xy 223.368955 -116.188224) (xy 223.373268 -116.130954) (xy 223.386114 -116.074977) (xy 223.407204 -116.021557)
			(xy 223.436062 -115.971901) (xy 223.472035 -115.927131) (xy 223.492822 -115.907312) (xy 223.500224 -115.899791)
			(xy 223.508747 -115.88051) (xy 223.509332 -115.869974) (xy 223.509332 -115.795298) (xy 223.508808 -115.784748)
			(xy 223.500268 -115.765453) (xy 223.492822 -115.75796) (xy 223.473758 -115.739813) (xy 223.440301 -115.699182)
			(xy 223.412743 -115.65434) (xy 223.391605 -115.606137) (xy 223.37729 -115.555488) (xy 223.370069 -115.503353)
			(xy 223.369632 -115.477036) (xy 223.370118 -115.449785) (xy 223.377874 -115.395837) (xy 223.393229 -115.343542)
			(xy 223.415871 -115.293965) (xy 223.445337 -115.248115) (xy 223.481028 -115.206924) (xy 223.522219 -115.171233)
			(xy 223.568069 -115.141767) (xy 223.617646 -115.119125) (xy 223.669941 -115.10377) (xy 223.723889 -115.096014)
			(xy 223.778391 -115.096014) (xy 223.832339 -115.10377) (xy 223.884634 -115.119125) (xy 223.934211 -115.141767)
			(xy 223.980061 -115.171233) (xy 224.021252 -115.206924) (xy 224.056943 -115.248115) (xy 224.086409 -115.293965)
			(xy 224.109051 -115.343542) (xy 224.124406 -115.395837) (xy 224.132162 -115.449785) (xy 224.132648 -115.477036)
			(xy 224.132221 -115.503352) (xy 224.12498 -115.555482) (xy 224.110654 -115.606127) (xy 224.089514 -115.654326)
			(xy 224.06196 -115.699168) (xy 224.028514 -115.739805) (xy 224.009458 -115.75796) (xy 224.002081 -115.765502)
			(xy 223.99354 -115.784766) (xy 223.992948 -115.795298) (xy 223.992948 -115.869974) (xy 223.993464 -115.880526)
			(xy 224.002007 -115.899822) (xy 224.009458 -115.907312) (xy 224.03028 -115.927097) (xy 224.066251 -115.971876)
			(xy 224.095107 -116.021539) (xy 224.116195 -116.074966) (xy 224.12904 -116.130949) (xy 224.133352 -116.188224)
			(xy 225.907203 -116.188224) (xy 225.911514 -116.130957) (xy 225.924357 -116.074981) (xy 225.945443 -116.021562)
			(xy 225.974294 -115.971906) (xy 226.010261 -115.927133) (xy 226.031044 -115.907312) (xy 226.038434 -115.89978)
			(xy 226.046967 -115.880508) (xy 226.047554 -115.869974) (xy 226.047554 -115.795298) (xy 226.047053 -115.784745)
			(xy 226.0385 -115.765449) (xy 226.031044 -115.75796) (xy 226.011965 -115.739828) (xy 225.978512 -115.699192)
			(xy 225.950958 -115.654346) (xy 225.929824 -115.606141) (xy 225.915511 -115.55549) (xy 225.90829 -115.503353)
			(xy 225.907854 -115.477036) (xy 225.90834 -115.449785) (xy 225.916096 -115.395837) (xy 225.931451 -115.343542)
			(xy 225.954093 -115.293965) (xy 225.983559 -115.248115) (xy 226.01925 -115.206924) (xy 226.060441 -115.171233)
			(xy 226.106291 -115.141767) (xy 226.155868 -115.119125) (xy 226.208163 -115.10377) (xy 226.262111 -115.096014)
			(xy 226.316613 -115.096014) (xy 226.370561 -115.10377) (xy 226.422856 -115.119125) (xy 226.472433 -115.141767)
			(xy 226.518283 -115.171233) (xy 226.559474 -115.206924) (xy 226.595165 -115.248115) (xy 226.624631 -115.293965)
			(xy 226.647273 -115.343542) (xy 226.662628 -115.395837) (xy 226.670384 -115.449785) (xy 226.67087 -115.477036)
			(xy 226.670436 -115.503351) (xy 226.663196 -115.555482) (xy 226.648871 -115.606125) (xy 226.627732 -115.654324)
			(xy 226.60018 -115.699167) (xy 226.566735 -115.739805) (xy 226.54768 -115.75796) (xy 226.540291 -115.765492)
			(xy 226.53176 -115.784764) (xy 226.53117 -115.795298) (xy 226.53117 -115.869974) (xy 226.531708 -115.880522)
			(xy 226.540238 -115.899817) (xy 226.54768 -115.907312) (xy 226.568506 -115.927095) (xy 226.604484 -115.971871)
			(xy 226.633345 -116.021534) (xy 226.654438 -116.074961) (xy 226.667286 -116.130946) (xy 226.668309 -116.144533)
			(xy 230.110137 -116.144533) (xy 230.114448 -116.087265) (xy 230.127291 -116.03129) (xy 230.148377 -115.977871)
			(xy 230.17723 -115.928215) (xy 230.213198 -115.883444) (xy 230.233982 -115.863624) (xy 230.241372 -115.856093)
			(xy 230.249904 -115.83682) (xy 230.250492 -115.826286) (xy 230.250492 -115.75161) (xy 230.249973 -115.741059)
			(xy 230.241431 -115.721764) (xy 230.233982 -115.714272) (xy 230.213242 -115.694404) (xy 230.177267 -115.649638)
			(xy 230.148405 -115.599988) (xy 230.12731 -115.546573) (xy 230.114457 -115.4906) (xy 230.110137 -115.433333)
			(xy 230.114448 -115.376065) (xy 230.127291 -115.32009) (xy 230.148377 -115.266671) (xy 230.17723 -115.217015)
			(xy 230.213198 -115.172244) (xy 230.233982 -115.152424) (xy 230.241372 -115.144893) (xy 230.249904 -115.12562)
			(xy 230.250492 -115.115086) (xy 230.250492 -115.04041) (xy 230.249973 -115.029859) (xy 230.241431 -115.010564)
			(xy 230.233982 -115.003072) (xy 230.214916 -114.984927) (xy 230.181461 -114.944294) (xy 230.153904 -114.899452)
			(xy 230.132767 -114.851249) (xy 230.118452 -114.8006) (xy 230.111229 -114.748465) (xy 230.110792 -114.722148)
			(xy 230.1113 -114.694896) (xy 230.11905 -114.640947) (xy 230.1344 -114.58865) (xy 230.157037 -114.53907)
			(xy 230.1865 -114.493217) (xy 230.222189 -114.452023) (xy 230.263378 -114.416329) (xy 230.309228 -114.38686)
			(xy 230.358805 -114.364217) (xy 230.4111 -114.348861) (xy 230.465048 -114.341103) (xy 230.4923 -114.34064)
			(xy 230.518615 -114.341095) (xy 230.570744 -114.34833) (xy 230.621388 -114.362651) (xy 230.669587 -114.383786)
			(xy 230.71443 -114.411335) (xy 230.755068 -114.444777) (xy 230.773224 -114.46383) (xy 230.780744 -114.471234)
			(xy 230.800025 -114.479759) (xy 230.810562 -114.48034) (xy 230.885238 -114.48034) (xy 230.895784 -114.479779)
			(xy 230.915079 -114.471265) (xy 230.922576 -114.46383) (xy 230.940756 -114.444799) (xy 230.98138 -114.411338)
			(xy 231.026215 -114.383775) (xy 231.074411 -114.362632) (xy 231.125054 -114.34831) (xy 231.177185 -114.341081)
			(xy 231.2035 -114.34064) (xy 231.230755 -114.341055) (xy 231.28471 -114.348814) (xy 231.337012 -114.364172)
			(xy 231.386595 -114.386818) (xy 231.426389 -114.412395) (xy 232.727135 -114.412395) (xy 232.727135 -114.360405)
			(xy 232.735269 -114.309056) (xy 232.751336 -114.259612) (xy 232.774941 -114.21329) (xy 232.805502 -114.171231)
			(xy 232.842266 -114.134472) (xy 232.884329 -114.103917) (xy 232.930654 -114.080318) (xy 232.980101 -114.064258)
			(xy 233.031451 -114.056132) (xy 233.057446 -114.055652) (xy 233.084091 -114.056131) (xy 233.136694 -114.064663)
			(xy 233.187244 -114.081529) (xy 233.234431 -114.106293) (xy 233.277029 -114.138312) (xy 233.313934 -114.176754)
			(xy 233.32948 -114.1984) (xy 233.337844 -114.209686) (xy 233.359517 -114.227541) (xy 233.385231 -114.238824)
			(xy 233.413046 -114.242682) (xy 233.440861 -114.238824) (xy 233.466575 -114.227541) (xy 233.488248 -114.209686)
			(xy 233.496612 -114.1984) (xy 233.512202 -114.176793) (xy 233.549115 -114.138375) (xy 233.59171 -114.106373)
			(xy 233.638886 -114.081616) (xy 233.689421 -114.064743) (xy 233.742007 -114.056191) (xy 233.768646 -114.055652)
			(xy 233.794628 -114.056245) (xy 233.84595 -114.064381) (xy 233.895369 -114.080444) (xy 233.941666 -114.104039)
			(xy 233.983703 -114.134586) (xy 234.020444 -114.171332) (xy 234.050985 -114.213373) (xy 234.074574 -114.259674)
			(xy 234.09063 -114.309095) (xy 234.098758 -114.360418) (xy 234.098758 -114.412382) (xy 234.09063 -114.463705)
			(xy 234.074574 -114.513126) (xy 234.050985 -114.559427) (xy 234.020444 -114.601468) (xy 233.983703 -114.638214)
			(xy 233.945097 -114.666268) (xy 236.640876 -114.666268) (xy 236.644947 -114.610646) (xy 236.657073 -114.556209)
			(xy 236.676996 -114.504118) (xy 236.704292 -114.455483) (xy 236.738378 -114.41134) (xy 236.778527 -114.372631)
			(xy 236.823885 -114.34018) (xy 236.873485 -114.314679) (xy 236.926269 -114.296672) (xy 236.981112 -114.286542)
			(xy 237.036846 -114.284505) (xy 237.092283 -114.290605) (xy 237.14624 -114.304711) (xy 237.197569 -114.326523)
			(xy 237.245175 -114.355577) (xy 237.288043 -114.391252) (xy 237.32526 -114.432789) (xy 237.356033 -114.479302)
			(xy 237.379705 -114.529799) (xy 237.395773 -114.583206) (xy 237.403893 -114.638382) (xy 237.404402 -114.666268)
			(xy 237.403893 -114.694154) (xy 237.395773 -114.74933) (xy 237.379705 -114.802737) (xy 237.356033 -114.853234)
			(xy 237.32526 -114.899747) (xy 237.288043 -114.941284) (xy 237.245175 -114.976959) (xy 237.197569 -115.006013)
			(xy 237.14624 -115.027825) (xy 237.092283 -115.041931) (xy 237.036846 -115.048031) (xy 236.981112 -115.045994)
			(xy 236.926269 -115.035864) (xy 236.873485 -115.017857) (xy 236.823885 -114.992356) (xy 236.778527 -114.959905)
			(xy 236.738378 -114.921196) (xy 236.704292 -114.877053) (xy 236.676996 -114.828418) (xy 236.657073 -114.776327)
			(xy 236.644947 -114.72189) (xy 236.640876 -114.666268) (xy 233.945097 -114.666268) (xy 233.941666 -114.668761)
			(xy 233.895369 -114.692356) (xy 233.84595 -114.708419) (xy 233.794628 -114.716555) (xy 233.768646 -114.717068)
			(xy 233.742001 -114.716586) (xy 233.689399 -114.708054) (xy 233.638849 -114.691187) (xy 233.591663 -114.666424)
			(xy 233.549064 -114.634406) (xy 233.512158 -114.595965) (xy 233.496612 -114.57432) (xy 233.488248 -114.563034)
			(xy 233.466575 -114.545179) (xy 233.440861 -114.533896) (xy 233.413046 -114.530038) (xy 233.385231 -114.533896)
			(xy 233.359517 -114.545179) (xy 233.337844 -114.563034) (xy 233.32948 -114.57432) (xy 233.3139 -114.595935)
			(xy 233.276985 -114.634351) (xy 233.234387 -114.666352) (xy 233.18721 -114.691108) (xy 233.136673 -114.707979)
			(xy 233.084085 -114.716529) (xy 233.057446 -114.717068) (xy 233.031451 -114.716668) (xy 232.980101 -114.708542)
			(xy 232.930654 -114.692482) (xy 232.884329 -114.668883) (xy 232.842266 -114.638328) (xy 232.805502 -114.601569)
			(xy 232.774941 -114.55951) (xy 232.751336 -114.513188) (xy 232.735269 -114.463744) (xy 232.727135 -114.412395)
			(xy 231.426389 -114.412395) (xy 231.432451 -114.416291) (xy 231.473645 -114.451989) (xy 231.509338 -114.493188)
			(xy 231.538805 -114.539047) (xy 231.561445 -114.588633) (xy 231.576797 -114.640937) (xy 231.584548 -114.694893)
			(xy 231.585008 -114.722148) (xy 231.58457 -114.748463) (xy 231.577329 -114.800593) (xy 231.563004 -114.851236)
			(xy 231.541866 -114.899435) (xy 231.514315 -114.944277) (xy 231.480872 -114.984916) (xy 231.461818 -115.003072)
			(xy 231.454429 -115.010604) (xy 231.445897 -115.029876) (xy 231.445308 -115.04041) (xy 231.445308 -115.115086)
			(xy 231.445829 -115.125637) (xy 231.45437 -115.144932) (xy 231.461818 -115.152424) (xy 231.482654 -115.172196)
			(xy 231.518629 -115.216975) (xy 231.547487 -115.26664) (xy 231.565585 -115.312489) (xy 232.727211 -115.312489)
			(xy 232.727211 -115.260511) (xy 232.735343 -115.209174) (xy 232.751406 -115.159741) (xy 232.775005 -115.113429)
			(xy 232.805559 -115.071381) (xy 232.842316 -115.034629) (xy 232.884369 -115.004081) (xy 232.930683 -114.980489)
			(xy 232.980119 -114.964432) (xy 233.031457 -114.956308) (xy 233.057446 -114.955828) (xy 233.084091 -114.956318)
			(xy 233.136692 -114.964848) (xy 233.187242 -114.981713) (xy 233.234428 -115.006475) (xy 233.277027 -115.038492)
			(xy 233.313933 -115.076932) (xy 233.32948 -115.098576) (xy 233.337844 -115.109862) (xy 233.359517 -115.127717)
			(xy 233.385231 -115.139) (xy 233.413046 -115.142858) (xy 233.440861 -115.139) (xy 233.466575 -115.127717)
			(xy 233.488248 -115.109862) (xy 233.496612 -115.098576) (xy 233.512195 -115.076964) (xy 233.54911 -115.038547)
			(xy 233.591707 -115.006547) (xy 233.638884 -114.98179) (xy 233.68942 -114.964918) (xy 233.742007 -114.956367)
			(xy 233.768646 -114.955828) (xy 233.794634 -114.956269) (xy 233.845968 -114.964406) (xy 233.895398 -114.980473)
			(xy 233.941706 -115.004074) (xy 233.983753 -115.034628) (xy 234.020502 -115.071383) (xy 234.05105 -115.113433)
			(xy 234.074645 -115.159745) (xy 234.090705 -115.209177) (xy 234.098835 -115.260512) (xy 234.098835 -115.312488)
			(xy 234.090704 -115.363823) (xy 234.074645 -115.413255) (xy 234.05105 -115.459567) (xy 234.020502 -115.501617)
			(xy 233.983753 -115.538372) (xy 233.941706 -115.568926) (xy 233.895398 -115.592527) (xy 233.845968 -115.608594)
			(xy 233.794634 -115.616731) (xy 233.768646 -115.617244) (xy 233.742 -115.616772) (xy 233.689397 -115.608239)
			(xy 233.638847 -115.591372) (xy 233.59166 -115.566606) (xy 233.549062 -115.534586) (xy 233.512158 -115.496142)
			(xy 233.496612 -115.474496) (xy 233.488248 -115.46321) (xy 233.466575 -115.445355) (xy 233.440861 -115.434072)
			(xy 233.413046 -115.430214) (xy 233.385231 -115.434072) (xy 233.359517 -115.445355) (xy 233.337844 -115.46321)
			(xy 233.32948 -115.474496) (xy 233.313923 -115.496128) (xy 233.277 -115.53454) (xy 233.234397 -115.566536)
			(xy 233.187215 -115.591288) (xy 233.136676 -115.608157) (xy 233.084086 -115.616705) (xy 233.057446 -115.617244)
			(xy 233.031457 -115.616692) (xy 232.980119 -115.608568) (xy 232.930683 -115.592511) (xy 232.884369 -115.568919)
			(xy 232.842316 -115.538371) (xy 232.805559 -115.501619) (xy 232.775005 -115.45957) (xy 232.751406 -115.413259)
			(xy 232.735343 -115.363826) (xy 232.727211 -115.312489) (xy 231.565585 -115.312489) (xy 231.568577 -115.320069)
			(xy 231.581422 -115.376054) (xy 231.585733 -115.433333) (xy 231.581413 -115.49061) (xy 231.568557 -115.546594)
			(xy 231.547458 -115.600018) (xy 231.518592 -115.649678) (xy 231.482609 -115.694452) (xy 231.461818 -115.714272)
			(xy 231.454429 -115.721804) (xy 231.445897 -115.741076) (xy 231.445308 -115.75161) (xy 231.445308 -115.826286)
			(xy 231.445829 -115.836837) (xy 231.45437 -115.856132) (xy 231.461818 -115.863624) (xy 231.482654 -115.883396)
			(xy 231.518629 -115.928175) (xy 231.547487 -115.97784) (xy 231.568577 -116.031269) (xy 231.581422 -116.087254)
			(xy 231.585733 -116.144533) (xy 231.581413 -116.20181) (xy 231.578959 -116.212495) (xy 232.727133 -116.212495)
			(xy 232.727133 -116.160505) (xy 232.735267 -116.109156) (xy 232.751334 -116.059711) (xy 232.774939 -116.013389)
			(xy 232.8055 -115.97133) (xy 232.842265 -115.93457) (xy 232.884328 -115.904015) (xy 232.930653 -115.880417)
			(xy 232.9801 -115.864356) (xy 233.031451 -115.85623) (xy 233.057446 -115.85575) (xy 233.084091 -115.85623)
			(xy 233.136694 -115.864762) (xy 233.187244 -115.881628) (xy 233.23443 -115.906392) (xy 233.277029 -115.93841)
			(xy 233.313934 -115.976852) (xy 233.32948 -115.998498) (xy 233.337844 -116.009784) (xy 233.359517 -116.027639)
			(xy 233.385231 -116.038922) (xy 233.413046 -116.04278) (xy 233.440861 -116.038922) (xy 233.466575 -116.027639)
			(xy 233.488248 -116.009784) (xy 233.496612 -115.998498) (xy 233.512202 -115.976891) (xy 233.549115 -115.938473)
			(xy 233.59171 -115.906471) (xy 233.638886 -115.881714) (xy 233.689421 -115.864841) (xy 233.742007 -115.856289)
			(xy 233.768646 -115.85575) (xy 233.794627 -115.856347) (xy 233.84595 -115.864483) (xy 233.895368 -115.880546)
			(xy 233.941665 -115.904141) (xy 233.983702 -115.934687) (xy 233.985283 -115.936268) (xy 235.270546 -115.936268)
			(xy 235.274617 -115.880646) (xy 235.286743 -115.826209) (xy 235.306666 -115.774118) (xy 235.333962 -115.725483)
			(xy 235.368048 -115.68134) (xy 235.408197 -115.642631) (xy 235.453555 -115.61018) (xy 235.503155 -115.584679)
			(xy 235.555939 -115.566672) (xy 235.610782 -115.556542) (xy 235.666516 -115.554505) (xy 235.721953 -115.560605)
			(xy 235.77591 -115.574711) (xy 235.827239 -115.596523) (xy 235.874845 -115.625577) (xy 235.917713 -115.661252)
			(xy 235.95493 -115.702789) (xy 235.985703 -115.749302) (xy 236.009375 -115.799799) (xy 236.025443 -115.853206)
			(xy 236.033563 -115.908382) (xy 236.034072 -115.936268) (xy 236.033563 -115.964154) (xy 236.025443 -116.01933)
			(xy 236.009375 -116.072737) (xy 235.985703 -116.123234) (xy 235.95493 -116.169747) (xy 235.917713 -116.211284)
			(xy 235.874845 -116.246959) (xy 235.827239 -116.276013) (xy 235.77591 -116.297825) (xy 235.721953 -116.311931)
			(xy 235.666516 -116.318031) (xy 235.610782 -116.315994) (xy 235.555939 -116.305864) (xy 235.503155 -116.287857)
			(xy 235.453555 -116.262356) (xy 235.408197 -116.229905) (xy 235.368048 -116.191196) (xy 235.333962 -116.147053)
			(xy 235.306666 -116.098418) (xy 235.286743 -116.046327) (xy 235.274617 -115.99189) (xy 235.270546 -115.936268)
			(xy 233.985283 -115.936268) (xy 234.020442 -115.971434) (xy 234.050983 -116.013474) (xy 234.074572 -116.059775)
			(xy 234.090628 -116.109195) (xy 234.098756 -116.160518) (xy 234.098756 -116.212482) (xy 234.090628 -116.263805)
			(xy 234.074572 -116.313225) (xy 234.050983 -116.359526) (xy 234.020442 -116.401566) (xy 233.983702 -116.438313)
			(xy 233.970963 -116.44757) (xy 236.707678 -116.44757) (xy 236.711749 -116.391948) (xy 236.723875 -116.337511)
			(xy 236.743798 -116.28542) (xy 236.771094 -116.236785) (xy 236.80518 -116.192642) (xy 236.845329 -116.153933)
			(xy 236.890687 -116.121482) (xy 236.940287 -116.095981) (xy 236.993071 -116.077974) (xy 237.047914 -116.067844)
			(xy 237.103648 -116.065807) (xy 237.159085 -116.071907) (xy 237.213042 -116.086013) (xy 237.264371 -116.107825)
			(xy 237.311977 -116.136879) (xy 237.354845 -116.172554) (xy 237.392062 -116.214091) (xy 237.422835 -116.260604)
			(xy 237.446507 -116.311101) (xy 237.462575 -116.364508) (xy 237.470695 -116.419684) (xy 237.471204 -116.44757)
			(xy 237.470695 -116.475456) (xy 237.462575 -116.530632) (xy 237.446507 -116.584039) (xy 237.422835 -116.634536)
			(xy 237.392062 -116.681049) (xy 237.354845 -116.722586) (xy 237.311977 -116.758261) (xy 237.264371 -116.787315)
			(xy 237.213042 -116.809127) (xy 237.159085 -116.823233) (xy 237.103648 -116.829333) (xy 237.047914 -116.827296)
			(xy 236.993071 -116.817166) (xy 236.940287 -116.799159) (xy 236.890687 -116.773658) (xy 236.845329 -116.741207)
			(xy 236.80518 -116.702498) (xy 236.771094 -116.658355) (xy 236.743798 -116.60972) (xy 236.723875 -116.557629)
			(xy 236.711749 -116.503192) (xy 236.707678 -116.44757) (xy 233.970963 -116.44757) (xy 233.941665 -116.468859)
			(xy 233.895368 -116.492454) (xy 233.84595 -116.508517) (xy 233.794627 -116.516653) (xy 233.768646 -116.517166)
			(xy 233.742001 -116.516685) (xy 233.689399 -116.508153) (xy 233.638849 -116.491286) (xy 233.591663 -116.466523)
			(xy 233.549064 -116.434505) (xy 233.512158 -116.396063) (xy 233.496612 -116.374418) (xy 233.488248 -116.363132)
			(xy 233.466575 -116.345277) (xy 233.440861 -116.333994) (xy 233.413046 -116.330136) (xy 233.385231 -116.333994)
			(xy 233.359517 -116.345277) (xy 233.337844 -116.363132) (xy 233.32948 -116.374418) (xy 233.3139 -116.396033)
			(xy 233.276984 -116.434449) (xy 233.234387 -116.46645) (xy 233.187209 -116.491206) (xy 233.136673 -116.508077)
			(xy 233.084085 -116.516627) (xy 233.057446 -116.517166) (xy 233.031451 -116.51677) (xy 232.9801 -116.508644)
			(xy 232.930654 -116.492583) (xy 232.884328 -116.468985) (xy 232.842265 -116.43843) (xy 232.8055 -116.40167)
			(xy 232.774939 -116.359611) (xy 232.751334 -116.313289) (xy 232.735267 -116.263844) (xy 232.727133 -116.212495)
			(xy 231.578959 -116.212495) (xy 231.568557 -116.257794) (xy 231.547458 -116.311218) (xy 231.518592 -116.360878)
			(xy 231.482609 -116.405652) (xy 231.461818 -116.425472) (xy 231.454429 -116.433004) (xy 231.445897 -116.452276)
			(xy 231.445308 -116.46281) (xy 231.445308 -116.537486) (xy 231.445829 -116.548037) (xy 231.45437 -116.567332)
			(xy 231.461818 -116.574824) (xy 231.480882 -116.592971) (xy 231.514337 -116.633603) (xy 231.541895 -116.678445)
			(xy 231.563032 -116.726648) (xy 231.577347 -116.777296) (xy 231.58457 -116.829431) (xy 231.585008 -116.855748)
			(xy 231.584567 -116.883) (xy 231.576804 -116.93695) (xy 231.561443 -116.989245) (xy 231.538796 -117.038823)
			(xy 231.509325 -117.084673) (xy 231.485302 -117.112393) (xy 232.727155 -117.112393) (xy 232.727155 -117.060407)
			(xy 232.735289 -117.009061) (xy 232.751355 -116.959619) (xy 232.774958 -116.9133) (xy 232.805517 -116.871244)
			(xy 232.842279 -116.834487) (xy 232.88434 -116.803934) (xy 232.930662 -116.780337) (xy 232.980106 -116.764278)
			(xy 233.031453 -116.756152) (xy 233.057446 -116.755672) (xy 233.084092 -116.756143) (xy 233.136695 -116.764675)
			(xy 233.187246 -116.781542) (xy 233.234433 -116.806308) (xy 233.277031 -116.838328) (xy 233.313935 -116.876773)
			(xy 233.32948 -116.89842) (xy 233.337844 -116.909706) (xy 233.359517 -116.927561) (xy 233.385231 -116.938844)
			(xy 233.413046 -116.942702) (xy 233.440861 -116.938844) (xy 233.466575 -116.927561) (xy 233.488248 -116.909706)
			(xy 233.496612 -116.89842) (xy 233.512179 -116.876796) (xy 233.549099 -116.838383) (xy 233.5917 -116.806385)
			(xy 233.63888 -116.781631) (xy 233.689418 -116.764761) (xy 233.742006 -116.756211) (xy 233.768646 -116.755672)
			(xy 233.794629 -116.756225) (xy 233.845955 -116.764361) (xy 233.895376 -116.780425) (xy 233.941677 -116.804022)
			(xy 233.983716 -116.83457) (xy 234.02046 -116.871319) (xy 234.051002 -116.913362) (xy 234.074593 -116.959666)
			(xy 234.09065 -117.00909) (xy 234.098779 -117.060417) (xy 234.098779 -117.112383) (xy 234.09065 -117.16371)
			(xy 234.074593 -117.213134) (xy 234.051002 -117.259438) (xy 234.02046 -117.301481) (xy 233.983716 -117.33823)
			(xy 233.941677 -117.368778) (xy 233.895376 -117.392375) (xy 233.845955 -117.408439) (xy 233.794629 -117.416575)
			(xy 233.768646 -117.417088) (xy 233.742001 -117.416597) (xy 233.6894 -117.408066) (xy 233.638851 -117.391201)
			(xy 233.591665 -117.366439) (xy 233.549066 -117.334423) (xy 233.512159 -117.295984) (xy 233.496612 -117.27434)
			(xy 233.488248 -117.263054) (xy 233.466575 -117.245199) (xy 233.440861 -117.233916) (xy 233.413046 -117.230058)
			(xy 233.385231 -117.233916) (xy 233.359517 -117.245199) (xy 233.337844 -117.263054) (xy 233.32948 -117.27434)
			(xy 233.313906 -117.295959) (xy 233.276989 -117.334375) (xy 233.23439 -117.366374) (xy 233.187211 -117.391129)
			(xy 233.136674 -117.408) (xy 233.084085 -117.416549) (xy 233.057446 -117.417088) (xy 233.031453 -117.416648)
			(xy 232.980106 -117.408522) (xy 232.930662 -117.392463) (xy 232.88434 -117.368866) (xy 232.842279 -117.338313)
			(xy 232.805517 -117.301556) (xy 232.774958 -117.2595) (xy 232.751355 -117.213181) (xy 232.735289 -117.163739)
			(xy 232.727155 -117.112393) (xy 231.485302 -117.112393) (xy 231.473629 -117.125863) (xy 231.432434 -117.161553)
			(xy 231.386581 -117.191019) (xy 231.337 -117.213659) (xy 231.284703 -117.229014) (xy 231.230752 -117.23677)
			(xy 231.2035 -117.237256) (xy 231.177185 -117.236803) (xy 231.125056 -117.229567) (xy 231.074412 -117.215246)
			(xy 231.026213 -117.194111) (xy 230.98137 -117.166562) (xy 230.940732 -117.133119) (xy 230.922576 -117.114066)
			(xy 230.915056 -117.106662) (xy 230.895775 -117.098136) (xy 230.885238 -117.097556) (xy 230.810562 -117.097556)
			(xy 230.800017 -117.098118) (xy 230.780722 -117.106632) (xy 230.773224 -117.114066) (xy 230.755063 -117.133116)
			(xy 230.714433 -117.166571) (xy 230.669593 -117.194129) (xy 230.621394 -117.215268) (xy 230.570748 -117.229587)
			(xy 230.518616 -117.236815) (xy 230.4923 -117.237256) (xy 230.465051 -117.236722) (xy 230.411107 -117.228967)
			(xy 230.358816 -117.213614) (xy 230.309242 -117.190977) (xy 230.263394 -117.161515) (xy 230.222205 -117.125829)
			(xy 230.186514 -117.084644) (xy 230.157046 -117.0388) (xy 230.134402 -116.989229) (xy 230.119043 -116.93694)
			(xy 230.111281 -116.882997) (xy 230.110792 -116.855748) (xy 230.111227 -116.829433) (xy 230.118469 -116.777303)
			(xy 230.132795 -116.72666) (xy 230.153933 -116.678461) (xy 230.181485 -116.633618) (xy 230.214928 -116.59298)
			(xy 230.233982 -116.574824) (xy 230.241372 -116.567293) (xy 230.249904 -116.54802) (xy 230.250492 -116.537486)
			(xy 230.250492 -116.46281) (xy 230.249973 -116.452259) (xy 230.241431 -116.432964) (xy 230.233982 -116.425472)
			(xy 230.213242 -116.405604) (xy 230.177267 -116.360838) (xy 230.148405 -116.311188) (xy 230.12731 -116.257773)
			(xy 230.114457 -116.2018) (xy 230.110137 -116.144533) (xy 226.668309 -116.144533) (xy 226.671599 -116.188224)
			(xy 226.667279 -116.245502) (xy 226.654424 -116.301485) (xy 226.633324 -116.35491) (xy 226.604456 -116.404569)
			(xy 226.568472 -116.449341) (xy 226.54768 -116.46916) (xy 226.540291 -116.476692) (xy 226.53176 -116.495964)
			(xy 226.53117 -116.506498) (xy 226.53117 -116.581174) (xy 226.531708 -116.591722) (xy 226.540238 -116.611017)
			(xy 226.54768 -116.618512) (xy 226.566731 -116.636673) (xy 226.600189 -116.677301) (xy 226.627749 -116.72214)
			(xy 226.648889 -116.77034) (xy 226.663207 -116.820987) (xy 226.670432 -116.87312) (xy 226.67087 -116.899436)
			(xy 226.670384 -116.926687) (xy 226.662628 -116.980635) (xy 226.647273 -117.03293) (xy 226.624631 -117.082507)
			(xy 226.595165 -117.128357) (xy 226.559474 -117.169548) (xy 226.518283 -117.205239) (xy 226.472433 -117.234705)
			(xy 226.422856 -117.257347) (xy 226.370561 -117.272702) (xy 226.316613 -117.280458) (xy 226.262111 -117.280458)
			(xy 226.208163 -117.272702) (xy 226.155868 -117.257347) (xy 226.106291 -117.234705) (xy 226.060441 -117.205239)
			(xy 226.01925 -117.169548) (xy 225.983559 -117.128357) (xy 225.954093 -117.082507) (xy 225.931451 -117.03293)
			(xy 225.916096 -116.980635) (xy 225.90834 -116.926687) (xy 225.907854 -116.899436) (xy 225.908262 -116.87312)
			(xy 225.915506 -116.820988) (xy 225.929836 -116.770343) (xy 225.950979 -116.722144) (xy 225.978537 -116.677302)
			(xy 226.011987 -116.636666) (xy 226.031044 -116.618512) (xy 226.038434 -116.61098) (xy 226.046967 -116.591708)
			(xy 226.047554 -116.581174) (xy 226.047554 -116.506498) (xy 226.047053 -116.495945) (xy 226.0385 -116.476649)
			(xy 226.031044 -116.46916) (xy 226.010294 -116.449303) (xy 225.974322 -116.404534) (xy 225.945464 -116.354882)
			(xy 225.924372 -116.301465) (xy 225.911521 -116.245492) (xy 225.907203 -116.188224) (xy 224.133352 -116.188224)
			(xy 224.129033 -116.2455) (xy 224.11618 -116.301481) (xy 224.095085 -116.354905) (xy 224.066223 -116.404564)
			(xy 224.030247 -116.449339) (xy 224.009458 -116.46916) (xy 224.002081 -116.476702) (xy 223.99354 -116.495966)
			(xy 223.992948 -116.506498) (xy 223.992948 -116.581174) (xy 223.993464 -116.591726) (xy 224.002007 -116.611022)
			(xy 224.009458 -116.618512) (xy 224.028523 -116.636657) (xy 224.061977 -116.677291) (xy 224.089534 -116.722133)
			(xy 224.11067 -116.770336) (xy 224.124986 -116.820985) (xy 224.13221 -116.873119) (xy 224.132648 -116.899436)
			(xy 224.132162 -116.926687) (xy 224.124406 -116.980635) (xy 224.109051 -117.03293) (xy 224.086409 -117.082507)
			(xy 224.056943 -117.128357) (xy 224.021252 -117.169548) (xy 223.980061 -117.205239) (xy 223.934211 -117.234705)
			(xy 223.884634 -117.257347) (xy 223.832339 -117.272702) (xy 223.778391 -117.280458) (xy 223.723889 -117.280458)
			(xy 223.669941 -117.272702) (xy 223.617646 -117.257347) (xy 223.568069 -117.234705) (xy 223.522219 -117.205239)
			(xy 223.481028 -117.169548) (xy 223.445337 -117.128357) (xy 223.415871 -117.082507) (xy 223.393229 -117.03293)
			(xy 223.377874 -116.980635) (xy 223.370118 -116.926687) (xy 223.369632 -116.899436) (xy 223.370047 -116.87312)
			(xy 223.377291 -116.820989) (xy 223.39162 -116.770345) (xy 223.412762 -116.722146) (xy 223.440318 -116.677304)
			(xy 223.473766 -116.636667) (xy 223.492822 -116.618512) (xy 223.500224 -116.610991) (xy 223.508747 -116.59171)
			(xy 223.509332 -116.581174) (xy 223.509332 -116.506498) (xy 223.508808 -116.495948) (xy 223.500268 -116.476653)
			(xy 223.492822 -116.46916) (xy 223.472068 -116.449305) (xy 223.436089 -116.404539) (xy 223.407225 -116.354887)
			(xy 223.386128 -116.30147) (xy 223.373275 -116.245494) (xy 223.368955 -116.188224) (xy 215.964516 -116.188224)
			(xy 215.964516 -117.294914) (xy 216.75852 -117.294914) (xy 216.75899 -117.2686) (xy 216.766224 -117.216471)
			(xy 216.780542 -117.165828) (xy 216.801674 -117.117629) (xy 216.82922 -117.072786) (xy 216.862658 -117.032146)
			(xy 216.88171 -117.01399) (xy 216.88912 -117.006475) (xy 216.897639 -116.98719) (xy 216.89822 -116.976652)
			(xy 216.89822 -116.901976) (xy 216.897658 -116.89143) (xy 216.889145 -116.872135) (xy 216.88171 -116.864638)
			(xy 216.862633 -116.846504) (xy 216.829178 -116.80587) (xy 216.801621 -116.761025) (xy 216.780486 -116.71282)
			(xy 216.766174 -116.662169) (xy 216.758955 -116.610031) (xy 216.75852 -116.583714) (xy 216.759006 -116.556463)
			(xy 216.766762 -116.502515) (xy 216.782117 -116.45022) (xy 216.804759 -116.400643) (xy 216.834225 -116.354793)
			(xy 216.869916 -116.313602) (xy 216.911107 -116.277911) (xy 216.956957 -116.248445) (xy 217.006534 -116.225803)
			(xy 217.058829 -116.210448) (xy 217.112777 -116.202692) (xy 217.167279 -116.202692) (xy 217.221227 -116.210448)
			(xy 217.273522 -116.225803) (xy 217.323099 -116.248445) (xy 217.368949 -116.277911) (xy 217.41014 -116.313602)
			(xy 217.445831 -116.354793) (xy 217.475297 -116.400643) (xy 217.497939 -116.45022) (xy 217.513294 -116.502515)
			(xy 217.52105 -116.556463) (xy 217.521536 -116.583714) (xy 217.521066 -116.610028) (xy 217.51383 -116.662156)
			(xy 217.499511 -116.712798) (xy 217.478379 -116.760997) (xy 217.450834 -116.80584) (xy 217.417397 -116.846481)
			(xy 217.398346 -116.864638) (xy 217.390933 -116.87215) (xy 217.382413 -116.891437) (xy 217.381836 -116.901976)
			(xy 217.381836 -116.976652) (xy 217.382367 -116.987202) (xy 217.3909 -117.006498) (xy 217.398346 -117.01399)
			(xy 217.417398 -117.032148) (xy 217.450854 -117.072779) (xy 217.478412 -117.117619) (xy 217.499551 -117.165819)
			(xy 217.513869 -117.216465) (xy 217.521096 -117.268598) (xy 217.521536 -117.294914) (xy 218.79052 -117.294914)
			(xy 218.79099 -117.2686) (xy 218.798224 -117.216471) (xy 218.812542 -117.165828) (xy 218.833674 -117.117629)
			(xy 218.86122 -117.072786) (xy 218.894658 -117.032146) (xy 218.91371 -117.01399) (xy 218.92112 -117.006475)
			(xy 218.929639 -116.98719) (xy 218.93022 -116.976652) (xy 218.93022 -116.901976) (xy 218.929658 -116.89143)
			(xy 218.921145 -116.872135) (xy 218.91371 -116.864638) (xy 218.894633 -116.846504) (xy 218.861178 -116.80587)
			(xy 218.833621 -116.761025) (xy 218.812486 -116.71282) (xy 218.798174 -116.662169) (xy 218.790955 -116.610031)
			(xy 218.79052 -116.583714) (xy 218.791006 -116.556463) (xy 218.798762 -116.502515) (xy 218.814117 -116.45022)
			(xy 218.836759 -116.400643) (xy 218.866225 -116.354793) (xy 218.901916 -116.313602) (xy 218.943107 -116.277911)
			(xy 218.988957 -116.248445) (xy 219.038534 -116.225803) (xy 219.090829 -116.210448) (xy 219.144777 -116.202692)
			(xy 219.199279 -116.202692) (xy 219.253227 -116.210448) (xy 219.305522 -116.225803) (xy 219.355099 -116.248445)
			(xy 219.400949 -116.277911) (xy 219.44214 -116.313602) (xy 219.477831 -116.354793) (xy 219.507297 -116.400643)
			(xy 219.529939 -116.45022) (xy 219.545294 -116.502515) (xy 219.55305 -116.556463) (xy 219.553536 -116.583714)
			(xy 219.553066 -116.610028) (xy 219.54583 -116.662156) (xy 219.531511 -116.712798) (xy 219.510379 -116.760997)
			(xy 219.482834 -116.80584) (xy 219.449397 -116.846481) (xy 219.430346 -116.864638) (xy 219.422933 -116.87215)
			(xy 219.414413 -116.891437) (xy 219.413836 -116.901976) (xy 219.413836 -116.976652) (xy 219.414367 -116.987202)
			(xy 219.4229 -117.006498) (xy 219.430346 -117.01399) (xy 219.449398 -117.032148) (xy 219.482854 -117.072779)
			(xy 219.510412 -117.117619) (xy 219.531551 -117.165819) (xy 219.545869 -117.216465) (xy 219.553096 -117.268598)
			(xy 219.553536 -117.294914) (xy 220.82252 -117.294914) (xy 220.82299 -117.2686) (xy 220.830224 -117.216471)
			(xy 220.844542 -117.165828) (xy 220.865674 -117.117629) (xy 220.89322 -117.072786) (xy 220.926658 -117.032146)
			(xy 220.94571 -117.01399) (xy 220.95312 -117.006475) (xy 220.961639 -116.98719) (xy 220.96222 -116.976652)
			(xy 220.96222 -116.901976) (xy 220.961658 -116.89143) (xy 220.953145 -116.872135) (xy 220.94571 -116.864638)
			(xy 220.926633 -116.846504) (xy 220.893178 -116.80587) (xy 220.865621 -116.761025) (xy 220.844486 -116.71282)
			(xy 220.830174 -116.662169) (xy 220.822955 -116.610031) (xy 220.82252 -116.583714) (xy 220.823006 -116.556463)
			(xy 220.830762 -116.502515) (xy 220.846117 -116.45022) (xy 220.868759 -116.400643) (xy 220.898225 -116.354793)
			(xy 220.933916 -116.313602) (xy 220.975107 -116.277911) (xy 221.020957 -116.248445) (xy 221.070534 -116.225803)
			(xy 221.122829 -116.210448) (xy 221.176777 -116.202692) (xy 221.231279 -116.202692) (xy 221.285227 -116.210448)
			(xy 221.337522 -116.225803) (xy 221.387099 -116.248445) (xy 221.432949 -116.277911) (xy 221.47414 -116.313602)
			(xy 221.509831 -116.354793) (xy 221.539297 -116.400643) (xy 221.561939 -116.45022) (xy 221.577294 -116.502515)
			(xy 221.58505 -116.556463) (xy 221.585536 -116.583714) (xy 221.585066 -116.610028) (xy 221.57783 -116.662156)
			(xy 221.563511 -116.712798) (xy 221.542379 -116.760997) (xy 221.514834 -116.80584) (xy 221.481397 -116.846481)
			(xy 221.462346 -116.864638) (xy 221.454933 -116.87215) (xy 221.446413 -116.891437) (xy 221.445836 -116.901976)
			(xy 221.445836 -116.976652) (xy 221.446367 -116.987202) (xy 221.4549 -117.006498) (xy 221.462346 -117.01399)
			(xy 221.481398 -117.032148) (xy 221.514854 -117.072779) (xy 221.542412 -117.117619) (xy 221.563551 -117.165819)
			(xy 221.577869 -117.216465) (xy 221.585096 -117.268598) (xy 221.585536 -117.294914) (xy 221.58505 -117.322165)
			(xy 221.577294 -117.376113) (xy 221.561939 -117.428408) (xy 221.539297 -117.477985) (xy 221.509831 -117.523835)
			(xy 221.47414 -117.565026) (xy 221.432949 -117.600717) (xy 221.387099 -117.630183) (xy 221.337522 -117.652825)
			(xy 221.285227 -117.66818) (xy 221.231279 -117.675936) (xy 221.176777 -117.675936) (xy 221.122829 -117.66818)
			(xy 221.070534 -117.652825) (xy 221.020957 -117.630183) (xy 220.975107 -117.600717) (xy 220.933916 -117.565026)
			(xy 220.898225 -117.523835) (xy 220.868759 -117.477985) (xy 220.846117 -117.428408) (xy 220.830762 -117.376113)
			(xy 220.823006 -117.322165) (xy 220.82252 -117.294914) (xy 219.553536 -117.294914) (xy 219.55305 -117.322165)
			(xy 219.545294 -117.376113) (xy 219.529939 -117.428408) (xy 219.507297 -117.477985) (xy 219.477831 -117.523835)
			(xy 219.44214 -117.565026) (xy 219.400949 -117.600717) (xy 219.355099 -117.630183) (xy 219.305522 -117.652825)
			(xy 219.253227 -117.66818) (xy 219.199279 -117.675936) (xy 219.144777 -117.675936) (xy 219.090829 -117.66818)
			(xy 219.038534 -117.652825) (xy 218.988957 -117.630183) (xy 218.943107 -117.600717) (xy 218.901916 -117.565026)
			(xy 218.866225 -117.523835) (xy 218.836759 -117.477985) (xy 218.814117 -117.428408) (xy 218.798762 -117.376113)
			(xy 218.791006 -117.322165) (xy 218.79052 -117.294914) (xy 217.521536 -117.294914) (xy 217.52105 -117.322165)
			(xy 217.513294 -117.376113) (xy 217.497939 -117.428408) (xy 217.475297 -117.477985) (xy 217.445831 -117.523835)
			(xy 217.41014 -117.565026) (xy 217.368949 -117.600717) (xy 217.323099 -117.630183) (xy 217.273522 -117.652825)
			(xy 217.221227 -117.66818) (xy 217.167279 -117.675936) (xy 217.112777 -117.675936) (xy 217.058829 -117.66818)
			(xy 217.006534 -117.652825) (xy 216.956957 -117.630183) (xy 216.911107 -117.600717) (xy 216.869916 -117.565026)
			(xy 216.834225 -117.523835) (xy 216.804759 -117.477985) (xy 216.782117 -117.428408) (xy 216.766762 -117.376113)
			(xy 216.759006 -117.322165) (xy 216.75852 -117.294914) (xy 215.964516 -117.294914) (xy 215.964516 -117.719348)
			(xy 236.702598 -117.719348) (xy 236.706669 -117.663726) (xy 236.718795 -117.609289) (xy 236.738718 -117.557198)
			(xy 236.766014 -117.508563) (xy 236.8001 -117.46442) (xy 236.840249 -117.425711) (xy 236.885607 -117.39326)
			(xy 236.935207 -117.367759) (xy 236.987991 -117.349752) (xy 237.042834 -117.339622) (xy 237.098568 -117.337585)
			(xy 237.154005 -117.343685) (xy 237.207962 -117.357791) (xy 237.259291 -117.379603) (xy 237.306897 -117.408657)
			(xy 237.349765 -117.444332) (xy 237.386982 -117.485869) (xy 237.417755 -117.532382) (xy 237.441427 -117.582879)
			(xy 237.457495 -117.636286) (xy 237.465615 -117.691462) (xy 237.466124 -117.719348) (xy 237.465615 -117.747234)
			(xy 237.457495 -117.80241) (xy 237.441427 -117.855817) (xy 237.417755 -117.906314) (xy 237.386982 -117.952827)
			(xy 237.349765 -117.994364) (xy 237.306897 -118.030039) (xy 237.259291 -118.059093) (xy 237.207962 -118.080905)
			(xy 237.154005 -118.095011) (xy 237.098568 -118.101111) (xy 237.042834 -118.099074) (xy 236.987991 -118.088944)
			(xy 236.935207 -118.070937) (xy 236.885607 -118.045436) (xy 236.840249 -118.012985) (xy 236.8001 -117.974276)
			(xy 236.766014 -117.930133) (xy 236.738718 -117.881498) (xy 236.718795 -117.829407) (xy 236.706669 -117.77497)
			(xy 236.702598 -117.719348) (xy 215.964516 -117.719348) (xy 215.964516 -117.724428) (xy 215.964996 -117.734765)
			(xy 215.973114 -117.753779) (xy 215.980264 -117.761258) (xy 216.006934 -117.786658) (xy 216.034112 -117.812566)
			(xy 216.04183 -117.819111) (xy 216.060822 -117.82605) (xy 216.070942 -117.826028) (xy 216.071196 -117.826028)
			(xy 216.089992 -117.82552) (xy 216.117243 -117.825983) (xy 216.171191 -117.833738) (xy 216.223486 -117.849092)
			(xy 216.273064 -117.871733) (xy 216.318914 -117.901198) (xy 216.360105 -117.936889) (xy 216.395797 -117.978079)
			(xy 216.425263 -118.023929) (xy 216.447905 -118.073506) (xy 216.46326 -118.125801) (xy 216.470922 -118.179088)
			(xy 230.817926 -118.179088) (xy 230.821997 -118.123466) (xy 230.834123 -118.069029) (xy 230.854046 -118.016938)
			(xy 230.881342 -117.968303) (xy 230.915428 -117.92416) (xy 230.955577 -117.885451) (xy 231.000935 -117.853)
			(xy 231.050535 -117.827499) (xy 231.103319 -117.809492) (xy 231.158162 -117.799362) (xy 231.213896 -117.797325)
			(xy 231.269333 -117.803425) (xy 231.32329 -117.817531) (xy 231.374619 -117.839343) (xy 231.422225 -117.868397)
			(xy 231.465093 -117.904072) (xy 231.50231 -117.945609) (xy 231.533083 -117.992122) (xy 231.556755 -118.042619)
			(xy 231.572823 -118.096026) (xy 231.580943 -118.151202) (xy 231.581452 -118.179088) (xy 231.580943 -118.206974)
			(xy 231.572823 -118.26215) (xy 231.556755 -118.315557) (xy 231.533083 -118.366054) (xy 231.50231 -118.412567)
			(xy 231.465093 -118.454104) (xy 231.422225 -118.489779) (xy 231.374619 -118.518833) (xy 231.32329 -118.540645)
			(xy 231.269333 -118.554751) (xy 231.213896 -118.560851) (xy 231.158162 -118.558814) (xy 231.103319 -118.548684)
			(xy 231.050535 -118.530677) (xy 231.000935 -118.505176) (xy 230.955577 -118.472725) (xy 230.915428 -118.434016)
			(xy 230.881342 -118.389873) (xy 230.854046 -118.341238) (xy 230.834123 -118.289147) (xy 230.821997 -118.23471)
			(xy 230.817926 -118.179088) (xy 216.470922 -118.179088) (xy 216.471017 -118.179749) (xy 216.471017 -118.234251)
			(xy 216.46326 -118.288199) (xy 216.447905 -118.340494) (xy 216.425263 -118.390071) (xy 216.395797 -118.435921)
			(xy 216.360105 -118.477111) (xy 216.318914 -118.512802) (xy 216.273064 -118.542267) (xy 216.223486 -118.564908)
			(xy 216.171191 -118.580262) (xy 216.117243 -118.588017) (xy 216.089992 -118.588536) (xy 216.071196 -118.588028)
			(xy 216.070942 -118.588028) (xy 216.060826 -118.588015) (xy 216.041846 -118.594967) (xy 216.034112 -118.60149)
			(xy 216.006934 -118.627398) (xy 215.980264 -118.652798) (xy 215.973102 -118.660273) (xy 215.964963 -118.679286)
			(xy 215.964516 -118.689628) (xy 215.964516 -118.740428) (xy 215.964516 -118.742206) (xy 215.965147 -118.750579)
			(xy 215.971103 -118.766268) (xy 215.9762 -118.77294) (xy 215.98001 -118.777004) (xy 216.032842 -118.827804)
			(xy 216.036707 -118.831287) (xy 216.045541 -118.836782) (xy 216.050368 -118.838726) (xy 216.059766 -118.842282)
			(xy 216.07018 -118.841774) (xy 216.085928 -118.84152) (xy 216.113176 -118.842008) (xy 216.167117 -118.849767)
			(xy 216.219404 -118.865124) (xy 216.268974 -118.887765) (xy 216.314818 -118.91723) (xy 216.356001 -118.952918)
			(xy 216.391687 -118.994105) (xy 216.421149 -119.039951) (xy 216.443786 -119.089522) (xy 216.459139 -119.141811)
			(xy 216.461978 -119.16156) (xy 232.432604 -119.16156) (xy 232.436675 -119.105938) (xy 232.448801 -119.051501)
			(xy 232.468724 -118.99941) (xy 232.49602 -118.950775) (xy 232.530106 -118.906632) (xy 232.570255 -118.867923)
			(xy 232.615613 -118.835472) (xy 232.665213 -118.809971) (xy 232.717997 -118.791964) (xy 232.77284 -118.781834)
			(xy 232.828574 -118.779797) (xy 232.884011 -118.785897) (xy 232.937968 -118.800003) (xy 232.989297 -118.821815)
			(xy 233.036903 -118.850869) (xy 233.079771 -118.886544) (xy 233.116988 -118.928081) (xy 233.147761 -118.974594)
			(xy 233.171433 -119.025091) (xy 233.187501 -119.078498) (xy 233.195621 -119.133674) (xy 233.19613 -119.16156)
			(xy 233.195621 -119.189446) (xy 233.192697 -119.209312) (xy 233.799124 -119.209312) (xy 233.803195 -119.15369)
			(xy 233.815321 -119.099253) (xy 233.835244 -119.047162) (xy 233.86254 -118.998527) (xy 233.896626 -118.954384)
			(xy 233.936775 -118.915675) (xy 233.982133 -118.883224) (xy 234.031733 -118.857723) (xy 234.084517 -118.839716)
			(xy 234.13936 -118.829586) (xy 234.195094 -118.827549) (xy 234.250531 -118.833649) (xy 234.304488 -118.847755)
			(xy 234.355817 -118.869567) (xy 234.403423 -118.898621) (xy 234.446291 -118.934296) (xy 234.483508 -118.975833)
			(xy 234.514281 -119.022346) (xy 234.537953 -119.072843) (xy 234.554021 -119.12625) (xy 234.55619 -119.140986)
			(xy 235.177836 -119.140986) (xy 235.181907 -119.085364) (xy 235.194033 -119.030927) (xy 235.213956 -118.978836)
			(xy 235.241252 -118.930201) (xy 235.275338 -118.886058) (xy 235.315487 -118.847349) (xy 235.360845 -118.814898)
			(xy 235.410445 -118.789397) (xy 235.463229 -118.77139) (xy 235.518072 -118.76126) (xy 235.573806 -118.759223)
			(xy 235.629243 -118.765323) (xy 235.6832 -118.779429) (xy 235.734529 -118.801241) (xy 235.782135 -118.830295)
			(xy 235.825003 -118.86597) (xy 235.86222 -118.907507) (xy 235.892993 -118.95402) (xy 235.916665 -119.004517)
			(xy 235.932733 -119.057924) (xy 235.940583 -119.111268) (xy 236.70463 -119.111268) (xy 236.708701 -119.055646)
			(xy 236.720827 -119.001209) (xy 236.74075 -118.949118) (xy 236.768046 -118.900483) (xy 236.802132 -118.85634)
			(xy 236.842281 -118.817631) (xy 236.887639 -118.78518) (xy 236.937239 -118.759679) (xy 236.990023 -118.741672)
			(xy 237.044866 -118.731542) (xy 237.1006 -118.729505) (xy 237.156037 -118.735605) (xy 237.209994 -118.749711)
			(xy 237.261323 -118.771523) (xy 237.308929 -118.800577) (xy 237.351797 -118.836252) (xy 237.389014 -118.877789)
			(xy 237.419787 -118.924302) (xy 237.443459 -118.974799) (xy 237.459527 -119.028206) (xy 237.467647 -119.083382)
			(xy 237.468156 -119.111268) (xy 237.467647 -119.139154) (xy 237.459527 -119.19433) (xy 237.443459 -119.247737)
			(xy 237.419787 -119.298234) (xy 237.389014 -119.344747) (xy 237.351797 -119.386284) (xy 237.308929 -119.421959)
			(xy 237.261323 -119.451013) (xy 237.209994 -119.472825) (xy 237.156037 -119.486931) (xy 237.1006 -119.493031)
			(xy 237.044866 -119.490994) (xy 236.990023 -119.480864) (xy 236.937239 -119.462857) (xy 236.887639 -119.437356)
			(xy 236.842281 -119.404905) (xy 236.802132 -119.366196) (xy 236.768046 -119.322053) (xy 236.74075 -119.273418)
			(xy 236.720827 -119.221327) (xy 236.708701 -119.16689) (xy 236.70463 -119.111268) (xy 235.940583 -119.111268)
			(xy 235.940853 -119.1131) (xy 235.941362 -119.140986) (xy 235.940853 -119.168872) (xy 235.932733 -119.224048)
			(xy 235.916665 -119.277455) (xy 235.892993 -119.327952) (xy 235.86222 -119.374465) (xy 235.825003 -119.416002)
			(xy 235.782135 -119.451677) (xy 235.734529 -119.480731) (xy 235.6832 -119.502543) (xy 235.629243 -119.516649)
			(xy 235.573806 -119.522749) (xy 235.518072 -119.520712) (xy 235.463229 -119.510582) (xy 235.410445 -119.492575)
			(xy 235.360845 -119.467074) (xy 235.315487 -119.434623) (xy 235.275338 -119.395914) (xy 235.241252 -119.351771)
			(xy 235.213956 -119.303136) (xy 235.194033 -119.251045) (xy 235.181907 -119.196608) (xy 235.177836 -119.140986)
			(xy 234.55619 -119.140986) (xy 234.562141 -119.181426) (xy 234.56265 -119.209312) (xy 234.562141 -119.237198)
			(xy 234.554021 -119.292374) (xy 234.537953 -119.345781) (xy 234.514281 -119.396278) (xy 234.483508 -119.442791)
			(xy 234.446291 -119.484328) (xy 234.403423 -119.520003) (xy 234.355817 -119.549057) (xy 234.304488 -119.570869)
			(xy 234.250531 -119.584975) (xy 234.195094 -119.591075) (xy 234.13936 -119.589038) (xy 234.084517 -119.578908)
			(xy 234.031733 -119.560901) (xy 233.982133 -119.5354) (xy 233.936775 -119.502949) (xy 233.896626 -119.46424)
			(xy 233.86254 -119.420097) (xy 233.835244 -119.371462) (xy 233.815321 -119.319371) (xy 233.803195 -119.264934)
			(xy 233.799124 -119.209312) (xy 233.192697 -119.209312) (xy 233.187501 -119.244622) (xy 233.171433 -119.298029)
			(xy 233.147761 -119.348526) (xy 233.116988 -119.395039) (xy 233.079771 -119.436576) (xy 233.036903 -119.472251)
			(xy 232.989297 -119.501305) (xy 232.937968 -119.523117) (xy 232.884011 -119.537223) (xy 232.828574 -119.543323)
			(xy 232.77284 -119.541286) (xy 232.717997 -119.531156) (xy 232.665213 -119.513149) (xy 232.615613 -119.487648)
			(xy 232.570255 -119.455197) (xy 232.530106 -119.416488) (xy 232.49602 -119.372345) (xy 232.468724 -119.32371)
			(xy 232.448801 -119.271619) (xy 232.436675 -119.217182) (xy 232.432604 -119.16156) (xy 216.461978 -119.16156)
			(xy 216.466894 -119.195752) (xy 216.466894 -119.250248) (xy 216.459139 -119.304189) (xy 216.443786 -119.356478)
			(xy 216.421149 -119.406049) (xy 216.391687 -119.451895) (xy 216.356001 -119.493082) (xy 216.314818 -119.52877)
			(xy 216.268974 -119.558235) (xy 216.219404 -119.580876) (xy 216.167117 -119.596233) (xy 216.113176 -119.603992)
			(xy 216.085928 -119.604536) (xy 216.07018 -119.604282) (xy 216.059766 -119.603774) (xy 216.050368 -119.60733)
			(xy 216.045527 -119.609244) (xy 216.036698 -119.614754) (xy 216.032842 -119.618252) (xy 215.98001 -119.669052)
			(xy 215.9762 -119.673116) (xy 215.971062 -119.679766) (xy 215.965091 -119.695466) (xy 215.964516 -119.70385)
			(xy 215.964516 -120.779794) (xy 230.950768 -120.779794) (xy 230.954839 -120.724172) (xy 230.966965 -120.669735)
			(xy 230.986888 -120.617644) (xy 231.014184 -120.569009) (xy 231.04827 -120.524866) (xy 231.088419 -120.486157)
			(xy 231.133777 -120.453706) (xy 231.183377 -120.428205) (xy 231.236161 -120.410198) (xy 231.291004 -120.400068)
			(xy 231.346738 -120.398031) (xy 231.402175 -120.404131) (xy 231.456132 -120.418237) (xy 231.507461 -120.440049)
			(xy 231.555067 -120.469103) (xy 231.597935 -120.504778) (xy 231.635152 -120.546315) (xy 231.665925 -120.592828)
			(xy 231.689597 -120.643325) (xy 231.705665 -120.696732) (xy 231.713785 -120.751908) (xy 231.714294 -120.779794)
			(xy 231.713785 -120.80768) (xy 231.705665 -120.862856) (xy 231.689597 -120.916263) (xy 231.665925 -120.96676)
			(xy 231.635152 -121.013273) (xy 231.597935 -121.05481) (xy 231.555067 -121.090485) (xy 231.507461 -121.119539)
			(xy 231.456132 -121.141351) (xy 231.402175 -121.155457) (xy 231.346738 -121.161557) (xy 231.291004 -121.15952)
			(xy 231.236161 -121.14939) (xy 231.183377 -121.131383) (xy 231.133777 -121.105882) (xy 231.088419 -121.073431)
			(xy 231.04827 -121.034722) (xy 231.014184 -120.990579) (xy 230.986888 -120.941944) (xy 230.966965 -120.889853)
			(xy 230.954839 -120.835416) (xy 230.950768 -120.779794) (xy 215.964516 -120.779794) (xy 215.964516 -121.742962)
			(xy 220.459298 -121.742962) (xy 220.463369 -121.68734) (xy 220.475495 -121.632903) (xy 220.495418 -121.580812)
			(xy 220.522714 -121.532177) (xy 220.5568 -121.488034) (xy 220.596949 -121.449325) (xy 220.642307 -121.416874)
			(xy 220.691907 -121.391373) (xy 220.744691 -121.373366) (xy 220.799534 -121.363236) (xy 220.855268 -121.361199)
			(xy 220.910705 -121.367299) (xy 220.964662 -121.381405) (xy 221.005578 -121.398792) (xy 233.551728 -121.398792)
			(xy 233.555799 -121.34317) (xy 233.567925 -121.288733) (xy 233.587848 -121.236642) (xy 233.615144 -121.188007)
			(xy 233.64923 -121.143864) (xy 233.689379 -121.105155) (xy 233.734737 -121.072704) (xy 233.784337 -121.047203)
			(xy 233.837121 -121.029196) (xy 233.891964 -121.019066) (xy 233.947698 -121.017029) (xy 234.003135 -121.023129)
			(xy 234.057092 -121.037235) (xy 234.108421 -121.059047) (xy 234.156027 -121.088101) (xy 234.198895 -121.123776)
			(xy 234.236112 -121.165313) (xy 234.266885 -121.211826) (xy 234.290557 -121.262323) (xy 234.306625 -121.31573)
			(xy 234.314745 -121.370906) (xy 234.315254 -121.398792) (xy 234.567728 -121.398792) (xy 234.571799 -121.34317)
			(xy 234.583925 -121.288733) (xy 234.603848 -121.236642) (xy 234.631144 -121.188007) (xy 234.66523 -121.143864)
			(xy 234.705379 -121.105155) (xy 234.750737 -121.072704) (xy 234.800337 -121.047203) (xy 234.853121 -121.029196)
			(xy 234.907964 -121.019066) (xy 234.963698 -121.017029) (xy 235.019135 -121.023129) (xy 235.073092 -121.037235)
			(xy 235.124421 -121.059047) (xy 235.172027 -121.088101) (xy 235.214895 -121.123776) (xy 235.252112 -121.165313)
			(xy 235.282885 -121.211826) (xy 235.306557 -121.262323) (xy 235.322625 -121.31573) (xy 235.330745 -121.370906)
			(xy 235.331254 -121.398792) (xy 235.583728 -121.398792) (xy 235.587799 -121.34317) (xy 235.599925 -121.288733)
			(xy 235.619848 -121.236642) (xy 235.647144 -121.188007) (xy 235.68123 -121.143864) (xy 235.721379 -121.105155)
			(xy 235.766737 -121.072704) (xy 235.816337 -121.047203) (xy 235.869121 -121.029196) (xy 235.923964 -121.019066)
			(xy 235.979698 -121.017029) (xy 236.035135 -121.023129) (xy 236.089092 -121.037235) (xy 236.140421 -121.059047)
			(xy 236.188027 -121.088101) (xy 236.230895 -121.123776) (xy 236.268112 -121.165313) (xy 236.298885 -121.211826)
			(xy 236.322557 -121.262323) (xy 236.338625 -121.31573) (xy 236.346745 -121.370906) (xy 236.347254 -121.398792)
			(xy 236.346745 -121.426678) (xy 236.338625 -121.481854) (xy 236.322557 -121.535261) (xy 236.298885 -121.585758)
			(xy 236.268112 -121.632271) (xy 236.230895 -121.673808) (xy 236.188027 -121.709483) (xy 236.140421 -121.738537)
			(xy 236.089092 -121.760349) (xy 236.035135 -121.774455) (xy 235.979698 -121.780555) (xy 235.923964 -121.778518)
			(xy 235.869121 -121.768388) (xy 235.816337 -121.750381) (xy 235.766737 -121.72488) (xy 235.721379 -121.692429)
			(xy 235.68123 -121.65372) (xy 235.647144 -121.609577) (xy 235.619848 -121.560942) (xy 235.599925 -121.508851)
			(xy 235.587799 -121.454414) (xy 235.583728 -121.398792) (xy 235.331254 -121.398792) (xy 235.330745 -121.426678)
			(xy 235.322625 -121.481854) (xy 235.306557 -121.535261) (xy 235.282885 -121.585758) (xy 235.252112 -121.632271)
			(xy 235.214895 -121.673808) (xy 235.172027 -121.709483) (xy 235.124421 -121.738537) (xy 235.073092 -121.760349)
			(xy 235.019135 -121.774455) (xy 234.963698 -121.780555) (xy 234.907964 -121.778518) (xy 234.853121 -121.768388)
			(xy 234.800337 -121.750381) (xy 234.750737 -121.72488) (xy 234.705379 -121.692429) (xy 234.66523 -121.65372)
			(xy 234.631144 -121.609577) (xy 234.603848 -121.560942) (xy 234.583925 -121.508851) (xy 234.571799 -121.454414)
			(xy 234.567728 -121.398792) (xy 234.315254 -121.398792) (xy 234.314745 -121.426678) (xy 234.306625 -121.481854)
			(xy 234.290557 -121.535261) (xy 234.266885 -121.585758) (xy 234.236112 -121.632271) (xy 234.198895 -121.673808)
			(xy 234.156027 -121.709483) (xy 234.108421 -121.738537) (xy 234.057092 -121.760349) (xy 234.003135 -121.774455)
			(xy 233.947698 -121.780555) (xy 233.891964 -121.778518) (xy 233.837121 -121.768388) (xy 233.784337 -121.750381)
			(xy 233.734737 -121.72488) (xy 233.689379 -121.692429) (xy 233.64923 -121.65372) (xy 233.615144 -121.609577)
			(xy 233.587848 -121.560942) (xy 233.567925 -121.508851) (xy 233.555799 -121.454414) (xy 233.551728 -121.398792)
			(xy 221.005578 -121.398792) (xy 221.015991 -121.403217) (xy 221.063597 -121.432271) (xy 221.106465 -121.467946)
			(xy 221.143682 -121.509483) (xy 221.174455 -121.555996) (xy 221.198127 -121.606493) (xy 221.214195 -121.6599)
			(xy 221.222315 -121.715076) (xy 221.222824 -121.742962) (xy 221.222315 -121.770848) (xy 221.214195 -121.826024)
			(xy 221.198127 -121.879431) (xy 221.174455 -121.929928) (xy 221.143682 -121.976441) (xy 221.106465 -122.017978)
			(xy 221.063597 -122.053653) (xy 221.015991 -122.082707) (xy 220.964662 -122.104519) (xy 220.910705 -122.118625)
			(xy 220.855268 -122.124725) (xy 220.799534 -122.122688) (xy 220.744691 -122.112558) (xy 220.691907 -122.094551)
			(xy 220.642307 -122.06905) (xy 220.596949 -122.036599) (xy 220.5568 -121.99789) (xy 220.522714 -121.953747)
			(xy 220.495418 -121.905112) (xy 220.475495 -121.853021) (xy 220.463369 -121.798584) (xy 220.459298 -121.742962)
			(xy 215.964516 -121.742962) (xy 215.964516 -122.758962) (xy 218.430854 -122.758962) (xy 218.434925 -122.70334)
			(xy 218.447051 -122.648903) (xy 218.466974 -122.596812) (xy 218.49427 -122.548177) (xy 218.528356 -122.504034)
			(xy 218.568505 -122.465325) (xy 218.613863 -122.432874) (xy 218.663463 -122.407373) (xy 218.716247 -122.389366)
			(xy 218.77109 -122.379236) (xy 218.826824 -122.377199) (xy 218.882261 -122.383299) (xy 218.936218 -122.397405)
			(xy 218.987547 -122.419217) (xy 219.035153 -122.448271) (xy 219.078021 -122.483946) (xy 219.115238 -122.525483)
			(xy 219.146011 -122.571996) (xy 219.169683 -122.622493) (xy 219.185751 -122.6759) (xy 219.193871 -122.731076)
			(xy 219.19438 -122.758962) (xy 219.193871 -122.786848) (xy 219.185751 -122.842024) (xy 219.169683 -122.895431)
			(xy 219.146011 -122.945928) (xy 219.115238 -122.992441) (xy 219.078021 -123.033978) (xy 219.035153 -123.069653)
			(xy 218.987547 -123.098707) (xy 218.936218 -123.120519) (xy 218.882261 -123.134625) (xy 218.826824 -123.140725)
			(xy 218.77109 -123.138688) (xy 218.716247 -123.128558) (xy 218.663463 -123.110551) (xy 218.613863 -123.08505)
			(xy 218.568505 -123.052599) (xy 218.528356 -123.01389) (xy 218.49427 -122.969747) (xy 218.466974 -122.921112)
			(xy 218.447051 -122.869021) (xy 218.434925 -122.814584) (xy 218.430854 -122.758962) (xy 215.964516 -122.758962)
			(xy 215.964516 -123.774962) (xy 218.430854 -123.774962) (xy 218.434925 -123.71934) (xy 218.447051 -123.664903)
			(xy 218.466974 -123.612812) (xy 218.49427 -123.564177) (xy 218.528356 -123.520034) (xy 218.568505 -123.481325)
			(xy 218.613863 -123.448874) (xy 218.663463 -123.423373) (xy 218.716247 -123.405366) (xy 218.77109 -123.395236)
			(xy 218.826824 -123.393199) (xy 218.882261 -123.399299) (xy 218.936218 -123.413405) (xy 218.987547 -123.435217)
			(xy 219.035153 -123.464271) (xy 219.078021 -123.499946) (xy 219.115238 -123.541483) (xy 219.146011 -123.587996)
			(xy 219.169683 -123.638493) (xy 219.185751 -123.6919) (xy 219.193871 -123.747076) (xy 219.19438 -123.774962)
			(xy 220.586298 -123.774962) (xy 220.590369 -123.71934) (xy 220.602495 -123.664903) (xy 220.622418 -123.612812)
			(xy 220.649714 -123.564177) (xy 220.6838 -123.520034) (xy 220.723949 -123.481325) (xy 220.769307 -123.448874)
			(xy 220.818907 -123.423373) (xy 220.871691 -123.405366) (xy 220.926534 -123.395236) (xy 220.982268 -123.393199)
			(xy 221.037705 -123.399299) (xy 221.091662 -123.413405) (xy 221.142991 -123.435217) (xy 221.190597 -123.464271)
			(xy 221.233465 -123.499946) (xy 221.241599 -123.509024) (xy 223.888298 -123.509024) (xy 223.892369 -123.453402)
			(xy 223.904495 -123.398965) (xy 223.924418 -123.346874) (xy 223.951714 -123.298239) (xy 223.9858 -123.254096)
			(xy 224.025949 -123.215387) (xy 224.071307 -123.182936) (xy 224.120907 -123.157435) (xy 224.173691 -123.139428)
			(xy 224.228534 -123.129298) (xy 224.284268 -123.127261) (xy 224.339705 -123.133361) (xy 224.393662 -123.147467)
			(xy 224.444991 -123.169279) (xy 224.492597 -123.198333) (xy 224.535465 -123.234008) (xy 224.572682 -123.275545)
			(xy 224.603455 -123.322058) (xy 224.627127 -123.372555) (xy 224.643195 -123.425962) (xy 224.651315 -123.481138)
			(xy 224.651824 -123.509024) (xy 224.651606 -123.520962) (xy 226.047298 -123.520962) (xy 226.051369 -123.46534)
			(xy 226.063495 -123.410903) (xy 226.083418 -123.358812) (xy 226.110714 -123.310177) (xy 226.1448 -123.266034)
			(xy 226.184949 -123.227325) (xy 226.230307 -123.194874) (xy 226.279907 -123.169373) (xy 226.332691 -123.151366)
			(xy 226.387534 -123.141236) (xy 226.443268 -123.139199) (xy 226.498705 -123.145299) (xy 226.552662 -123.159405)
			(xy 226.603991 -123.181217) (xy 226.651597 -123.210271) (xy 226.694465 -123.245946) (xy 226.731682 -123.287483)
			(xy 226.762455 -123.333996) (xy 226.786127 -123.384493) (xy 226.802195 -123.4379) (xy 226.810315 -123.493076)
			(xy 226.810824 -123.520962) (xy 226.810315 -123.548848) (xy 226.802195 -123.604024) (xy 226.786127 -123.657431)
			(xy 226.762455 -123.707928) (xy 226.731682 -123.754441) (xy 226.694465 -123.795978) (xy 226.651597 -123.831653)
			(xy 226.603991 -123.860707) (xy 226.552662 -123.882519) (xy 226.498705 -123.896625) (xy 226.443268 -123.902725)
			(xy 226.387534 -123.900688) (xy 226.332691 -123.890558) (xy 226.279907 -123.872551) (xy 226.230307 -123.84705)
			(xy 226.184949 -123.814599) (xy 226.1448 -123.77589) (xy 226.110714 -123.731747) (xy 226.083418 -123.683112)
			(xy 226.063495 -123.631021) (xy 226.051369 -123.576584) (xy 226.047298 -123.520962) (xy 224.651606 -123.520962)
			(xy 224.651315 -123.53691) (xy 224.643195 -123.592086) (xy 224.627127 -123.645493) (xy 224.603455 -123.69599)
			(xy 224.572682 -123.742503) (xy 224.535465 -123.78404) (xy 224.492597 -123.819715) (xy 224.444991 -123.848769)
			(xy 224.393662 -123.870581) (xy 224.339705 -123.884687) (xy 224.284268 -123.890787) (xy 224.228534 -123.88875)
			(xy 224.173691 -123.87862) (xy 224.120907 -123.860613) (xy 224.071307 -123.835112) (xy 224.025949 -123.802661)
			(xy 223.9858 -123.763952) (xy 223.951714 -123.719809) (xy 223.924418 -123.671174) (xy 223.904495 -123.619083)
			(xy 223.892369 -123.564646) (xy 223.888298 -123.509024) (xy 221.241599 -123.509024) (xy 221.270682 -123.541483)
			(xy 221.301455 -123.587996) (xy 221.325127 -123.638493) (xy 221.341195 -123.6919) (xy 221.349315 -123.747076)
			(xy 221.349824 -123.774962) (xy 221.349315 -123.802848) (xy 221.341195 -123.858024) (xy 221.325127 -123.911431)
			(xy 221.301455 -123.961928) (xy 221.270682 -124.008441) (xy 221.233465 -124.049978) (xy 221.190597 -124.085653)
			(xy 221.142991 -124.114707) (xy 221.091662 -124.136519) (xy 221.037705 -124.150625) (xy 220.982268 -124.156725)
			(xy 220.926534 -124.154688) (xy 220.871691 -124.144558) (xy 220.818907 -124.126551) (xy 220.769307 -124.10105)
			(xy 220.723949 -124.068599) (xy 220.6838 -124.02989) (xy 220.649714 -123.985747) (xy 220.622418 -123.937112)
			(xy 220.602495 -123.885021) (xy 220.590369 -123.830584) (xy 220.586298 -123.774962) (xy 219.19438 -123.774962)
			(xy 219.193871 -123.802848) (xy 219.185751 -123.858024) (xy 219.169683 -123.911431) (xy 219.146011 -123.961928)
			(xy 219.115238 -124.008441) (xy 219.078021 -124.049978) (xy 219.035153 -124.085653) (xy 218.987547 -124.114707)
			(xy 218.936218 -124.136519) (xy 218.882261 -124.150625) (xy 218.826824 -124.156725) (xy 218.77109 -124.154688)
			(xy 218.716247 -124.144558) (xy 218.663463 -124.126551) (xy 218.613863 -124.10105) (xy 218.568505 -124.068599)
			(xy 218.528356 -124.02989) (xy 218.49427 -123.985747) (xy 218.466974 -123.937112) (xy 218.447051 -123.885021)
			(xy 218.434925 -123.830584) (xy 218.430854 -123.774962) (xy 215.964516 -123.774962) (xy 215.964516 -125.738128)
			(xy 217.592908 -125.738128) (xy 217.596979 -125.682506) (xy 217.609105 -125.628069) (xy 217.629028 -125.575978)
			(xy 217.656324 -125.527343) (xy 217.69041 -125.4832) (xy 217.730559 -125.444491) (xy 217.775917 -125.41204)
			(xy 217.825517 -125.386539) (xy 217.878301 -125.368532) (xy 217.933144 -125.358402) (xy 217.988878 -125.356365)
			(xy 218.044315 -125.362465) (xy 218.098272 -125.376571) (xy 218.149601 -125.398383) (xy 218.197207 -125.427437)
			(xy 218.240075 -125.463112) (xy 218.277292 -125.504649) (xy 218.308065 -125.551162) (xy 218.331737 -125.601659)
			(xy 218.347805 -125.655066) (xy 218.355925 -125.710242) (xy 218.356434 -125.738128) (xy 218.355925 -125.766014)
			(xy 218.347805 -125.82119) (xy 218.331737 -125.874597) (xy 218.308065 -125.925094) (xy 218.277292 -125.971607)
			(xy 218.240075 -126.013144) (xy 218.197207 -126.048819) (xy 218.149601 -126.077873) (xy 218.098272 -126.099685)
			(xy 218.044315 -126.113791) (xy 217.988878 -126.119891) (xy 217.933144 -126.117854) (xy 217.878301 -126.107724)
			(xy 217.825517 -126.089717) (xy 217.775917 -126.064216) (xy 217.730559 -126.031765) (xy 217.69041 -125.993056)
			(xy 217.656324 -125.948913) (xy 217.629028 -125.900278) (xy 217.609105 -125.848187) (xy 217.596979 -125.79375)
			(xy 217.592908 -125.738128) (xy 215.964516 -125.738128) (xy 215.964516 -125.870716) (xy 215.965532 -125.880368)
			(xy 215.967162 -125.887611) (xy 215.974006 -125.900777) (xy 215.978994 -125.906276) (xy 215.99525 -125.922532)
			(xy 216.002097 -125.92993) (xy 216.009827 -125.948529) (xy 216.010236 -125.9586) (xy 216.010236 -130.121406)
			(xy 216.010661 -130.131475) (xy 216.018381 -130.150075) (xy 216.025222 -130.157474) (xy 217.203274 -131.335526)
			(xy 217.226172 -131.35909) (xy 217.267126 -131.410474) (xy 217.302074 -131.466117) (xy 217.330578 -131.52532)
			(xy 217.352279 -131.58734) (xy 217.366906 -131.651399) (xy 217.374274 -131.716692) (xy 217.374724 -131.749546)
			(xy 217.374724 -139.294108) (xy 217.375149 -139.304177) (xy 217.382868 -139.322777) (xy 217.38971 -139.330176)
		)
		(stroke
			(width 0)
			(type solid)
		)
		(fill yes)
		(layer "In7.Cu")
		(net "GND")
	)
	(gr_poly
		(pts
			(xy 163.657788 -289.10788) (xy 163.667809 -289.107462) (xy 163.686327 -289.099793) (xy 163.700498 -289.08562)
			(xy 163.708164 -289.067101) (xy 163.708588 -289.05708) (xy 163.708588 -289.045142) (xy 163.698174 -289.02406)
			(xy 163.688776 -289.016948) (xy 163.670587 -289.002385) (xy 163.638418 -288.968679) (xy 163.611737 -288.930481)
			(xy 163.591162 -288.888677) (xy 163.577171 -288.844234) (xy 163.570086 -288.798183) (xy 163.56965 -288.774886)
			(xy 163.570172 -288.749631) (xy 163.578485 -288.699809) (xy 163.594886 -288.652035) (xy 163.618927 -288.607612)
			(xy 163.649951 -288.567752) (xy 163.687113 -288.533542) (xy 163.729399 -288.505916) (xy 163.775655 -288.485626)
			(xy 163.82462 -288.473226) (xy 163.874958 -288.469055) (xy 163.925296 -288.473226) (xy 163.974261 -288.485626)
			(xy 164.020517 -288.505916) (xy 164.062803 -288.533542) (xy 164.099965 -288.567752) (xy 164.130989 -288.607612)
			(xy 164.15503 -288.652035) (xy 164.171431 -288.699809) (xy 164.179744 -288.749631) (xy 164.180266 -288.774886)
			(xy 164.179864 -288.797996) (xy 164.172939 -288.843693) (xy 164.159199 -288.887823) (xy 164.138961 -288.929375)
			(xy 164.126164 -288.948622) (xy 164.118036 -288.960306) (xy 164.116258 -288.9885) (xy 164.164772 -289.080702)
			(xy 164.169422 -289.088685) (xy 164.183244 -289.100921) (xy 164.200501 -289.107476) (xy 164.20973 -289.10788)
			(xy 164.912802 -289.10788) (xy 164.922872 -289.107456) (xy 164.941474 -289.099739) (xy 164.94887 -289.092894)
			(xy 165.12286 -288.918904) (xy 165.129711 -288.911508) (xy 165.137454 -288.892909) (xy 165.137846 -288.882836)
			(xy 165.137846 -288.172652) (xy 165.137496 -288.163668) (xy 165.13128 -288.14681) (xy 165.119603 -288.133155)
			(xy 165.111938 -288.128456) (xy 165.02253 -288.078164) (xy 164.995352 -288.078672) (xy 164.983414 -288.085784)
			(xy 164.959348 -288.099715) (xy 164.9074 -288.119537) (xy 164.852719 -288.129607) (xy 164.824918 -288.130234)
			(xy 164.799657 -288.129743) (xy 164.749824 -288.12143) (xy 164.702039 -288.105028) (xy 164.657606 -288.080984)
			(xy 164.617736 -288.049954) (xy 164.583518 -288.012785) (xy 164.555884 -287.970491) (xy 164.535589 -287.924225)
			(xy 164.523186 -287.875249) (xy 164.519014 -287.8249) (xy 164.523186 -287.774551) (xy 164.535589 -287.725575)
			(xy 164.555884 -287.679309) (xy 164.583518 -287.637015) (xy 164.617736 -287.599846) (xy 164.657606 -287.568816)
			(xy 164.702039 -287.544772) (xy 164.749824 -287.52837) (xy 164.799657 -287.520057) (xy 164.824918 -287.519618)
			(xy 164.84708 -287.519994) (xy 164.890943 -287.526368) (xy 164.912294 -287.532318) (xy 164.925502 -287.536382)
			(xy 164.95268 -287.529524) (xy 164.962586 -287.519618) (xy 164.969301 -287.512185) (xy 164.976934 -287.493689)
			(xy 164.976927 -287.473679) (xy 164.969282 -287.455187) (xy 164.962586 -287.447736) (xy 164.875464 -287.360614)
			(xy 164.868064 -287.353772) (xy 164.849466 -287.346048) (xy 164.839396 -287.345628) (xy 164.650166 -287.345628)
			(xy 164.645086 -287.353756) (xy 164.304726 -287.353756) (xy 164.286184 -287.346136) (xy 164.285676 -287.345628)
			(xy 164.277802 -287.345628) (xy 164.267731 -287.345206) (xy 164.249123 -287.337495) (xy 164.241734 -287.330642)
			(xy 164.14115 -287.230058) (xy 164.134305 -287.22266) (xy 164.126578 -287.204061) (xy 164.126164 -287.19399)
			(xy 164.126164 -287.186116) (xy 164.075872 -287.135824) (xy 164.041836 -287.131252) (xy 164.02685 -287.139888)
			(xy 164.003559 -287.152559) (xy 163.95369 -287.17056) (xy 163.901467 -287.179702) (xy 163.874958 -287.180274)
			(xy 163.849708 -287.179749) (xy 163.799897 -287.171431) (xy 163.752134 -287.155028) (xy 163.707723 -287.130988)
			(xy 163.667873 -287.099967) (xy 163.633672 -287.06281) (xy 163.606053 -287.020532) (xy 163.585769 -286.974284)
			(xy 163.573373 -286.925328) (xy 163.569203 -286.875) (xy 163.573373 -286.824672) (xy 163.585769 -286.775716)
			(xy 163.606053 -286.729468) (xy 163.633672 -286.68719) (xy 163.667873 -286.650033) (xy 163.707723 -286.619012)
			(xy 163.752134 -286.594972) (xy 163.799897 -286.578569) (xy 163.849708 -286.570251) (xy 163.874958 -286.569658)
			(xy 163.898384 -286.570107) (xy 163.944689 -286.577245) (xy 163.96716 -286.583882) (xy 163.978844 -286.587692)
			(xy 164.002466 -286.583628) (xy 164.078666 -286.528002) (xy 164.087882 -286.520386) (xy 164.098598 -286.499049)
			(xy 164.09924 -286.487108) (xy 164.09924 -286.31261) (xy 164.09859 -286.300678) (xy 164.087852 -286.279362)
			(xy 164.078666 -286.271716) (xy 164.002466 -286.21609) (xy 163.978844 -286.212026) (xy 163.96716 -286.215836)
			(xy 163.944697 -286.222509) (xy 163.898388 -286.229661) (xy 163.874958 -286.23006) (xy 163.849709 -286.229535)
			(xy 163.7999 -286.221217) (xy 163.75214 -286.204815) (xy 163.70773 -286.180777) (xy 163.667883 -286.149757)
			(xy 163.633683 -286.112602) (xy 163.606066 -286.070325) (xy 163.585782 -286.024079) (xy 163.573387 -285.975126)
			(xy 163.569217 -285.9248) (xy 163.573387 -285.874474) (xy 163.585782 -285.825521) (xy 163.606066 -285.779275)
			(xy 163.633683 -285.736998) (xy 163.667883 -285.699843) (xy 163.70773 -285.668823) (xy 163.75214 -285.644785)
			(xy 163.7999 -285.628383) (xy 163.849709 -285.620065) (xy 163.874958 -285.619444) (xy 163.898384 -285.619893)
			(xy 163.94469 -285.627031) (xy 163.96716 -285.633668) (xy 163.978844 -285.637478) (xy 164.002466 -285.633414)
			(xy 164.078666 -285.577788) (xy 164.08788 -285.570171) (xy 164.09859 -285.548834) (xy 164.09924 -285.536894)
			(xy 164.09924 -285.36265) (xy 164.098598 -285.350713) (xy 164.08787 -285.329384) (xy 164.078666 -285.321756)
			(xy 164.002466 -285.26613) (xy 163.978844 -285.262066) (xy 163.96716 -285.265876) (xy 163.944697 -285.272548)
			(xy 163.898387 -285.279699) (xy 163.874958 -285.2801) (xy 163.849706 -285.279575) (xy 163.799891 -285.271256)
			(xy 163.752124 -285.254852) (xy 163.707708 -285.23081) (xy 163.667855 -285.199786) (xy 163.633652 -285.162626)
			(xy 163.60603 -285.120344) (xy 163.585744 -285.074092) (xy 163.573347 -285.025132) (xy 163.569177 -284.9748)
			(xy 163.573347 -284.924468) (xy 163.585744 -284.875508) (xy 163.60603 -284.829256) (xy 163.633652 -284.786974)
			(xy 163.667855 -284.749814) (xy 163.707708 -284.71879) (xy 163.752124 -284.694748) (xy 163.799891 -284.678344)
			(xy 163.849706 -284.670025) (xy 163.874958 -284.669484) (xy 163.898384 -284.669932) (xy 163.94469 -284.677069)
			(xy 163.96716 -284.683708) (xy 163.978844 -284.687518) (xy 164.002466 -284.683454) (xy 164.078666 -284.627828)
			(xy 164.087887 -284.620214) (xy 164.098613 -284.598877) (xy 164.09924 -284.586934) (xy 164.09924 -284.41269)
			(xy 164.098607 -284.400749) (xy 164.087888 -284.379406) (xy 164.078666 -284.371796) (xy 164.002466 -284.31617)
			(xy 163.978844 -284.312106) (xy 163.96716 -284.315916) (xy 163.944697 -284.322588) (xy 163.898387 -284.329737)
			(xy 163.874958 -284.33014) (xy 163.849702 -284.329615) (xy 163.799881 -284.321295) (xy 163.752108 -284.304889)
			(xy 163.707687 -284.280844) (xy 163.667828 -284.249816) (xy 163.63362 -284.212651) (xy 163.605995 -284.170363)
			(xy 163.585707 -284.124105) (xy 163.573308 -284.075139) (xy 163.569137 -284.0248) (xy 163.573308 -283.974461)
			(xy 163.585707 -283.925495) (xy 163.605995 -283.879237) (xy 163.63362 -283.836949) (xy 163.667828 -283.799784)
			(xy 163.707687 -283.768756) (xy 163.752108 -283.744711) (xy 163.799881 -283.728305) (xy 163.849702 -283.719985)
			(xy 163.874958 -283.719524) (xy 163.898384 -283.719972) (xy 163.94469 -283.72711) (xy 163.96716 -283.733748)
			(xy 163.978844 -283.737558) (xy 164.002466 -283.733494) (xy 164.078666 -283.677868) (xy 164.087894 -283.670257)
			(xy 164.098637 -283.64892) (xy 164.09924 -283.636974) (xy 164.09924 -283.46273) (xy 164.098594 -283.450795)
			(xy 164.087861 -283.429473) (xy 164.078666 -283.421836) (xy 164.002466 -283.36621) (xy 163.978844 -283.362146)
			(xy 163.96716 -283.365956) (xy 163.944697 -283.372629) (xy 163.898388 -283.37978) (xy 163.874958 -283.38018)
			(xy 163.849707 -283.379655) (xy 163.799895 -283.371337) (xy 163.752132 -283.354934) (xy 163.707719 -283.330893)
			(xy 163.667869 -283.299872) (xy 163.633668 -283.262714) (xy 163.606048 -283.220434) (xy 163.585763 -283.174186)
			(xy 163.573367 -283.125229) (xy 163.569197 -283.0749) (xy 163.573367 -283.024571) (xy 163.585763 -282.975614)
			(xy 163.606048 -282.929366) (xy 163.633668 -282.887086) (xy 163.667869 -282.849928) (xy 163.707719 -282.818907)
			(xy 163.752132 -282.794866) (xy 163.799895 -282.778463) (xy 163.849707 -282.770145) (xy 163.874958 -282.769564)
			(xy 163.898384 -282.770013) (xy 163.944689 -282.777151) (xy 163.96716 -282.783788) (xy 163.978844 -282.787598)
			(xy 164.002466 -282.783534) (xy 164.078666 -282.727908) (xy 164.087884 -282.720293) (xy 164.098602 -282.698955)
			(xy 164.09924 -282.687014) (xy 164.09924 -281.83967) (xy 164.099068 -281.832503) (xy 164.095192 -281.818708)
			(xy 164.09162 -281.812492) (xy 164.076915 -281.787953) (xy 164.05596 -281.734729) (xy 164.045293 -281.678532)
			(xy 164.04463 -281.649932) (xy 164.045306 -281.621335) (xy 164.056001 -281.565149) (xy 164.07695 -281.511929)
			(xy 164.09162 -281.487372) (xy 164.095175 -281.481149) (xy 164.09905 -281.467358) (xy 164.09924 -281.460194)
			(xy 164.09924 -280.889456) (xy 164.099066 -280.88229) (xy 164.095187 -280.868497) (xy 164.09162 -280.862278)
			(xy 164.076916 -280.837739) (xy 164.055964 -280.784515) (xy 164.045299 -280.728318) (xy 164.04463 -280.699718)
			(xy 164.045298 -280.671119) (xy 164.055979 -280.614926) (xy 164.076916 -280.561696) (xy 164.09162 -280.537158)
			(xy 164.095174 -280.530935) (xy 164.099045 -280.517143) (xy 164.09924 -280.50998) (xy 164.09924 -279.939496)
			(xy 164.099071 -279.932328) (xy 164.095202 -279.918529) (xy 164.09162 -279.912318) (xy 164.076912 -279.88778)
			(xy 164.055954 -279.834556) (xy 164.045282 -279.778359) (xy 164.04463 -279.749758) (xy 164.045304 -279.721161)
			(xy 164.055995 -279.664973) (xy 164.07694 -279.61175) (xy 164.09162 -279.587198) (xy 164.095166 -279.580973)
			(xy 164.099021 -279.567182) (xy 164.09924 -279.56002) (xy 164.09924 -278.989536) (xy 164.099077 -278.982366)
			(xy 164.095216 -278.968562) (xy 164.09162 -278.962358) (xy 164.076909 -278.937821) (xy 164.055943 -278.884598)
			(xy 164.045264 -278.8284) (xy 164.04463 -278.799798) (xy 164.0453 -278.7712) (xy 164.055984 -278.715008)
			(xy 164.076924 -278.661781) (xy 164.09162 -278.637238) (xy 164.095171 -278.631014) (xy 164.099037 -278.617223)
			(xy 164.09924 -278.61006) (xy 164.09924 -278.039576) (xy 164.099068 -278.032409) (xy 164.095194 -278.018613)
			(xy 164.09162 -278.012398) (xy 164.076914 -277.98786) (xy 164.055959 -277.934635) (xy 164.045291 -277.878438)
			(xy 164.04463 -277.849838) (xy 164.045306 -277.821241) (xy 164.056 -277.765055) (xy 164.076948 -277.711834)
			(xy 164.09162 -277.687278) (xy 164.09543 -277.680928) (xy 164.09924 -277.667466) (xy 164.09924 -277.63851)
			(xy 164.09938 -277.63362) (xy 164.101307 -277.624031) (xy 164.10305 -277.61946) (xy 164.122354 -277.571708)
			(xy 164.124129 -277.56708) (xy 164.12605 -277.557359) (xy 164.126164 -277.552404) (xy 164.126164 -277.160482)
			(xy 164.125737 -277.150414) (xy 164.118014 -277.131818) (xy 164.111178 -277.124414) (xy 163.829238 -276.842474)
			(xy 163.798504 -276.836378) (xy 163.78428 -276.842728) (xy 163.738306 -276.861016) (xy 163.728987 -276.864997)
			(xy 163.714259 -276.878892) (xy 163.706021 -276.897388) (xy 163.705286 -276.907498) (xy 163.704177 -276.932341)
			(xy 163.6949 -276.981193) (xy 163.677831 -277.027897) (xy 163.653421 -277.071219) (xy 163.622315 -277.110014)
			(xy 163.585335 -277.143258) (xy 163.543458 -277.170071) (xy 163.497791 -277.189746) (xy 163.449539 -277.201763)
			(xy 163.399978 -277.205805) (xy 163.350417 -277.201763) (xy 163.302165 -277.189746) (xy 163.256498 -277.170071)
			(xy 163.214621 -277.143258) (xy 163.177641 -277.110014) (xy 163.146535 -277.071219) (xy 163.122125 -277.027897)
			(xy 163.105056 -276.981193) (xy 163.095779 -276.932341) (xy 163.09467 -276.907498) (xy 163.094038 -276.897362)
			(xy 163.085814 -276.878811) (xy 163.071024 -276.864918) (xy 163.06165 -276.861016) (xy 163.021816 -276.84572)
			(xy 162.944744 -276.809087) (xy 162.907726 -276.787864) (xy 162.89528 -276.780752) (xy 162.867594 -276.781006)
			(xy 162.766756 -276.842728) (xy 162.753802 -276.867366) (xy 162.754818 -276.88159) (xy 162.755326 -276.899878)
			(xy 162.754804 -276.925133) (xy 162.746491 -276.974955) (xy 162.73009 -277.022729) (xy 162.706049 -277.067152)
			(xy 162.675025 -277.107012) (xy 162.637863 -277.141222) (xy 162.595577 -277.168848) (xy 162.549321 -277.189138)
			(xy 162.500356 -277.201538) (xy 162.450018 -277.205709) (xy 162.39968 -277.201538) (xy 162.350715 -277.189138)
			(xy 162.304459 -277.168848) (xy 162.262173 -277.141222) (xy 162.225011 -277.107012) (xy 162.193987 -277.067152)
			(xy 162.169946 -277.022729) (xy 162.153545 -276.974955) (xy 162.145232 -276.925133) (xy 162.14471 -276.899878)
			(xy 162.145218 -276.88159) (xy 162.146234 -276.867366) (xy 162.13328 -276.842728) (xy 162.032442 -276.781006)
			(xy 162.004756 -276.780752) (xy 161.99231 -276.787864) (xy 161.955292 -276.809087) (xy 161.878219 -276.845717)
			(xy 161.838386 -276.861016) (xy 161.829056 -276.864988) (xy 161.814305 -276.878877) (xy 161.806052 -276.897381)
			(xy 161.805366 -276.907498) (xy 161.804257 -276.932341) (xy 161.79498 -276.981193) (xy 161.777911 -277.027897)
			(xy 161.753501 -277.071219) (xy 161.722395 -277.110014) (xy 161.685415 -277.143258) (xy 161.643538 -277.170071)
			(xy 161.597871 -277.189746) (xy 161.549619 -277.201763) (xy 161.500058 -277.205805) (xy 161.450497 -277.201763)
			(xy 161.402245 -277.189746) (xy 161.356578 -277.170071) (xy 161.314701 -277.143258) (xy 161.277721 -277.110014)
			(xy 161.246615 -277.071219) (xy 161.222205 -277.027897) (xy 161.205136 -276.981193) (xy 161.195859 -276.932341)
			(xy 161.19475 -276.907498) (xy 161.194117 -276.897363) (xy 161.185892 -276.878815) (xy 161.1711 -276.864927)
			(xy 161.16173 -276.861016) (xy 161.121828 -276.845734) (xy 161.044625 -276.809108) (xy 161.007552 -276.787864)
			(xy 160.995106 -276.780498) (xy 160.96742 -276.780752) (xy 160.866582 -276.842474) (xy 160.853628 -276.867366)
			(xy 160.854644 -276.88159) (xy 160.855152 -276.899878) (xy 160.85463 -276.925133) (xy 160.846317 -276.974955)
			(xy 160.829916 -277.022729) (xy 160.805875 -277.067152) (xy 160.774851 -277.107012) (xy 160.737689 -277.141222)
			(xy 160.695403 -277.168848) (xy 160.649147 -277.189138) (xy 160.600182 -277.201538) (xy 160.549844 -277.205709)
			(xy 160.499506 -277.201538) (xy 160.450541 -277.189138) (xy 160.404285 -277.168848) (xy 160.361999 -277.141222)
			(xy 160.324837 -277.107012) (xy 160.293813 -277.067152) (xy 160.269772 -277.022729) (xy 160.253371 -276.974955)
			(xy 160.245058 -276.925133) (xy 160.244536 -276.899878) (xy 160.245155 -276.871254) (xy 160.255758 -276.814997)
			(xy 160.265618 -276.788118) (xy 160.270444 -276.776434) (xy 160.267396 -276.751542) (xy 160.21304 -276.671532)
			(xy 160.20552 -276.661626) (xy 160.183551 -276.650024) (xy 160.17113 -276.649434) (xy 159.978598 -276.649434)
			(xy 159.966182 -276.650053) (xy 159.944219 -276.66164) (xy 159.936688 -276.671532) (xy 159.882332 -276.751542)
			(xy 159.879284 -276.776434) (xy 159.88411 -276.788118) (xy 159.893965 -276.815) (xy 159.904584 -276.871254)
			(xy 159.905192 -276.899878) (xy 159.904747 -276.923872) (xy 159.897243 -276.971269) (xy 159.882417 -277.016909)
			(xy 159.860632 -277.059667) (xy 159.832427 -277.09849) (xy 159.798495 -277.132423) (xy 159.759672 -277.160629)
			(xy 159.716914 -277.182414) (xy 159.671275 -277.197242) (xy 159.623878 -277.204747) (xy 159.599884 -277.205186)
			(xy 159.585702 -277.204999) (xy 159.557463 -277.202324) (xy 159.543496 -277.199852) (xy 159.53105 -277.197566)
			(xy 159.507428 -277.204932) (xy 159.429958 -277.282402) (xy 159.422592 -277.306024) (xy 159.424878 -277.31847)
			(xy 159.427365 -277.332435) (xy 159.430041 -277.360675) (xy 159.430212 -277.374858) (xy 159.430027 -277.389041)
			(xy 159.427358 -277.417281) (xy 159.424878 -277.431246) (xy 159.422592 -277.443692) (xy 159.429958 -277.467314)
			(xy 159.507428 -277.544784) (xy 159.53105 -277.55215) (xy 159.543496 -277.549864) (xy 159.557461 -277.547378)
			(xy 159.585701 -277.544704) (xy 159.599884 -277.54453) (xy 159.625139 -277.545021) (xy 159.674962 -277.553333)
			(xy 159.722736 -277.569732) (xy 159.76716 -277.593771) (xy 159.807021 -277.624794) (xy 159.841232 -277.661955)
			(xy 159.86886 -277.70424) (xy 159.889151 -277.750497) (xy 159.901551 -277.799462) (xy 159.905722 -277.8498)
			(xy 159.905719 -277.849838) (xy 160.24404 -277.849838) (xy 160.248 -277.800784) (xy 160.259777 -277.753)
			(xy 160.279068 -277.707724) (xy 160.305371 -277.666128) (xy 160.338006 -277.629291) (xy 160.376127 -277.598166)
			(xy 160.418748 -277.573559) (xy 160.464764 -277.556107) (xy 160.512983 -277.546263) (xy 160.562158 -277.544282)
			(xy 160.611013 -277.550214) (xy 160.658284 -277.563906) (xy 160.702746 -277.585004) (xy 160.743249 -277.61296)
			(xy 160.778742 -277.647052) (xy 160.808307 -277.686396) (xy 160.831178 -277.729973) (xy 160.846762 -277.776654)
			(xy 160.854657 -277.825231) (xy 160.855152 -277.849838) (xy 161.194254 -277.849838) (xy 161.198214 -277.800784)
			(xy 161.209991 -277.753) (xy 161.229282 -277.707724) (xy 161.255585 -277.666128) (xy 161.28822 -277.629291)
			(xy 161.326341 -277.598166) (xy 161.368962 -277.573559) (xy 161.414978 -277.556107) (xy 161.463197 -277.546263)
			(xy 161.512372 -277.544282) (xy 161.561227 -277.550214) (xy 161.608498 -277.563906) (xy 161.65296 -277.585004)
			(xy 161.693463 -277.61296) (xy 161.728956 -277.647052) (xy 161.758521 -277.686396) (xy 161.781392 -277.729973)
			(xy 161.796976 -277.776654) (xy 161.804871 -277.825231) (xy 161.805366 -277.849838) (xy 162.144214 -277.849838)
			(xy 162.148174 -277.800784) (xy 162.159951 -277.753) (xy 162.179242 -277.707724) (xy 162.205545 -277.666128)
			(xy 162.23818 -277.629291) (xy 162.276301 -277.598166) (xy 162.318922 -277.573559) (xy 162.364938 -277.556107)
			(xy 162.413157 -277.546263) (xy 162.462332 -277.544282) (xy 162.511187 -277.550214) (xy 162.558458 -277.563906)
			(xy 162.60292 -277.585004) (xy 162.643423 -277.61296) (xy 162.678916 -277.647052) (xy 162.708481 -277.686396)
			(xy 162.731352 -277.729973) (xy 162.746936 -277.776654) (xy 162.754831 -277.825231) (xy 162.755326 -277.849838)
			(xy 163.094174 -277.849838) (xy 163.098134 -277.800784) (xy 163.109911 -277.753) (xy 163.129202 -277.707724)
			(xy 163.155505 -277.666128) (xy 163.18814 -277.629291) (xy 163.226261 -277.598166) (xy 163.268882 -277.573559)
			(xy 163.314898 -277.556107) (xy 163.363117 -277.546263) (xy 163.412292 -277.544282) (xy 163.461147 -277.550214)
			(xy 163.508418 -277.563906) (xy 163.55288 -277.585004) (xy 163.593383 -277.61296) (xy 163.628876 -277.647052)
			(xy 163.658441 -277.686396) (xy 163.681312 -277.729973) (xy 163.696896 -277.776654) (xy 163.704791 -277.825231)
			(xy 163.705286 -277.849838) (xy 163.704791 -277.874445) (xy 163.696896 -277.923022) (xy 163.681312 -277.969703)
			(xy 163.658441 -278.01328) (xy 163.628876 -278.052624) (xy 163.593383 -278.086716) (xy 163.55288 -278.114672)
			(xy 163.508418 -278.13577) (xy 163.461147 -278.149462) (xy 163.412292 -278.155394) (xy 163.363117 -278.153413)
			(xy 163.314898 -278.143569) (xy 163.268882 -278.126117) (xy 163.226261 -278.10151) (xy 163.18814 -278.070385)
			(xy 163.155505 -278.033548) (xy 163.129202 -277.991952) (xy 163.109911 -277.946676) (xy 163.098134 -277.898892)
			(xy 163.094174 -277.849838) (xy 162.755326 -277.849838) (xy 162.754831 -277.874445) (xy 162.746936 -277.923022)
			(xy 162.731352 -277.969703) (xy 162.708481 -278.01328) (xy 162.678916 -278.052624) (xy 162.643423 -278.086716)
			(xy 162.60292 -278.114672) (xy 162.558458 -278.13577) (xy 162.511187 -278.149462) (xy 162.462332 -278.155394)
			(xy 162.413157 -278.153413) (xy 162.364938 -278.143569) (xy 162.318922 -278.126117) (xy 162.276301 -278.10151)
			(xy 162.23818 -278.070385) (xy 162.205545 -278.033548) (xy 162.179242 -277.991952) (xy 162.159951 -277.946676)
			(xy 162.148174 -277.898892) (xy 162.144214 -277.849838) (xy 161.805366 -277.849838) (xy 161.804871 -277.874445)
			(xy 161.796976 -277.923022) (xy 161.781392 -277.969703) (xy 161.758521 -278.01328) (xy 161.728956 -278.052624)
			(xy 161.693463 -278.086716) (xy 161.65296 -278.114672) (xy 161.608498 -278.13577) (xy 161.561227 -278.149462)
			(xy 161.512372 -278.155394) (xy 161.463197 -278.153413) (xy 161.414978 -278.143569) (xy 161.368962 -278.126117)
			(xy 161.326341 -278.10151) (xy 161.28822 -278.070385) (xy 161.255585 -278.033548) (xy 161.229282 -277.991952)
			(xy 161.209991 -277.946676) (xy 161.198214 -277.898892) (xy 161.194254 -277.849838) (xy 160.855152 -277.849838)
			(xy 160.854657 -277.874445) (xy 160.846762 -277.923022) (xy 160.831178 -277.969703) (xy 160.808307 -278.01328)
			(xy 160.778742 -278.052624) (xy 160.743249 -278.086716) (xy 160.702746 -278.114672) (xy 160.658284 -278.13577)
			(xy 160.611013 -278.149462) (xy 160.562158 -278.155394) (xy 160.512983 -278.153413) (xy 160.464764 -278.143569)
			(xy 160.418748 -278.126117) (xy 160.376127 -278.10151) (xy 160.338006 -278.070385) (xy 160.305371 -278.033548)
			(xy 160.279068 -277.991952) (xy 160.259777 -277.946676) (xy 160.248 -277.898892) (xy 160.24404 -277.849838)
			(xy 159.905719 -277.849838) (xy 159.901551 -277.900138) (xy 159.889151 -277.949103) (xy 159.86886 -277.99536)
			(xy 159.841232 -278.037645) (xy 159.807021 -278.074806) (xy 159.76716 -278.105829) (xy 159.722736 -278.129868)
			(xy 159.674962 -278.146267) (xy 159.625139 -278.154579) (xy 159.599884 -278.155146) (xy 159.585702 -278.154959)
			(xy 159.557463 -278.152284) (xy 159.543496 -278.149812) (xy 159.53105 -278.147526) (xy 159.507428 -278.154892)
			(xy 159.429958 -278.232362) (xy 159.422592 -278.255984) (xy 159.424878 -278.26843) (xy 159.427362 -278.282395)
			(xy 159.430033 -278.310635) (xy 159.430212 -278.324818) (xy 159.430025 -278.339) (xy 159.42735 -278.367239)
			(xy 159.424878 -278.381206) (xy 159.422592 -278.393652) (xy 159.429958 -278.417274) (xy 159.507428 -278.494744)
			(xy 159.53105 -278.50211) (xy 159.543496 -278.499824) (xy 159.557461 -278.497338) (xy 159.585701 -278.494664)
			(xy 159.599884 -278.49449) (xy 159.623878 -278.494935) (xy 159.671276 -278.50244) (xy 159.716916 -278.517267)
			(xy 159.759674 -278.539051) (xy 159.798498 -278.567257) (xy 159.832432 -278.601188) (xy 159.860639 -278.640011)
			(xy 159.882426 -278.682768) (xy 159.897256 -278.728407) (xy 159.904764 -278.775804) (xy 159.905192 -278.799798)
			(xy 159.905006 -278.81398) (xy 159.902332 -278.84222) (xy 159.899858 -278.856186) (xy 159.897572 -278.868632)
			(xy 159.904938 -278.892254) (xy 159.982408 -278.969724) (xy 160.00603 -278.97709) (xy 160.018476 -278.974804)
			(xy 160.032441 -278.972317) (xy 160.060681 -278.969642) (xy 160.074864 -278.96947) (xy 160.089047 -278.969655)
			(xy 160.117287 -278.972325) (xy 160.131252 -278.974804) (xy 160.143698 -278.97709) (xy 160.16732 -278.969724)
			(xy 160.24479 -278.892254) (xy 160.252156 -278.868632) (xy 160.24987 -278.856186) (xy 160.247384 -278.842221)
			(xy 160.244712 -278.813981) (xy 160.244536 -278.799798) (xy 160.245022 -278.774982) (xy 160.253052 -278.726002)
			(xy 160.268899 -278.678967) (xy 160.292147 -278.635116) (xy 160.322183 -278.595603) (xy 160.358216 -278.56147)
			(xy 160.399296 -278.533615) (xy 160.444341 -278.512774) (xy 160.492165 -278.499494) (xy 160.541506 -278.494125)
			(xy 160.591067 -278.49681) (xy 160.63954 -278.507477) (xy 160.685649 -278.525846) (xy 160.728179 -278.551432)
			(xy 160.766009 -278.583561) (xy 160.798144 -278.621387) (xy 160.823735 -278.663914) (xy 160.84211 -278.71002)
			(xy 160.852784 -278.758492) (xy 160.855028 -278.799798) (xy 161.194254 -278.799798) (xy 161.198214 -278.750744)
			(xy 161.209991 -278.70296) (xy 161.229282 -278.657684) (xy 161.255585 -278.616088) (xy 161.28822 -278.579251)
			(xy 161.326341 -278.548126) (xy 161.368962 -278.523519) (xy 161.414978 -278.506067) (xy 161.463197 -278.496223)
			(xy 161.512372 -278.494242) (xy 161.561227 -278.500174) (xy 161.608498 -278.513866) (xy 161.65296 -278.534964)
			(xy 161.693463 -278.56292) (xy 161.728956 -278.597012) (xy 161.758521 -278.636356) (xy 161.781392 -278.679933)
			(xy 161.796976 -278.726614) (xy 161.804871 -278.775191) (xy 161.805366 -278.799798) (xy 162.144214 -278.799798)
			(xy 162.148174 -278.750744) (xy 162.159951 -278.70296) (xy 162.179242 -278.657684) (xy 162.205545 -278.616088)
			(xy 162.23818 -278.579251) (xy 162.276301 -278.548126) (xy 162.318922 -278.523519) (xy 162.364938 -278.506067)
			(xy 162.413157 -278.496223) (xy 162.462332 -278.494242) (xy 162.511187 -278.500174) (xy 162.558458 -278.513866)
			(xy 162.60292 -278.534964) (xy 162.643423 -278.56292) (xy 162.678916 -278.597012) (xy 162.708481 -278.636356)
			(xy 162.731352 -278.679933) (xy 162.746936 -278.726614) (xy 162.754831 -278.775191) (xy 162.755326 -278.799798)
			(xy 163.094174 -278.799798) (xy 163.098134 -278.750744) (xy 163.109911 -278.70296) (xy 163.129202 -278.657684)
			(xy 163.155505 -278.616088) (xy 163.18814 -278.579251) (xy 163.226261 -278.548126) (xy 163.268882 -278.523519)
			(xy 163.314898 -278.506067) (xy 163.363117 -278.496223) (xy 163.412292 -278.494242) (xy 163.461147 -278.500174)
			(xy 163.508418 -278.513866) (xy 163.55288 -278.534964) (xy 163.593383 -278.56292) (xy 163.628876 -278.597012)
			(xy 163.658441 -278.636356) (xy 163.681312 -278.679933) (xy 163.696896 -278.726614) (xy 163.704791 -278.775191)
			(xy 163.705286 -278.799798) (xy 163.704791 -278.824405) (xy 163.696896 -278.872982) (xy 163.681312 -278.919663)
			(xy 163.658441 -278.96324) (xy 163.628876 -279.002584) (xy 163.593383 -279.036676) (xy 163.55288 -279.064632)
			(xy 163.508418 -279.08573) (xy 163.461147 -279.099422) (xy 163.412292 -279.105354) (xy 163.363117 -279.103373)
			(xy 163.314898 -279.093529) (xy 163.268882 -279.076077) (xy 163.226261 -279.05147) (xy 163.18814 -279.020345)
			(xy 163.155505 -278.983508) (xy 163.129202 -278.941912) (xy 163.109911 -278.896636) (xy 163.098134 -278.848852)
			(xy 163.094174 -278.799798) (xy 162.755326 -278.799798) (xy 162.754831 -278.824405) (xy 162.746936 -278.872982)
			(xy 162.731352 -278.919663) (xy 162.708481 -278.96324) (xy 162.678916 -279.002584) (xy 162.643423 -279.036676)
			(xy 162.60292 -279.064632) (xy 162.558458 -279.08573) (xy 162.511187 -279.099422) (xy 162.462332 -279.105354)
			(xy 162.413157 -279.103373) (xy 162.364938 -279.093529) (xy 162.318922 -279.076077) (xy 162.276301 -279.05147)
			(xy 162.23818 -279.020345) (xy 162.205545 -278.983508) (xy 162.179242 -278.941912) (xy 162.159951 -278.896636)
			(xy 162.148174 -278.848852) (xy 162.144214 -278.799798) (xy 161.805366 -278.799798) (xy 161.804871 -278.824405)
			(xy 161.796976 -278.872982) (xy 161.781392 -278.919663) (xy 161.758521 -278.96324) (xy 161.728956 -279.002584)
			(xy 161.693463 -279.036676) (xy 161.65296 -279.064632) (xy 161.608498 -279.08573) (xy 161.561227 -279.099422)
			(xy 161.512372 -279.105354) (xy 161.463197 -279.103373) (xy 161.414978 -279.093529) (xy 161.368962 -279.076077)
			(xy 161.326341 -279.05147) (xy 161.28822 -279.020345) (xy 161.255585 -278.983508) (xy 161.229282 -278.941912)
			(xy 161.209991 -278.896636) (xy 161.198214 -278.848852) (xy 161.194254 -278.799798) (xy 160.855028 -278.799798)
			(xy 160.855476 -278.808052) (xy 160.850114 -278.857394) (xy 160.836841 -278.905219) (xy 160.816005 -278.950267)
			(xy 160.788157 -278.991351) (xy 160.754028 -279.027388) (xy 160.71452 -279.05743) (xy 160.670671 -279.080684)
			(xy 160.623638 -279.096538) (xy 160.57466 -279.104575) (xy 160.549844 -279.105106) (xy 160.535661 -279.104921)
			(xy 160.507421 -279.102252) (xy 160.493456 -279.099772) (xy 160.48101 -279.097486) (xy 160.457388 -279.104852)
			(xy 160.379918 -279.182322) (xy 160.372552 -279.205944) (xy 160.374838 -279.21839) (xy 160.377325 -279.232355)
			(xy 160.379999 -279.260595) (xy 160.380172 -279.274778) (xy 160.379986 -279.288961) (xy 160.377315 -279.3172)
			(xy 160.374838 -279.331166) (xy 160.372552 -279.343612) (xy 160.379918 -279.367234) (xy 160.457388 -279.444704)
			(xy 160.48101 -279.45207) (xy 160.493456 -279.449784) (xy 160.507421 -279.447301) (xy 160.535661 -279.444633)
			(xy 160.549844 -279.44445) (xy 160.5751 -279.444975) (xy 160.624923 -279.453296) (xy 160.672698 -279.469703)
			(xy 160.71712 -279.493749) (xy 160.756979 -279.524778) (xy 160.791188 -279.561944) (xy 160.818814 -279.604233)
			(xy 160.839103 -279.650492) (xy 160.851502 -279.69946) (xy 160.855648 -279.749504) (xy 161.194254 -279.749504)
			(xy 161.198214 -279.70045) (xy 161.209991 -279.652666) (xy 161.229282 -279.60739) (xy 161.255585 -279.565794)
			(xy 161.28822 -279.528957) (xy 161.326341 -279.497832) (xy 161.368962 -279.473225) (xy 161.414978 -279.455773)
			(xy 161.463197 -279.445929) (xy 161.512372 -279.443948) (xy 161.561227 -279.44988) (xy 161.608498 -279.463572)
			(xy 161.65296 -279.48467) (xy 161.693463 -279.512626) (xy 161.728956 -279.546718) (xy 161.758521 -279.586062)
			(xy 161.781392 -279.629639) (xy 161.796976 -279.67632) (xy 161.804871 -279.724897) (xy 161.805366 -279.749504)
			(xy 161.805361 -279.749758) (xy 162.144214 -279.749758) (xy 162.148174 -279.700704) (xy 162.159951 -279.65292)
			(xy 162.179242 -279.607644) (xy 162.205545 -279.566048) (xy 162.23818 -279.529211) (xy 162.276301 -279.498086)
			(xy 162.318922 -279.473479) (xy 162.364938 -279.456027) (xy 162.413157 -279.446183) (xy 162.462332 -279.444202)
			(xy 162.511187 -279.450134) (xy 162.558458 -279.463826) (xy 162.60292 -279.484924) (xy 162.643423 -279.51288)
			(xy 162.678916 -279.546972) (xy 162.708481 -279.586316) (xy 162.731352 -279.629893) (xy 162.746936 -279.676574)
			(xy 162.754831 -279.725151) (xy 162.755321 -279.749504) (xy 163.094174 -279.749504) (xy 163.098134 -279.70045)
			(xy 163.109911 -279.652666) (xy 163.129202 -279.60739) (xy 163.155505 -279.565794) (xy 163.18814 -279.528957)
			(xy 163.226261 -279.497832) (xy 163.268882 -279.473225) (xy 163.314898 -279.455773) (xy 163.363117 -279.445929)
			(xy 163.412292 -279.443948) (xy 163.461147 -279.44988) (xy 163.508418 -279.463572) (xy 163.55288 -279.48467)
			(xy 163.593383 -279.512626) (xy 163.628876 -279.546718) (xy 163.658441 -279.586062) (xy 163.681312 -279.629639)
			(xy 163.696896 -279.67632) (xy 163.704791 -279.724897) (xy 163.705286 -279.749504) (xy 163.704791 -279.774111)
			(xy 163.696896 -279.822688) (xy 163.681312 -279.869369) (xy 163.658441 -279.912946) (xy 163.628876 -279.95229)
			(xy 163.593383 -279.986382) (xy 163.55288 -280.014338) (xy 163.508418 -280.035436) (xy 163.461147 -280.049128)
			(xy 163.412292 -280.05506) (xy 163.363117 -280.053079) (xy 163.314898 -280.043235) (xy 163.268882 -280.025783)
			(xy 163.226261 -280.001176) (xy 163.18814 -279.970051) (xy 163.155505 -279.933214) (xy 163.129202 -279.891618)
			(xy 163.109911 -279.846342) (xy 163.098134 -279.798558) (xy 163.094174 -279.749504) (xy 162.755321 -279.749504)
			(xy 162.755326 -279.749758) (xy 162.754831 -279.774365) (xy 162.746936 -279.822942) (xy 162.731352 -279.869623)
			(xy 162.708481 -279.9132) (xy 162.678916 -279.952544) (xy 162.643423 -279.986636) (xy 162.60292 -280.014592)
			(xy 162.558458 -280.03569) (xy 162.511187 -280.049382) (xy 162.462332 -280.055314) (xy 162.413157 -280.053333)
			(xy 162.364938 -280.043489) (xy 162.318922 -280.026037) (xy 162.276301 -280.00143) (xy 162.23818 -279.970305)
			(xy 162.205545 -279.933468) (xy 162.179242 -279.891872) (xy 162.159951 -279.846596) (xy 162.148174 -279.798812)
			(xy 162.144214 -279.749758) (xy 161.805361 -279.749758) (xy 161.804871 -279.774111) (xy 161.796976 -279.822688)
			(xy 161.781392 -279.869369) (xy 161.758521 -279.912946) (xy 161.728956 -279.95229) (xy 161.693463 -279.986382)
			(xy 161.65296 -280.014338) (xy 161.608498 -280.035436) (xy 161.561227 -280.049128) (xy 161.512372 -280.05506)
			(xy 161.463197 -280.053079) (xy 161.414978 -280.043235) (xy 161.368962 -280.025783) (xy 161.326341 -280.001176)
			(xy 161.28822 -279.970051) (xy 161.255585 -279.933214) (xy 161.229282 -279.891618) (xy 161.209991 -279.846342)
			(xy 161.198214 -279.798558) (xy 161.194254 -279.749504) (xy 160.855648 -279.749504) (xy 160.855673 -279.7498)
			(xy 160.851502 -279.80014) (xy 160.839103 -279.849108) (xy 160.818814 -279.895367) (xy 160.791188 -279.937656)
			(xy 160.756979 -279.974822) (xy 160.71712 -280.005851) (xy 160.672698 -280.029897) (xy 160.624923 -280.046304)
			(xy 160.5751 -280.054625) (xy 160.549844 -280.055066) (xy 160.535661 -280.054882) (xy 160.507421 -280.052213)
			(xy 160.493456 -280.049732) (xy 160.48101 -280.047446) (xy 160.457388 -280.054812) (xy 160.379918 -280.132282)
			(xy 160.372552 -280.155904) (xy 160.374838 -280.16835) (xy 160.377322 -280.182315) (xy 160.379991 -280.210555)
			(xy 160.380172 -280.224738) (xy 160.379988 -280.238921) (xy 160.37732 -280.267161) (xy 160.374838 -280.281126)
			(xy 160.372552 -280.293572) (xy 160.379918 -280.317194) (xy 160.457388 -280.394664) (xy 160.48101 -280.40203)
			(xy 160.493456 -280.399744) (xy 160.507421 -280.397261) (xy 160.535661 -280.394592) (xy 160.549844 -280.39441)
			(xy 160.574662 -280.394899) (xy 160.623644 -280.402936) (xy 160.67068 -280.418792) (xy 160.714532 -280.442047)
			(xy 160.754044 -280.472091) (xy 160.788175 -280.50813) (xy 160.816026 -280.549217) (xy 160.836864 -280.594268)
			(xy 160.850139 -280.642096) (xy 160.855501 -280.691442) (xy 160.855052 -280.699718) (xy 161.194254 -280.699718)
			(xy 161.198214 -280.650664) (xy 161.209991 -280.60288) (xy 161.229282 -280.557604) (xy 161.255585 -280.516008)
			(xy 161.28822 -280.479171) (xy 161.326341 -280.448046) (xy 161.368962 -280.423439) (xy 161.414978 -280.405987)
			(xy 161.463197 -280.396143) (xy 161.512372 -280.394162) (xy 161.561227 -280.400094) (xy 161.608498 -280.413786)
			(xy 161.65296 -280.434884) (xy 161.693463 -280.46284) (xy 161.728956 -280.496932) (xy 161.758521 -280.536276)
			(xy 161.781392 -280.579853) (xy 161.796976 -280.626534) (xy 161.804871 -280.675111) (xy 161.805366 -280.699718)
			(xy 162.144214 -280.699718) (xy 162.148174 -280.650664) (xy 162.159951 -280.60288) (xy 162.179242 -280.557604)
			(xy 162.205545 -280.516008) (xy 162.23818 -280.479171) (xy 162.276301 -280.448046) (xy 162.318922 -280.423439)
			(xy 162.364938 -280.405987) (xy 162.413157 -280.396143) (xy 162.462332 -280.394162) (xy 162.511187 -280.400094)
			(xy 162.558458 -280.413786) (xy 162.60292 -280.434884) (xy 162.643423 -280.46284) (xy 162.678916 -280.496932)
			(xy 162.708481 -280.536276) (xy 162.731352 -280.579853) (xy 162.746936 -280.626534) (xy 162.754831 -280.675111)
			(xy 162.755326 -280.699718) (xy 163.094174 -280.699718) (xy 163.098134 -280.650664) (xy 163.109911 -280.60288)
			(xy 163.129202 -280.557604) (xy 163.155505 -280.516008) (xy 163.18814 -280.479171) (xy 163.226261 -280.448046)
			(xy 163.268882 -280.423439) (xy 163.314898 -280.405987) (xy 163.363117 -280.396143) (xy 163.412292 -280.394162)
			(xy 163.461147 -280.400094) (xy 163.508418 -280.413786) (xy 163.55288 -280.434884) (xy 163.593383 -280.46284)
			(xy 163.628876 -280.496932) (xy 163.658441 -280.536276) (xy 163.681312 -280.579853) (xy 163.696896 -280.626534)
			(xy 163.704791 -280.675111) (xy 163.705286 -280.699718) (xy 163.704791 -280.724325) (xy 163.696896 -280.772902)
			(xy 163.681312 -280.819583) (xy 163.658441 -280.86316) (xy 163.628876 -280.902504) (xy 163.593383 -280.936596)
			(xy 163.55288 -280.964552) (xy 163.508418 -280.98565) (xy 163.461147 -280.999342) (xy 163.412292 -281.005274)
			(xy 163.363117 -281.003293) (xy 163.314898 -280.993449) (xy 163.268882 -280.975997) (xy 163.226261 -280.95139)
			(xy 163.18814 -280.920265) (xy 163.155505 -280.883428) (xy 163.129202 -280.841832) (xy 163.109911 -280.796556)
			(xy 163.098134 -280.748772) (xy 163.094174 -280.699718) (xy 162.755326 -280.699718) (xy 162.754831 -280.724325)
			(xy 162.746936 -280.772902) (xy 162.731352 -280.819583) (xy 162.708481 -280.86316) (xy 162.678916 -280.902504)
			(xy 162.643423 -280.936596) (xy 162.60292 -280.964552) (xy 162.558458 -280.98565) (xy 162.511187 -280.999342)
			(xy 162.462332 -281.005274) (xy 162.413157 -281.003293) (xy 162.364938 -280.993449) (xy 162.318922 -280.975997)
			(xy 162.276301 -280.95139) (xy 162.23818 -280.920265) (xy 162.205545 -280.883428) (xy 162.179242 -280.841832)
			(xy 162.159951 -280.796556) (xy 162.148174 -280.748772) (xy 162.144214 -280.699718) (xy 161.805366 -280.699718)
			(xy 161.804871 -280.724325) (xy 161.796976 -280.772902) (xy 161.781392 -280.819583) (xy 161.758521 -280.86316)
			(xy 161.728956 -280.902504) (xy 161.693463 -280.936596) (xy 161.65296 -280.964552) (xy 161.608498 -280.98565)
			(xy 161.561227 -280.999342) (xy 161.512372 -281.005274) (xy 161.463197 -281.003293) (xy 161.414978 -280.993449)
			(xy 161.368962 -280.975997) (xy 161.326341 -280.95139) (xy 161.28822 -280.920265) (xy 161.255585 -280.883428)
			(xy 161.229282 -280.841832) (xy 161.209991 -280.796556) (xy 161.198214 -280.748772) (xy 161.194254 -280.699718)
			(xy 160.855052 -280.699718) (xy 160.852811 -280.741006) (xy 160.842137 -280.789482) (xy 160.823762 -280.835592)
			(xy 160.798169 -280.878122) (xy 160.766033 -280.915952) (xy 160.728201 -280.948084) (xy 160.685668 -280.973673)
			(xy 160.639557 -280.992045) (xy 160.59108 -281.002714) (xy 160.541516 -281.005401) (xy 160.492171 -281.000034)
			(xy 160.444343 -280.986755) (xy 160.399294 -280.965913) (xy 160.35821 -280.938059) (xy 160.322173 -280.903924)
			(xy 160.292133 -280.86441) (xy 160.268881 -280.820556) (xy 160.25303 -280.773519) (xy 160.244997 -280.724536)
			(xy 160.244536 -280.699718) (xy 160.244722 -280.685535) (xy 160.247393 -280.657296) (xy 160.24987 -280.64333)
			(xy 160.252156 -280.630884) (xy 160.24479 -280.607262) (xy 160.16732 -280.529792) (xy 160.143698 -280.522426)
			(xy 160.131252 -280.524712) (xy 160.117287 -280.527195) (xy 160.089047 -280.529864) (xy 160.074864 -280.530046)
			(xy 160.049607 -280.529521) (xy 159.999784 -280.521202) (xy 159.952009 -280.504796) (xy 159.907586 -280.480751)
			(xy 159.867727 -280.449722) (xy 159.833517 -280.412557) (xy 159.805891 -280.370268) (xy 159.785601 -280.324008)
			(xy 159.773202 -280.275041) (xy 159.769031 -280.2247) (xy 159.773202 -280.174359) (xy 159.785601 -280.125392)
			(xy 159.805891 -280.079132) (xy 159.833517 -280.036843) (xy 159.867727 -279.999678) (xy 159.907586 -279.968649)
			(xy 159.952009 -279.944604) (xy 159.999784 -279.928198) (xy 160.049607 -279.919879) (xy 160.074864 -279.91943)
			(xy 160.089047 -279.919615) (xy 160.117286 -279.922285) (xy 160.131252 -279.924764) (xy 160.143698 -279.92705)
			(xy 160.16732 -279.919684) (xy 160.24479 -279.842214) (xy 160.252156 -279.818592) (xy 160.24987 -279.806146)
			(xy 160.247386 -279.792181) (xy 160.244718 -279.763941) (xy 160.244536 -279.749758) (xy 160.24472 -279.735575)
			(xy 160.247388 -279.707335) (xy 160.24987 -279.69337) (xy 160.252156 -279.680924) (xy 160.24479 -279.657302)
			(xy 160.16732 -279.579832) (xy 160.143698 -279.572466) (xy 160.131252 -279.574752) (xy 160.117287 -279.577236)
			(xy 160.089047 -279.579905) (xy 160.074864 -279.580086) (xy 160.050875 -279.579613) (xy 160.003489 -279.572102)
			(xy 159.957861 -279.557271) (xy 159.915115 -279.535485) (xy 159.876303 -279.507281) (xy 159.842381 -279.473352)
			(xy 159.814184 -279.434535) (xy 159.792407 -279.391785) (xy 159.777584 -279.346154) (xy 159.770083 -279.298767)
			(xy 159.769556 -279.274778) (xy 159.769744 -279.260596) (xy 159.772419 -279.232357) (xy 159.77489 -279.21839)
			(xy 159.777176 -279.205944) (xy 159.76981 -279.182322) (xy 159.69234 -279.104852) (xy 159.668718 -279.097486)
			(xy 159.656272 -279.099772) (xy 159.642307 -279.102257) (xy 159.614067 -279.104927) (xy 159.599884 -279.105106)
			(xy 159.585702 -279.104919) (xy 159.557463 -279.102244) (xy 159.543496 -279.099772) (xy 159.53105 -279.097486)
			(xy 159.507428 -279.104852) (xy 159.429958 -279.182322) (xy 159.422592 -279.205944) (xy 159.424878 -279.21839)
			(xy 159.427364 -279.232355) (xy 159.430038 -279.260595) (xy 159.430212 -279.274778) (xy 159.429728 -279.2996)
			(xy 159.4217 -279.348589) (xy 159.405852 -279.395635) (xy 159.382601 -279.439497) (xy 159.352561 -279.479019)
			(xy 159.316522 -279.513161) (xy 159.275434 -279.541023) (xy 159.23038 -279.56187) (xy 159.182547 -279.575153)
			(xy 159.133195 -279.580522) (xy 159.083625 -279.577837) (xy 159.035142 -279.567167) (xy 158.989024 -279.548794)
			(xy 158.946486 -279.523202) (xy 158.908648 -279.491064) (xy 158.876509 -279.453229) (xy 158.850914 -279.410693)
			(xy 158.832538 -279.364576) (xy 158.821865 -279.316093) (xy 158.819177 -279.266523) (xy 158.824544 -279.21717)
			(xy 158.837824 -279.169336) (xy 158.858669 -279.124281) (xy 158.886528 -279.083192) (xy 158.920667 -279.047151)
			(xy 158.960188 -279.017108) (xy 159.004048 -278.993855) (xy 159.051093 -278.978004) (xy 159.100082 -278.969974)
			(xy 159.124904 -278.96947) (xy 159.139086 -278.969657) (xy 159.167326 -278.97233) (xy 159.181292 -278.974804)
			(xy 159.193738 -278.97709) (xy 159.21736 -278.969724) (xy 159.29483 -278.892254) (xy 159.302196 -278.868632)
			(xy 159.29991 -278.856186) (xy 159.297425 -278.842221) (xy 159.294753 -278.813981) (xy 159.294576 -278.799798)
			(xy 159.294763 -278.785616) (xy 159.297436 -278.757376) (xy 159.29991 -278.74341) (xy 159.302196 -278.730964)
			(xy 159.29483 -278.707342) (xy 159.21736 -278.629872) (xy 159.193738 -278.622506) (xy 159.181292 -278.624792)
			(xy 159.167327 -278.627277) (xy 159.139087 -278.62995) (xy 159.124904 -278.630126) (xy 159.099645 -278.629634)
			(xy 159.049815 -278.621319) (xy 159.002033 -278.604916) (xy 158.957603 -278.580872) (xy 158.917736 -278.549843)
			(xy 158.88352 -278.512675) (xy 158.855889 -278.470383) (xy 158.835596 -278.424119) (xy 158.823194 -278.375146)
			(xy 158.819022 -278.3248) (xy 158.823194 -278.274454) (xy 158.835596 -278.225481) (xy 158.855889 -278.179217)
			(xy 158.88352 -278.136925) (xy 158.917736 -278.099757) (xy 158.957603 -278.068728) (xy 159.002033 -278.044684)
			(xy 159.049815 -278.028281) (xy 159.099645 -278.019966) (xy 159.124904 -278.01951) (xy 159.139086 -278.019697)
			(xy 159.167326 -278.022371) (xy 159.181292 -278.024844) (xy 159.193738 -278.02713) (xy 159.21736 -278.019764)
			(xy 159.29483 -277.942294) (xy 159.302196 -277.918672) (xy 159.29991 -277.906226) (xy 159.297423 -277.892261)
			(xy 159.294748 -277.864021) (xy 159.294576 -277.849838) (xy 159.294761 -277.835655) (xy 159.297431 -277.807415)
			(xy 159.29991 -277.79345) (xy 159.302196 -277.781004) (xy 159.29483 -277.757382) (xy 159.21736 -277.679912)
			(xy 159.193738 -277.672546) (xy 159.181292 -277.674832) (xy 159.167327 -277.677318) (xy 159.139087 -277.679991)
			(xy 159.124904 -277.680166) (xy 159.09965 -277.679674) (xy 159.049829 -277.671361) (xy 159.002057 -277.654961)
			(xy 158.957636 -277.630922) (xy 158.917777 -277.599899) (xy 158.883568 -277.562739) (xy 158.855942 -277.520454)
			(xy 158.835652 -277.4742) (xy 158.823253 -277.425236) (xy 158.819082 -277.3749) (xy 158.823253 -277.324564)
			(xy 158.835652 -277.2756) (xy 158.855942 -277.229346) (xy 158.883568 -277.187061) (xy 158.917777 -277.149901)
			(xy 158.957636 -277.118878) (xy 159.002057 -277.094839) (xy 159.049829 -277.078439) (xy 159.09965 -277.070126)
			(xy 159.124904 -277.06955) (xy 159.139086 -277.069737) (xy 159.167326 -277.07241) (xy 159.181292 -277.074884)
			(xy 159.193738 -277.07717) (xy 159.21736 -277.069804) (xy 159.29483 -276.992334) (xy 159.302196 -276.968712)
			(xy 159.29991 -276.956266) (xy 159.297426 -276.942301) (xy 159.294756 -276.914061) (xy 159.294576 -276.899878)
			(xy 159.294764 -276.885696) (xy 159.297439 -276.857457) (xy 159.29991 -276.84349) (xy 159.302196 -276.831044)
			(xy 159.29483 -276.807422) (xy 159.21736 -276.729952) (xy 159.193738 -276.722586) (xy 159.181292 -276.724872)
			(xy 159.167327 -276.727357) (xy 159.139087 -276.73003) (xy 159.124904 -276.730206) (xy 159.100911 -276.72976)
			(xy 159.053515 -276.722254) (xy 159.007877 -276.707426) (xy 158.96512 -276.68564) (xy 158.926298 -276.657435)
			(xy 158.892366 -276.623503) (xy 158.864161 -276.584681) (xy 158.842375 -276.541925) (xy 158.827547 -276.496287)
			(xy 158.82004 -276.448891) (xy 158.819596 -276.424898) (xy 158.820059 -276.400598) (xy 158.827743 -276.35261)
			(xy 158.842932 -276.306445) (xy 158.865243 -276.263269) (xy 158.894112 -276.224173) (xy 158.928811 -276.190145)
			(xy 158.948374 -276.175724) (xy 158.957518 -276.16912) (xy 158.968694 -276.15007) (xy 158.97606 -276.061424)
			(xy 158.976429 -276.050274) (xy 158.968781 -276.029341) (xy 158.961328 -276.021038) (xy 158.578804 -275.638514)
			(xy 158.570543 -275.630992) (xy 158.549581 -275.623339) (xy 158.538418 -275.623782) (xy 158.449772 -275.631148)
			(xy 158.430722 -275.642324) (xy 158.424118 -275.651468) (xy 158.409674 -275.67101) (xy 158.375634 -275.705687)
			(xy 158.336538 -275.734543) (xy 158.29337 -275.756852) (xy 158.247217 -275.772052) (xy 158.19924 -275.779761)
			(xy 158.174944 -275.780246) (xy 158.150948 -275.779803) (xy 158.103544 -275.772302) (xy 158.057898 -275.757478)
			(xy 158.015134 -275.735696) (xy 157.976303 -275.707491) (xy 157.942362 -275.67356) (xy 157.914147 -275.634737)
			(xy 157.892354 -275.591977) (xy 157.877517 -275.546335) (xy 157.870003 -275.498934) (xy 157.869636 -275.474938)
			(xy 157.870103 -275.45064) (xy 157.877794 -275.402655) (xy 157.892988 -275.356495) (xy 157.915301 -275.313323)
			(xy 157.94417 -275.274231) (xy 157.978866 -275.240204) (xy 157.998414 -275.225764) (xy 158.007558 -275.21916)
			(xy 158.018734 -275.20011) (xy 158.0261 -275.111464) (xy 158.026478 -275.100309) (xy 158.018846 -275.079362)
			(xy 158.011368 -275.071078) (xy 157.97276 -275.03247) (xy 157.965912 -275.025073) (xy 157.958179 -275.006474)
			(xy 157.957774 -274.996402) (xy 157.957774 -274.75942) (xy 157.957351 -274.750293) (xy 157.950837 -274.733237)
			(xy 157.945074 -274.726146) (xy 157.927438 -274.705084) (xy 157.899267 -274.657928) (xy 157.879981 -274.606495)
			(xy 157.8702 -274.552443) (xy 157.869636 -274.524978) (xy 157.870192 -274.497511) (xy 157.879967 -274.443456)
			(xy 157.899252 -274.39202) (xy 157.927424 -274.344862) (xy 157.945074 -274.32381) (xy 157.950808 -274.316705)
			(xy 157.957303 -274.299655) (xy 157.957774 -274.290536) (xy 157.957774 -273.809206) (xy 157.957349 -273.80008)
			(xy 157.950831 -273.783027) (xy 157.945074 -273.775932) (xy 157.927439 -273.754869) (xy 157.899271 -273.707713)
			(xy 157.879987 -273.65628) (xy 157.870208 -273.602229) (xy 157.869636 -273.574764) (xy 157.870194 -273.547298)
			(xy 157.879971 -273.493244) (xy 157.899257 -273.441809) (xy 157.927431 -273.394653) (xy 157.945074 -273.373596)
			(xy 157.950806 -273.36649) (xy 157.957297 -273.34944) (xy 157.957774 -273.340322) (xy 157.957774 -272.859246)
			(xy 157.957356 -272.850117) (xy 157.950848 -272.833055) (xy 157.945074 -272.825972) (xy 157.927436 -272.80491)
			(xy 157.899262 -272.757755) (xy 157.879971 -272.706322) (xy 157.870185 -272.65227) (xy 157.869636 -272.624804)
			(xy 157.87019 -272.597337) (xy 157.879961 -272.543279) (xy 157.899242 -272.49184) (xy 157.927412 -272.444679)
			(xy 157.945074 -272.423636) (xy 157.950811 -272.416532) (xy 157.957316 -272.399482) (xy 157.957774 -272.390362)
			(xy 157.957774 -266.325604) (xy 157.957068 -266.312874) (xy 157.944931 -266.290489) (xy 157.93466 -266.282932)
			(xy 157.852618 -266.229338) (xy 157.827218 -266.227306) (xy 157.81528 -266.23264) (xy 157.790958 -266.242834)
			(xy 157.740214 -266.257197) (xy 157.687979 -266.264456) (xy 157.66161 -266.264898) (xy 157.634357 -266.264435)
			(xy 157.580407 -266.25668) (xy 157.528109 -266.241325) (xy 157.478529 -266.218684) (xy 157.432676 -266.189217)
			(xy 157.391483 -266.153524) (xy 157.355789 -266.112332) (xy 157.326321 -266.06648) (xy 157.303679 -266.0169)
			(xy 157.288322 -265.964603) (xy 157.280565 -265.910653) (xy 157.280565 -265.856147) (xy 157.288322 -265.802197)
			(xy 157.303679 -265.7499) (xy 157.326321 -265.70032) (xy 157.355789 -265.654468) (xy 157.391483 -265.613276)
			(xy 157.432676 -265.577583) (xy 157.478529 -265.548116) (xy 157.528109 -265.525475) (xy 157.580407 -265.51012)
			(xy 157.634357 -265.502365) (xy 157.66161 -265.501882) (xy 157.687981 -265.502304) (xy 157.740224 -265.509537)
			(xy 157.790968 -265.523916) (xy 157.81528 -265.53414) (xy 157.827218 -265.539474) (xy 157.852618 -265.537442)
			(xy 157.93466 -265.483848) (xy 157.941591 -265.478986) (xy 157.952004 -265.465649) (xy 157.957475 -265.449638)
			(xy 157.957774 -265.441176) (xy 157.957774 -264.597642) (xy 157.957337 -264.587666) (xy 157.949798 -264.569198)
			(xy 157.935771 -264.555015) (xy 157.926786 -264.550652) (xy 157.826202 -264.508488) (xy 157.79623 -264.514076)
			(xy 157.785054 -264.524998) (xy 157.763539 -264.545261) (xy 157.715418 -264.579571) (xy 157.662582 -264.60605)
			(xy 157.606295 -264.624065) (xy 157.547904 -264.633186) (xy 157.518354 -264.63371) (xy 157.491105 -264.633221)
			(xy 157.437162 -264.625459) (xy 157.384872 -264.6101) (xy 157.335301 -264.587456) (xy 157.289456 -264.557988)
			(xy 157.248271 -264.522297) (xy 157.212584 -264.481107) (xy 157.183122 -264.435259) (xy 157.160484 -264.385685)
			(xy 157.145131 -264.333393) (xy 157.137376 -264.279449) (xy 157.137376 -264.224951) (xy 157.145131 -264.171007)
			(xy 157.160484 -264.118715) (xy 157.183122 -264.069141) (xy 157.212584 -264.023293) (xy 157.248271 -263.982103)
			(xy 157.289456 -263.946412) (xy 157.335301 -263.916944) (xy 157.384872 -263.8943) (xy 157.437162 -263.878941)
			(xy 157.491105 -263.871179) (xy 157.518354 -263.870694) (xy 157.547904 -263.871245) (xy 157.606298 -263.880352)
			(xy 157.662589 -263.898354) (xy 157.715431 -263.924822) (xy 157.763559 -263.959122) (xy 157.785054 -263.979406)
			(xy 157.79623 -263.990328) (xy 157.826202 -263.995916) (xy 157.926786 -263.953752) (xy 157.935782 -263.949413)
			(xy 157.949797 -263.93521) (xy 157.957345 -263.91674) (xy 157.957774 -263.906762) (xy 157.957774 -263.651492)
			(xy 157.955996 -263.595612) (xy 157.955996 -263.08304) (xy 157.955585 -263.073429) (xy 157.948541 -263.055544)
			(xy 157.94228 -263.048242) (xy 157.887924 -262.990584) (xy 157.870398 -262.982202) (xy 157.860746 -262.981694)
			(xy 157.83204 -262.979385) (xy 157.775751 -262.967217) (xy 157.721931 -262.946727) (xy 157.671801 -262.918381)
			(xy 157.626501 -262.882823) (xy 157.58706 -262.840861) (xy 157.554373 -262.793448) (xy 157.529183 -262.741661)
			(xy 157.512063 -262.686676) (xy 157.503401 -262.629742) (xy 157.50286 -262.600948) (xy 157.503393 -262.571993)
			(xy 157.512135 -262.514745) (xy 157.529426 -262.459476) (xy 157.554869 -262.407454) (xy 157.587879 -262.359873)
			(xy 157.6277 -262.317825) (xy 157.673415 -262.282276) (xy 157.69844 -262.2677) (xy 157.71114 -262.260842)
			(xy 157.724856 -262.236204) (xy 157.721046 -262.117078) (xy 157.705552 -262.093456) (xy 157.692344 -262.08736)
			(xy 157.668212 -262.075407) (xy 157.623276 -262.045726) (xy 157.582958 -262.010025) (xy 157.548057 -261.969012)
			(xy 157.519266 -261.923502) (xy 157.497156 -261.874397) (xy 157.482166 -261.822672) (xy 157.474594 -261.769354)
			(xy 157.474158 -261.742428) (xy 157.474621 -261.71515) (xy 157.482387 -261.661149) (xy 157.497766 -261.608806)
			(xy 157.520444 -261.559186) (xy 157.549958 -261.513302) (xy 157.585706 -261.47209) (xy 157.62696 -261.43639)
			(xy 157.672878 -261.40693) (xy 157.722524 -261.38431) (xy 157.774886 -261.368992) (xy 157.828895 -261.361289)
			(xy 157.856174 -261.36092) (xy 157.866334 -261.36092) (xy 157.884876 -261.3533) (xy 157.942788 -261.295388)
			(xy 157.949634 -261.287989) (xy 157.957366 -261.269391) (xy 157.957774 -261.25932) (xy 157.957774 -260.320282)
			(xy 157.957347 -260.310214) (xy 157.949625 -260.291616) (xy 157.942788 -260.284214) (xy 156.765244 -259.10667)
			(xy 156.757846 -259.099825) (xy 156.739247 -259.0921) (xy 156.729176 -259.091684) (xy 141.367256 -259.091684)
			(xy 141.357189 -259.092115) (xy 141.338595 -259.099838) (xy 141.331188 -259.10667) (xy 140.93698 -259.500878)
			(xy 140.930137 -259.508277) (xy 140.922419 -259.526876) (xy 140.921994 -259.536946) (xy 140.921994 -259.576316)
			(xy 146.345146 -259.576316) (xy 146.349217 -259.520694) (xy 146.361343 -259.466257) (xy 146.381266 -259.414166)
			(xy 146.408562 -259.365531) (xy 146.442648 -259.321388) (xy 146.482797 -259.282679) (xy 146.528155 -259.250228)
			(xy 146.577755 -259.224727) (xy 146.630539 -259.20672) (xy 146.685382 -259.19659) (xy 146.741116 -259.194553)
			(xy 146.796553 -259.200653) (xy 146.85051 -259.214759) (xy 146.901839 -259.236571) (xy 146.949445 -259.265625)
			(xy 146.992313 -259.3013) (xy 147.02953 -259.342837) (xy 147.060303 -259.38935) (xy 147.083975 -259.439847)
			(xy 147.100043 -259.493254) (xy 147.108163 -259.54843) (xy 147.108672 -259.576316) (xy 147.234146 -259.576316)
			(xy 147.238217 -259.520694) (xy 147.250343 -259.466257) (xy 147.270266 -259.414166) (xy 147.297562 -259.365531)
			(xy 147.331648 -259.321388) (xy 147.371797 -259.282679) (xy 147.417155 -259.250228) (xy 147.466755 -259.224727)
			(xy 147.519539 -259.20672) (xy 147.574382 -259.19659) (xy 147.630116 -259.194553) (xy 147.685553 -259.200653)
			(xy 147.73951 -259.214759) (xy 147.790839 -259.236571) (xy 147.838445 -259.265625) (xy 147.881313 -259.3013)
			(xy 147.91853 -259.342837) (xy 147.949303 -259.38935) (xy 147.972975 -259.439847) (xy 147.989043 -259.493254)
			(xy 147.997163 -259.54843) (xy 147.997672 -259.576316) (xy 147.997163 -259.604202) (xy 147.989043 -259.659378)
			(xy 147.972975 -259.712785) (xy 147.949303 -259.763282) (xy 147.91853 -259.809795) (xy 147.881313 -259.851332)
			(xy 147.838445 -259.887007) (xy 147.790839 -259.916061) (xy 147.73951 -259.937873) (xy 147.685553 -259.951979)
			(xy 147.630116 -259.958079) (xy 147.574382 -259.956042) (xy 147.519539 -259.945912) (xy 147.466755 -259.927905)
			(xy 147.417155 -259.902404) (xy 147.371797 -259.869953) (xy 147.331648 -259.831244) (xy 147.297562 -259.787101)
			(xy 147.270266 -259.738466) (xy 147.250343 -259.686375) (xy 147.238217 -259.631938) (xy 147.234146 -259.576316)
			(xy 147.108672 -259.576316) (xy 147.108163 -259.604202) (xy 147.100043 -259.659378) (xy 147.083975 -259.712785)
			(xy 147.060303 -259.763282) (xy 147.02953 -259.809795) (xy 146.992313 -259.851332) (xy 146.949445 -259.887007)
			(xy 146.901839 -259.916061) (xy 146.85051 -259.937873) (xy 146.796553 -259.951979) (xy 146.741116 -259.958079)
			(xy 146.685382 -259.956042) (xy 146.630539 -259.945912) (xy 146.577755 -259.927905) (xy 146.528155 -259.902404)
			(xy 146.482797 -259.869953) (xy 146.442648 -259.831244) (xy 146.408562 -259.787101) (xy 146.381266 -259.738466)
			(xy 146.361343 -259.686375) (xy 146.349217 -259.631938) (xy 146.345146 -259.576316) (xy 140.921994 -259.576316)
			(xy 140.921994 -260.096762) (xy 143.758918 -260.096762) (xy 143.762989 -260.04114) (xy 143.775115 -259.986703)
			(xy 143.795038 -259.934612) (xy 143.822334 -259.885977) (xy 143.85642 -259.841834) (xy 143.896569 -259.803125)
			(xy 143.941927 -259.770674) (xy 143.991527 -259.745173) (xy 144.044311 -259.727166) (xy 144.099154 -259.717036)
			(xy 144.154888 -259.714999) (xy 144.210325 -259.721099) (xy 144.264282 -259.735205) (xy 144.315611 -259.757017)
			(xy 144.363217 -259.786071) (xy 144.406085 -259.821746) (xy 144.443302 -259.863283) (xy 144.474075 -259.909796)
			(xy 144.497747 -259.960293) (xy 144.513815 -260.0137) (xy 144.521935 -260.068876) (xy 144.522444 -260.096762)
			(xy 144.521935 -260.124648) (xy 144.513815 -260.179824) (xy 144.497747 -260.233231) (xy 144.474075 -260.283728)
			(xy 144.443302 -260.330241) (xy 144.436067 -260.338316) (xy 150.396194 -260.338316) (xy 150.396746 -260.308934)
			(xy 150.405774 -260.250868) (xy 150.423604 -260.194874) (xy 150.449813 -260.142279) (xy 150.483782 -260.094327)
			(xy 150.524705 -260.052154) (xy 150.547832 -260.034024) (xy 150.55723 -260.026658) (xy 150.567644 -260.006084)
			(xy 150.569168 -259.902198) (xy 150.559262 -259.881116) (xy 150.550118 -259.87375) (xy 150.528267 -259.855547)
			(xy 150.489727 -259.813728) (xy 150.45782 -259.766652) (xy 150.433253 -259.715362) (xy 150.41657 -259.660993)
			(xy 150.408142 -259.604751) (xy 150.407624 -259.576316) (xy 150.40811 -259.549065) (xy 150.415866 -259.495117)
			(xy 150.431221 -259.442822) (xy 150.453863 -259.393245) (xy 150.483329 -259.347395) (xy 150.51902 -259.306204)
			(xy 150.560211 -259.270513) (xy 150.606061 -259.241047) (xy 150.655638 -259.218405) (xy 150.707933 -259.20305)
			(xy 150.761881 -259.195294) (xy 150.816383 -259.195294) (xy 150.870331 -259.20305) (xy 150.922626 -259.218405)
			(xy 150.972203 -259.241047) (xy 151.018053 -259.270513) (xy 151.059244 -259.306204) (xy 151.094935 -259.347395)
			(xy 151.124401 -259.393245) (xy 151.147043 -259.442822) (xy 151.162398 -259.495117) (xy 151.170154 -259.549065)
			(xy 151.17064 -259.576316) (xy 151.170098 -259.605698) (xy 151.161066 -259.663764) (xy 151.143233 -259.719757)
			(xy 151.117022 -259.772352) (xy 151.083052 -259.820304) (xy 151.042129 -259.862477) (xy 151.019002 -259.880608)
			(xy 151.009604 -259.887974) (xy 150.99919 -259.908548) (xy 150.997666 -260.012434) (xy 151.007572 -260.033516)
			(xy 151.016716 -260.040882) (xy 151.038541 -260.059114) (xy 151.077082 -260.100928) (xy 151.108991 -260.147998)
			(xy 151.133562 -260.199283) (xy 151.15025 -260.253645) (xy 151.158687 -260.309883) (xy 151.15921 -260.338316)
			(xy 151.792684 -260.338316) (xy 151.796755 -260.282694) (xy 151.808881 -260.228257) (xy 151.828804 -260.176166)
			(xy 151.8561 -260.127531) (xy 151.890186 -260.083388) (xy 151.930335 -260.044679) (xy 151.975693 -260.012228)
			(xy 152.025293 -259.986727) (xy 152.078077 -259.96872) (xy 152.13292 -259.95859) (xy 152.188654 -259.956553)
			(xy 152.244091 -259.962653) (xy 152.298048 -259.976759) (xy 152.349377 -259.998571) (xy 152.396983 -260.027625)
			(xy 152.439851 -260.0633) (xy 152.477068 -260.104837) (xy 152.507841 -260.15135) (xy 152.531513 -260.201847)
			(xy 152.547581 -260.255254) (xy 152.555701 -260.31043) (xy 152.55621 -260.338316) (xy 152.679144 -260.338316)
			(xy 152.683215 -260.282694) (xy 152.695341 -260.228257) (xy 152.715264 -260.176166) (xy 152.74256 -260.127531)
			(xy 152.776646 -260.083388) (xy 152.816795 -260.044679) (xy 152.862153 -260.012228) (xy 152.911753 -259.986727)
			(xy 152.964537 -259.96872) (xy 153.01938 -259.95859) (xy 153.075114 -259.956553) (xy 153.130551 -259.962653)
			(xy 153.184508 -259.976759) (xy 153.235837 -259.998571) (xy 153.283443 -260.027625) (xy 153.326311 -260.0633)
			(xy 153.363528 -260.104837) (xy 153.394301 -260.15135) (xy 153.417973 -260.201847) (xy 153.434041 -260.255254)
			(xy 153.442161 -260.31043) (xy 153.44267 -260.338316) (xy 153.442161 -260.366202) (xy 153.434041 -260.421378)
			(xy 153.417973 -260.474785) (xy 153.394301 -260.525282) (xy 153.363528 -260.571795) (xy 153.326311 -260.613332)
			(xy 153.283443 -260.649007) (xy 153.235837 -260.678061) (xy 153.184508 -260.699873) (xy 153.130551 -260.713979)
			(xy 153.075114 -260.720079) (xy 153.01938 -260.718042) (xy 152.964537 -260.707912) (xy 152.911753 -260.689905)
			(xy 152.862153 -260.664404) (xy 152.816795 -260.631953) (xy 152.776646 -260.593244) (xy 152.74256 -260.549101)
			(xy 152.715264 -260.500466) (xy 152.695341 -260.448375) (xy 152.683215 -260.393938) (xy 152.679144 -260.338316)
			(xy 152.55621 -260.338316) (xy 152.555701 -260.366202) (xy 152.547581 -260.421378) (xy 152.531513 -260.474785)
			(xy 152.507841 -260.525282) (xy 152.477068 -260.571795) (xy 152.439851 -260.613332) (xy 152.396983 -260.649007)
			(xy 152.349377 -260.678061) (xy 152.298048 -260.699873) (xy 152.244091 -260.713979) (xy 152.188654 -260.720079)
			(xy 152.13292 -260.718042) (xy 152.078077 -260.707912) (xy 152.025293 -260.689905) (xy 151.975693 -260.664404)
			(xy 151.930335 -260.631953) (xy 151.890186 -260.593244) (xy 151.8561 -260.549101) (xy 151.828804 -260.500466)
			(xy 151.808881 -260.448375) (xy 151.796755 -260.393938) (xy 151.792684 -260.338316) (xy 151.15921 -260.338316)
			(xy 151.158724 -260.365567) (xy 151.150968 -260.419515) (xy 151.135613 -260.47181) (xy 151.112971 -260.521387)
			(xy 151.083505 -260.567237) (xy 151.047814 -260.608428) (xy 151.006623 -260.644119) (xy 150.960773 -260.673585)
			(xy 150.911196 -260.696227) (xy 150.858901 -260.711582) (xy 150.804953 -260.719338) (xy 150.750451 -260.719338)
			(xy 150.696503 -260.711582) (xy 150.644208 -260.696227) (xy 150.594631 -260.673585) (xy 150.548781 -260.644119)
			(xy 150.50759 -260.608428) (xy 150.471899 -260.567237) (xy 150.442433 -260.521387) (xy 150.419791 -260.47181)
			(xy 150.404436 -260.419515) (xy 150.39668 -260.365567) (xy 150.396194 -260.338316) (xy 144.436067 -260.338316)
			(xy 144.406085 -260.371778) (xy 144.363217 -260.407453) (xy 144.315611 -260.436507) (xy 144.264282 -260.458319)
			(xy 144.210325 -260.472425) (xy 144.154888 -260.478525) (xy 144.099154 -260.476488) (xy 144.044311 -260.466358)
			(xy 143.991527 -260.448351) (xy 143.941927 -260.42285) (xy 143.896569 -260.390399) (xy 143.85642 -260.35169)
			(xy 143.822334 -260.307547) (xy 143.795038 -260.258912) (xy 143.775115 -260.206821) (xy 143.762989 -260.152384)
			(xy 143.758918 -260.096762) (xy 140.921994 -260.096762) (xy 140.921994 -261.812786) (xy 140.922219 -261.817951)
			(xy 143.143466 -261.817951) (xy 143.143466 -261.763449) (xy 143.151222 -261.709501) (xy 143.166576 -261.657207)
			(xy 143.189217 -261.607629) (xy 143.218682 -261.561779) (xy 143.254372 -261.520588) (xy 143.295561 -261.484895)
			(xy 143.34141 -261.455427) (xy 143.390986 -261.432784) (xy 143.44328 -261.417427) (xy 143.497227 -261.409667)
			(xy 143.524478 -261.40918) (xy 143.553396 -261.409684) (xy 143.610569 -261.418411) (xy 143.66577 -261.43567)
			(xy 143.717732 -261.461064) (xy 143.765265 -261.494012) (xy 143.80728 -261.533758) (xy 143.825468 -261.556246)
			(xy 143.83304 -261.564997) (xy 143.853791 -261.575184) (xy 143.865346 -261.575804) (xy 143.94561 -261.575804)
			(xy 143.957178 -261.575238) (xy 143.977949 -261.56504) (xy 143.985488 -261.556246) (xy 144.003672 -261.533757)
			(xy 144.045695 -261.494025) (xy 144.093232 -261.461088) (xy 144.145194 -261.435701) (xy 144.200392 -261.418445)
			(xy 144.257562 -261.409716) (xy 144.286478 -261.40918) (xy 144.313731 -261.409666) (xy 144.367683 -261.41742)
			(xy 144.419981 -261.432774) (xy 144.469563 -261.455414) (xy 144.499198 -261.474458) (xy 144.86966 -261.474458)
			(xy 144.873731 -261.418836) (xy 144.885857 -261.364399) (xy 144.90578 -261.312308) (xy 144.933076 -261.263673)
			(xy 144.967162 -261.21953) (xy 145.007311 -261.180821) (xy 145.052669 -261.14837) (xy 145.102269 -261.122869)
			(xy 145.155053 -261.104862) (xy 145.209896 -261.094732) (xy 145.26563 -261.092695) (xy 145.321067 -261.098795)
			(xy 145.375024 -261.112901) (xy 145.426353 -261.134713) (xy 145.473959 -261.163767) (xy 145.516827 -261.199442)
			(xy 145.554044 -261.240979) (xy 145.584817 -261.287492) (xy 145.608489 -261.337989) (xy 145.624557 -261.391396)
			(xy 145.632677 -261.446572) (xy 145.633186 -261.474458) (xy 146.354798 -261.474458) (xy 146.358869 -261.418836)
			(xy 146.370995 -261.364399) (xy 146.390918 -261.312308) (xy 146.418214 -261.263673) (xy 146.4523 -261.21953)
			(xy 146.492449 -261.180821) (xy 146.537807 -261.14837) (xy 146.587407 -261.122869) (xy 146.640191 -261.104862)
			(xy 146.695034 -261.094732) (xy 146.750768 -261.092695) (xy 146.806205 -261.098795) (xy 146.860162 -261.112901)
			(xy 146.911491 -261.134713) (xy 146.959097 -261.163767) (xy 147.001965 -261.199442) (xy 147.039182 -261.240979)
			(xy 147.069955 -261.287492) (xy 147.093627 -261.337989) (xy 147.109695 -261.391396) (xy 147.117815 -261.446572)
			(xy 147.118324 -261.474458) (xy 147.117815 -261.502344) (xy 147.109695 -261.55752) (xy 147.093627 -261.610927)
			(xy 147.069955 -261.661424) (xy 147.039182 -261.707937) (xy 147.001965 -261.749474) (xy 146.959097 -261.785149)
			(xy 146.911491 -261.814203) (xy 146.860162 -261.836015) (xy 146.806205 -261.850121) (xy 146.750768 -261.856221)
			(xy 146.695034 -261.854184) (xy 146.640191 -261.844054) (xy 146.587407 -261.826047) (xy 146.537807 -261.800546)
			(xy 146.492449 -261.768095) (xy 146.4523 -261.729386) (xy 146.418214 -261.685243) (xy 146.390918 -261.636608)
			(xy 146.370995 -261.584517) (xy 146.358869 -261.53008) (xy 146.354798 -261.474458) (xy 145.633186 -261.474458)
			(xy 145.632677 -261.502344) (xy 145.624557 -261.55752) (xy 145.608489 -261.610927) (xy 145.584817 -261.661424)
			(xy 145.554044 -261.707937) (xy 145.516827 -261.749474) (xy 145.473959 -261.785149) (xy 145.426353 -261.814203)
			(xy 145.375024 -261.836015) (xy 145.321067 -261.850121) (xy 145.26563 -261.856221) (xy 145.209896 -261.854184)
			(xy 145.155053 -261.844054) (xy 145.102269 -261.826047) (xy 145.052669 -261.800546) (xy 145.007311 -261.768095)
			(xy 144.967162 -261.729386) (xy 144.933076 -261.685243) (xy 144.90578 -261.636608) (xy 144.885857 -261.584517)
			(xy 144.873731 -261.53008) (xy 144.86966 -261.474458) (xy 144.499198 -261.474458) (xy 144.515417 -261.484881)
			(xy 144.556611 -261.520573) (xy 144.592306 -261.561765) (xy 144.621775 -261.607618) (xy 144.644419 -261.657198)
			(xy 144.659775 -261.709496) (xy 144.667533 -261.763447) (xy 144.667533 -261.817953) (xy 144.659775 -261.871904)
			(xy 144.644419 -261.924202) (xy 144.621775 -261.973782) (xy 144.592306 -262.019635) (xy 144.556611 -262.060827)
			(xy 144.515417 -262.096519) (xy 144.469563 -262.125986) (xy 144.419981 -262.148626) (xy 144.367683 -262.16398)
			(xy 144.313731 -262.171734) (xy 144.286478 -262.172196) (xy 144.257563 -262.171623) (xy 144.200394 -262.162906)
			(xy 144.145197 -262.145659) (xy 144.093235 -262.120277) (xy 144.045699 -262.087343) (xy 144.00368 -262.047611)
			(xy 143.985488 -262.02513) (xy 143.977939 -262.016355) (xy 143.95717 -262.006182) (xy 143.94561 -262.005572)
			(xy 143.865346 -262.005572) (xy 143.853778 -262.006144) (xy 143.833005 -262.016335) (xy 143.825468 -262.02513)
			(xy 143.807303 -262.047635) (xy 143.765277 -262.087368) (xy 143.717736 -262.120303) (xy 143.66577 -262.145688)
			(xy 143.610568 -262.162939) (xy 143.553395 -262.171664) (xy 143.524478 -262.172196) (xy 143.497227 -262.171733)
			(xy 143.44328 -262.163973) (xy 143.390986 -262.148616) (xy 143.34141 -262.125973) (xy 143.295561 -262.096505)
			(xy 143.254372 -262.060812) (xy 143.218682 -262.019621) (xy 143.189217 -261.973771) (xy 143.166576 -261.924193)
			(xy 143.151222 -261.871899) (xy 143.143466 -261.817951) (xy 140.922219 -261.817951) (xy 140.922432 -261.822849)
			(xy 140.930168 -261.841432) (xy 140.93698 -261.848854) (xy 141.429232 -262.341106) (xy 141.436633 -262.347947)
			(xy 141.455231 -262.355668) (xy 141.4653 -262.356092) (xy 149.648164 -262.356092) (xy 149.658229 -262.356526)
			(xy 149.676818 -262.364256) (xy 149.684232 -262.371078) (xy 149.93239 -262.619236) (xy 149.939732 -262.626055)
			(xy 149.958195 -262.633801) (xy 149.968204 -262.634222) (xy 150.049738 -262.63473) (xy 150.068026 -262.62711)
			(xy 150.075392 -262.619998) (xy 150.096908 -262.599738) (xy 150.14503 -262.565434) (xy 150.197867 -262.538962)
			(xy 150.254153 -262.520953) (xy 150.312543 -262.511839) (xy 150.342092 -262.511286) (xy 150.369345 -262.511749)
			(xy 150.423297 -262.519505) (xy 150.475597 -262.53486) (xy 150.525178 -262.557502) (xy 150.571033 -262.58697)
			(xy 150.612227 -262.622663) (xy 150.647922 -262.663856) (xy 150.677391 -262.70971) (xy 150.700035 -262.75929)
			(xy 150.715392 -262.811589) (xy 150.721919 -262.85698) (xy 153.136852 -262.85698) (xy 153.140923 -262.801358)
			(xy 153.153049 -262.746921) (xy 153.172972 -262.69483) (xy 153.200268 -262.646195) (xy 153.234354 -262.602052)
			(xy 153.274503 -262.563343) (xy 153.319861 -262.530892) (xy 153.369461 -262.505391) (xy 153.422245 -262.487384)
			(xy 153.477088 -262.477254) (xy 153.532822 -262.475217) (xy 153.588259 -262.481317) (xy 153.642216 -262.495423)
			(xy 153.693545 -262.517235) (xy 153.741151 -262.546289) (xy 153.784019 -262.581964) (xy 153.821236 -262.623501)
			(xy 153.852009 -262.670014) (xy 153.875681 -262.720511) (xy 153.891749 -262.773918) (xy 153.899869 -262.829094)
			(xy 153.900378 -262.85698) (xy 153.899869 -262.884866) (xy 153.891749 -262.940042) (xy 153.875681 -262.993449)
			(xy 153.852009 -263.043946) (xy 153.821236 -263.090459) (xy 153.784019 -263.131996) (xy 153.741151 -263.167671)
			(xy 153.693545 -263.196725) (xy 153.642216 -263.218537) (xy 153.588259 -263.232643) (xy 153.532822 -263.238743)
			(xy 153.477088 -263.236706) (xy 153.422245 -263.226576) (xy 153.369461 -263.208569) (xy 153.319861 -263.183068)
			(xy 153.274503 -263.150617) (xy 153.234354 -263.111908) (xy 153.200268 -263.067765) (xy 153.172972 -263.01913)
			(xy 153.153049 -262.967039) (xy 153.140923 -262.912602) (xy 153.136852 -262.85698) (xy 150.721919 -262.85698)
			(xy 150.72315 -262.865541) (xy 150.7236 -262.892794) (xy 150.723046 -262.922343) (xy 150.713934 -262.980734)
			(xy 150.695926 -263.037021) (xy 150.669455 -263.089858) (xy 150.635152 -263.137981) (xy 150.614888 -263.159494)
			(xy 150.607776 -263.16686) (xy 150.600156 -263.185148) (xy 150.600664 -263.266682) (xy 150.601197 -263.276672)
			(xy 150.608902 -263.295112) (xy 150.61565 -263.302496) (xy 150.690834 -263.37768) (xy 154.048204 -263.37768)
			(xy 154.052275 -263.322058) (xy 154.064401 -263.267621) (xy 154.084324 -263.21553) (xy 154.11162 -263.166895)
			(xy 154.145706 -263.122752) (xy 154.185855 -263.084043) (xy 154.231213 -263.051592) (xy 154.280813 -263.026091)
			(xy 154.333597 -263.008084) (xy 154.38844 -262.997954) (xy 154.444174 -262.995917) (xy 154.499611 -263.002017)
			(xy 154.553568 -263.016123) (xy 154.604897 -263.037935) (xy 154.652503 -263.066989) (xy 154.695371 -263.102664)
			(xy 154.732588 -263.144201) (xy 154.763361 -263.190714) (xy 154.787033 -263.241211) (xy 154.803101 -263.294618)
			(xy 154.811221 -263.349794) (xy 154.81173 -263.37768) (xy 154.811221 -263.405566) (xy 154.803101 -263.460742)
			(xy 154.787033 -263.514149) (xy 154.763361 -263.564646) (xy 154.732588 -263.611159) (xy 154.695371 -263.652696)
			(xy 154.652503 -263.688371) (xy 154.604897 -263.717425) (xy 154.553568 -263.739237) (xy 154.499611 -263.753343)
			(xy 154.444174 -263.759443) (xy 154.38844 -263.757406) (xy 154.333597 -263.747276) (xy 154.280813 -263.729269)
			(xy 154.231213 -263.703768) (xy 154.185855 -263.671317) (xy 154.145706 -263.632608) (xy 154.11162 -263.588465)
			(xy 154.084324 -263.53983) (xy 154.064401 -263.487739) (xy 154.052275 -263.433302) (xy 154.048204 -263.37768)
			(xy 150.690834 -263.37768) (xy 151.95677 -264.643616) (xy 153.652218 -264.643616) (xy 153.656289 -264.587994)
			(xy 153.668415 -264.533557) (xy 153.688338 -264.481466) (xy 153.715634 -264.432831) (xy 153.74972 -264.388688)
			(xy 153.789869 -264.349979) (xy 153.835227 -264.317528) (xy 153.884827 -264.292027) (xy 153.937611 -264.27402)
			(xy 153.992454 -264.26389) (xy 154.048188 -264.261853) (xy 154.103625 -264.267953) (xy 154.157582 -264.282059)
			(xy 154.208911 -264.303871) (xy 154.256517 -264.332925) (xy 154.299385 -264.3686) (xy 154.336602 -264.410137)
			(xy 154.367375 -264.45665) (xy 154.391047 -264.507147) (xy 154.407115 -264.560554) (xy 154.415235 -264.61573)
			(xy 154.415744 -264.643616) (xy 154.415235 -264.671502) (xy 154.407115 -264.726678) (xy 154.391047 -264.780085)
			(xy 154.367375 -264.830582) (xy 154.336602 -264.877095) (xy 154.299385 -264.918632) (xy 154.256517 -264.954307)
			(xy 154.208911 -264.983361) (xy 154.157582 -265.005173) (xy 154.103625 -265.019279) (xy 154.048188 -265.025379)
			(xy 153.992454 -265.023342) (xy 153.937611 -265.013212) (xy 153.884827 -264.995205) (xy 153.835227 -264.969704)
			(xy 153.789869 -264.937253) (xy 153.74972 -264.898544) (xy 153.715634 -264.854401) (xy 153.688338 -264.805766)
			(xy 153.668415 -264.753675) (xy 153.656289 -264.699238) (xy 153.652218 -264.643616) (xy 151.95677 -264.643616)
			(xy 152.477724 -265.16457) (xy 156.563058 -265.16457) (xy 156.567129 -265.108948) (xy 156.579255 -265.054511)
			(xy 156.599178 -265.00242) (xy 156.626474 -264.953785) (xy 156.66056 -264.909642) (xy 156.700709 -264.870933)
			(xy 156.746067 -264.838482) (xy 156.795667 -264.812981) (xy 156.848451 -264.794974) (xy 156.903294 -264.784844)
			(xy 156.959028 -264.782807) (xy 157.014465 -264.788907) (xy 157.068422 -264.803013) (xy 157.119751 -264.824825)
			(xy 157.167357 -264.853879) (xy 157.210225 -264.889554) (xy 157.247442 -264.931091) (xy 157.278215 -264.977604)
			(xy 157.301887 -265.028101) (xy 157.317955 -265.081508) (xy 157.326075 -265.136684) (xy 157.326584 -265.16457)
			(xy 157.326075 -265.192456) (xy 157.317955 -265.247632) (xy 157.301887 -265.301039) (xy 157.278215 -265.351536)
			(xy 157.247442 -265.398049) (xy 157.210225 -265.439586) (xy 157.167357 -265.475261) (xy 157.119751 -265.504315)
			(xy 157.068422 -265.526127) (xy 157.014465 -265.540233) (xy 156.959028 -265.546333) (xy 156.903294 -265.544296)
			(xy 156.848451 -265.534166) (xy 156.795667 -265.516159) (xy 156.746067 -265.490658) (xy 156.700709 -265.458207)
			(xy 156.66056 -265.419498) (xy 156.626474 -265.375355) (xy 156.599178 -265.32672) (xy 156.579255 -265.274629)
			(xy 156.567129 -265.220192) (xy 156.563058 -265.16457) (xy 152.477724 -265.16457) (xy 153.831036 -266.517882)
			(xy 156.497018 -266.517882) (xy 156.501089 -266.46226) (xy 156.513215 -266.407823) (xy 156.533138 -266.355732)
			(xy 156.560434 -266.307097) (xy 156.59452 -266.262954) (xy 156.634669 -266.224245) (xy 156.680027 -266.191794)
			(xy 156.729627 -266.166293) (xy 156.782411 -266.148286) (xy 156.837254 -266.138156) (xy 156.892988 -266.136119)
			(xy 156.948425 -266.142219) (xy 157.002382 -266.156325) (xy 157.053711 -266.178137) (xy 157.101317 -266.207191)
			(xy 157.144185 -266.242866) (xy 157.181402 -266.284403) (xy 157.212175 -266.330916) (xy 157.235847 -266.381413)
			(xy 157.251915 -266.43482) (xy 157.260035 -266.489996) (xy 157.260544 -266.517882) (xy 157.260035 -266.545768)
			(xy 157.251915 -266.600944) (xy 157.235847 -266.654351) (xy 157.212175 -266.704848) (xy 157.181402 -266.751361)
			(xy 157.144185 -266.792898) (xy 157.101317 -266.828573) (xy 157.053711 -266.857627) (xy 157.002382 -266.879439)
			(xy 156.948425 -266.893545) (xy 156.892988 -266.899645) (xy 156.837254 -266.897608) (xy 156.782411 -266.887478)
			(xy 156.729627 -266.869471) (xy 156.680027 -266.84397) (xy 156.634669 -266.811519) (xy 156.59452 -266.77281)
			(xy 156.560434 -266.728667) (xy 156.533138 -266.680032) (xy 156.513215 -266.627941) (xy 156.501089 -266.573504)
			(xy 156.497018 -266.517882) (xy 153.831036 -266.517882) (xy 153.928572 -266.615418) (xy 153.935419 -266.622816)
			(xy 153.943151 -266.641414) (xy 153.943558 -266.651486) (xy 153.943558 -266.963398) (xy 154.756102 -266.963398)
			(xy 154.760173 -266.907776) (xy 154.772299 -266.853339) (xy 154.792222 -266.801248) (xy 154.819518 -266.752613)
			(xy 154.853604 -266.70847) (xy 154.893753 -266.669761) (xy 154.939111 -266.63731) (xy 154.988711 -266.611809)
			(xy 155.041495 -266.593802) (xy 155.096338 -266.583672) (xy 155.152072 -266.581635) (xy 155.207509 -266.587735)
			(xy 155.261466 -266.601841) (xy 155.312795 -266.623653) (xy 155.360401 -266.652707) (xy 155.403269 -266.688382)
			(xy 155.440486 -266.729919) (xy 155.471259 -266.776432) (xy 155.494931 -266.826929) (xy 155.510999 -266.880336)
			(xy 155.519119 -266.935512) (xy 155.519628 -266.963398) (xy 155.519119 -266.991284) (xy 155.510999 -267.04646)
			(xy 155.494931 -267.099867) (xy 155.471259 -267.150364) (xy 155.440486 -267.196877) (xy 155.403269 -267.238414)
			(xy 155.360401 -267.274089) (xy 155.312795 -267.303143) (xy 155.261466 -267.324955) (xy 155.207509 -267.339061)
			(xy 155.152072 -267.345161) (xy 155.096338 -267.343124) (xy 155.041495 -267.332994) (xy 154.988711 -267.314987)
			(xy 154.939111 -267.289486) (xy 154.893753 -267.257035) (xy 154.853604 -267.218326) (xy 154.819518 -267.174183)
			(xy 154.792222 -267.125548) (xy 154.772299 -267.073457) (xy 154.760173 -267.01902) (xy 154.756102 -266.963398)
			(xy 153.943558 -266.963398) (xy 153.943558 -268.339062) (xy 156.865826 -268.339062) (xy 156.869897 -268.28344)
			(xy 156.882023 -268.229003) (xy 156.901946 -268.176912) (xy 156.929242 -268.128277) (xy 156.963328 -268.084134)
			(xy 157.003477 -268.045425) (xy 157.048835 -268.012974) (xy 157.098435 -267.987473) (xy 157.151219 -267.969466)
			(xy 157.206062 -267.959336) (xy 157.261796 -267.957299) (xy 157.317233 -267.963399) (xy 157.37119 -267.977505)
			(xy 157.422519 -267.999317) (xy 157.470125 -268.028371) (xy 157.512993 -268.064046) (xy 157.55021 -268.105583)
			(xy 157.580983 -268.152096) (xy 157.604655 -268.202593) (xy 157.620723 -268.256) (xy 157.628843 -268.311176)
			(xy 157.629352 -268.339062) (xy 157.628843 -268.366948) (xy 157.620723 -268.422124) (xy 157.604655 -268.475531)
			(xy 157.580983 -268.526028) (xy 157.55021 -268.572541) (xy 157.512993 -268.614078) (xy 157.470125 -268.649753)
			(xy 157.422519 -268.678807) (xy 157.37119 -268.700619) (xy 157.317233 -268.714725) (xy 157.261796 -268.720825)
			(xy 157.206062 -268.718788) (xy 157.151219 -268.708658) (xy 157.098435 -268.690651) (xy 157.048835 -268.66515)
			(xy 157.003477 -268.632699) (xy 156.963328 -268.59399) (xy 156.929242 -268.549847) (xy 156.901946 -268.501212)
			(xy 156.882023 -268.449121) (xy 156.869897 -268.394684) (xy 156.865826 -268.339062) (xy 153.943558 -268.339062)
			(xy 153.943558 -269.987014) (xy 155.308552 -269.987014) (xy 155.312623 -269.931392) (xy 155.324749 -269.876955)
			(xy 155.344672 -269.824864) (xy 155.371968 -269.776229) (xy 155.406054 -269.732086) (xy 155.446203 -269.693377)
			(xy 155.491561 -269.660926) (xy 155.541161 -269.635425) (xy 155.593945 -269.617418) (xy 155.648788 -269.607288)
			(xy 155.704522 -269.605251) (xy 155.759959 -269.611351) (xy 155.813916 -269.625457) (xy 155.865245 -269.647269)
			(xy 155.912851 -269.676323) (xy 155.955719 -269.711998) (xy 155.992936 -269.753535) (xy 156.023709 -269.800048)
			(xy 156.047381 -269.850545) (xy 156.063449 -269.903952) (xy 156.071569 -269.959128) (xy 156.072078 -269.987014)
			(xy 156.071569 -270.0149) (xy 156.063449 -270.070076) (xy 156.047381 -270.123483) (xy 156.023709 -270.17398)
			(xy 155.992936 -270.220493) (xy 155.955719 -270.26203) (xy 155.912851 -270.297705) (xy 155.865245 -270.326759)
			(xy 155.813916 -270.348571) (xy 155.759959 -270.362677) (xy 155.704522 -270.368777) (xy 155.648788 -270.36674)
			(xy 155.593945 -270.35661) (xy 155.541161 -270.338603) (xy 155.491561 -270.313102) (xy 155.446203 -270.280651)
			(xy 155.406054 -270.241942) (xy 155.371968 -270.197799) (xy 155.344672 -270.149164) (xy 155.324749 -270.097073)
			(xy 155.312623 -270.042636) (xy 155.308552 -269.987014) (xy 153.943558 -269.987014) (xy 153.943558 -272.624804)
			(xy 154.0693 -272.624804) (xy 154.07326 -272.57575) (xy 154.085037 -272.527966) (xy 154.104328 -272.48269)
			(xy 154.130631 -272.441094) (xy 154.163266 -272.404257) (xy 154.201387 -272.373132) (xy 154.244008 -272.348525)
			(xy 154.290024 -272.331073) (xy 154.338243 -272.321229) (xy 154.387418 -272.319248) (xy 154.436273 -272.32518)
			(xy 154.483544 -272.338872) (xy 154.528006 -272.35997) (xy 154.568509 -272.387926) (xy 154.604002 -272.422018)
			(xy 154.633567 -272.461362) (xy 154.656438 -272.504939) (xy 154.672022 -272.55162) (xy 154.679917 -272.600197)
			(xy 154.680412 -272.624804) (xy 155.01926 -272.624804) (xy 155.02322 -272.57575) (xy 155.034997 -272.527966)
			(xy 155.054288 -272.48269) (xy 155.080591 -272.441094) (xy 155.113226 -272.404257) (xy 155.151347 -272.373132)
			(xy 155.193968 -272.348525) (xy 155.239984 -272.331073) (xy 155.288203 -272.321229) (xy 155.337378 -272.319248)
			(xy 155.386233 -272.32518) (xy 155.433504 -272.338872) (xy 155.477966 -272.35997) (xy 155.518469 -272.387926)
			(xy 155.553962 -272.422018) (xy 155.583527 -272.461362) (xy 155.606398 -272.504939) (xy 155.621982 -272.55162)
			(xy 155.629877 -272.600197) (xy 155.630372 -272.624804) (xy 155.96922 -272.624804) (xy 155.97318 -272.57575)
			(xy 155.984957 -272.527966) (xy 156.004248 -272.48269) (xy 156.030551 -272.441094) (xy 156.063186 -272.404257)
			(xy 156.101307 -272.373132) (xy 156.143928 -272.348525) (xy 156.189944 -272.331073) (xy 156.238163 -272.321229)
			(xy 156.287338 -272.319248) (xy 156.336193 -272.32518) (xy 156.383464 -272.338872) (xy 156.427926 -272.35997)
			(xy 156.468429 -272.387926) (xy 156.503922 -272.422018) (xy 156.533487 -272.461362) (xy 156.556358 -272.504939)
			(xy 156.571942 -272.55162) (xy 156.579837 -272.600197) (xy 156.580332 -272.624804) (xy 156.91918 -272.624804)
			(xy 156.92314 -272.57575) (xy 156.934917 -272.527966) (xy 156.954208 -272.48269) (xy 156.980511 -272.441094)
			(xy 157.013146 -272.404257) (xy 157.051267 -272.373132) (xy 157.093888 -272.348525) (xy 157.139904 -272.331073)
			(xy 157.188123 -272.321229) (xy 157.237298 -272.319248) (xy 157.286153 -272.32518) (xy 157.333424 -272.338872)
			(xy 157.377886 -272.35997) (xy 157.418389 -272.387926) (xy 157.453882 -272.422018) (xy 157.483447 -272.461362)
			(xy 157.506318 -272.504939) (xy 157.521902 -272.55162) (xy 157.529797 -272.600197) (xy 157.530292 -272.624804)
			(xy 157.529797 -272.649411) (xy 157.521902 -272.697988) (xy 157.506318 -272.744669) (xy 157.483447 -272.788246)
			(xy 157.453882 -272.82759) (xy 157.418389 -272.861682) (xy 157.377886 -272.889638) (xy 157.333424 -272.910736)
			(xy 157.286153 -272.924428) (xy 157.237298 -272.93036) (xy 157.188123 -272.928379) (xy 157.139904 -272.918535)
			(xy 157.093888 -272.901083) (xy 157.051267 -272.876476) (xy 157.013146 -272.845351) (xy 156.980511 -272.808514)
			(xy 156.954208 -272.766918) (xy 156.934917 -272.721642) (xy 156.92314 -272.673858) (xy 156.91918 -272.624804)
			(xy 156.580332 -272.624804) (xy 156.579837 -272.649411) (xy 156.571942 -272.697988) (xy 156.556358 -272.744669)
			(xy 156.533487 -272.788246) (xy 156.503922 -272.82759) (xy 156.468429 -272.861682) (xy 156.427926 -272.889638)
			(xy 156.383464 -272.910736) (xy 156.336193 -272.924428) (xy 156.287338 -272.93036) (xy 156.238163 -272.928379)
			(xy 156.189944 -272.918535) (xy 156.143928 -272.901083) (xy 156.101307 -272.876476) (xy 156.063186 -272.845351)
			(xy 156.030551 -272.808514) (xy 156.004248 -272.766918) (xy 155.984957 -272.721642) (xy 155.97318 -272.673858)
			(xy 155.96922 -272.624804) (xy 155.630372 -272.624804) (xy 155.629877 -272.649411) (xy 155.621982 -272.697988)
			(xy 155.606398 -272.744669) (xy 155.583527 -272.788246) (xy 155.553962 -272.82759) (xy 155.518469 -272.861682)
			(xy 155.477966 -272.889638) (xy 155.433504 -272.910736) (xy 155.386233 -272.924428) (xy 155.337378 -272.93036)
			(xy 155.288203 -272.928379) (xy 155.239984 -272.918535) (xy 155.193968 -272.901083) (xy 155.151347 -272.876476)
			(xy 155.113226 -272.845351) (xy 155.080591 -272.808514) (xy 155.054288 -272.766918) (xy 155.034997 -272.721642)
			(xy 155.02322 -272.673858) (xy 155.01926 -272.624804) (xy 154.680412 -272.624804) (xy 154.679917 -272.649411)
			(xy 154.672022 -272.697988) (xy 154.656438 -272.744669) (xy 154.633567 -272.788246) (xy 154.604002 -272.82759)
			(xy 154.568509 -272.861682) (xy 154.528006 -272.889638) (xy 154.483544 -272.910736) (xy 154.436273 -272.924428)
			(xy 154.387418 -272.93036) (xy 154.338243 -272.928379) (xy 154.290024 -272.918535) (xy 154.244008 -272.901083)
			(xy 154.201387 -272.876476) (xy 154.163266 -272.845351) (xy 154.130631 -272.808514) (xy 154.104328 -272.766918)
			(xy 154.085037 -272.721642) (xy 154.07326 -272.673858) (xy 154.0693 -272.624804) (xy 153.943558 -272.624804)
			(xy 153.943558 -273.574764) (xy 154.069046 -273.574764) (xy 154.073006 -273.52571) (xy 154.084783 -273.477926)
			(xy 154.104074 -273.43265) (xy 154.130377 -273.391054) (xy 154.163012 -273.354217) (xy 154.201133 -273.323092)
			(xy 154.243754 -273.298485) (xy 154.28977 -273.281033) (xy 154.337989 -273.271189) (xy 154.387164 -273.269208)
			(xy 154.436019 -273.27514) (xy 154.48329 -273.288832) (xy 154.527752 -273.30993) (xy 154.568255 -273.337886)
			(xy 154.603748 -273.371978) (xy 154.633313 -273.411322) (xy 154.656184 -273.454899) (xy 154.671768 -273.50158)
			(xy 154.679663 -273.550157) (xy 154.680158 -273.574764) (xy 155.01926 -273.574764) (xy 155.02322 -273.52571)
			(xy 155.034997 -273.477926) (xy 155.054288 -273.43265) (xy 155.080591 -273.391054) (xy 155.113226 -273.354217)
			(xy 155.151347 -273.323092) (xy 155.193968 -273.298485) (xy 155.239984 -273.281033) (xy 155.288203 -273.271189)
			(xy 155.337378 -273.269208) (xy 155.386233 -273.27514) (xy 155.433504 -273.288832) (xy 155.477966 -273.30993)
			(xy 155.518469 -273.337886) (xy 155.553962 -273.371978) (xy 155.583527 -273.411322) (xy 155.606398 -273.454899)
			(xy 155.621982 -273.50158) (xy 155.629877 -273.550157) (xy 155.630372 -273.574764) (xy 155.96922 -273.574764)
			(xy 155.97318 -273.52571) (xy 155.984957 -273.477926) (xy 156.004248 -273.43265) (xy 156.030551 -273.391054)
			(xy 156.063186 -273.354217) (xy 156.101307 -273.323092) (xy 156.143928 -273.298485) (xy 156.189944 -273.281033)
			(xy 156.238163 -273.271189) (xy 156.287338 -273.269208) (xy 156.336193 -273.27514) (xy 156.383464 -273.288832)
			(xy 156.427926 -273.30993) (xy 156.468429 -273.337886) (xy 156.503922 -273.371978) (xy 156.533487 -273.411322)
			(xy 156.556358 -273.454899) (xy 156.571942 -273.50158) (xy 156.579837 -273.550157) (xy 156.580332 -273.574764)
			(xy 156.91918 -273.574764) (xy 156.92314 -273.52571) (xy 156.934917 -273.477926) (xy 156.954208 -273.43265)
			(xy 156.980511 -273.391054) (xy 157.013146 -273.354217) (xy 157.051267 -273.323092) (xy 157.093888 -273.298485)
			(xy 157.139904 -273.281033) (xy 157.188123 -273.271189) (xy 157.237298 -273.269208) (xy 157.286153 -273.27514)
			(xy 157.333424 -273.288832) (xy 157.377886 -273.30993) (xy 157.418389 -273.337886) (xy 157.453882 -273.371978)
			(xy 157.483447 -273.411322) (xy 157.506318 -273.454899) (xy 157.521902 -273.50158) (xy 157.529797 -273.550157)
			(xy 157.530292 -273.574764) (xy 157.529797 -273.599371) (xy 157.521902 -273.647948) (xy 157.506318 -273.694629)
			(xy 157.483447 -273.738206) (xy 157.453882 -273.77755) (xy 157.418389 -273.811642) (xy 157.377886 -273.839598)
			(xy 157.333424 -273.860696) (xy 157.286153 -273.874388) (xy 157.237298 -273.88032) (xy 157.188123 -273.878339)
			(xy 157.139904 -273.868495) (xy 157.093888 -273.851043) (xy 157.051267 -273.826436) (xy 157.013146 -273.795311)
			(xy 156.980511 -273.758474) (xy 156.954208 -273.716878) (xy 156.934917 -273.671602) (xy 156.92314 -273.623818)
			(xy 156.91918 -273.574764) (xy 156.580332 -273.574764) (xy 156.579837 -273.599371) (xy 156.571942 -273.647948)
			(xy 156.556358 -273.694629) (xy 156.533487 -273.738206) (xy 156.503922 -273.77755) (xy 156.468429 -273.811642)
			(xy 156.427926 -273.839598) (xy 156.383464 -273.860696) (xy 156.336193 -273.874388) (xy 156.287338 -273.88032)
			(xy 156.238163 -273.878339) (xy 156.189944 -273.868495) (xy 156.143928 -273.851043) (xy 156.101307 -273.826436)
			(xy 156.063186 -273.795311) (xy 156.030551 -273.758474) (xy 156.004248 -273.716878) (xy 155.984957 -273.671602)
			(xy 155.97318 -273.623818) (xy 155.96922 -273.574764) (xy 155.630372 -273.574764) (xy 155.629877 -273.599371)
			(xy 155.621982 -273.647948) (xy 155.606398 -273.694629) (xy 155.583527 -273.738206) (xy 155.553962 -273.77755)
			(xy 155.518469 -273.811642) (xy 155.477966 -273.839598) (xy 155.433504 -273.860696) (xy 155.386233 -273.874388)
			(xy 155.337378 -273.88032) (xy 155.288203 -273.878339) (xy 155.239984 -273.868495) (xy 155.193968 -273.851043)
			(xy 155.151347 -273.826436) (xy 155.113226 -273.795311) (xy 155.080591 -273.758474) (xy 155.054288 -273.716878)
			(xy 155.034997 -273.671602) (xy 155.02322 -273.623818) (xy 155.01926 -273.574764) (xy 154.680158 -273.574764)
			(xy 154.679663 -273.599371) (xy 154.671768 -273.647948) (xy 154.656184 -273.694629) (xy 154.633313 -273.738206)
			(xy 154.603748 -273.77755) (xy 154.568255 -273.811642) (xy 154.527752 -273.839598) (xy 154.48329 -273.860696)
			(xy 154.436019 -273.874388) (xy 154.387164 -273.88032) (xy 154.337989 -273.878339) (xy 154.28977 -273.868495)
			(xy 154.243754 -273.851043) (xy 154.201133 -273.826436) (xy 154.163012 -273.795311) (xy 154.130377 -273.758474)
			(xy 154.104074 -273.716878) (xy 154.084783 -273.671602) (xy 154.073006 -273.623818) (xy 154.069046 -273.574764)
			(xy 153.943558 -273.574764) (xy 153.943558 -274.524978) (xy 154.0693 -274.524978) (xy 154.07326 -274.475924)
			(xy 154.085037 -274.42814) (xy 154.104328 -274.382864) (xy 154.130631 -274.341268) (xy 154.163266 -274.304431)
			(xy 154.201387 -274.273306) (xy 154.244008 -274.248699) (xy 154.290024 -274.231247) (xy 154.338243 -274.221403)
			(xy 154.387418 -274.219422) (xy 154.436273 -274.225354) (xy 154.483544 -274.239046) (xy 154.528006 -274.260144)
			(xy 154.568509 -274.2881) (xy 154.604002 -274.322192) (xy 154.633567 -274.361536) (xy 154.656438 -274.405113)
			(xy 154.672022 -274.451794) (xy 154.679917 -274.500371) (xy 154.680412 -274.524978) (xy 155.01926 -274.524978)
			(xy 155.02322 -274.475924) (xy 155.034997 -274.42814) (xy 155.054288 -274.382864) (xy 155.080591 -274.341268)
			(xy 155.113226 -274.304431) (xy 155.151347 -274.273306) (xy 155.193968 -274.248699) (xy 155.239984 -274.231247)
			(xy 155.288203 -274.221403) (xy 155.337378 -274.219422) (xy 155.386233 -274.225354) (xy 155.433504 -274.239046)
			(xy 155.477966 -274.260144) (xy 155.518469 -274.2881) (xy 155.553962 -274.322192) (xy 155.583527 -274.361536)
			(xy 155.606398 -274.405113) (xy 155.621982 -274.451794) (xy 155.629877 -274.500371) (xy 155.630372 -274.524978)
			(xy 155.96922 -274.524978) (xy 155.97318 -274.475924) (xy 155.984957 -274.42814) (xy 156.004248 -274.382864)
			(xy 156.030551 -274.341268) (xy 156.063186 -274.304431) (xy 156.101307 -274.273306) (xy 156.143928 -274.248699)
			(xy 156.189944 -274.231247) (xy 156.238163 -274.221403) (xy 156.287338 -274.219422) (xy 156.336193 -274.225354)
			(xy 156.383464 -274.239046) (xy 156.427926 -274.260144) (xy 156.468429 -274.2881) (xy 156.503922 -274.322192)
			(xy 156.533487 -274.361536) (xy 156.556358 -274.405113) (xy 156.571942 -274.451794) (xy 156.579837 -274.500371)
			(xy 156.580332 -274.524978) (xy 156.91918 -274.524978) (xy 156.92314 -274.475924) (xy 156.934917 -274.42814)
			(xy 156.954208 -274.382864) (xy 156.980511 -274.341268) (xy 157.013146 -274.304431) (xy 157.051267 -274.273306)
			(xy 157.093888 -274.248699) (xy 157.139904 -274.231247) (xy 157.188123 -274.221403) (xy 157.237298 -274.219422)
			(xy 157.286153 -274.225354) (xy 157.333424 -274.239046) (xy 157.377886 -274.260144) (xy 157.418389 -274.2881)
			(xy 157.453882 -274.322192) (xy 157.483447 -274.361536) (xy 157.506318 -274.405113) (xy 157.521902 -274.451794)
			(xy 157.529797 -274.500371) (xy 157.530292 -274.524978) (xy 157.529797 -274.549585) (xy 157.521902 -274.598162)
			(xy 157.506318 -274.644843) (xy 157.483447 -274.68842) (xy 157.453882 -274.727764) (xy 157.418389 -274.761856)
			(xy 157.377886 -274.789812) (xy 157.333424 -274.81091) (xy 157.286153 -274.824602) (xy 157.237298 -274.830534)
			(xy 157.188123 -274.828553) (xy 157.139904 -274.818709) (xy 157.093888 -274.801257) (xy 157.051267 -274.77665)
			(xy 157.013146 -274.745525) (xy 156.980511 -274.708688) (xy 156.954208 -274.667092) (xy 156.934917 -274.621816)
			(xy 156.92314 -274.574032) (xy 156.91918 -274.524978) (xy 156.580332 -274.524978) (xy 156.579837 -274.549585)
			(xy 156.571942 -274.598162) (xy 156.556358 -274.644843) (xy 156.533487 -274.68842) (xy 156.503922 -274.727764)
			(xy 156.468429 -274.761856) (xy 156.427926 -274.789812) (xy 156.383464 -274.81091) (xy 156.336193 -274.824602)
			(xy 156.287338 -274.830534) (xy 156.238163 -274.828553) (xy 156.189944 -274.818709) (xy 156.143928 -274.801257)
			(xy 156.101307 -274.77665) (xy 156.063186 -274.745525) (xy 156.030551 -274.708688) (xy 156.004248 -274.667092)
			(xy 155.984957 -274.621816) (xy 155.97318 -274.574032) (xy 155.96922 -274.524978) (xy 155.630372 -274.524978)
			(xy 155.629877 -274.549585) (xy 155.621982 -274.598162) (xy 155.606398 -274.644843) (xy 155.583527 -274.68842)
			(xy 155.553962 -274.727764) (xy 155.518469 -274.761856) (xy 155.477966 -274.789812) (xy 155.433504 -274.81091)
			(xy 155.386233 -274.824602) (xy 155.337378 -274.830534) (xy 155.288203 -274.828553) (xy 155.239984 -274.818709)
			(xy 155.193968 -274.801257) (xy 155.151347 -274.77665) (xy 155.113226 -274.745525) (xy 155.080591 -274.708688)
			(xy 155.054288 -274.667092) (xy 155.034997 -274.621816) (xy 155.02322 -274.574032) (xy 155.01926 -274.524978)
			(xy 154.680412 -274.524978) (xy 154.679917 -274.549585) (xy 154.672022 -274.598162) (xy 154.656438 -274.644843)
			(xy 154.633567 -274.68842) (xy 154.604002 -274.727764) (xy 154.568509 -274.761856) (xy 154.528006 -274.789812)
			(xy 154.483544 -274.81091) (xy 154.436273 -274.824602) (xy 154.387418 -274.830534) (xy 154.338243 -274.828553)
			(xy 154.290024 -274.818709) (xy 154.244008 -274.801257) (xy 154.201387 -274.77665) (xy 154.163266 -274.745525)
			(xy 154.130631 -274.708688) (xy 154.104328 -274.667092) (xy 154.085037 -274.621816) (xy 154.07326 -274.574032)
			(xy 154.0693 -274.524978) (xy 153.943558 -274.524978) (xy 153.943558 -275.474938) (xy 154.0693 -275.474938)
			(xy 154.07326 -275.425884) (xy 154.085037 -275.3781) (xy 154.104328 -275.332824) (xy 154.130631 -275.291228)
			(xy 154.163266 -275.254391) (xy 154.201387 -275.223266) (xy 154.244008 -275.198659) (xy 154.290024 -275.181207)
			(xy 154.338243 -275.171363) (xy 154.387418 -275.169382) (xy 154.436273 -275.175314) (xy 154.483544 -275.189006)
			(xy 154.528006 -275.210104) (xy 154.568509 -275.23806) (xy 154.604002 -275.272152) (xy 154.633567 -275.311496)
			(xy 154.656438 -275.355073) (xy 154.672022 -275.401754) (xy 154.679917 -275.450331) (xy 154.680412 -275.474938)
			(xy 155.01926 -275.474938) (xy 155.02322 -275.425884) (xy 155.034997 -275.3781) (xy 155.054288 -275.332824)
			(xy 155.080591 -275.291228) (xy 155.113226 -275.254391) (xy 155.151347 -275.223266) (xy 155.193968 -275.198659)
			(xy 155.239984 -275.181207) (xy 155.288203 -275.171363) (xy 155.337378 -275.169382) (xy 155.386233 -275.175314)
			(xy 155.433504 -275.189006) (xy 155.477966 -275.210104) (xy 155.518469 -275.23806) (xy 155.553962 -275.272152)
			(xy 155.583527 -275.311496) (xy 155.606398 -275.355073) (xy 155.621982 -275.401754) (xy 155.629877 -275.450331)
			(xy 155.630372 -275.474938) (xy 155.96922 -275.474938) (xy 155.97318 -275.425884) (xy 155.984957 -275.3781)
			(xy 156.004248 -275.332824) (xy 156.030551 -275.291228) (xy 156.063186 -275.254391) (xy 156.101307 -275.223266)
			(xy 156.143928 -275.198659) (xy 156.189944 -275.181207) (xy 156.238163 -275.171363) (xy 156.287338 -275.169382)
			(xy 156.336193 -275.175314) (xy 156.383464 -275.189006) (xy 156.427926 -275.210104) (xy 156.468429 -275.23806)
			(xy 156.503922 -275.272152) (xy 156.533487 -275.311496) (xy 156.556358 -275.355073) (xy 156.571942 -275.401754)
			(xy 156.579837 -275.450331) (xy 156.580332 -275.474938) (xy 156.91918 -275.474938) (xy 156.92314 -275.425884)
			(xy 156.934917 -275.3781) (xy 156.954208 -275.332824) (xy 156.980511 -275.291228) (xy 157.013146 -275.254391)
			(xy 157.051267 -275.223266) (xy 157.093888 -275.198659) (xy 157.139904 -275.181207) (xy 157.188123 -275.171363)
			(xy 157.237298 -275.169382) (xy 157.286153 -275.175314) (xy 157.333424 -275.189006) (xy 157.377886 -275.210104)
			(xy 157.418389 -275.23806) (xy 157.453882 -275.272152) (xy 157.483447 -275.311496) (xy 157.506318 -275.355073)
			(xy 157.521902 -275.401754) (xy 157.529797 -275.450331) (xy 157.530292 -275.474938) (xy 157.529797 -275.499545)
			(xy 157.521902 -275.548122) (xy 157.506318 -275.594803) (xy 157.483447 -275.63838) (xy 157.453882 -275.677724)
			(xy 157.418389 -275.711816) (xy 157.377886 -275.739772) (xy 157.333424 -275.76087) (xy 157.286153 -275.774562)
			(xy 157.237298 -275.780494) (xy 157.188123 -275.778513) (xy 157.139904 -275.768669) (xy 157.093888 -275.751217)
			(xy 157.051267 -275.72661) (xy 157.013146 -275.695485) (xy 156.980511 -275.658648) (xy 156.954208 -275.617052)
			(xy 156.934917 -275.571776) (xy 156.92314 -275.523992) (xy 156.91918 -275.474938) (xy 156.580332 -275.474938)
			(xy 156.579837 -275.499545) (xy 156.571942 -275.548122) (xy 156.556358 -275.594803) (xy 156.533487 -275.63838)
			(xy 156.503922 -275.677724) (xy 156.468429 -275.711816) (xy 156.427926 -275.739772) (xy 156.383464 -275.76087)
			(xy 156.336193 -275.774562) (xy 156.287338 -275.780494) (xy 156.238163 -275.778513) (xy 156.189944 -275.768669)
			(xy 156.143928 -275.751217) (xy 156.101307 -275.72661) (xy 156.063186 -275.695485) (xy 156.030551 -275.658648)
			(xy 156.004248 -275.617052) (xy 155.984957 -275.571776) (xy 155.97318 -275.523992) (xy 155.96922 -275.474938)
			(xy 155.630372 -275.474938) (xy 155.629877 -275.499545) (xy 155.621982 -275.548122) (xy 155.606398 -275.594803)
			(xy 155.583527 -275.63838) (xy 155.553962 -275.677724) (xy 155.518469 -275.711816) (xy 155.477966 -275.739772)
			(xy 155.433504 -275.76087) (xy 155.386233 -275.774562) (xy 155.337378 -275.780494) (xy 155.288203 -275.778513)
			(xy 155.239984 -275.768669) (xy 155.193968 -275.751217) (xy 155.151347 -275.72661) (xy 155.113226 -275.695485)
			(xy 155.080591 -275.658648) (xy 155.054288 -275.617052) (xy 155.034997 -275.571776) (xy 155.02322 -275.523992)
			(xy 155.01926 -275.474938) (xy 154.680412 -275.474938) (xy 154.679917 -275.499545) (xy 154.672022 -275.548122)
			(xy 154.656438 -275.594803) (xy 154.633567 -275.63838) (xy 154.604002 -275.677724) (xy 154.568509 -275.711816)
			(xy 154.528006 -275.739772) (xy 154.483544 -275.76087) (xy 154.436273 -275.774562) (xy 154.387418 -275.780494)
			(xy 154.338243 -275.778513) (xy 154.290024 -275.768669) (xy 154.244008 -275.751217) (xy 154.201387 -275.72661)
			(xy 154.163266 -275.695485) (xy 154.130631 -275.658648) (xy 154.104328 -275.617052) (xy 154.085037 -275.571776)
			(xy 154.07326 -275.523992) (xy 154.0693 -275.474938) (xy 153.943558 -275.474938) (xy 153.943558 -276.424898)
			(xy 154.0693 -276.424898) (xy 154.07326 -276.375844) (xy 154.085037 -276.32806) (xy 154.104328 -276.282784)
			(xy 154.130631 -276.241188) (xy 154.163266 -276.204351) (xy 154.201387 -276.173226) (xy 154.244008 -276.148619)
			(xy 154.290024 -276.131167) (xy 154.338243 -276.121323) (xy 154.387418 -276.119342) (xy 154.436273 -276.125274)
			(xy 154.483544 -276.138966) (xy 154.528006 -276.160064) (xy 154.568509 -276.18802) (xy 154.604002 -276.222112)
			(xy 154.633567 -276.261456) (xy 154.656438 -276.305033) (xy 154.672022 -276.351714) (xy 154.679917 -276.400291)
			(xy 154.680412 -276.424898) (xy 155.01926 -276.424898) (xy 155.02322 -276.375844) (xy 155.034997 -276.32806)
			(xy 155.054288 -276.282784) (xy 155.080591 -276.241188) (xy 155.113226 -276.204351) (xy 155.151347 -276.173226)
			(xy 155.193968 -276.148619) (xy 155.239984 -276.131167) (xy 155.288203 -276.121323) (xy 155.337378 -276.119342)
			(xy 155.386233 -276.125274) (xy 155.433504 -276.138966) (xy 155.477966 -276.160064) (xy 155.518469 -276.18802)
			(xy 155.553962 -276.222112) (xy 155.583527 -276.261456) (xy 155.606398 -276.305033) (xy 155.621982 -276.351714)
			(xy 155.629877 -276.400291) (xy 155.630372 -276.424898) (xy 155.96922 -276.424898) (xy 155.97318 -276.375844)
			(xy 155.984957 -276.32806) (xy 156.004248 -276.282784) (xy 156.030551 -276.241188) (xy 156.063186 -276.204351)
			(xy 156.101307 -276.173226) (xy 156.143928 -276.148619) (xy 156.189944 -276.131167) (xy 156.238163 -276.121323)
			(xy 156.287338 -276.119342) (xy 156.336193 -276.125274) (xy 156.383464 -276.138966) (xy 156.427926 -276.160064)
			(xy 156.468429 -276.18802) (xy 156.503922 -276.222112) (xy 156.533487 -276.261456) (xy 156.556358 -276.305033)
			(xy 156.571942 -276.351714) (xy 156.579837 -276.400291) (xy 156.580332 -276.424898) (xy 156.91918 -276.424898)
			(xy 156.92314 -276.375844) (xy 156.934917 -276.32806) (xy 156.954208 -276.282784) (xy 156.980511 -276.241188)
			(xy 157.013146 -276.204351) (xy 157.051267 -276.173226) (xy 157.093888 -276.148619) (xy 157.139904 -276.131167)
			(xy 157.188123 -276.121323) (xy 157.237298 -276.119342) (xy 157.286153 -276.125274) (xy 157.333424 -276.138966)
			(xy 157.377886 -276.160064) (xy 157.418389 -276.18802) (xy 157.453882 -276.222112) (xy 157.483447 -276.261456)
			(xy 157.506318 -276.305033) (xy 157.521902 -276.351714) (xy 157.529797 -276.400291) (xy 157.530292 -276.424898)
			(xy 157.86914 -276.424898) (xy 157.8731 -276.375844) (xy 157.884877 -276.32806) (xy 157.904168 -276.282784)
			(xy 157.930471 -276.241188) (xy 157.963106 -276.204351) (xy 158.001227 -276.173226) (xy 158.043848 -276.148619)
			(xy 158.089864 -276.131167) (xy 158.138083 -276.121323) (xy 158.187258 -276.119342) (xy 158.236113 -276.125274)
			(xy 158.283384 -276.138966) (xy 158.327846 -276.160064) (xy 158.368349 -276.18802) (xy 158.403842 -276.222112)
			(xy 158.433407 -276.261456) (xy 158.456278 -276.305033) (xy 158.471862 -276.351714) (xy 158.479757 -276.400291)
			(xy 158.480252 -276.424898) (xy 158.479757 -276.449505) (xy 158.471862 -276.498082) (xy 158.456278 -276.544763)
			(xy 158.433407 -276.58834) (xy 158.403842 -276.627684) (xy 158.368349 -276.661776) (xy 158.327846 -276.689732)
			(xy 158.283384 -276.71083) (xy 158.236113 -276.724522) (xy 158.187258 -276.730454) (xy 158.138083 -276.728473)
			(xy 158.089864 -276.718629) (xy 158.043848 -276.701177) (xy 158.001227 -276.67657) (xy 157.963106 -276.645445)
			(xy 157.930471 -276.608608) (xy 157.904168 -276.567012) (xy 157.884877 -276.521736) (xy 157.8731 -276.473952)
			(xy 157.86914 -276.424898) (xy 157.530292 -276.424898) (xy 157.529797 -276.449505) (xy 157.521902 -276.498082)
			(xy 157.506318 -276.544763) (xy 157.483447 -276.58834) (xy 157.453882 -276.627684) (xy 157.418389 -276.661776)
			(xy 157.377886 -276.689732) (xy 157.333424 -276.71083) (xy 157.286153 -276.724522) (xy 157.237298 -276.730454)
			(xy 157.188123 -276.728473) (xy 157.139904 -276.718629) (xy 157.093888 -276.701177) (xy 157.051267 -276.67657)
			(xy 157.013146 -276.645445) (xy 156.980511 -276.608608) (xy 156.954208 -276.567012) (xy 156.934917 -276.521736)
			(xy 156.92314 -276.473952) (xy 156.91918 -276.424898) (xy 156.580332 -276.424898) (xy 156.579837 -276.449505)
			(xy 156.571942 -276.498082) (xy 156.556358 -276.544763) (xy 156.533487 -276.58834) (xy 156.503922 -276.627684)
			(xy 156.468429 -276.661776) (xy 156.427926 -276.689732) (xy 156.383464 -276.71083) (xy 156.336193 -276.724522)
			(xy 156.287338 -276.730454) (xy 156.238163 -276.728473) (xy 156.189944 -276.718629) (xy 156.143928 -276.701177)
			(xy 156.101307 -276.67657) (xy 156.063186 -276.645445) (xy 156.030551 -276.608608) (xy 156.004248 -276.567012)
			(xy 155.984957 -276.521736) (xy 155.97318 -276.473952) (xy 155.96922 -276.424898) (xy 155.630372 -276.424898)
			(xy 155.629877 -276.449505) (xy 155.621982 -276.498082) (xy 155.606398 -276.544763) (xy 155.583527 -276.58834)
			(xy 155.553962 -276.627684) (xy 155.518469 -276.661776) (xy 155.477966 -276.689732) (xy 155.433504 -276.71083)
			(xy 155.386233 -276.724522) (xy 155.337378 -276.730454) (xy 155.288203 -276.728473) (xy 155.239984 -276.718629)
			(xy 155.193968 -276.701177) (xy 155.151347 -276.67657) (xy 155.113226 -276.645445) (xy 155.080591 -276.608608)
			(xy 155.054288 -276.567012) (xy 155.034997 -276.521736) (xy 155.02322 -276.473952) (xy 155.01926 -276.424898)
			(xy 154.680412 -276.424898) (xy 154.679917 -276.449505) (xy 154.672022 -276.498082) (xy 154.656438 -276.544763)
			(xy 154.633567 -276.58834) (xy 154.604002 -276.627684) (xy 154.568509 -276.661776) (xy 154.528006 -276.689732)
			(xy 154.483544 -276.71083) (xy 154.436273 -276.724522) (xy 154.387418 -276.730454) (xy 154.338243 -276.728473)
			(xy 154.290024 -276.718629) (xy 154.244008 -276.701177) (xy 154.201387 -276.67657) (xy 154.163266 -276.645445)
			(xy 154.130631 -276.608608) (xy 154.104328 -276.567012) (xy 154.085037 -276.521736) (xy 154.07326 -276.473952)
			(xy 154.0693 -276.424898) (xy 153.943558 -276.424898) (xy 153.943558 -277.374858) (xy 154.0693 -277.374858)
			(xy 154.07326 -277.325804) (xy 154.085037 -277.27802) (xy 154.104328 -277.232744) (xy 154.130631 -277.191148)
			(xy 154.163266 -277.154311) (xy 154.201387 -277.123186) (xy 154.244008 -277.098579) (xy 154.290024 -277.081127)
			(xy 154.338243 -277.071283) (xy 154.387418 -277.069302) (xy 154.436273 -277.075234) (xy 154.483544 -277.088926)
			(xy 154.528006 -277.110024) (xy 154.568509 -277.13798) (xy 154.604002 -277.172072) (xy 154.633567 -277.211416)
			(xy 154.656438 -277.254993) (xy 154.672022 -277.301674) (xy 154.679917 -277.350251) (xy 154.680412 -277.374858)
			(xy 155.01926 -277.374858) (xy 155.02322 -277.325804) (xy 155.034997 -277.27802) (xy 155.054288 -277.232744)
			(xy 155.080591 -277.191148) (xy 155.113226 -277.154311) (xy 155.151347 -277.123186) (xy 155.193968 -277.098579)
			(xy 155.239984 -277.081127) (xy 155.288203 -277.071283) (xy 155.337378 -277.069302) (xy 155.386233 -277.075234)
			(xy 155.433504 -277.088926) (xy 155.477966 -277.110024) (xy 155.518469 -277.13798) (xy 155.553962 -277.172072)
			(xy 155.583527 -277.211416) (xy 155.606398 -277.254993) (xy 155.621982 -277.301674) (xy 155.629877 -277.350251)
			(xy 155.630372 -277.374858) (xy 155.96922 -277.374858) (xy 155.97318 -277.325804) (xy 155.984957 -277.27802)
			(xy 156.004248 -277.232744) (xy 156.030551 -277.191148) (xy 156.063186 -277.154311) (xy 156.101307 -277.123186)
			(xy 156.143928 -277.098579) (xy 156.189944 -277.081127) (xy 156.238163 -277.071283) (xy 156.287338 -277.069302)
			(xy 156.336193 -277.075234) (xy 156.383464 -277.088926) (xy 156.427926 -277.110024) (xy 156.468429 -277.13798)
			(xy 156.503922 -277.172072) (xy 156.533487 -277.211416) (xy 156.556358 -277.254993) (xy 156.571942 -277.301674)
			(xy 156.579837 -277.350251) (xy 156.580332 -277.374858) (xy 156.91918 -277.374858) (xy 156.92314 -277.325804)
			(xy 156.934917 -277.27802) (xy 156.954208 -277.232744) (xy 156.980511 -277.191148) (xy 157.013146 -277.154311)
			(xy 157.051267 -277.123186) (xy 157.093888 -277.098579) (xy 157.139904 -277.081127) (xy 157.188123 -277.071283)
			(xy 157.237298 -277.069302) (xy 157.286153 -277.075234) (xy 157.333424 -277.088926) (xy 157.377886 -277.110024)
			(xy 157.418389 -277.13798) (xy 157.453882 -277.172072) (xy 157.483447 -277.211416) (xy 157.506318 -277.254993)
			(xy 157.521902 -277.301674) (xy 157.529797 -277.350251) (xy 157.530292 -277.374858) (xy 157.86914 -277.374858)
			(xy 157.8731 -277.325804) (xy 157.884877 -277.27802) (xy 157.904168 -277.232744) (xy 157.930471 -277.191148)
			(xy 157.963106 -277.154311) (xy 158.001227 -277.123186) (xy 158.043848 -277.098579) (xy 158.089864 -277.081127)
			(xy 158.138083 -277.071283) (xy 158.187258 -277.069302) (xy 158.236113 -277.075234) (xy 158.283384 -277.088926)
			(xy 158.327846 -277.110024) (xy 158.368349 -277.13798) (xy 158.403842 -277.172072) (xy 158.433407 -277.211416)
			(xy 158.456278 -277.254993) (xy 158.471862 -277.301674) (xy 158.479757 -277.350251) (xy 158.480252 -277.374858)
			(xy 158.479757 -277.399465) (xy 158.471862 -277.448042) (xy 158.456278 -277.494723) (xy 158.433407 -277.5383)
			(xy 158.403842 -277.577644) (xy 158.368349 -277.611736) (xy 158.327846 -277.639692) (xy 158.283384 -277.66079)
			(xy 158.236113 -277.674482) (xy 158.187258 -277.680414) (xy 158.138083 -277.678433) (xy 158.089864 -277.668589)
			(xy 158.043848 -277.651137) (xy 158.001227 -277.62653) (xy 157.963106 -277.595405) (xy 157.930471 -277.558568)
			(xy 157.904168 -277.516972) (xy 157.884877 -277.471696) (xy 157.8731 -277.423912) (xy 157.86914 -277.374858)
			(xy 157.530292 -277.374858) (xy 157.529797 -277.399465) (xy 157.521902 -277.448042) (xy 157.506318 -277.494723)
			(xy 157.483447 -277.5383) (xy 157.453882 -277.577644) (xy 157.418389 -277.611736) (xy 157.377886 -277.639692)
			(xy 157.333424 -277.66079) (xy 157.286153 -277.674482) (xy 157.237298 -277.680414) (xy 157.188123 -277.678433)
			(xy 157.139904 -277.668589) (xy 157.093888 -277.651137) (xy 157.051267 -277.62653) (xy 157.013146 -277.595405)
			(xy 156.980511 -277.558568) (xy 156.954208 -277.516972) (xy 156.934917 -277.471696) (xy 156.92314 -277.423912)
			(xy 156.91918 -277.374858) (xy 156.580332 -277.374858) (xy 156.579837 -277.399465) (xy 156.571942 -277.448042)
			(xy 156.556358 -277.494723) (xy 156.533487 -277.5383) (xy 156.503922 -277.577644) (xy 156.468429 -277.611736)
			(xy 156.427926 -277.639692) (xy 156.383464 -277.66079) (xy 156.336193 -277.674482) (xy 156.287338 -277.680414)
			(xy 156.238163 -277.678433) (xy 156.189944 -277.668589) (xy 156.143928 -277.651137) (xy 156.101307 -277.62653)
			(xy 156.063186 -277.595405) (xy 156.030551 -277.558568) (xy 156.004248 -277.516972) (xy 155.984957 -277.471696)
			(xy 155.97318 -277.423912) (xy 155.96922 -277.374858) (xy 155.630372 -277.374858) (xy 155.629877 -277.399465)
			(xy 155.621982 -277.448042) (xy 155.606398 -277.494723) (xy 155.583527 -277.5383) (xy 155.553962 -277.577644)
			(xy 155.518469 -277.611736) (xy 155.477966 -277.639692) (xy 155.433504 -277.66079) (xy 155.386233 -277.674482)
			(xy 155.337378 -277.680414) (xy 155.288203 -277.678433) (xy 155.239984 -277.668589) (xy 155.193968 -277.651137)
			(xy 155.151347 -277.62653) (xy 155.113226 -277.595405) (xy 155.080591 -277.558568) (xy 155.054288 -277.516972)
			(xy 155.034997 -277.471696) (xy 155.02322 -277.423912) (xy 155.01926 -277.374858) (xy 154.680412 -277.374858)
			(xy 154.679917 -277.399465) (xy 154.672022 -277.448042) (xy 154.656438 -277.494723) (xy 154.633567 -277.5383)
			(xy 154.604002 -277.577644) (xy 154.568509 -277.611736) (xy 154.528006 -277.639692) (xy 154.483544 -277.66079)
			(xy 154.436273 -277.674482) (xy 154.387418 -277.680414) (xy 154.338243 -277.678433) (xy 154.290024 -277.668589)
			(xy 154.244008 -277.651137) (xy 154.201387 -277.62653) (xy 154.163266 -277.595405) (xy 154.130631 -277.558568)
			(xy 154.104328 -277.516972) (xy 154.085037 -277.471696) (xy 154.07326 -277.423912) (xy 154.0693 -277.374858)
			(xy 153.943558 -277.374858) (xy 153.943558 -278.324818) (xy 154.0693 -278.324818) (xy 154.07326 -278.275764)
			(xy 154.085037 -278.22798) (xy 154.104328 -278.182704) (xy 154.130631 -278.141108) (xy 154.163266 -278.104271)
			(xy 154.201387 -278.073146) (xy 154.244008 -278.048539) (xy 154.290024 -278.031087) (xy 154.338243 -278.021243)
			(xy 154.387418 -278.019262) (xy 154.436273 -278.025194) (xy 154.483544 -278.038886) (xy 154.528006 -278.059984)
			(xy 154.568509 -278.08794) (xy 154.604002 -278.122032) (xy 154.633567 -278.161376) (xy 154.656438 -278.204953)
			(xy 154.672022 -278.251634) (xy 154.679917 -278.300211) (xy 154.680412 -278.324818) (xy 155.01926 -278.324818)
			(xy 155.02322 -278.275764) (xy 155.034997 -278.22798) (xy 155.054288 -278.182704) (xy 155.080591 -278.141108)
			(xy 155.113226 -278.104271) (xy 155.151347 -278.073146) (xy 155.193968 -278.048539) (xy 155.239984 -278.031087)
			(xy 155.288203 -278.021243) (xy 155.337378 -278.019262) (xy 155.386233 -278.025194) (xy 155.433504 -278.038886)
			(xy 155.477966 -278.059984) (xy 155.518469 -278.08794) (xy 155.553962 -278.122032) (xy 155.583527 -278.161376)
			(xy 155.606398 -278.204953) (xy 155.621982 -278.251634) (xy 155.629877 -278.300211) (xy 155.630372 -278.324818)
			(xy 155.96922 -278.324818) (xy 155.97318 -278.275764) (xy 155.984957 -278.22798) (xy 156.004248 -278.182704)
			(xy 156.030551 -278.141108) (xy 156.063186 -278.104271) (xy 156.101307 -278.073146) (xy 156.143928 -278.048539)
			(xy 156.189944 -278.031087) (xy 156.238163 -278.021243) (xy 156.287338 -278.019262) (xy 156.336193 -278.025194)
			(xy 156.383464 -278.038886) (xy 156.427926 -278.059984) (xy 156.468429 -278.08794) (xy 156.503922 -278.122032)
			(xy 156.533487 -278.161376) (xy 156.556358 -278.204953) (xy 156.571942 -278.251634) (xy 156.579837 -278.300211)
			(xy 156.580332 -278.324818) (xy 156.91918 -278.324818) (xy 156.92314 -278.275764) (xy 156.934917 -278.22798)
			(xy 156.954208 -278.182704) (xy 156.980511 -278.141108) (xy 157.013146 -278.104271) (xy 157.051267 -278.073146)
			(xy 157.093888 -278.048539) (xy 157.139904 -278.031087) (xy 157.188123 -278.021243) (xy 157.237298 -278.019262)
			(xy 157.286153 -278.025194) (xy 157.333424 -278.038886) (xy 157.377886 -278.059984) (xy 157.418389 -278.08794)
			(xy 157.453882 -278.122032) (xy 157.483447 -278.161376) (xy 157.506318 -278.204953) (xy 157.521902 -278.251634)
			(xy 157.529797 -278.300211) (xy 157.530292 -278.324818) (xy 157.86914 -278.324818) (xy 157.8731 -278.275764)
			(xy 157.884877 -278.22798) (xy 157.904168 -278.182704) (xy 157.930471 -278.141108) (xy 157.963106 -278.104271)
			(xy 158.001227 -278.073146) (xy 158.043848 -278.048539) (xy 158.089864 -278.031087) (xy 158.138083 -278.021243)
			(xy 158.187258 -278.019262) (xy 158.236113 -278.025194) (xy 158.283384 -278.038886) (xy 158.327846 -278.059984)
			(xy 158.368349 -278.08794) (xy 158.403842 -278.122032) (xy 158.433407 -278.161376) (xy 158.456278 -278.204953)
			(xy 158.471862 -278.251634) (xy 158.479757 -278.300211) (xy 158.480252 -278.324818) (xy 158.479757 -278.349425)
			(xy 158.471862 -278.398002) (xy 158.456278 -278.444683) (xy 158.433407 -278.48826) (xy 158.403842 -278.527604)
			(xy 158.368349 -278.561696) (xy 158.327846 -278.589652) (xy 158.283384 -278.61075) (xy 158.236113 -278.624442)
			(xy 158.187258 -278.630374) (xy 158.138083 -278.628393) (xy 158.089864 -278.618549) (xy 158.043848 -278.601097)
			(xy 158.001227 -278.57649) (xy 157.963106 -278.545365) (xy 157.930471 -278.508528) (xy 157.904168 -278.466932)
			(xy 157.884877 -278.421656) (xy 157.8731 -278.373872) (xy 157.86914 -278.324818) (xy 157.530292 -278.324818)
			(xy 157.529797 -278.349425) (xy 157.521902 -278.398002) (xy 157.506318 -278.444683) (xy 157.483447 -278.48826)
			(xy 157.453882 -278.527604) (xy 157.418389 -278.561696) (xy 157.377886 -278.589652) (xy 157.333424 -278.61075)
			(xy 157.286153 -278.624442) (xy 157.237298 -278.630374) (xy 157.188123 -278.628393) (xy 157.139904 -278.618549)
			(xy 157.093888 -278.601097) (xy 157.051267 -278.57649) (xy 157.013146 -278.545365) (xy 156.980511 -278.508528)
			(xy 156.954208 -278.466932) (xy 156.934917 -278.421656) (xy 156.92314 -278.373872) (xy 156.91918 -278.324818)
			(xy 156.580332 -278.324818) (xy 156.579837 -278.349425) (xy 156.571942 -278.398002) (xy 156.556358 -278.444683)
			(xy 156.533487 -278.48826) (xy 156.503922 -278.527604) (xy 156.468429 -278.561696) (xy 156.427926 -278.589652)
			(xy 156.383464 -278.61075) (xy 156.336193 -278.624442) (xy 156.287338 -278.630374) (xy 156.238163 -278.628393)
			(xy 156.189944 -278.618549) (xy 156.143928 -278.601097) (xy 156.101307 -278.57649) (xy 156.063186 -278.545365)
			(xy 156.030551 -278.508528) (xy 156.004248 -278.466932) (xy 155.984957 -278.421656) (xy 155.97318 -278.373872)
			(xy 155.96922 -278.324818) (xy 155.630372 -278.324818) (xy 155.629877 -278.349425) (xy 155.621982 -278.398002)
			(xy 155.606398 -278.444683) (xy 155.583527 -278.48826) (xy 155.553962 -278.527604) (xy 155.518469 -278.561696)
			(xy 155.477966 -278.589652) (xy 155.433504 -278.61075) (xy 155.386233 -278.624442) (xy 155.337378 -278.630374)
			(xy 155.288203 -278.628393) (xy 155.239984 -278.618549) (xy 155.193968 -278.601097) (xy 155.151347 -278.57649)
			(xy 155.113226 -278.545365) (xy 155.080591 -278.508528) (xy 155.054288 -278.466932) (xy 155.034997 -278.421656)
			(xy 155.02322 -278.373872) (xy 155.01926 -278.324818) (xy 154.680412 -278.324818) (xy 154.679917 -278.349425)
			(xy 154.672022 -278.398002) (xy 154.656438 -278.444683) (xy 154.633567 -278.48826) (xy 154.604002 -278.527604)
			(xy 154.568509 -278.561696) (xy 154.528006 -278.589652) (xy 154.483544 -278.61075) (xy 154.436273 -278.624442)
			(xy 154.387418 -278.630374) (xy 154.338243 -278.628393) (xy 154.290024 -278.618549) (xy 154.244008 -278.601097)
			(xy 154.201387 -278.57649) (xy 154.163266 -278.545365) (xy 154.130631 -278.508528) (xy 154.104328 -278.466932)
			(xy 154.085037 -278.421656) (xy 154.07326 -278.373872) (xy 154.0693 -278.324818) (xy 153.943558 -278.324818)
			(xy 153.943558 -279.274778) (xy 154.0693 -279.274778) (xy 154.07326 -279.225724) (xy 154.085037 -279.17794)
			(xy 154.104328 -279.132664) (xy 154.130631 -279.091068) (xy 154.163266 -279.054231) (xy 154.201387 -279.023106)
			(xy 154.244008 -278.998499) (xy 154.290024 -278.981047) (xy 154.338243 -278.971203) (xy 154.387418 -278.969222)
			(xy 154.436273 -278.975154) (xy 154.483544 -278.988846) (xy 154.528006 -279.009944) (xy 154.568509 -279.0379)
			(xy 154.604002 -279.071992) (xy 154.633567 -279.111336) (xy 154.656438 -279.154913) (xy 154.672022 -279.201594)
			(xy 154.679917 -279.250171) (xy 154.680412 -279.274778) (xy 155.01926 -279.274778) (xy 155.02322 -279.225724)
			(xy 155.034997 -279.17794) (xy 155.054288 -279.132664) (xy 155.080591 -279.091068) (xy 155.113226 -279.054231)
			(xy 155.151347 -279.023106) (xy 155.193968 -278.998499) (xy 155.239984 -278.981047) (xy 155.288203 -278.971203)
			(xy 155.337378 -278.969222) (xy 155.386233 -278.975154) (xy 155.433504 -278.988846) (xy 155.477966 -279.009944)
			(xy 155.518469 -279.0379) (xy 155.553962 -279.071992) (xy 155.583527 -279.111336) (xy 155.606398 -279.154913)
			(xy 155.621982 -279.201594) (xy 155.629877 -279.250171) (xy 155.630372 -279.274778) (xy 155.96922 -279.274778)
			(xy 155.97318 -279.225724) (xy 155.984957 -279.17794) (xy 156.004248 -279.132664) (xy 156.030551 -279.091068)
			(xy 156.063186 -279.054231) (xy 156.101307 -279.023106) (xy 156.143928 -278.998499) (xy 156.189944 -278.981047)
			(xy 156.238163 -278.971203) (xy 156.287338 -278.969222) (xy 156.336193 -278.975154) (xy 156.383464 -278.988846)
			(xy 156.427926 -279.009944) (xy 156.468429 -279.0379) (xy 156.503922 -279.071992) (xy 156.533487 -279.111336)
			(xy 156.556358 -279.154913) (xy 156.571942 -279.201594) (xy 156.579837 -279.250171) (xy 156.580332 -279.274778)
			(xy 156.91918 -279.274778) (xy 156.92314 -279.225724) (xy 156.934917 -279.17794) (xy 156.954208 -279.132664)
			(xy 156.980511 -279.091068) (xy 157.013146 -279.054231) (xy 157.051267 -279.023106) (xy 157.093888 -278.998499)
			(xy 157.139904 -278.981047) (xy 157.188123 -278.971203) (xy 157.237298 -278.969222) (xy 157.286153 -278.975154)
			(xy 157.333424 -278.988846) (xy 157.377886 -279.009944) (xy 157.418389 -279.0379) (xy 157.453882 -279.071992)
			(xy 157.483447 -279.111336) (xy 157.506318 -279.154913) (xy 157.521902 -279.201594) (xy 157.529797 -279.250171)
			(xy 157.530292 -279.274778) (xy 157.86914 -279.274778) (xy 157.8731 -279.225724) (xy 157.884877 -279.17794)
			(xy 157.904168 -279.132664) (xy 157.930471 -279.091068) (xy 157.963106 -279.054231) (xy 158.001227 -279.023106)
			(xy 158.043848 -278.998499) (xy 158.089864 -278.981047) (xy 158.138083 -278.971203) (xy 158.187258 -278.969222)
			(xy 158.236113 -278.975154) (xy 158.283384 -278.988846) (xy 158.327846 -279.009944) (xy 158.368349 -279.0379)
			(xy 158.403842 -279.071992) (xy 158.433407 -279.111336) (xy 158.456278 -279.154913) (xy 158.471862 -279.201594)
			(xy 158.479757 -279.250171) (xy 158.480252 -279.274778) (xy 158.479757 -279.299385) (xy 158.471862 -279.347962)
			(xy 158.456278 -279.394643) (xy 158.433407 -279.43822) (xy 158.403842 -279.477564) (xy 158.368349 -279.511656)
			(xy 158.327846 -279.539612) (xy 158.283384 -279.56071) (xy 158.236113 -279.574402) (xy 158.187258 -279.580334)
			(xy 158.138083 -279.578353) (xy 158.089864 -279.568509) (xy 158.043848 -279.551057) (xy 158.001227 -279.52645)
			(xy 157.963106 -279.495325) (xy 157.930471 -279.458488) (xy 157.904168 -279.416892) (xy 157.884877 -279.371616)
			(xy 157.8731 -279.323832) (xy 157.86914 -279.274778) (xy 157.530292 -279.274778) (xy 157.529797 -279.299385)
			(xy 157.521902 -279.347962) (xy 157.506318 -279.394643) (xy 157.483447 -279.43822) (xy 157.453882 -279.477564)
			(xy 157.418389 -279.511656) (xy 157.377886 -279.539612) (xy 157.333424 -279.56071) (xy 157.286153 -279.574402)
			(xy 157.237298 -279.580334) (xy 157.188123 -279.578353) (xy 157.139904 -279.568509) (xy 157.093888 -279.551057)
			(xy 157.051267 -279.52645) (xy 157.013146 -279.495325) (xy 156.980511 -279.458488) (xy 156.954208 -279.416892)
			(xy 156.934917 -279.371616) (xy 156.92314 -279.323832) (xy 156.91918 -279.274778) (xy 156.580332 -279.274778)
			(xy 156.579837 -279.299385) (xy 156.571942 -279.347962) (xy 156.556358 -279.394643) (xy 156.533487 -279.43822)
			(xy 156.503922 -279.477564) (xy 156.468429 -279.511656) (xy 156.427926 -279.539612) (xy 156.383464 -279.56071)
			(xy 156.336193 -279.574402) (xy 156.287338 -279.580334) (xy 156.238163 -279.578353) (xy 156.189944 -279.568509)
			(xy 156.143928 -279.551057) (xy 156.101307 -279.52645) (xy 156.063186 -279.495325) (xy 156.030551 -279.458488)
			(xy 156.004248 -279.416892) (xy 155.984957 -279.371616) (xy 155.97318 -279.323832) (xy 155.96922 -279.274778)
			(xy 155.630372 -279.274778) (xy 155.629877 -279.299385) (xy 155.621982 -279.347962) (xy 155.606398 -279.394643)
			(xy 155.583527 -279.43822) (xy 155.553962 -279.477564) (xy 155.518469 -279.511656) (xy 155.477966 -279.539612)
			(xy 155.433504 -279.56071) (xy 155.386233 -279.574402) (xy 155.337378 -279.580334) (xy 155.288203 -279.578353)
			(xy 155.239984 -279.568509) (xy 155.193968 -279.551057) (xy 155.151347 -279.52645) (xy 155.113226 -279.495325)
			(xy 155.080591 -279.458488) (xy 155.054288 -279.416892) (xy 155.034997 -279.371616) (xy 155.02322 -279.323832)
			(xy 155.01926 -279.274778) (xy 154.680412 -279.274778) (xy 154.679917 -279.299385) (xy 154.672022 -279.347962)
			(xy 154.656438 -279.394643) (xy 154.633567 -279.43822) (xy 154.604002 -279.477564) (xy 154.568509 -279.511656)
			(xy 154.528006 -279.539612) (xy 154.483544 -279.56071) (xy 154.436273 -279.574402) (xy 154.387418 -279.580334)
			(xy 154.338243 -279.578353) (xy 154.290024 -279.568509) (xy 154.244008 -279.551057) (xy 154.201387 -279.52645)
			(xy 154.163266 -279.495325) (xy 154.130631 -279.458488) (xy 154.104328 -279.416892) (xy 154.085037 -279.371616)
			(xy 154.07326 -279.323832) (xy 154.0693 -279.274778) (xy 153.943558 -279.274778) (xy 153.943558 -279.435306)
			(xy 153.943984 -279.445374) (xy 153.951706 -279.463972) (xy 153.958544 -279.471374) (xy 154.402028 -279.914858)
			(xy 154.416252 -279.922224) (xy 154.424126 -279.923494) (xy 154.447564 -279.927773) (xy 154.492826 -279.942641)
			(xy 154.535227 -279.964362) (xy 154.573739 -279.992408) (xy 154.607423 -280.026098) (xy 154.635464 -280.064614)
			(xy 154.657178 -280.107019) (xy 154.672039 -280.152283) (xy 154.676348 -280.175716) (xy 154.677618 -280.18359)
			(xy 154.684984 -280.197814) (xy 154.711908 -280.224738) (xy 155.01926 -280.224738) (xy 155.02322 -280.175684)
			(xy 155.034997 -280.1279) (xy 155.054288 -280.082624) (xy 155.080591 -280.041028) (xy 155.113226 -280.004191)
			(xy 155.151347 -279.973066) (xy 155.193968 -279.948459) (xy 155.239984 -279.931007) (xy 155.288203 -279.921163)
			(xy 155.337378 -279.919182) (xy 155.386233 -279.925114) (xy 155.433504 -279.938806) (xy 155.477966 -279.959904)
			(xy 155.518469 -279.98786) (xy 155.553962 -280.021952) (xy 155.583527 -280.061296) (xy 155.606398 -280.104873)
			(xy 155.621982 -280.151554) (xy 155.629877 -280.200131) (xy 155.630372 -280.224738) (xy 155.96922 -280.224738)
			(xy 155.97318 -280.175684) (xy 155.984957 -280.1279) (xy 156.004248 -280.082624) (xy 156.030551 -280.041028)
			(xy 156.063186 -280.004191) (xy 156.101307 -279.973066) (xy 156.143928 -279.948459) (xy 156.189944 -279.931007)
			(xy 156.238163 -279.921163) (xy 156.287338 -279.919182) (xy 156.336193 -279.925114) (xy 156.383464 -279.938806)
			(xy 156.427926 -279.959904) (xy 156.468429 -279.98786) (xy 156.503922 -280.021952) (xy 156.533487 -280.061296)
			(xy 156.556358 -280.104873) (xy 156.571942 -280.151554) (xy 156.579837 -280.200131) (xy 156.580332 -280.224738)
			(xy 156.91918 -280.224738) (xy 156.92314 -280.175684) (xy 156.934917 -280.1279) (xy 156.954208 -280.082624)
			(xy 156.980511 -280.041028) (xy 157.013146 -280.004191) (xy 157.051267 -279.973066) (xy 157.093888 -279.948459)
			(xy 157.139904 -279.931007) (xy 157.188123 -279.921163) (xy 157.237298 -279.919182) (xy 157.286153 -279.925114)
			(xy 157.333424 -279.938806) (xy 157.377886 -279.959904) (xy 157.418389 -279.98786) (xy 157.453882 -280.021952)
			(xy 157.483447 -280.061296) (xy 157.506318 -280.104873) (xy 157.521902 -280.151554) (xy 157.529797 -280.200131)
			(xy 157.530292 -280.224738) (xy 157.86914 -280.224738) (xy 157.8731 -280.175684) (xy 157.884877 -280.1279)
			(xy 157.904168 -280.082624) (xy 157.930471 -280.041028) (xy 157.963106 -280.004191) (xy 158.001227 -279.973066)
			(xy 158.043848 -279.948459) (xy 158.089864 -279.931007) (xy 158.138083 -279.921163) (xy 158.187258 -279.919182)
			(xy 158.236113 -279.925114) (xy 158.283384 -279.938806) (xy 158.327846 -279.959904) (xy 158.368349 -279.98786)
			(xy 158.403842 -280.021952) (xy 158.433407 -280.061296) (xy 158.456278 -280.104873) (xy 158.471862 -280.151554)
			(xy 158.479757 -280.200131) (xy 158.480252 -280.224738) (xy 158.8191 -280.224738) (xy 158.82306 -280.175684)
			(xy 158.834837 -280.1279) (xy 158.854128 -280.082624) (xy 158.880431 -280.041028) (xy 158.913066 -280.004191)
			(xy 158.951187 -279.973066) (xy 158.993808 -279.948459) (xy 159.039824 -279.931007) (xy 159.088043 -279.921163)
			(xy 159.137218 -279.919182) (xy 159.186073 -279.925114) (xy 159.233344 -279.938806) (xy 159.277806 -279.959904)
			(xy 159.318309 -279.98786) (xy 159.353802 -280.021952) (xy 159.383367 -280.061296) (xy 159.406238 -280.104873)
			(xy 159.421822 -280.151554) (xy 159.429717 -280.200131) (xy 159.430212 -280.224738) (xy 159.429717 -280.249345)
			(xy 159.421822 -280.297922) (xy 159.406238 -280.344603) (xy 159.383367 -280.38818) (xy 159.353802 -280.427524)
			(xy 159.318309 -280.461616) (xy 159.277806 -280.489572) (xy 159.233344 -280.51067) (xy 159.186073 -280.524362)
			(xy 159.137218 -280.530294) (xy 159.088043 -280.528313) (xy 159.039824 -280.518469) (xy 158.993808 -280.501017)
			(xy 158.951187 -280.47641) (xy 158.913066 -280.445285) (xy 158.880431 -280.408448) (xy 158.854128 -280.366852)
			(xy 158.834837 -280.321576) (xy 158.82306 -280.273792) (xy 158.8191 -280.224738) (xy 158.480252 -280.224738)
			(xy 158.479757 -280.249345) (xy 158.471862 -280.297922) (xy 158.456278 -280.344603) (xy 158.433407 -280.38818)
			(xy 158.403842 -280.427524) (xy 158.368349 -280.461616) (xy 158.327846 -280.489572) (xy 158.283384 -280.51067)
			(xy 158.236113 -280.524362) (xy 158.187258 -280.530294) (xy 158.138083 -280.528313) (xy 158.089864 -280.518469)
			(xy 158.043848 -280.501017) (xy 158.001227 -280.47641) (xy 157.963106 -280.445285) (xy 157.930471 -280.408448)
			(xy 157.904168 -280.366852) (xy 157.884877 -280.321576) (xy 157.8731 -280.273792) (xy 157.86914 -280.224738)
			(xy 157.530292 -280.224738) (xy 157.529797 -280.249345) (xy 157.521902 -280.297922) (xy 157.506318 -280.344603)
			(xy 157.483447 -280.38818) (xy 157.453882 -280.427524) (xy 157.418389 -280.461616) (xy 157.377886 -280.489572)
			(xy 157.333424 -280.51067) (xy 157.286153 -280.524362) (xy 157.237298 -280.530294) (xy 157.188123 -280.528313)
			(xy 157.139904 -280.518469) (xy 157.093888 -280.501017) (xy 157.051267 -280.47641) (xy 157.013146 -280.445285)
			(xy 156.980511 -280.408448) (xy 156.954208 -280.366852) (xy 156.934917 -280.321576) (xy 156.92314 -280.273792)
			(xy 156.91918 -280.224738) (xy 156.580332 -280.224738) (xy 156.579837 -280.249345) (xy 156.571942 -280.297922)
			(xy 156.556358 -280.344603) (xy 156.533487 -280.38818) (xy 156.503922 -280.427524) (xy 156.468429 -280.461616)
			(xy 156.427926 -280.489572) (xy 156.383464 -280.51067) (xy 156.336193 -280.524362) (xy 156.287338 -280.530294)
			(xy 156.238163 -280.528313) (xy 156.189944 -280.518469) (xy 156.143928 -280.501017) (xy 156.101307 -280.47641)
			(xy 156.063186 -280.445285) (xy 156.030551 -280.408448) (xy 156.004248 -280.366852) (xy 155.984957 -280.321576)
			(xy 155.97318 -280.273792) (xy 155.96922 -280.224738) (xy 155.630372 -280.224738) (xy 155.629877 -280.249345)
			(xy 155.621982 -280.297922) (xy 155.606398 -280.344603) (xy 155.583527 -280.38818) (xy 155.553962 -280.427524)
			(xy 155.518469 -280.461616) (xy 155.477966 -280.489572) (xy 155.433504 -280.51067) (xy 155.386233 -280.524362)
			(xy 155.337378 -280.530294) (xy 155.288203 -280.528313) (xy 155.239984 -280.518469) (xy 155.193968 -280.501017)
			(xy 155.151347 -280.47641) (xy 155.113226 -280.445285) (xy 155.080591 -280.408448) (xy 155.054288 -280.366852)
			(xy 155.034997 -280.321576) (xy 155.02322 -280.273792) (xy 155.01926 -280.224738) (xy 154.711908 -280.224738)
			(xy 155.352242 -280.865072) (xy 155.366466 -280.872438) (xy 155.37434 -280.873708) (xy 155.397749 -280.877996)
			(xy 155.442952 -280.892871) (xy 155.485299 -280.914581) (xy 155.523762 -280.942601) (xy 155.557411 -280.976252)
			(xy 155.585429 -281.014717) (xy 155.607136 -281.057065) (xy 155.622008 -281.102269) (xy 155.626308 -281.125676)
			(xy 155.627578 -281.13355) (xy 155.634944 -281.147774) (xy 155.662122 -281.174952) (xy 155.96922 -281.174952)
			(xy 155.97318 -281.125898) (xy 155.984957 -281.078114) (xy 156.004248 -281.032838) (xy 156.030551 -280.991242)
			(xy 156.063186 -280.954405) (xy 156.101307 -280.92328) (xy 156.143928 -280.898673) (xy 156.189944 -280.881221)
			(xy 156.238163 -280.871377) (xy 156.287338 -280.869396) (xy 156.336193 -280.875328) (xy 156.383464 -280.88902)
			(xy 156.427926 -280.910118) (xy 156.468429 -280.938074) (xy 156.503922 -280.972166) (xy 156.533487 -281.01151)
			(xy 156.556358 -281.055087) (xy 156.571942 -281.101768) (xy 156.579837 -281.150345) (xy 156.580332 -281.174952)
			(xy 156.91918 -281.174952) (xy 156.92314 -281.125898) (xy 156.934917 -281.078114) (xy 156.954208 -281.032838)
			(xy 156.980511 -280.991242) (xy 157.013146 -280.954405) (xy 157.051267 -280.92328) (xy 157.093888 -280.898673)
			(xy 157.139904 -280.881221) (xy 157.188123 -280.871377) (xy 157.237298 -280.869396) (xy 157.286153 -280.875328)
			(xy 157.333424 -280.88902) (xy 157.377886 -280.910118) (xy 157.418389 -280.938074) (xy 157.453882 -280.972166)
			(xy 157.483447 -281.01151) (xy 157.506318 -281.055087) (xy 157.521902 -281.101768) (xy 157.529797 -281.150345)
			(xy 157.530292 -281.174952) (xy 157.86914 -281.174952) (xy 157.8731 -281.125898) (xy 157.884877 -281.078114)
			(xy 157.904168 -281.032838) (xy 157.930471 -280.991242) (xy 157.963106 -280.954405) (xy 158.001227 -280.92328)
			(xy 158.043848 -280.898673) (xy 158.089864 -280.881221) (xy 158.138083 -280.871377) (xy 158.187258 -280.869396)
			(xy 158.236113 -280.875328) (xy 158.283384 -280.88902) (xy 158.327846 -280.910118) (xy 158.368349 -280.938074)
			(xy 158.403842 -280.972166) (xy 158.433407 -281.01151) (xy 158.456278 -281.055087) (xy 158.471862 -281.101768)
			(xy 158.479757 -281.150345) (xy 158.480252 -281.174952) (xy 158.8191 -281.174952) (xy 158.82306 -281.125898)
			(xy 158.834837 -281.078114) (xy 158.854128 -281.032838) (xy 158.880431 -280.991242) (xy 158.913066 -280.954405)
			(xy 158.951187 -280.92328) (xy 158.993808 -280.898673) (xy 159.039824 -280.881221) (xy 159.088043 -280.871377)
			(xy 159.137218 -280.869396) (xy 159.186073 -280.875328) (xy 159.233344 -280.88902) (xy 159.277806 -280.910118)
			(xy 159.318309 -280.938074) (xy 159.353802 -280.972166) (xy 159.383367 -281.01151) (xy 159.406238 -281.055087)
			(xy 159.421822 -281.101768) (xy 159.429717 -281.150345) (xy 159.430212 -281.174952) (xy 159.429717 -281.199559)
			(xy 159.421822 -281.248136) (xy 159.406238 -281.294817) (xy 159.383367 -281.338394) (xy 159.353802 -281.377738)
			(xy 159.318309 -281.41183) (xy 159.277806 -281.439786) (xy 159.233344 -281.460884) (xy 159.186073 -281.474576)
			(xy 159.137218 -281.480508) (xy 159.088043 -281.478527) (xy 159.039824 -281.468683) (xy 158.993808 -281.451231)
			(xy 158.951187 -281.426624) (xy 158.913066 -281.395499) (xy 158.880431 -281.358662) (xy 158.854128 -281.317066)
			(xy 158.834837 -281.27179) (xy 158.82306 -281.224006) (xy 158.8191 -281.174952) (xy 158.480252 -281.174952)
			(xy 158.479757 -281.199559) (xy 158.471862 -281.248136) (xy 158.456278 -281.294817) (xy 158.433407 -281.338394)
			(xy 158.403842 -281.377738) (xy 158.368349 -281.41183) (xy 158.327846 -281.439786) (xy 158.283384 -281.460884)
			(xy 158.236113 -281.474576) (xy 158.187258 -281.480508) (xy 158.138083 -281.478527) (xy 158.089864 -281.468683)
			(xy 158.043848 -281.451231) (xy 158.001227 -281.426624) (xy 157.963106 -281.395499) (xy 157.930471 -281.358662)
			(xy 157.904168 -281.317066) (xy 157.884877 -281.27179) (xy 157.8731 -281.224006) (xy 157.86914 -281.174952)
			(xy 157.530292 -281.174952) (xy 157.529797 -281.199559) (xy 157.521902 -281.248136) (xy 157.506318 -281.294817)
			(xy 157.483447 -281.338394) (xy 157.453882 -281.377738) (xy 157.418389 -281.41183) (xy 157.377886 -281.439786)
			(xy 157.333424 -281.460884) (xy 157.286153 -281.474576) (xy 157.237298 -281.480508) (xy 157.188123 -281.478527)
			(xy 157.139904 -281.468683) (xy 157.093888 -281.451231) (xy 157.051267 -281.426624) (xy 157.013146 -281.395499)
			(xy 156.980511 -281.358662) (xy 156.954208 -281.317066) (xy 156.934917 -281.27179) (xy 156.92314 -281.224006)
			(xy 156.91918 -281.174952) (xy 156.580332 -281.174952) (xy 156.579837 -281.199559) (xy 156.571942 -281.248136)
			(xy 156.556358 -281.294817) (xy 156.533487 -281.338394) (xy 156.503922 -281.377738) (xy 156.468429 -281.41183)
			(xy 156.427926 -281.439786) (xy 156.383464 -281.460884) (xy 156.336193 -281.474576) (xy 156.287338 -281.480508)
			(xy 156.238163 -281.478527) (xy 156.189944 -281.468683) (xy 156.143928 -281.451231) (xy 156.101307 -281.426624)
			(xy 156.063186 -281.395499) (xy 156.030551 -281.358662) (xy 156.004248 -281.317066) (xy 155.984957 -281.27179)
			(xy 155.97318 -281.224006) (xy 155.96922 -281.174952) (xy 155.662122 -281.174952) (xy 156.302202 -281.815032)
			(xy 156.316426 -281.822398) (xy 156.3243 -281.823668) (xy 156.347707 -281.82796) (xy 156.392905 -281.84284)
			(xy 156.435247 -281.864553) (xy 156.473707 -281.892575) (xy 156.507352 -281.926224) (xy 156.535368 -281.964688)
			(xy 156.557076 -282.007033) (xy 156.57195 -282.052234) (xy 156.576268 -282.075636) (xy 156.577538 -282.08351)
			(xy 156.584904 -282.097734) (xy 156.612082 -282.124912) (xy 156.91918 -282.124912) (xy 156.92314 -282.075858)
			(xy 156.934917 -282.028074) (xy 156.954208 -281.982798) (xy 156.980511 -281.941202) (xy 157.013146 -281.904365)
			(xy 157.051267 -281.87324) (xy 157.093888 -281.848633) (xy 157.139904 -281.831181) (xy 157.188123 -281.821337)
			(xy 157.237298 -281.819356) (xy 157.286153 -281.825288) (xy 157.333424 -281.83898) (xy 157.377886 -281.860078)
			(xy 157.418389 -281.888034) (xy 157.453882 -281.922126) (xy 157.483447 -281.96147) (xy 157.506318 -282.005047)
			(xy 157.521902 -282.051728) (xy 157.529797 -282.100305) (xy 157.530292 -282.124912) (xy 157.86914 -282.124912)
			(xy 157.8731 -282.075858) (xy 157.884877 -282.028074) (xy 157.904168 -281.982798) (xy 157.930471 -281.941202)
			(xy 157.963106 -281.904365) (xy 158.001227 -281.87324) (xy 158.043848 -281.848633) (xy 158.089864 -281.831181)
			(xy 158.138083 -281.821337) (xy 158.187258 -281.819356) (xy 158.236113 -281.825288) (xy 158.283384 -281.83898)
			(xy 158.327846 -281.860078) (xy 158.368349 -281.888034) (xy 158.403842 -281.922126) (xy 158.433407 -281.96147)
			(xy 158.456278 -282.005047) (xy 158.471862 -282.051728) (xy 158.479757 -282.100305) (xy 158.480252 -282.124912)
			(xy 158.8191 -282.124912) (xy 158.82306 -282.075858) (xy 158.834837 -282.028074) (xy 158.854128 -281.982798)
			(xy 158.880431 -281.941202) (xy 158.913066 -281.904365) (xy 158.951187 -281.87324) (xy 158.993808 -281.848633)
			(xy 159.039824 -281.831181) (xy 159.088043 -281.821337) (xy 159.137218 -281.819356) (xy 159.186073 -281.825288)
			(xy 159.233344 -281.83898) (xy 159.277806 -281.860078) (xy 159.318309 -281.888034) (xy 159.353802 -281.922126)
			(xy 159.383367 -281.96147) (xy 159.406238 -282.005047) (xy 159.421822 -282.051728) (xy 159.429717 -282.100305)
			(xy 159.430046 -282.116639) (xy 159.769193 -282.116639) (xy 159.774556 -282.067291) (xy 159.787832 -282.019462)
			(xy 159.808671 -281.97441) (xy 159.836524 -281.933322) (xy 159.870657 -281.897282) (xy 159.91017 -281.867239)
			(xy 159.954024 -281.843983) (xy 160.001062 -281.828129) (xy 160.050045 -281.820093) (xy 160.074864 -281.819604)
			(xy 160.089047 -281.819785) (xy 160.117287 -281.822454) (xy 160.131252 -281.824938) (xy 160.143698 -281.827224)
			(xy 160.16732 -281.819858) (xy 160.24479 -281.742388) (xy 160.252156 -281.718766) (xy 160.24987 -281.70632)
			(xy 160.247386 -281.692355) (xy 160.244719 -281.664115) (xy 160.244536 -281.649932) (xy 160.245058 -281.624677)
			(xy 160.253371 -281.574855) (xy 160.269772 -281.527081) (xy 160.293813 -281.482658) (xy 160.324837 -281.442798)
			(xy 160.361999 -281.408588) (xy 160.404285 -281.380962) (xy 160.450541 -281.360672) (xy 160.499506 -281.348272)
			(xy 160.549844 -281.344101) (xy 160.600182 -281.348272) (xy 160.649147 -281.360672) (xy 160.695403 -281.380962)
			(xy 160.737689 -281.408588) (xy 160.774851 -281.442798) (xy 160.805875 -281.482658) (xy 160.829916 -281.527081)
			(xy 160.846317 -281.574855) (xy 160.85463 -281.624677) (xy 160.855152 -281.649932) (xy 160.854979 -281.664115)
			(xy 160.852304 -281.692355) (xy 160.849818 -281.70632) (xy 160.847532 -281.718766) (xy 160.854898 -281.742642)
			(xy 160.932114 -281.819858) (xy 160.956244 -281.827224) (xy 160.968436 -281.824938) (xy 160.982464 -281.82245)
			(xy 161.010832 -281.81978) (xy 161.025078 -281.819604) (xy 161.039261 -281.819784) (xy 161.067501 -281.822454)
			(xy 161.081466 -281.824938) (xy 161.093912 -281.827224) (xy 161.117534 -281.819858) (xy 161.195004 -281.742388)
			(xy 161.20237 -281.718766) (xy 161.200084 -281.70632) (xy 161.1976 -281.692355) (xy 161.194933 -281.664115)
			(xy 161.19475 -281.649932) (xy 161.195272 -281.624677) (xy 161.203585 -281.574855) (xy 161.219986 -281.527081)
			(xy 161.244027 -281.482658) (xy 161.275051 -281.442798) (xy 161.312213 -281.408588) (xy 161.354499 -281.380962)
			(xy 161.400755 -281.360672) (xy 161.44972 -281.348272) (xy 161.500058 -281.344101) (xy 161.550396 -281.348272)
			(xy 161.599361 -281.360672) (xy 161.645617 -281.380962) (xy 161.687903 -281.408588) (xy 161.725065 -281.442798)
			(xy 161.756089 -281.482658) (xy 161.78013 -281.527081) (xy 161.796531 -281.574855) (xy 161.804844 -281.624677)
			(xy 161.805366 -281.649932) (xy 161.805194 -281.664115) (xy 161.802519 -281.692355) (xy 161.800032 -281.70632)
			(xy 161.797746 -281.718766) (xy 161.805112 -281.742388) (xy 161.882582 -281.819858) (xy 161.906204 -281.827224)
			(xy 161.91865 -281.824938) (xy 161.932615 -281.822459) (xy 161.960855 -281.819789) (xy 161.975038 -281.819604)
			(xy 161.989221 -281.819775) (xy 162.017461 -281.822451) (xy 162.031426 -281.824938) (xy 162.043872 -281.827224)
			(xy 162.067494 -281.819858) (xy 162.144964 -281.742388) (xy 162.15233 -281.718766) (xy 162.150044 -281.70632)
			(xy 162.147561 -281.692355) (xy 162.144893 -281.664115) (xy 162.14471 -281.649932) (xy 162.145143 -281.625108)
			(xy 162.15317 -281.576114) (xy 162.169018 -281.529064) (xy 162.192269 -281.485198) (xy 162.22231 -281.445671)
			(xy 162.258351 -281.411525) (xy 162.299441 -281.383659) (xy 162.344498 -281.362809) (xy 162.392334 -281.349522)
			(xy 162.44169 -281.34415) (xy 162.491265 -281.346833) (xy 162.539752 -281.357502) (xy 162.585875 -281.375874)
			(xy 162.628418 -281.401467) (xy 162.66626 -281.433604) (xy 162.698404 -281.471441) (xy 162.724003 -281.51398)
			(xy 162.742383 -281.5601) (xy 162.75306 -281.608586) (xy 162.755304 -281.649932) (xy 163.094174 -281.649932)
			(xy 163.098134 -281.600878) (xy 163.109911 -281.553094) (xy 163.129202 -281.507818) (xy 163.155505 -281.466222)
			(xy 163.18814 -281.429385) (xy 163.226261 -281.39826) (xy 163.268882 -281.373653) (xy 163.314898 -281.356201)
			(xy 163.363117 -281.346357) (xy 163.412292 -281.344376) (xy 163.461147 -281.350308) (xy 163.508418 -281.364)
			(xy 163.55288 -281.385098) (xy 163.593383 -281.413054) (xy 163.628876 -281.447146) (xy 163.658441 -281.48649)
			(xy 163.681312 -281.530067) (xy 163.696896 -281.576748) (xy 163.704791 -281.625325) (xy 163.705286 -281.649932)
			(xy 163.704791 -281.674539) (xy 163.696896 -281.723116) (xy 163.681312 -281.769797) (xy 163.658441 -281.813374)
			(xy 163.628876 -281.852718) (xy 163.593383 -281.88681) (xy 163.55288 -281.914766) (xy 163.508418 -281.935864)
			(xy 163.461147 -281.949556) (xy 163.412292 -281.955488) (xy 163.363117 -281.953507) (xy 163.314898 -281.943663)
			(xy 163.268882 -281.926211) (xy 163.226261 -281.901604) (xy 163.18814 -281.870479) (xy 163.155505 -281.833642)
			(xy 163.129202 -281.792046) (xy 163.109911 -281.74677) (xy 163.098134 -281.698986) (xy 163.094174 -281.649932)
			(xy 162.755304 -281.649932) (xy 162.755751 -281.65816) (xy 162.750387 -281.707517) (xy 162.737109 -281.755355)
			(xy 162.716265 -281.800416) (xy 162.688407 -281.84151) (xy 162.654267 -281.877556) (xy 162.614745 -281.907604)
			(xy 162.570882 -281.930862) (xy 162.523835 -281.946718) (xy 162.474842 -281.954753) (xy 162.450018 -281.95524)
			(xy 162.435835 -281.95506) (xy 162.407595 -281.95239) (xy 162.39363 -281.949906) (xy 162.381184 -281.94762)
			(xy 162.357562 -281.954986) (xy 162.280092 -282.032456) (xy 162.272726 -282.056078) (xy 162.275012 -282.068524)
			(xy 162.277488 -282.08249) (xy 162.28016 -282.110729) (xy 162.280346 -282.124912) (xy 162.279824 -282.150167)
			(xy 162.271511 -282.199989) (xy 162.25511 -282.247763) (xy 162.231069 -282.292186) (xy 162.200045 -282.332046)
			(xy 162.162883 -282.366256) (xy 162.120597 -282.393882) (xy 162.074341 -282.414172) (xy 162.025376 -282.426572)
			(xy 161.975038 -282.430743) (xy 161.9247 -282.426572) (xy 161.875735 -282.414172) (xy 161.829479 -282.393882)
			(xy 161.787193 -282.366256) (xy 161.750031 -282.332046) (xy 161.719007 -282.292186) (xy 161.694966 -282.247763)
			(xy 161.678565 -282.199989) (xy 161.670252 -282.150167) (xy 161.66973 -282.124912) (xy 161.669908 -282.110729)
			(xy 161.672579 -282.082489) (xy 161.675064 -282.068524) (xy 161.67735 -282.056078) (xy 161.669984 -282.032456)
			(xy 161.592514 -281.954986) (xy 161.568892 -281.94762) (xy 161.556446 -281.949906) (xy 161.542481 -281.952386)
			(xy 161.514241 -281.955055) (xy 161.500058 -281.95524) (xy 161.485875 -281.955069) (xy 161.457635 -281.952393)
			(xy 161.44367 -281.949906) (xy 161.431224 -281.94762) (xy 161.407602 -281.954986) (xy 161.330132 -282.032456)
			(xy 161.322766 -282.056078) (xy 161.325052 -282.068524) (xy 161.327527 -282.08249) (xy 161.3302 -282.11073)
			(xy 161.330386 -282.124912) (xy 161.329864 -282.150167) (xy 161.321551 -282.199989) (xy 161.30515 -282.247763)
			(xy 161.281109 -282.292186) (xy 161.250085 -282.332046) (xy 161.212923 -282.366256) (xy 161.170637 -282.393882)
			(xy 161.124381 -282.414172) (xy 161.075416 -282.426572) (xy 161.025078 -282.430743) (xy 160.97474 -282.426572)
			(xy 160.925775 -282.414172) (xy 160.879519 -282.393882) (xy 160.837233 -282.366256) (xy 160.800071 -282.332046)
			(xy 160.769047 -282.292186) (xy 160.745006 -282.247763) (xy 160.728605 -282.199989) (xy 160.720292 -282.150167)
			(xy 160.71977 -282.124912) (xy 160.719949 -282.110729) (xy 160.722619 -282.082489) (xy 160.725104 -282.068524)
			(xy 160.72739 -282.056078) (xy 160.720024 -282.032202) (xy 160.642808 -281.954986) (xy 160.618678 -281.94762)
			(xy 160.606486 -281.949906) (xy 160.592457 -281.95239) (xy 160.56409 -281.955062) (xy 160.549844 -281.95524)
			(xy 160.535661 -281.955057) (xy 160.507421 -281.952389) (xy 160.493456 -281.949906) (xy 160.48101 -281.94762)
			(xy 160.457388 -281.954986) (xy 160.379918 -282.032456) (xy 160.372552 -282.056078) (xy 160.374838 -282.068524)
			(xy 160.377313 -282.08249) (xy 160.379986 -282.11073) (xy 160.380172 -282.124912) (xy 160.379709 -282.149731)
			(xy 160.371677 -282.198715) (xy 160.355826 -282.245754) (xy 160.332574 -282.28961) (xy 160.302534 -282.329126)
			(xy 160.266496 -282.363261) (xy 160.225411 -282.391117) (xy 160.180361 -282.41196) (xy 160.132532 -282.425239)
			(xy 160.083185 -282.430607) (xy 160.03362 -282.42792) (xy 159.985142 -282.41725) (xy 159.939029 -282.398879)
			(xy 159.896495 -282.373289) (xy 159.858662 -282.341155) (xy 159.826525 -282.303324) (xy 159.800932 -282.260793)
			(xy 159.782557 -282.214681) (xy 159.771883 -282.166204) (xy 159.769193 -282.116639) (xy 159.430046 -282.116639)
			(xy 159.430212 -282.124912) (xy 159.429717 -282.149519) (xy 159.421822 -282.198096) (xy 159.406238 -282.244777)
			(xy 159.383367 -282.288354) (xy 159.353802 -282.327698) (xy 159.318309 -282.36179) (xy 159.277806 -282.389746)
			(xy 159.233344 -282.410844) (xy 159.186073 -282.424536) (xy 159.137218 -282.430468) (xy 159.088043 -282.428487)
			(xy 159.039824 -282.418643) (xy 158.993808 -282.401191) (xy 158.951187 -282.376584) (xy 158.913066 -282.345459)
			(xy 158.880431 -282.308622) (xy 158.854128 -282.267026) (xy 158.834837 -282.22175) (xy 158.82306 -282.173966)
			(xy 158.8191 -282.124912) (xy 158.480252 -282.124912) (xy 158.479757 -282.149519) (xy 158.471862 -282.198096)
			(xy 158.456278 -282.244777) (xy 158.433407 -282.288354) (xy 158.403842 -282.327698) (xy 158.368349 -282.36179)
			(xy 158.327846 -282.389746) (xy 158.283384 -282.410844) (xy 158.236113 -282.424536) (xy 158.187258 -282.430468)
			(xy 158.138083 -282.428487) (xy 158.089864 -282.418643) (xy 158.043848 -282.401191) (xy 158.001227 -282.376584)
			(xy 157.963106 -282.345459) (xy 157.930471 -282.308622) (xy 157.904168 -282.267026) (xy 157.884877 -282.22175)
			(xy 157.8731 -282.173966) (xy 157.86914 -282.124912) (xy 157.530292 -282.124912) (xy 157.529797 -282.149519)
			(xy 157.521902 -282.198096) (xy 157.506318 -282.244777) (xy 157.483447 -282.288354) (xy 157.453882 -282.327698)
			(xy 157.418389 -282.36179) (xy 157.377886 -282.389746) (xy 157.333424 -282.410844) (xy 157.286153 -282.424536)
			(xy 157.237298 -282.430468) (xy 157.188123 -282.428487) (xy 157.139904 -282.418643) (xy 157.093888 -282.401191)
			(xy 157.051267 -282.376584) (xy 157.013146 -282.345459) (xy 156.980511 -282.308622) (xy 156.954208 -282.267026)
			(xy 156.934917 -282.22175) (xy 156.92314 -282.173966) (xy 156.91918 -282.124912) (xy 156.612082 -282.124912)
			(xy 157.252162 -282.764992) (xy 157.266386 -282.772358) (xy 157.27426 -282.773628) (xy 157.29767 -282.777917)
			(xy 157.342876 -282.792792) (xy 157.385225 -282.814501) (xy 157.423693 -282.84252) (xy 157.457348 -282.876168)
			(xy 157.485372 -282.914631) (xy 157.507089 -282.956978) (xy 157.521971 -283.002181) (xy 157.526228 -283.025596)
			(xy 157.527498 -283.03347) (xy 157.534864 -283.047694) (xy 157.562042 -283.074872) (xy 157.86914 -283.074872)
			(xy 157.8731 -283.025818) (xy 157.884877 -282.978034) (xy 157.904168 -282.932758) (xy 157.930471 -282.891162)
			(xy 157.963106 -282.854325) (xy 158.001227 -282.8232) (xy 158.043848 -282.798593) (xy 158.089864 -282.781141)
			(xy 158.138083 -282.771297) (xy 158.187258 -282.769316) (xy 158.236113 -282.775248) (xy 158.283384 -282.78894)
			(xy 158.327846 -282.810038) (xy 158.368349 -282.837994) (xy 158.403842 -282.872086) (xy 158.433407 -282.91143)
			(xy 158.456278 -282.955007) (xy 158.471862 -283.001688) (xy 158.479757 -283.050265) (xy 158.480252 -283.074872)
			(xy 158.8191 -283.074872) (xy 158.82306 -283.025818) (xy 158.834837 -282.978034) (xy 158.854128 -282.932758)
			(xy 158.880431 -282.891162) (xy 158.913066 -282.854325) (xy 158.951187 -282.8232) (xy 158.993808 -282.798593)
			(xy 159.039824 -282.781141) (xy 159.088043 -282.771297) (xy 159.137218 -282.769316) (xy 159.186073 -282.775248)
			(xy 159.233344 -282.78894) (xy 159.277806 -282.810038) (xy 159.318309 -282.837994) (xy 159.353802 -282.872086)
			(xy 159.383367 -282.91143) (xy 159.406238 -282.955007) (xy 159.421822 -283.001688) (xy 159.429717 -283.050265)
			(xy 159.430212 -283.074872) (xy 159.76906 -283.074872) (xy 159.77302 -283.025818) (xy 159.784797 -282.978034)
			(xy 159.804088 -282.932758) (xy 159.830391 -282.891162) (xy 159.863026 -282.854325) (xy 159.901147 -282.8232)
			(xy 159.943768 -282.798593) (xy 159.989784 -282.781141) (xy 160.038003 -282.771297) (xy 160.087178 -282.769316)
			(xy 160.136033 -282.775248) (xy 160.183304 -282.78894) (xy 160.227766 -282.810038) (xy 160.268269 -282.837994)
			(xy 160.303762 -282.872086) (xy 160.333327 -282.91143) (xy 160.356198 -282.955007) (xy 160.371782 -283.001688)
			(xy 160.379677 -283.050265) (xy 160.380172 -283.074872) (xy 160.719274 -283.074872) (xy 160.723234 -283.025818)
			(xy 160.735011 -282.978034) (xy 160.754302 -282.932758) (xy 160.780605 -282.891162) (xy 160.81324 -282.854325)
			(xy 160.851361 -282.8232) (xy 160.893982 -282.798593) (xy 160.939998 -282.781141) (xy 160.988217 -282.771297)
			(xy 161.037392 -282.769316) (xy 161.086247 -282.775248) (xy 161.133518 -282.78894) (xy 161.17798 -282.810038)
			(xy 161.218483 -282.837994) (xy 161.253976 -282.872086) (xy 161.283541 -282.91143) (xy 161.306412 -282.955007)
			(xy 161.321996 -283.001688) (xy 161.329891 -283.050265) (xy 161.330386 -283.074872) (xy 161.669234 -283.074872)
			(xy 161.673194 -283.025818) (xy 161.684971 -282.978034) (xy 161.704262 -282.932758) (xy 161.730565 -282.891162)
			(xy 161.7632 -282.854325) (xy 161.801321 -282.8232) (xy 161.843942 -282.798593) (xy 161.889958 -282.781141)
			(xy 161.938177 -282.771297) (xy 161.987352 -282.769316) (xy 162.036207 -282.775248) (xy 162.083478 -282.78894)
			(xy 162.12794 -282.810038) (xy 162.168443 -282.837994) (xy 162.203936 -282.872086) (xy 162.233501 -282.91143)
			(xy 162.256372 -282.955007) (xy 162.271956 -283.001688) (xy 162.279851 -283.050265) (xy 162.280346 -283.074872)
			(xy 162.619194 -283.074872) (xy 162.623154 -283.025818) (xy 162.634931 -282.978034) (xy 162.654222 -282.932758)
			(xy 162.680525 -282.891162) (xy 162.71316 -282.854325) (xy 162.751281 -282.8232) (xy 162.793902 -282.798593)
			(xy 162.839918 -282.781141) (xy 162.888137 -282.771297) (xy 162.937312 -282.769316) (xy 162.986167 -282.775248)
			(xy 163.033438 -282.78894) (xy 163.0779 -282.810038) (xy 163.118403 -282.837994) (xy 163.153896 -282.872086)
			(xy 163.183461 -282.91143) (xy 163.206332 -282.955007) (xy 163.221916 -283.001688) (xy 163.229811 -283.050265)
			(xy 163.230306 -283.074872) (xy 163.229811 -283.099479) (xy 163.221916 -283.148056) (xy 163.206332 -283.194737)
			(xy 163.183461 -283.238314) (xy 163.153896 -283.277658) (xy 163.118403 -283.31175) (xy 163.0779 -283.339706)
			(xy 163.033438 -283.360804) (xy 162.986167 -283.374496) (xy 162.937312 -283.380428) (xy 162.888137 -283.378447)
			(xy 162.839918 -283.368603) (xy 162.793902 -283.351151) (xy 162.751281 -283.326544) (xy 162.71316 -283.295419)
			(xy 162.680525 -283.258582) (xy 162.654222 -283.216986) (xy 162.634931 -283.17171) (xy 162.623154 -283.123926)
			(xy 162.619194 -283.074872) (xy 162.280346 -283.074872) (xy 162.279851 -283.099479) (xy 162.271956 -283.148056)
			(xy 162.256372 -283.194737) (xy 162.233501 -283.238314) (xy 162.203936 -283.277658) (xy 162.168443 -283.31175)
			(xy 162.12794 -283.339706) (xy 162.083478 -283.360804) (xy 162.036207 -283.374496) (xy 161.987352 -283.380428)
			(xy 161.938177 -283.378447) (xy 161.889958 -283.368603) (xy 161.843942 -283.351151) (xy 161.801321 -283.326544)
			(xy 161.7632 -283.295419) (xy 161.730565 -283.258582) (xy 161.704262 -283.216986) (xy 161.684971 -283.17171)
			(xy 161.673194 -283.123926) (xy 161.669234 -283.074872) (xy 161.330386 -283.074872) (xy 161.329891 -283.099479)
			(xy 161.321996 -283.148056) (xy 161.306412 -283.194737) (xy 161.283541 -283.238314) (xy 161.253976 -283.277658)
			(xy 161.218483 -283.31175) (xy 161.17798 -283.339706) (xy 161.133518 -283.360804) (xy 161.086247 -283.374496)
			(xy 161.037392 -283.380428) (xy 160.988217 -283.378447) (xy 160.939998 -283.368603) (xy 160.893982 -283.351151)
			(xy 160.851361 -283.326544) (xy 160.81324 -283.295419) (xy 160.780605 -283.258582) (xy 160.754302 -283.216986)
			(xy 160.735011 -283.17171) (xy 160.723234 -283.123926) (xy 160.719274 -283.074872) (xy 160.380172 -283.074872)
			(xy 160.379677 -283.099479) (xy 160.371782 -283.148056) (xy 160.356198 -283.194737) (xy 160.333327 -283.238314)
			(xy 160.303762 -283.277658) (xy 160.268269 -283.31175) (xy 160.227766 -283.339706) (xy 160.183304 -283.360804)
			(xy 160.136033 -283.374496) (xy 160.087178 -283.380428) (xy 160.038003 -283.378447) (xy 159.989784 -283.368603)
			(xy 159.943768 -283.351151) (xy 159.901147 -283.326544) (xy 159.863026 -283.295419) (xy 159.830391 -283.258582)
			(xy 159.804088 -283.216986) (xy 159.784797 -283.17171) (xy 159.77302 -283.123926) (xy 159.76906 -283.074872)
			(xy 159.430212 -283.074872) (xy 159.429717 -283.099479) (xy 159.421822 -283.148056) (xy 159.406238 -283.194737)
			(xy 159.383367 -283.238314) (xy 159.353802 -283.277658) (xy 159.318309 -283.31175) (xy 159.277806 -283.339706)
			(xy 159.233344 -283.360804) (xy 159.186073 -283.374496) (xy 159.137218 -283.380428) (xy 159.088043 -283.378447)
			(xy 159.039824 -283.368603) (xy 158.993808 -283.351151) (xy 158.951187 -283.326544) (xy 158.913066 -283.295419)
			(xy 158.880431 -283.258582) (xy 158.854128 -283.216986) (xy 158.834837 -283.17171) (xy 158.82306 -283.123926)
			(xy 158.8191 -283.074872) (xy 158.480252 -283.074872) (xy 158.479757 -283.099479) (xy 158.471862 -283.148056)
			(xy 158.456278 -283.194737) (xy 158.433407 -283.238314) (xy 158.403842 -283.277658) (xy 158.368349 -283.31175)
			(xy 158.327846 -283.339706) (xy 158.283384 -283.360804) (xy 158.236113 -283.374496) (xy 158.187258 -283.380428)
			(xy 158.138083 -283.378447) (xy 158.089864 -283.368603) (xy 158.043848 -283.351151) (xy 158.001227 -283.326544)
			(xy 157.963106 -283.295419) (xy 157.930471 -283.258582) (xy 157.904168 -283.216986) (xy 157.884877 -283.17171)
			(xy 157.8731 -283.123926) (xy 157.86914 -283.074872) (xy 157.562042 -283.074872) (xy 158.202122 -283.714952)
			(xy 158.216346 -283.722318) (xy 158.22422 -283.723588) (xy 158.247625 -283.727882) (xy 158.29282 -283.742764)
			(xy 158.335158 -283.764479) (xy 158.373614 -283.792502) (xy 158.407255 -283.826153) (xy 158.435266 -283.864616)
			(xy 158.45697 -283.906961) (xy 158.471839 -283.95216) (xy 158.476188 -283.975556) (xy 158.477458 -283.98343)
			(xy 158.484824 -283.997654) (xy 158.512002 -284.024832) (xy 158.8191 -284.024832) (xy 158.82306 -283.975778)
			(xy 158.834837 -283.927994) (xy 158.854128 -283.882718) (xy 158.880431 -283.841122) (xy 158.913066 -283.804285)
			(xy 158.951187 -283.77316) (xy 158.993808 -283.748553) (xy 159.039824 -283.731101) (xy 159.088043 -283.721257)
			(xy 159.137218 -283.719276) (xy 159.186073 -283.725208) (xy 159.233344 -283.7389) (xy 159.277806 -283.759998)
			(xy 159.318309 -283.787954) (xy 159.353802 -283.822046) (xy 159.383367 -283.86139) (xy 159.406238 -283.904967)
			(xy 159.421822 -283.951648) (xy 159.429717 -284.000225) (xy 159.430212 -284.024832) (xy 159.76906 -284.024832)
			(xy 159.77302 -283.975778) (xy 159.784797 -283.927994) (xy 159.804088 -283.882718) (xy 159.830391 -283.841122)
			(xy 159.863026 -283.804285) (xy 159.901147 -283.77316) (xy 159.943768 -283.748553) (xy 159.989784 -283.731101)
			(xy 160.038003 -283.721257) (xy 160.087178 -283.719276) (xy 160.136033 -283.725208) (xy 160.183304 -283.7389)
			(xy 160.227766 -283.759998) (xy 160.268269 -283.787954) (xy 160.303762 -283.822046) (xy 160.333327 -283.86139)
			(xy 160.356198 -283.904967) (xy 160.371782 -283.951648) (xy 160.379677 -284.000225) (xy 160.380172 -284.024832)
			(xy 160.719274 -284.024832) (xy 160.723234 -283.975778) (xy 160.735011 -283.927994) (xy 160.754302 -283.882718)
			(xy 160.780605 -283.841122) (xy 160.81324 -283.804285) (xy 160.851361 -283.77316) (xy 160.893982 -283.748553)
			(xy 160.939998 -283.731101) (xy 160.988217 -283.721257) (xy 161.037392 -283.719276) (xy 161.086247 -283.725208)
			(xy 161.133518 -283.7389) (xy 161.17798 -283.759998) (xy 161.218483 -283.787954) (xy 161.253976 -283.822046)
			(xy 161.283541 -283.86139) (xy 161.306412 -283.904967) (xy 161.321996 -283.951648) (xy 161.329891 -284.000225)
			(xy 161.330386 -284.024832) (xy 161.669234 -284.024832) (xy 161.673194 -283.975778) (xy 161.684971 -283.927994)
			(xy 161.704262 -283.882718) (xy 161.730565 -283.841122) (xy 161.7632 -283.804285) (xy 161.801321 -283.77316)
			(xy 161.843942 -283.748553) (xy 161.889958 -283.731101) (xy 161.938177 -283.721257) (xy 161.987352 -283.719276)
			(xy 162.036207 -283.725208) (xy 162.083478 -283.7389) (xy 162.12794 -283.759998) (xy 162.168443 -283.787954)
			(xy 162.203936 -283.822046) (xy 162.233501 -283.86139) (xy 162.256372 -283.904967) (xy 162.271956 -283.951648)
			(xy 162.279851 -284.000225) (xy 162.280346 -284.024832) (xy 162.619194 -284.024832) (xy 162.623154 -283.975778)
			(xy 162.634931 -283.927994) (xy 162.654222 -283.882718) (xy 162.680525 -283.841122) (xy 162.71316 -283.804285)
			(xy 162.751281 -283.77316) (xy 162.793902 -283.748553) (xy 162.839918 -283.731101) (xy 162.888137 -283.721257)
			(xy 162.937312 -283.719276) (xy 162.986167 -283.725208) (xy 163.033438 -283.7389) (xy 163.0779 -283.759998)
			(xy 163.118403 -283.787954) (xy 163.153896 -283.822046) (xy 163.183461 -283.86139) (xy 163.206332 -283.904967)
			(xy 163.221916 -283.951648) (xy 163.229811 -284.000225) (xy 163.230306 -284.024832) (xy 163.229811 -284.049439)
			(xy 163.221916 -284.098016) (xy 163.206332 -284.144697) (xy 163.183461 -284.188274) (xy 163.153896 -284.227618)
			(xy 163.118403 -284.26171) (xy 163.0779 -284.289666) (xy 163.033438 -284.310764) (xy 162.986167 -284.324456)
			(xy 162.937312 -284.330388) (xy 162.888137 -284.328407) (xy 162.839918 -284.318563) (xy 162.793902 -284.301111)
			(xy 162.751281 -284.276504) (xy 162.71316 -284.245379) (xy 162.680525 -284.208542) (xy 162.654222 -284.166946)
			(xy 162.634931 -284.12167) (xy 162.623154 -284.073886) (xy 162.619194 -284.024832) (xy 162.280346 -284.024832)
			(xy 162.279851 -284.049439) (xy 162.271956 -284.098016) (xy 162.256372 -284.144697) (xy 162.233501 -284.188274)
			(xy 162.203936 -284.227618) (xy 162.168443 -284.26171) (xy 162.12794 -284.289666) (xy 162.083478 -284.310764)
			(xy 162.036207 -284.324456) (xy 161.987352 -284.330388) (xy 161.938177 -284.328407) (xy 161.889958 -284.318563)
			(xy 161.843942 -284.301111) (xy 161.801321 -284.276504) (xy 161.7632 -284.245379) (xy 161.730565 -284.208542)
			(xy 161.704262 -284.166946) (xy 161.684971 -284.12167) (xy 161.673194 -284.073886) (xy 161.669234 -284.024832)
			(xy 161.330386 -284.024832) (xy 161.329891 -284.049439) (xy 161.321996 -284.098016) (xy 161.306412 -284.144697)
			(xy 161.283541 -284.188274) (xy 161.253976 -284.227618) (xy 161.218483 -284.26171) (xy 161.17798 -284.289666)
			(xy 161.133518 -284.310764) (xy 161.086247 -284.324456) (xy 161.037392 -284.330388) (xy 160.988217 -284.328407)
			(xy 160.939998 -284.318563) (xy 160.893982 -284.301111) (xy 160.851361 -284.276504) (xy 160.81324 -284.245379)
			(xy 160.780605 -284.208542) (xy 160.754302 -284.166946) (xy 160.735011 -284.12167) (xy 160.723234 -284.073886)
			(xy 160.719274 -284.024832) (xy 160.380172 -284.024832) (xy 160.379677 -284.049439) (xy 160.371782 -284.098016)
			(xy 160.356198 -284.144697) (xy 160.333327 -284.188274) (xy 160.303762 -284.227618) (xy 160.268269 -284.26171)
			(xy 160.227766 -284.289666) (xy 160.183304 -284.310764) (xy 160.136033 -284.324456) (xy 160.087178 -284.330388)
			(xy 160.038003 -284.328407) (xy 159.989784 -284.318563) (xy 159.943768 -284.301111) (xy 159.901147 -284.276504)
			(xy 159.863026 -284.245379) (xy 159.830391 -284.208542) (xy 159.804088 -284.166946) (xy 159.784797 -284.12167)
			(xy 159.77302 -284.073886) (xy 159.76906 -284.024832) (xy 159.430212 -284.024832) (xy 159.429717 -284.049439)
			(xy 159.421822 -284.098016) (xy 159.406238 -284.144697) (xy 159.383367 -284.188274) (xy 159.353802 -284.227618)
			(xy 159.318309 -284.26171) (xy 159.277806 -284.289666) (xy 159.233344 -284.310764) (xy 159.186073 -284.324456)
			(xy 159.137218 -284.330388) (xy 159.088043 -284.328407) (xy 159.039824 -284.318563) (xy 158.993808 -284.301111)
			(xy 158.951187 -284.276504) (xy 158.913066 -284.245379) (xy 158.880431 -284.208542) (xy 158.854128 -284.166946)
			(xy 158.834837 -284.12167) (xy 158.82306 -284.073886) (xy 158.8191 -284.024832) (xy 158.512002 -284.024832)
			(xy 159.152082 -284.664912) (xy 159.166306 -284.672278) (xy 159.17418 -284.673548) (xy 159.197588 -284.677839)
			(xy 159.24279 -284.692716) (xy 159.285136 -284.714427) (xy 159.3236 -284.742447) (xy 159.35725 -284.776096)
			(xy 159.38527 -284.81456) (xy 159.406982 -284.856905) (xy 159.42186 -284.902107) (xy 159.426148 -284.925516)
			(xy 159.427418 -284.93339) (xy 159.434784 -284.947614) (xy 159.461962 -284.974792) (xy 160.719274 -284.974792)
			(xy 160.723234 -284.925738) (xy 160.735011 -284.877954) (xy 160.754302 -284.832678) (xy 160.780605 -284.791082)
			(xy 160.81324 -284.754245) (xy 160.851361 -284.72312) (xy 160.893982 -284.698513) (xy 160.939998 -284.681061)
			(xy 160.988217 -284.671217) (xy 161.037392 -284.669236) (xy 161.086247 -284.675168) (xy 161.133518 -284.68886)
			(xy 161.17798 -284.709958) (xy 161.218483 -284.737914) (xy 161.253976 -284.772006) (xy 161.283541 -284.81135)
			(xy 161.306412 -284.854927) (xy 161.321996 -284.901608) (xy 161.329891 -284.950185) (xy 161.330386 -284.974792)
			(xy 161.669234 -284.974792) (xy 161.673194 -284.925738) (xy 161.684971 -284.877954) (xy 161.704262 -284.832678)
			(xy 161.730565 -284.791082) (xy 161.7632 -284.754245) (xy 161.801321 -284.72312) (xy 161.843942 -284.698513)
			(xy 161.889958 -284.681061) (xy 161.938177 -284.671217) (xy 161.987352 -284.669236) (xy 162.036207 -284.675168)
			(xy 162.083478 -284.68886) (xy 162.12794 -284.709958) (xy 162.168443 -284.737914) (xy 162.203936 -284.772006)
			(xy 162.233501 -284.81135) (xy 162.256372 -284.854927) (xy 162.271956 -284.901608) (xy 162.279851 -284.950185)
			(xy 162.280346 -284.974792) (xy 162.619194 -284.974792) (xy 162.623154 -284.925738) (xy 162.634931 -284.877954)
			(xy 162.654222 -284.832678) (xy 162.680525 -284.791082) (xy 162.71316 -284.754245) (xy 162.751281 -284.72312)
			(xy 162.793902 -284.698513) (xy 162.839918 -284.681061) (xy 162.888137 -284.671217) (xy 162.937312 -284.669236)
			(xy 162.986167 -284.675168) (xy 163.033438 -284.68886) (xy 163.0779 -284.709958) (xy 163.118403 -284.737914)
			(xy 163.153896 -284.772006) (xy 163.183461 -284.81135) (xy 163.206332 -284.854927) (xy 163.221916 -284.901608)
			(xy 163.229811 -284.950185) (xy 163.230306 -284.974792) (xy 163.229811 -284.999399) (xy 163.221916 -285.047976)
			(xy 163.206332 -285.094657) (xy 163.183461 -285.138234) (xy 163.153896 -285.177578) (xy 163.118403 -285.21167)
			(xy 163.0779 -285.239626) (xy 163.033438 -285.260724) (xy 162.986167 -285.274416) (xy 162.937312 -285.280348)
			(xy 162.888137 -285.278367) (xy 162.839918 -285.268523) (xy 162.793902 -285.251071) (xy 162.751281 -285.226464)
			(xy 162.71316 -285.195339) (xy 162.680525 -285.158502) (xy 162.654222 -285.116906) (xy 162.634931 -285.07163)
			(xy 162.623154 -285.023846) (xy 162.619194 -284.974792) (xy 162.280346 -284.974792) (xy 162.279851 -284.999399)
			(xy 162.271956 -285.047976) (xy 162.256372 -285.094657) (xy 162.233501 -285.138234) (xy 162.203936 -285.177578)
			(xy 162.168443 -285.21167) (xy 162.12794 -285.239626) (xy 162.083478 -285.260724) (xy 162.036207 -285.274416)
			(xy 161.987352 -285.280348) (xy 161.938177 -285.278367) (xy 161.889958 -285.268523) (xy 161.843942 -285.251071)
			(xy 161.801321 -285.226464) (xy 161.7632 -285.195339) (xy 161.730565 -285.158502) (xy 161.704262 -285.116906)
			(xy 161.684971 -285.07163) (xy 161.673194 -285.023846) (xy 161.669234 -284.974792) (xy 161.330386 -284.974792)
			(xy 161.329891 -284.999399) (xy 161.321996 -285.047976) (xy 161.306412 -285.094657) (xy 161.283541 -285.138234)
			(xy 161.253976 -285.177578) (xy 161.218483 -285.21167) (xy 161.17798 -285.239626) (xy 161.133518 -285.260724)
			(xy 161.086247 -285.274416) (xy 161.037392 -285.280348) (xy 160.988217 -285.278367) (xy 160.939998 -285.268523)
			(xy 160.893982 -285.251071) (xy 160.851361 -285.226464) (xy 160.81324 -285.195339) (xy 160.780605 -285.158502)
			(xy 160.754302 -285.116906) (xy 160.735011 -285.07163) (xy 160.723234 -285.023846) (xy 160.719274 -284.974792)
			(xy 159.461962 -284.974792) (xy 160.411922 -285.924752) (xy 160.719274 -285.924752) (xy 160.723234 -285.875698)
			(xy 160.735011 -285.827914) (xy 160.754302 -285.782638) (xy 160.780605 -285.741042) (xy 160.81324 -285.704205)
			(xy 160.851361 -285.67308) (xy 160.893982 -285.648473) (xy 160.939998 -285.631021) (xy 160.988217 -285.621177)
			(xy 161.037392 -285.619196) (xy 161.086247 -285.625128) (xy 161.133518 -285.63882) (xy 161.17798 -285.659918)
			(xy 161.218483 -285.687874) (xy 161.253976 -285.721966) (xy 161.283541 -285.76131) (xy 161.306412 -285.804887)
			(xy 161.321996 -285.851568) (xy 161.329891 -285.900145) (xy 161.330386 -285.924752) (xy 161.669234 -285.924752)
			(xy 161.673194 -285.875698) (xy 161.684971 -285.827914) (xy 161.704262 -285.782638) (xy 161.730565 -285.741042)
			(xy 161.7632 -285.704205) (xy 161.801321 -285.67308) (xy 161.843942 -285.648473) (xy 161.889958 -285.631021)
			(xy 161.938177 -285.621177) (xy 161.987352 -285.619196) (xy 162.036207 -285.625128) (xy 162.083478 -285.63882)
			(xy 162.12794 -285.659918) (xy 162.168443 -285.687874) (xy 162.203936 -285.721966) (xy 162.233501 -285.76131)
			(xy 162.256372 -285.804887) (xy 162.271956 -285.851568) (xy 162.279851 -285.900145) (xy 162.280346 -285.924752)
			(xy 162.619194 -285.924752) (xy 162.623154 -285.875698) (xy 162.634931 -285.827914) (xy 162.654222 -285.782638)
			(xy 162.680525 -285.741042) (xy 162.71316 -285.704205) (xy 162.751281 -285.67308) (xy 162.793902 -285.648473)
			(xy 162.839918 -285.631021) (xy 162.888137 -285.621177) (xy 162.937312 -285.619196) (xy 162.986167 -285.625128)
			(xy 163.033438 -285.63882) (xy 163.0779 -285.659918) (xy 163.118403 -285.687874) (xy 163.153896 -285.721966)
			(xy 163.183461 -285.76131) (xy 163.206332 -285.804887) (xy 163.221916 -285.851568) (xy 163.229811 -285.900145)
			(xy 163.230306 -285.924752) (xy 163.229811 -285.949359) (xy 163.221916 -285.997936) (xy 163.206332 -286.044617)
			(xy 163.183461 -286.088194) (xy 163.153896 -286.127538) (xy 163.118403 -286.16163) (xy 163.0779 -286.189586)
			(xy 163.033438 -286.210684) (xy 162.986167 -286.224376) (xy 162.937312 -286.230308) (xy 162.888137 -286.228327)
			(xy 162.839918 -286.218483) (xy 162.793902 -286.201031) (xy 162.751281 -286.176424) (xy 162.71316 -286.145299)
			(xy 162.680525 -286.108462) (xy 162.654222 -286.066866) (xy 162.634931 -286.02159) (xy 162.623154 -285.973806)
			(xy 162.619194 -285.924752) (xy 162.280346 -285.924752) (xy 162.279851 -285.949359) (xy 162.271956 -285.997936)
			(xy 162.256372 -286.044617) (xy 162.233501 -286.088194) (xy 162.203936 -286.127538) (xy 162.168443 -286.16163)
			(xy 162.12794 -286.189586) (xy 162.083478 -286.210684) (xy 162.036207 -286.224376) (xy 161.987352 -286.230308)
			(xy 161.938177 -286.228327) (xy 161.889958 -286.218483) (xy 161.843942 -286.201031) (xy 161.801321 -286.176424)
			(xy 161.7632 -286.145299) (xy 161.730565 -286.108462) (xy 161.704262 -286.066866) (xy 161.684971 -286.02159)
			(xy 161.673194 -285.973806) (xy 161.669234 -285.924752) (xy 161.330386 -285.924752) (xy 161.329891 -285.949359)
			(xy 161.321996 -285.997936) (xy 161.306412 -286.044617) (xy 161.283541 -286.088194) (xy 161.253976 -286.127538)
			(xy 161.218483 -286.16163) (xy 161.17798 -286.189586) (xy 161.133518 -286.210684) (xy 161.086247 -286.224376)
			(xy 161.037392 -286.230308) (xy 160.988217 -286.228327) (xy 160.939998 -286.218483) (xy 160.893982 -286.201031)
			(xy 160.851361 -286.176424) (xy 160.81324 -286.145299) (xy 160.780605 -286.108462) (xy 160.754302 -286.066866)
			(xy 160.735011 -286.02159) (xy 160.723234 -285.973806) (xy 160.719274 -285.924752) (xy 160.411922 -285.924752)
			(xy 161.052256 -286.565086) (xy 161.06648 -286.572452) (xy 161.074354 -286.573722) (xy 161.097764 -286.578011)
			(xy 161.142971 -286.592884) (xy 161.185322 -286.614593) (xy 161.223791 -286.642611) (xy 161.257447 -286.67626)
			(xy 161.285473 -286.714723) (xy 161.307191 -286.757069) (xy 161.322074 -286.802273) (xy 161.326322 -286.82569)
			(xy 161.327592 -286.833564) (xy 161.334958 -286.847788) (xy 161.362136 -286.874966) (xy 161.669234 -286.874966)
			(xy 161.673194 -286.825912) (xy 161.684971 -286.778128) (xy 161.704262 -286.732852) (xy 161.730565 -286.691256)
			(xy 161.7632 -286.654419) (xy 161.801321 -286.623294) (xy 161.843942 -286.598687) (xy 161.889958 -286.581235)
			(xy 161.938177 -286.571391) (xy 161.987352 -286.56941) (xy 162.036207 -286.575342) (xy 162.083478 -286.589034)
			(xy 162.12794 -286.610132) (xy 162.168443 -286.638088) (xy 162.203936 -286.67218) (xy 162.233501 -286.711524)
			(xy 162.256372 -286.755101) (xy 162.271956 -286.801782) (xy 162.279851 -286.850359) (xy 162.280346 -286.874966)
			(xy 162.619194 -286.874966) (xy 162.623154 -286.825912) (xy 162.634931 -286.778128) (xy 162.654222 -286.732852)
			(xy 162.680525 -286.691256) (xy 162.71316 -286.654419) (xy 162.751281 -286.623294) (xy 162.793902 -286.598687)
			(xy 162.839918 -286.581235) (xy 162.888137 -286.571391) (xy 162.937312 -286.56941) (xy 162.986167 -286.575342)
			(xy 163.033438 -286.589034) (xy 163.0779 -286.610132) (xy 163.118403 -286.638088) (xy 163.153896 -286.67218)
			(xy 163.183461 -286.711524) (xy 163.206332 -286.755101) (xy 163.221916 -286.801782) (xy 163.229811 -286.850359)
			(xy 163.230306 -286.874966) (xy 163.229811 -286.899573) (xy 163.221916 -286.94815) (xy 163.206332 -286.994831)
			(xy 163.183461 -287.038408) (xy 163.153896 -287.077752) (xy 163.118403 -287.111844) (xy 163.0779 -287.1398)
			(xy 163.033438 -287.160898) (xy 162.986167 -287.17459) (xy 162.937312 -287.180522) (xy 162.888137 -287.178541)
			(xy 162.839918 -287.168697) (xy 162.793902 -287.151245) (xy 162.751281 -287.126638) (xy 162.71316 -287.095513)
			(xy 162.680525 -287.058676) (xy 162.654222 -287.01708) (xy 162.634931 -286.971804) (xy 162.623154 -286.92402)
			(xy 162.619194 -286.874966) (xy 162.280346 -286.874966) (xy 162.279851 -286.899573) (xy 162.271956 -286.94815)
			(xy 162.256372 -286.994831) (xy 162.233501 -287.038408) (xy 162.203936 -287.077752) (xy 162.168443 -287.111844)
			(xy 162.12794 -287.1398) (xy 162.083478 -287.160898) (xy 162.036207 -287.17459) (xy 161.987352 -287.180522)
			(xy 161.938177 -287.178541) (xy 161.889958 -287.168697) (xy 161.843942 -287.151245) (xy 161.801321 -287.126638)
			(xy 161.7632 -287.095513) (xy 161.730565 -287.058676) (xy 161.704262 -287.01708) (xy 161.684971 -286.971804)
			(xy 161.673194 -286.92402) (xy 161.669234 -286.874966) (xy 161.362136 -286.874966) (xy 162.002216 -287.515046)
			(xy 162.01644 -287.522412) (xy 162.024314 -287.523682) (xy 162.047719 -287.527975) (xy 162.092916 -287.542857)
			(xy 162.135255 -287.564572) (xy 162.173712 -287.592594) (xy 162.207354 -287.626244) (xy 162.235367 -287.664708)
			(xy 162.257072 -287.707052) (xy 162.271942 -287.752252) (xy 162.276282 -287.77565) (xy 162.277552 -287.783524)
			(xy 162.284918 -287.797748) (xy 162.312096 -287.824926) (xy 162.619194 -287.824926) (xy 162.623154 -287.775872)
			(xy 162.634931 -287.728088) (xy 162.654222 -287.682812) (xy 162.680525 -287.641216) (xy 162.71316 -287.604379)
			(xy 162.751281 -287.573254) (xy 162.793902 -287.548647) (xy 162.839918 -287.531195) (xy 162.888137 -287.521351)
			(xy 162.937312 -287.51937) (xy 162.986167 -287.525302) (xy 163.033438 -287.538994) (xy 163.0779 -287.560092)
			(xy 163.118403 -287.588048) (xy 163.153896 -287.62214) (xy 163.183461 -287.661484) (xy 163.206332 -287.705061)
			(xy 163.221916 -287.751742) (xy 163.229811 -287.800319) (xy 163.230306 -287.824926) (xy 163.569154 -287.824926)
			(xy 163.573114 -287.775872) (xy 163.584891 -287.728088) (xy 163.604182 -287.682812) (xy 163.630485 -287.641216)
			(xy 163.66312 -287.604379) (xy 163.701241 -287.573254) (xy 163.743862 -287.548647) (xy 163.789878 -287.531195)
			(xy 163.838097 -287.521351) (xy 163.887272 -287.51937) (xy 163.936127 -287.525302) (xy 163.983398 -287.538994)
			(xy 164.02786 -287.560092) (xy 164.068363 -287.588048) (xy 164.103856 -287.62214) (xy 164.133421 -287.661484)
			(xy 164.156292 -287.705061) (xy 164.171876 -287.751742) (xy 164.179771 -287.800319) (xy 164.180266 -287.824926)
			(xy 164.179771 -287.849533) (xy 164.171876 -287.89811) (xy 164.156292 -287.944791) (xy 164.133421 -287.988368)
			(xy 164.103856 -288.027712) (xy 164.068363 -288.061804) (xy 164.02786 -288.08976) (xy 163.983398 -288.110858)
			(xy 163.936127 -288.12455) (xy 163.887272 -288.130482) (xy 163.838097 -288.128501) (xy 163.789878 -288.118657)
			(xy 163.743862 -288.101205) (xy 163.701241 -288.076598) (xy 163.66312 -288.045473) (xy 163.630485 -288.008636)
			(xy 163.604182 -287.96704) (xy 163.584891 -287.921764) (xy 163.573114 -287.87398) (xy 163.569154 -287.824926)
			(xy 163.230306 -287.824926) (xy 163.229811 -287.849533) (xy 163.221916 -287.89811) (xy 163.206332 -287.944791)
			(xy 163.183461 -287.988368) (xy 163.153896 -288.027712) (xy 163.118403 -288.061804) (xy 163.0779 -288.08976)
			(xy 163.033438 -288.110858) (xy 162.986167 -288.12455) (xy 162.937312 -288.130482) (xy 162.888137 -288.128501)
			(xy 162.839918 -288.118657) (xy 162.793902 -288.101205) (xy 162.751281 -288.076598) (xy 162.71316 -288.045473)
			(xy 162.680525 -288.008636) (xy 162.654222 -287.96704) (xy 162.634931 -287.921764) (xy 162.623154 -287.87398)
			(xy 162.619194 -287.824926) (xy 162.312096 -287.824926) (xy 162.952176 -288.465006) (xy 162.9664 -288.472372)
			(xy 162.974274 -288.473642) (xy 162.997683 -288.477932) (xy 163.042886 -288.492809) (xy 163.085233 -288.514519)
			(xy 163.123698 -288.542539) (xy 163.157349 -288.576188) (xy 163.185371 -288.614651) (xy 163.207084 -288.656997)
			(xy 163.221964 -288.702199) (xy 163.226242 -288.72561) (xy 163.227512 -288.733484) (xy 163.234878 -288.747708)
			(xy 163.539932 -289.052762) (xy 163.546776 -289.06016) (xy 163.554499 -289.07876) (xy 163.554918 -289.08883)
			(xy 163.573968 -289.10788)
		)
		(stroke
			(width 0)
			(type solid)
		)
		(fill yes)
		(layer "In7.Cu")
		(net "P1V8_VDDA_PEX1")
	)
	(gr_poly
		(pts
			(xy 137.129774 -258.834128) (xy 137.139825 -258.833623) (xy 137.158387 -258.825904) (xy 137.165842 -258.819142)
			(xy 137.168382 -258.816602) (xy 137.21842 -258.759452) (xy 137.225279 -258.750841) (xy 137.231602 -258.729776)
			(xy 137.230612 -258.718812) (xy 137.228901 -258.705544) (xy 137.227123 -258.678849) (xy 137.227056 -258.665472)
			(xy 137.227542 -258.638221) (xy 137.235298 -258.584273) (xy 137.250653 -258.531978) (xy 137.273295 -258.482401)
			(xy 137.302761 -258.436551) (xy 137.338452 -258.39536) (xy 137.379643 -258.359669) (xy 137.425493 -258.330203)
			(xy 137.47507 -258.307561) (xy 137.527365 -258.292206) (xy 137.581313 -258.28445) (xy 137.635815 -258.28445)
			(xy 137.689763 -258.292206) (xy 137.742058 -258.307561) (xy 137.791635 -258.330203) (xy 137.837485 -258.359669)
			(xy 137.878676 -258.39536) (xy 137.914367 -258.436551) (xy 137.943833 -258.482401) (xy 137.966475 -258.531978)
			(xy 137.98183 -258.584273) (xy 137.989586 -258.638221) (xy 137.990072 -258.665472) (xy 137.989999 -258.678849)
			(xy 137.988221 -258.705544) (xy 137.986516 -258.718812) (xy 137.984992 -258.729988) (xy 137.991342 -258.750816)
			(xy 138.047984 -258.816094) (xy 138.050524 -258.818634) (xy 138.051032 -258.819142) (xy 138.05843 -258.82599)
			(xy 138.077028 -258.833722) (xy 138.0871 -258.834128) (xy 138.932412 -258.834128) (xy 138.943521 -258.83357)
			(xy 138.963677 -258.824219) (xy 138.971274 -258.816094) (xy 139.028678 -258.747768) (xy 139.03452 -258.726432)
			(xy 139.032488 -258.715256) (xy 139.029925 -258.699441) (xy 139.027129 -258.667522) (xy 139.0269 -258.651502)
			(xy 139.0269 -258.647946) (xy 139.027524 -258.62079) (xy 139.035514 -258.567062) (xy 139.051045 -258.51501)
			(xy 139.073801 -258.465688) (xy 139.103323 -258.420092) (xy 139.139013 -258.379144) (xy 139.18015 -258.343672)
			(xy 139.225903 -258.314394) (xy 139.275346 -258.291901) (xy 139.327479 -258.276648) (xy 139.381249 -258.268944)
			(xy 139.435567 -258.268944) (xy 139.47126 -258.274058) (xy 144.86966 -258.274058) (xy 144.873731 -258.218436)
			(xy 144.885857 -258.163999) (xy 144.90578 -258.111908) (xy 144.933076 -258.063273) (xy 144.967162 -258.01913)
			(xy 145.007311 -257.980421) (xy 145.052669 -257.94797) (xy 145.102269 -257.922469) (xy 145.155053 -257.904462)
			(xy 145.209896 -257.894332) (xy 145.26563 -257.892295) (xy 145.321067 -257.898395) (xy 145.375024 -257.912501)
			(xy 145.426353 -257.934313) (xy 145.473959 -257.963367) (xy 145.516827 -257.999042) (xy 145.554044 -258.040579)
			(xy 145.584817 -258.087092) (xy 145.608489 -258.137589) (xy 145.624557 -258.190996) (xy 145.632677 -258.246172)
			(xy 145.633186 -258.274058) (xy 146.354798 -258.274058) (xy 146.358869 -258.218436) (xy 146.370995 -258.163999)
			(xy 146.390918 -258.111908) (xy 146.418214 -258.063273) (xy 146.4523 -258.01913) (xy 146.492449 -257.980421)
			(xy 146.537807 -257.94797) (xy 146.587407 -257.922469) (xy 146.640191 -257.904462) (xy 146.695034 -257.894332)
			(xy 146.750768 -257.892295) (xy 146.806205 -257.898395) (xy 146.860162 -257.912501) (xy 146.911491 -257.934313)
			(xy 146.959097 -257.963367) (xy 147.001965 -257.999042) (xy 147.039182 -258.040579) (xy 147.069955 -258.087092)
			(xy 147.093627 -258.137589) (xy 147.109695 -258.190996) (xy 147.117815 -258.246172) (xy 147.118324 -258.274058)
			(xy 147.117815 -258.301944) (xy 147.109695 -258.35712) (xy 147.093627 -258.410527) (xy 147.069955 -258.461024)
			(xy 147.039182 -258.507537) (xy 147.001965 -258.549074) (xy 146.959097 -258.584749) (xy 146.911491 -258.613803)
			(xy 146.860162 -258.635615) (xy 146.806205 -258.649721) (xy 146.750768 -258.655821) (xy 146.695034 -258.653784)
			(xy 146.640191 -258.643654) (xy 146.587407 -258.625647) (xy 146.537807 -258.600146) (xy 146.492449 -258.567695)
			(xy 146.4523 -258.528986) (xy 146.418214 -258.484843) (xy 146.390918 -258.436208) (xy 146.370995 -258.384117)
			(xy 146.358869 -258.32968) (xy 146.354798 -258.274058) (xy 145.633186 -258.274058) (xy 145.632677 -258.301944)
			(xy 145.624557 -258.35712) (xy 145.608489 -258.410527) (xy 145.584817 -258.461024) (xy 145.554044 -258.507537)
			(xy 145.516827 -258.549074) (xy 145.473959 -258.584749) (xy 145.426353 -258.613803) (xy 145.375024 -258.635615)
			(xy 145.321067 -258.649721) (xy 145.26563 -258.655821) (xy 145.209896 -258.653784) (xy 145.155053 -258.643654)
			(xy 145.102269 -258.625647) (xy 145.052669 -258.600146) (xy 145.007311 -258.567695) (xy 144.967162 -258.528986)
			(xy 144.933076 -258.484843) (xy 144.90578 -258.436208) (xy 144.885857 -258.384117) (xy 144.873731 -258.32968)
			(xy 144.86966 -258.274058) (xy 139.47126 -258.274058) (xy 139.489337 -258.276648) (xy 139.54147 -258.291901)
			(xy 139.590913 -258.314394) (xy 139.636666 -258.343672) (xy 139.677803 -258.379144) (xy 139.713493 -258.420092)
			(xy 139.743015 -258.465688) (xy 139.765771 -258.51501) (xy 139.781302 -258.567062) (xy 139.789292 -258.62079)
			(xy 139.789916 -258.647946) (xy 139.789916 -258.650232) (xy 139.789745 -258.666571) (xy 139.78695 -258.699128)
			(xy 139.784328 -258.715256) (xy 139.782296 -258.726432) (xy 139.788138 -258.747768) (xy 139.845542 -258.816094)
			(xy 139.853129 -258.824235) (xy 139.873289 -258.833597) (xy 139.884404 -258.834128) (xy 140.411454 -258.834128)
			(xy 140.421992 -258.833547) (xy 140.441278 -258.825028) (xy 140.448792 -258.817618) (xy 140.499592 -258.7625)
			(xy 140.503051 -258.758508) (xy 140.50843 -258.74942) (xy 140.51026 -258.744466) (xy 140.513816 -258.734052)
			(xy 140.5128 -258.723384) (xy 140.511276 -258.691126) (xy 140.511762 -258.663875) (xy 140.519518 -258.609927)
			(xy 140.534873 -258.557632) (xy 140.557515 -258.508055) (xy 140.586981 -258.462205) (xy 140.622672 -258.421014)
			(xy 140.663863 -258.385323) (xy 140.709713 -258.355857) (xy 140.75929 -258.333215) (xy 140.811585 -258.31786)
			(xy 140.865533 -258.310104) (xy 140.920035 -258.310104) (xy 140.973983 -258.31786) (xy 141.026278 -258.333215)
			(xy 141.075855 -258.355857) (xy 141.121705 -258.385323) (xy 141.162896 -258.421014) (xy 141.198587 -258.462205)
			(xy 141.228053 -258.508055) (xy 141.250695 -258.557632) (xy 141.26605 -258.609927) (xy 141.273806 -258.663875)
			(xy 141.274292 -258.691126) (xy 141.272768 -258.723384) (xy 141.272768 -258.723892) (xy 141.272006 -258.73456)
			(xy 141.275308 -258.74472) (xy 141.277191 -258.749691) (xy 141.2827 -258.75878) (xy 141.28623 -258.762754)
			(xy 141.33703 -258.817872) (xy 141.344553 -258.825245) (xy 141.363846 -258.833638) (xy 141.374368 -258.834128)
			(xy 155.409646 -258.834128) (xy 155.419713 -258.833697) (xy 155.438308 -258.825974) (xy 155.445714 -258.819142)
			(xy 157.349952 -256.914904) (xy 157.356804 -256.907508) (xy 157.364548 -256.88891) (xy 157.364938 -256.878836)
			(xy 157.364938 -249.432572) (xy 157.364508 -249.422505) (xy 157.35678 -249.403914) (xy 157.349952 -249.396504)
			(xy 153.483564 -245.530116) (xy 153.473068 -245.520317) (xy 153.447927 -245.506471) (xy 153.419927 -245.500164)
			(xy 153.391277 -245.501894) (xy 153.364239 -245.511525) (xy 153.340947 -245.528296) (xy 153.331672 -245.53926)
			(xy 153.31347 -245.561681) (xy 153.271452 -245.6013) (xy 153.223946 -245.634136) (xy 153.172035 -245.659439)
			(xy 153.116903 -245.676633) (xy 153.059811 -245.685324) (xy 153.030936 -245.685818) (xy 153.003664 -245.685357)
			(xy 152.949676 -245.677599) (xy 152.897342 -245.662235) (xy 152.847727 -245.639579) (xy 152.801842 -245.610092)
			(xy 152.760621 -245.574374) (xy 152.724904 -245.533152) (xy 152.695417 -245.487266) (xy 152.672762 -245.437651)
			(xy 152.6574 -245.385316) (xy 152.649642 -245.331328) (xy 152.649174 -245.304056) (xy 152.649707 -245.275184)
			(xy 152.658406 -245.218098) (xy 152.6756 -245.162973) (xy 152.700896 -245.111064) (xy 152.733719 -245.063556)
			(xy 152.77332 -245.021529) (xy 152.795732 -245.00332) (xy 152.806728 -244.994076) (xy 152.823506 -244.970775)
			(xy 152.833139 -244.943726) (xy 152.834869 -244.915065) (xy 152.828558 -244.887053) (xy 152.814704 -244.861903)
			(xy 152.804876 -244.851428) (xy 150.21433 -242.260882) (xy 150.203776 -242.251036) (xy 150.178486 -242.237155)
			(xy 150.150323 -242.230903) (xy 150.121535 -242.232779) (xy 150.09442 -242.242633) (xy 150.071145 -242.259678)
			(xy 150.06193 -242.270788) (xy 150.04375 -242.293592) (xy 150.001638 -242.333934) (xy 149.953875 -242.367395)
			(xy 149.901576 -242.393197) (xy 149.845959 -242.410737) (xy 149.788321 -242.419608) (xy 149.759162 -242.42014)
			(xy 149.731895 -242.419651) (xy 149.677917 -242.411885) (xy 149.625593 -242.396516) (xy 149.575989 -242.373857)
			(xy 149.530114 -242.34437) (xy 149.488903 -242.308654) (xy 149.453194 -242.267438) (xy 149.423714 -242.221558)
			(xy 149.401063 -242.171951) (xy 149.385702 -242.119625) (xy 149.377945 -242.065645) (xy 149.3774 -242.038378)
			(xy 149.377898 -242.010737) (xy 149.385884 -241.956033) (xy 149.401673 -241.903052) (xy 149.424934 -241.852901)
			(xy 149.455181 -241.806626) (xy 149.491783 -241.765195) (xy 149.533974 -241.729473) (xy 149.580875 -241.700205)
			(xy 149.631504 -241.678004) (xy 149.684805 -241.663333) (xy 149.712172 -241.65941) (xy 149.721062 -241.658394)
			(xy 149.73681 -241.650266) (xy 149.763226 -241.622072) (xy 149.769509 -241.614782) (xy 149.776559 -241.596891)
			(xy 149.776942 -241.587274) (xy 149.776942 -240.03254) (xy 149.776461 -240.022524) (xy 149.768811 -240.004011)
			(xy 149.754658 -239.989836) (xy 149.736157 -239.982155) (xy 149.726142 -239.98174) (xy 148.404834 -239.98174)
			(xy 148.400516 -239.981486) (xy 148.397976 -239.981232) (xy 148.383752 -239.981232) (xy 148.373338 -239.970818)
			(xy 148.371814 -239.969548) (xy 148.368766 -239.966754) (xy 148.122386 -239.720374) (xy 148.119592 -239.717326)
			(xy 148.118322 -239.715802) (xy 148.107908 -239.705388) (xy 148.107908 -239.691164) (xy 148.107654 -239.688624)
			(xy 148.1074 -239.684306) (xy 148.1074 -239.401858) (xy 148.106939 -239.388372) (xy 148.099792 -239.362362)
			(xy 148.086089 -239.339128) (xy 148.066782 -239.320289) (xy 148.043219 -239.307159) (xy 148.017041 -239.300653)
			(xy 147.990073 -239.301224) (xy 147.964193 -239.308832) (xy 147.95246 -239.315498) (xy 147.929821 -239.328917)
			(xy 147.881638 -239.350084) (xy 147.831002 -239.364425) (xy 147.778876 -239.371669) (xy 147.752562 -239.37214)
			(xy 147.725296 -239.371651) (xy 147.67132 -239.363885) (xy 147.618998 -239.348518) (xy 147.569395 -239.325861)
			(xy 147.523522 -239.296375) (xy 147.482311 -239.260662) (xy 147.446602 -239.219448) (xy 147.417121 -239.173572)
			(xy 147.394469 -239.123967) (xy 147.379106 -239.071643) (xy 147.371346 -239.017666) (xy 147.371346 -238.963134)
			(xy 147.379106 -238.909157) (xy 147.394469 -238.856833) (xy 147.417121 -238.807228) (xy 147.446602 -238.761352)
			(xy 147.482311 -238.720138) (xy 147.523522 -238.684425) (xy 147.569395 -238.654939) (xy 147.618998 -238.632282)
			(xy 147.67132 -238.616915) (xy 147.725296 -238.609149) (xy 147.752562 -238.608616) (xy 147.778876 -238.609074)
			(xy 147.831001 -238.616332) (xy 147.881636 -238.630676) (xy 147.929824 -238.651834) (xy 147.95246 -238.665258)
			(xy 147.96417 -238.67199) (xy 147.990064 -238.679645) (xy 148.017058 -238.680243) (xy 148.043265 -238.673741)
			(xy 148.06685 -238.660594) (xy 148.086162 -238.641723) (xy 148.09985 -238.618448) (xy 148.106956 -238.592398)
			(xy 148.1074 -238.578898) (xy 148.1074 -236.34065) (xy 148.107654 -236.336332) (xy 148.107908 -236.333792)
			(xy 148.107908 -236.319568) (xy 148.118322 -236.309154) (xy 148.119592 -236.30763) (xy 148.122386 -236.304582)
			(xy 148.495766 -235.931202) (xy 148.498814 -235.928408) (xy 148.500338 -235.927138) (xy 148.510752 -235.916724)
			(xy 148.524976 -235.916724) (xy 148.527516 -235.91647) (xy 148.531834 -235.916216) (xy 149.25421 -235.916216)
			(xy 149.269136 -235.915648) (xy 149.29769 -235.906933) (xy 149.322507 -235.890336) (xy 149.341468 -235.867276)
			(xy 149.352955 -235.83972) (xy 149.355988 -235.810019) (xy 149.350307 -235.78071) (xy 149.336398 -235.754293)
			(xy 149.326346 -235.743242) (xy 149.305785 -235.721667) (xy 149.270942 -235.673319) (xy 149.244037 -235.620143)
			(xy 149.225725 -235.563431) (xy 149.216451 -235.504562) (xy 149.215856 -235.474764) (xy 149.216344 -235.447513)
			(xy 149.224105 -235.393568) (xy 149.239463 -235.341275) (xy 149.262105 -235.2917) (xy 149.291572 -235.245852)
			(xy 149.327263 -235.204663) (xy 149.368452 -235.168972) (xy 149.4143 -235.139505) (xy 149.463875 -235.116863)
			(xy 149.516168 -235.101505) (xy 149.570113 -235.093744) (xy 149.597364 -235.093256) (xy 149.612739 -235.093436)
			(xy 149.643384 -235.095977) (xy 149.658578 -235.098336) (xy 149.659086 -235.098336) (xy 149.67004 -235.099562)
			(xy 149.691241 -235.093625) (xy 149.69998 -235.086906) (xy 149.759162 -235.036614) (xy 149.767193 -235.029046)
			(xy 149.776426 -235.009028) (xy 149.776942 -234.998006) (xy 149.776942 -203.356718) (xy 149.656038 -202.718924)
			(xy 149.489668 -201.840592) (xy 149.348952 -201.09815) (xy 149.336506 -201.08037) (xy 149.326854 -201.074782)
			(xy 149.302578 -201.060001) (xy 149.25829 -201.024381) (xy 149.219775 -200.982588) (xy 149.187883 -200.935545)
			(xy 149.16332 -200.884292) (xy 149.146629 -200.829964) (xy 149.13818 -200.773761) (xy 149.137624 -200.745344)
			(xy 149.137624 -200.743566) (xy 149.137878 -200.735946) (xy 149.137878 -200.735692) (xy 149.139261 -200.70511)
			(xy 149.150557 -200.644948) (xy 149.171304 -200.587357) (xy 149.200971 -200.533813) (xy 149.219412 -200.509378)
			(xy 149.227032 -200.499726) (xy 149.231858 -200.476358) (xy 149.227794 -200.462134) (xy 149.225869 -200.455824)
			(xy 149.219303 -200.444387) (xy 149.21484 -200.439528) (xy 148.235924 -199.460612) (xy 148.228522 -199.453776)
			(xy 148.209924 -199.446068) (xy 148.199856 -199.445626) (xy 145.648934 -199.445626) (xy 145.640383 -199.445946)
			(xy 145.624229 -199.45156) (xy 145.610821 -199.462175) (xy 145.606008 -199.469248) (xy 145.590921 -199.492128)
			(xy 145.555228 -199.533718) (xy 145.513951 -199.569771) (xy 145.46794 -199.599547) (xy 145.418141 -199.622432)
			(xy 145.36558 -199.637956) (xy 145.311339 -199.645799) (xy 145.256533 -199.645799) (xy 145.202292 -199.637956)
			(xy 145.149731 -199.622432) (xy 145.099932 -199.599547) (xy 145.053921 -199.569771) (xy 145.012644 -199.533718)
			(xy 144.976951 -199.492128) (xy 144.961864 -199.469248) (xy 144.957015 -199.462205) (xy 144.943624 -199.451588)
			(xy 144.927483 -199.445977) (xy 144.918938 -199.445626) (xy 143.20266 -199.445626) (xy 143.17599 -199.465184)
			(xy 143.17091 -199.481186) (xy 143.162464 -199.506731) (xy 143.139396 -199.555338) (xy 143.109727 -199.600221)
			(xy 143.074046 -199.640491) (xy 143.033062 -199.675349) (xy 142.987587 -199.704103) (xy 142.938524 -199.726183)
			(xy 142.886845 -199.741151) (xy 142.833575 -199.748709) (xy 142.779773 -199.748709) (xy 142.726503 -199.741151)
			(xy 142.674824 -199.726183) (xy 142.625761 -199.704103) (xy 142.580286 -199.675349) (xy 142.539302 -199.640491)
			(xy 142.503621 -199.600221) (xy 142.473952 -199.555338) (xy 142.450884 -199.506731) (xy 142.442438 -199.481186)
			(xy 142.43875 -199.471027) (xy 142.42442 -199.454876) (xy 142.404721 -199.446037) (xy 142.393924 -199.445626)
			(xy 142.202662 -199.445626) (xy 142.175992 -199.465184) (xy 142.170912 -199.481186) (xy 142.162466 -199.506731)
			(xy 142.139398 -199.555338) (xy 142.109729 -199.600221) (xy 142.074048 -199.640491) (xy 142.033064 -199.675349)
			(xy 141.987589 -199.704103) (xy 141.938526 -199.726183) (xy 141.886847 -199.741151) (xy 141.833577 -199.748709)
			(xy 141.779775 -199.748709) (xy 141.726505 -199.741151) (xy 141.674826 -199.726183) (xy 141.625763 -199.704103)
			(xy 141.580288 -199.675349) (xy 141.539304 -199.640491) (xy 141.503623 -199.600221) (xy 141.473954 -199.555338)
			(xy 141.450886 -199.506731) (xy 141.44244 -199.481186) (xy 141.438753 -199.471027) (xy 141.424422 -199.454876)
			(xy 141.404723 -199.446035) (xy 141.393926 -199.445626) (xy 141.218412 -199.445626) (xy 141.209364 -199.445987)
			(xy 141.192391 -199.452265) (xy 141.178654 -199.464044) (xy 141.173962 -199.471788) (xy 141.169898 -199.479154)
			(xy 141.168374 -199.483472) (xy 141.158923 -199.509953) (xy 141.133346 -199.560023) (xy 141.1007 -199.6058)
			(xy 141.061691 -199.646291) (xy 141.017164 -199.680621) (xy 140.968082 -199.708047) (xy 140.915507 -199.727975)
			(xy 140.860577 -199.739974) (xy 140.804482 -199.743784) (xy 140.748434 -199.739323) (xy 140.693648 -199.726687)
			(xy 140.641308 -199.70615) (xy 140.592547 -199.678157) (xy 140.548421 -199.643312) (xy 140.528802 -199.623172)
			(xy 140.52169 -199.615806) (xy 140.492226 -199.602598) (xy 140.481812 -199.59955) (xy 140.411962 -199.59955)
			(xy 140.401548 -199.602598) (xy 140.371576 -199.61606) (xy 140.364464 -199.62368) (xy 140.346383 -199.64222)
			(xy 140.306079 -199.674736) (xy 140.261742 -199.701496) (xy 140.214191 -199.722006) (xy 140.1643 -199.735888)
			(xy 140.112989 -199.742886) (xy 140.087096 -199.743314) (xy 140.062966 -199.743314) (xy 140.0556 -199.742806)
			(xy 140.030962 -199.73925) (xy 140.004935 -199.734932) (xy 139.954315 -199.720061) (xy 139.906228 -199.698355)
			(xy 139.861593 -199.670228) (xy 139.82126 -199.636217) (xy 139.785999 -199.596972) (xy 139.756485 -199.553241)
			(xy 139.73328 -199.505859) (xy 139.724638 -199.480932) (xy 139.724638 -199.480678) (xy 139.724384 -199.48017)
			(xy 139.721577 -199.472875) (xy 139.712267 -199.460329) (xy 139.706096 -199.455532) (xy 139.705842 -199.455278)
			(xy 139.699213 -199.450867) (xy 139.68408 -199.445943) (xy 139.676124 -199.445626) (xy 138.20267 -199.445626)
			(xy 138.176 -199.465184) (xy 138.17092 -199.481186) (xy 138.162474 -199.506731) (xy 138.139406 -199.555338)
			(xy 138.109737 -199.600221) (xy 138.074056 -199.640491) (xy 138.033072 -199.675349) (xy 137.987597 -199.704103)
			(xy 137.938534 -199.726183) (xy 137.886855 -199.741151) (xy 137.833585 -199.748709) (xy 137.779783 -199.748709)
			(xy 137.726513 -199.741151) (xy 137.674834 -199.726183) (xy 137.625771 -199.704103) (xy 137.580296 -199.675349)
			(xy 137.539312 -199.640491) (xy 137.503631 -199.600221) (xy 137.473962 -199.555338) (xy 137.450894 -199.506731)
			(xy 137.442448 -199.481186) (xy 137.438761 -199.471026) (xy 137.424431 -199.454872) (xy 137.404731 -199.446029)
			(xy 137.393934 -199.445626) (xy 136.228074 -199.445626) (xy 136.215435 -199.446307) (xy 136.193187 -199.458311)
			(xy 136.185656 -199.468486) (xy 136.180576 -199.476106) (xy 136.178544 -199.484996) (xy 136.172027 -199.511217)
			(xy 136.152601 -199.561633) (xy 136.126258 -199.608805) (xy 136.093523 -199.65179) (xy 136.055053 -199.689727)
			(xy 136.011616 -199.721858) (xy 135.964081 -199.747541) (xy 135.913399 -199.766262) (xy 135.860582 -199.777646)
			(xy 135.806688 -199.781466) (xy 135.752794 -199.777646) (xy 135.699977 -199.766262) (xy 135.649295 -199.747541)
			(xy 135.60176 -199.721858) (xy 135.558323 -199.689727) (xy 135.519853 -199.65179) (xy 135.487118 -199.608805)
			(xy 135.460775 -199.561633) (xy 135.441349 -199.511217) (xy 135.434832 -199.484996) (xy 135.4328 -199.476106)
			(xy 135.42772 -199.468486) (xy 135.420196 -199.458311) (xy 135.397939 -199.446336) (xy 135.385302 -199.445626)
			(xy 129.630424 -199.445626) (xy 129.620361 -199.446064) (xy 129.601779 -199.4538) (xy 129.594356 -199.460612)
			(xy 129.356612 -199.698356) (xy 129.350023 -199.705647) (xy 129.342416 -199.723749) (xy 129.342093 -199.743382)
			(xy 129.345182 -199.752712) (xy 129.348738 -199.761602) (xy 129.357374 -199.776588) (xy 129.360168 -199.77989)
			(xy 129.376477 -199.800443) (xy 129.403898 -199.845176) (xy 129.424928 -199.893245) (xy 129.43917 -199.943744)
			(xy 129.444504 -199.982328) (xy 144.191226 -199.982328) (xy 144.195297 -199.926706) (xy 144.207423 -199.872269)
			(xy 144.227346 -199.820178) (xy 144.254642 -199.771543) (xy 144.288728 -199.7274) (xy 144.328877 -199.688691)
			(xy 144.374235 -199.65624) (xy 144.423835 -199.630739) (xy 144.476619 -199.612732) (xy 144.531462 -199.602602)
			(xy 144.587196 -199.600565) (xy 144.642633 -199.606665) (xy 144.69659 -199.620771) (xy 144.747919 -199.642583)
			(xy 144.795525 -199.671637) (xy 144.838393 -199.707312) (xy 144.87561 -199.748849) (xy 144.906383 -199.795362)
			(xy 144.930055 -199.845859) (xy 144.946123 -199.899266) (xy 144.954243 -199.954442) (xy 144.954752 -199.982328)
			(xy 144.954243 -200.010214) (xy 144.948329 -200.0504) (xy 147.471382 -200.0504) (xy 147.475453 -199.994778)
			(xy 147.487579 -199.940341) (xy 147.507502 -199.88825) (xy 147.534798 -199.839615) (xy 147.568884 -199.795472)
			(xy 147.609033 -199.756763) (xy 147.654391 -199.724312) (xy 147.703991 -199.698811) (xy 147.756775 -199.680804)
			(xy 147.811618 -199.670674) (xy 147.867352 -199.668637) (xy 147.922789 -199.674737) (xy 147.976746 -199.688843)
			(xy 148.028075 -199.710655) (xy 148.075681 -199.739709) (xy 148.118549 -199.775384) (xy 148.155766 -199.816921)
			(xy 148.186539 -199.863434) (xy 148.210211 -199.913931) (xy 148.226279 -199.967338) (xy 148.234399 -200.022514)
			(xy 148.234908 -200.0504) (xy 148.234399 -200.078286) (xy 148.226279 -200.133462) (xy 148.210211 -200.186869)
			(xy 148.186539 -200.237366) (xy 148.155766 -200.283879) (xy 148.118549 -200.325416) (xy 148.075681 -200.361091)
			(xy 148.028075 -200.390145) (xy 147.976746 -200.411957) (xy 147.922789 -200.426063) (xy 147.867352 -200.432163)
			(xy 147.811618 -200.430126) (xy 147.756775 -200.419996) (xy 147.703991 -200.401989) (xy 147.654391 -200.376488)
			(xy 147.609033 -200.344037) (xy 147.568884 -200.305328) (xy 147.534798 -200.261185) (xy 147.507502 -200.21255)
			(xy 147.487579 -200.160459) (xy 147.475453 -200.106022) (xy 147.471382 -200.0504) (xy 144.948329 -200.0504)
			(xy 144.946123 -200.06539) (xy 144.930055 -200.118797) (xy 144.906383 -200.169294) (xy 144.87561 -200.215807)
			(xy 144.838393 -200.257344) (xy 144.795525 -200.293019) (xy 144.747919 -200.322073) (xy 144.69659 -200.343885)
			(xy 144.642633 -200.357991) (xy 144.587196 -200.364091) (xy 144.531462 -200.362054) (xy 144.476619 -200.351924)
			(xy 144.423835 -200.333917) (xy 144.374235 -200.308416) (xy 144.328877 -200.275965) (xy 144.288728 -200.237256)
			(xy 144.254642 -200.193113) (xy 144.227346 -200.144478) (xy 144.207423 -200.092387) (xy 144.195297 -200.03795)
			(xy 144.191226 -199.982328) (xy 129.444504 -199.982328) (xy 129.446355 -199.995718) (xy 129.446782 -200.021952)
			(xy 129.446274 -200.040494) (xy 129.445004 -200.055734) (xy 129.441898 -200.084509) (xy 129.428111 -200.140716)
			(xy 129.405996 -200.194198) (xy 129.376061 -200.243728) (xy 129.338992 -200.288172) (xy 129.295639 -200.326511)
			(xy 129.246995 -200.357866) (xy 129.194175 -200.381519) (xy 129.13839 -200.396927) (xy 129.109724 -200.40092)
			(xy 129.096008 -200.402444) (xy 129.070559 -200.404092) (xy 129.01963 -200.40143) (xy 128.969508 -200.392012)
			(xy 128.921087 -200.376006) (xy 128.875227 -200.353695) (xy 128.832746 -200.325479) (xy 128.813306 -200.308972)
			(xy 128.798066 -200.29551) (xy 128.758188 -200.29678) (xy 128.567942 -200.487026) (xy 128.560068 -200.497186)
			(xy 128.555242 -200.505568) (xy 128.553464 -200.514204) (xy 128.547551 -200.541918) (xy 128.528631 -200.595332)
			(xy 128.502021 -200.645361) (xy 128.468304 -200.690905) (xy 128.428223 -200.730961) (xy 128.382658 -200.764649)
			(xy 128.332612 -200.791228) (xy 128.279186 -200.810114) (xy 128.251458 -200.815956) (xy 128.244092 -200.817226)
			(xy 128.237234 -200.821036) (xy 128.2339 -200.822838) (xy 128.227771 -200.827296) (xy 128.225042 -200.829926)
			(xy 127.548818 -201.50615) (xy 128.185174 -201.50615) (xy 128.185174 -201.45165) (xy 128.192929 -201.397705)
			(xy 128.208283 -201.345413) (xy 128.230922 -201.295837) (xy 128.260385 -201.249988) (xy 128.296073 -201.208798)
			(xy 128.337259 -201.173106) (xy 128.383106 -201.143639) (xy 128.432679 -201.120995) (xy 128.48497 -201.105637)
			(xy 128.538914 -201.097876) (xy 128.566164 -201.097388) (xy 128.592767 -201.097869) (xy 128.645458 -201.105246)
			(xy 128.696613 -201.119875) (xy 128.745238 -201.141472) (xy 128.790388 -201.169619) (xy 128.831188 -201.203768)
			(xy 128.866846 -201.243256) (xy 128.88214 -201.265028) (xy 128.890474 -201.276508) (xy 128.912218 -201.294712)
			(xy 128.938131 -201.30623) (xy 128.966214 -201.31017) (xy 128.994297 -201.30623) (xy 129.02021 -201.294712)
			(xy 129.041954 -201.276508) (xy 129.050288 -201.265028) (xy 129.065575 -201.243252) (xy 129.101243 -201.203773)
			(xy 129.142048 -201.169631) (xy 129.187199 -201.141486) (xy 129.235822 -201.119885) (xy 129.286973 -201.105245)
			(xy 129.339662 -201.097851) (xy 129.366264 -201.097388) (xy 129.393518 -201.097857) (xy 129.447472 -201.10561)
			(xy 129.499774 -201.120962) (xy 129.549358 -201.143603) (xy 129.595215 -201.173069) (xy 129.636412 -201.208763)
			(xy 129.672109 -201.249956) (xy 129.70158 -201.29581) (xy 129.724225 -201.345392) (xy 129.739583 -201.397692)
			(xy 129.747341 -201.451646) (xy 129.747341 -201.506154) (xy 129.739583 -201.560108) (xy 129.724225 -201.612408)
			(xy 129.70158 -201.66199) (xy 129.672109 -201.707844) (xy 129.636412 -201.749037) (xy 129.595215 -201.784731)
			(xy 129.549358 -201.814197) (xy 129.499774 -201.836838) (xy 129.447472 -201.85219) (xy 129.393518 -201.859943)
			(xy 129.366264 -201.860404) (xy 129.339662 -201.859905) (xy 129.286971 -201.852532) (xy 129.235816 -201.837906)
			(xy 129.187192 -201.816312) (xy 129.142041 -201.788168) (xy 129.10124 -201.754021) (xy 129.065582 -201.714535)
			(xy 129.050288 -201.692764) (xy 129.041954 -201.681284) (xy 129.02021 -201.66308) (xy 128.994297 -201.651562)
			(xy 128.966214 -201.647622) (xy 128.938131 -201.651562) (xy 128.912218 -201.66308) (xy 128.890474 -201.681284)
			(xy 128.88214 -201.692764) (xy 128.866833 -201.714525) (xy 128.831169 -201.754005) (xy 128.790367 -201.788148)
			(xy 128.745219 -201.816295) (xy 128.6966 -201.837899) (xy 128.645452 -201.852541) (xy 128.592765 -201.859939)
			(xy 128.566164 -201.860404) (xy 128.538914 -201.859924) (xy 128.48497 -201.852163) (xy 128.432679 -201.836805)
			(xy 128.383106 -201.814161) (xy 128.337259 -201.784694) (xy 128.296073 -201.749002) (xy 128.260385 -201.707812)
			(xy 128.230922 -201.661963) (xy 128.208283 -201.612387) (xy 128.192929 -201.560095) (xy 128.185174 -201.50615)
			(xy 127.548818 -201.50615) (xy 127.474726 -201.580242) (xy 127.467883 -201.587641) (xy 127.46016 -201.60624)
			(xy 127.45974 -201.61631) (xy 127.45974 -202.172654) (xy 131.671247 -202.172654) (xy 131.671247 -202.118146)
			(xy 131.679005 -202.064193) (xy 131.694362 -202.011893) (xy 131.717006 -201.962311) (xy 131.746476 -201.916456)
			(xy 131.782172 -201.875262) (xy 131.823367 -201.839567) (xy 131.869223 -201.810099) (xy 131.918806 -201.787457)
			(xy 131.971106 -201.772102) (xy 132.02506 -201.764346) (xy 132.052314 -201.763884) (xy 132.081822 -201.764507)
			(xy 132.140124 -201.773684) (xy 132.168392 -201.782172) (xy 132.174996 -201.784204) (xy 132.188204 -201.784712)
			(xy 132.195316 -201.783188) (xy 132.201868 -201.781492) (xy 132.21384 -201.775192) (xy 132.218938 -201.770742)
			(xy 132.283454 -201.71029) (xy 132.28838 -201.705474) (xy 132.29559 -201.693741) (xy 132.297678 -201.687176)
			(xy 132.297678 -201.686922) (xy 132.299335 -201.680499) (xy 132.299592 -201.667242) (xy 132.298186 -201.66076)
			(xy 132.298186 -201.660506) (xy 132.292843 -201.637702) (xy 132.287112 -201.591215) (xy 132.286756 -201.567796)
			(xy 132.28726 -201.540543) (xy 132.295017 -201.486592) (xy 132.310374 -201.434294) (xy 132.333018 -201.384714)
			(xy 132.362487 -201.338861) (xy 132.398182 -201.297669) (xy 132.439376 -201.261976) (xy 132.48523 -201.232509)
			(xy 132.534811 -201.209868) (xy 132.58711 -201.194513) (xy 132.641062 -201.186758) (xy 132.695568 -201.18676)
			(xy 132.749519 -201.19452) (xy 132.801816 -201.209878) (xy 132.851396 -201.232523) (xy 132.897248 -201.261993)
			(xy 132.938439 -201.297689) (xy 132.974131 -201.338884) (xy 133.003596 -201.384739) (xy 133.026236 -201.434321)
			(xy 133.041589 -201.48662) (xy 133.049342 -201.540572) (xy 133.049339 -201.595078) (xy 133.041578 -201.649029)
			(xy 133.026218 -201.701326) (xy 133.003572 -201.750905) (xy 132.9741 -201.796756) (xy 132.938403 -201.837946)
			(xy 132.897207 -201.873637) (xy 132.851351 -201.903101) (xy 132.829154 -201.913236) (xy 134.558532 -201.913236)
			(xy 134.558995 -201.886236) (xy 134.566635 -201.83278) (xy 134.581738 -201.780936) (xy 134.604004 -201.73174)
			(xy 134.632986 -201.686177) (xy 134.668105 -201.645158) (xy 134.688072 -201.626978) (xy 134.695692 -201.620374)
			(xy 134.70001 -201.61123) (xy 134.70203 -201.60702) (xy 134.704716 -201.598077) (xy 134.705344 -201.59345)
			(xy 134.711694 -201.523854) (xy 134.712182 -201.514275) (xy 134.706817 -201.495873) (xy 134.70128 -201.48804)
			(xy 134.701026 -201.487532) (xy 134.685688 -201.467302) (xy 134.659944 -201.423546) (xy 134.640228 -201.376762)
			(xy 134.626889 -201.327778) (xy 134.620161 -201.277458) (xy 134.619746 -201.252074) (xy 134.620232 -201.224823)
			(xy 134.627988 -201.170875) (xy 134.643343 -201.11858) (xy 134.665985 -201.069003) (xy 134.695451 -201.023153)
			(xy 134.731142 -200.981962) (xy 134.772333 -200.946271) (xy 134.818183 -200.916805) (xy 134.86776 -200.894163)
			(xy 134.920055 -200.878808) (xy 134.974003 -200.871052) (xy 135.028505 -200.871052) (xy 135.082453 -200.878808)
			(xy 135.134748 -200.894163) (xy 135.184325 -200.916805) (xy 135.230175 -200.946271) (xy 135.271366 -200.981962)
			(xy 135.307057 -201.023153) (xy 135.336523 -201.069003) (xy 135.359165 -201.11858) (xy 135.37452 -201.170875)
			(xy 135.382276 -201.224823) (xy 135.382762 -201.252074) (xy 135.382308 -201.279074) (xy 135.374667 -201.332531)
			(xy 135.359561 -201.384375) (xy 135.337294 -201.433571) (xy 135.308311 -201.479133) (xy 135.27319 -201.520152)
			(xy 135.253222 -201.538332) (xy 135.245602 -201.544936) (xy 135.241284 -201.55408) (xy 135.239261 -201.558289)
			(xy 135.236577 -201.567232) (xy 135.23595 -201.57186) (xy 135.2296 -201.641456) (xy 135.229274 -201.647806)
			(xy 136.924794 -201.647806) (xy 136.928865 -201.592184) (xy 136.940991 -201.537747) (xy 136.960914 -201.485656)
			(xy 136.98821 -201.437021) (xy 137.022296 -201.392878) (xy 137.062445 -201.354169) (xy 137.107803 -201.321718)
			(xy 137.157403 -201.296217) (xy 137.210187 -201.27821) (xy 137.26503 -201.26808) (xy 137.320764 -201.266043)
			(xy 137.376201 -201.272143) (xy 137.430158 -201.286249) (xy 137.481487 -201.308061) (xy 137.529093 -201.337115)
			(xy 137.571961 -201.37279) (xy 137.609178 -201.414327) (xy 137.639951 -201.46084) (xy 137.663623 -201.511337)
			(xy 137.679691 -201.564744) (xy 137.687811 -201.61992) (xy 137.688255 -201.64425) (xy 137.924792 -201.64425)
			(xy 137.928863 -201.588628) (xy 137.940989 -201.534191) (xy 137.960912 -201.4821) (xy 137.988208 -201.433465)
			(xy 138.022294 -201.389322) (xy 138.062443 -201.350613) (xy 138.107801 -201.318162) (xy 138.157401 -201.292661)
			(xy 138.210185 -201.274654) (xy 138.265028 -201.264524) (xy 138.320762 -201.262487) (xy 138.376199 -201.268587)
			(xy 138.430156 -201.282693) (xy 138.481485 -201.304505) (xy 138.529091 -201.333559) (xy 138.571959 -201.369234)
			(xy 138.609176 -201.410771) (xy 138.639949 -201.457284) (xy 138.663621 -201.507781) (xy 138.679689 -201.561188)
			(xy 138.686979 -201.610722) (xy 139.424662 -201.610722) (xy 139.428733 -201.5551) (xy 139.440859 -201.500663)
			(xy 139.460782 -201.448572) (xy 139.488078 -201.399937) (xy 139.522164 -201.355794) (xy 139.562313 -201.317085)
			(xy 139.607671 -201.284634) (xy 139.657271 -201.259133) (xy 139.710055 -201.241126) (xy 139.764898 -201.230996)
			(xy 139.820632 -201.228959) (xy 139.876069 -201.235059) (xy 139.930026 -201.249165) (xy 139.981355 -201.270977)
			(xy 140.028961 -201.300031) (xy 140.071829 -201.335706) (xy 140.109046 -201.377243) (xy 140.139819 -201.423756)
			(xy 140.163491 -201.474253) (xy 140.179559 -201.52766) (xy 140.187679 -201.582836) (xy 140.188188 -201.610722)
			(xy 140.187691 -201.637949) (xy 140.925751 -201.637949) (xy 140.925752 -201.583442) (xy 140.93351 -201.52949)
			(xy 140.948867 -201.477191) (xy 140.971511 -201.42761) (xy 141.000981 -201.381756) (xy 141.036676 -201.340563)
			(xy 141.077871 -201.30487) (xy 141.123726 -201.275402) (xy 141.173308 -201.252761) (xy 141.225607 -201.237406)
			(xy 141.27956 -201.22965) (xy 141.334067 -201.229652) (xy 141.388019 -201.237411) (xy 141.440317 -201.25277)
			(xy 141.489898 -201.275415) (xy 141.535751 -201.304886) (xy 141.576943 -201.340582) (xy 141.612635 -201.381778)
			(xy 141.642102 -201.427633) (xy 141.656347 -201.45883) (xy 148.477222 -201.45883) (xy 148.481293 -201.403208)
			(xy 148.493419 -201.348771) (xy 148.513342 -201.29668) (xy 148.540638 -201.248045) (xy 148.574724 -201.203902)
			(xy 148.614873 -201.165193) (xy 148.660231 -201.132742) (xy 148.709831 -201.107241) (xy 148.762615 -201.089234)
			(xy 148.817458 -201.079104) (xy 148.873192 -201.077067) (xy 148.928629 -201.083167) (xy 148.982586 -201.097273)
			(xy 149.033915 -201.119085) (xy 149.081521 -201.148139) (xy 149.124389 -201.183814) (xy 149.161606 -201.225351)
			(xy 149.192379 -201.271864) (xy 149.216051 -201.322361) (xy 149.232119 -201.375768) (xy 149.240239 -201.430944)
			(xy 149.240748 -201.45883) (xy 149.240239 -201.486716) (xy 149.232119 -201.541892) (xy 149.216051 -201.595299)
			(xy 149.192379 -201.645796) (xy 149.161606 -201.692309) (xy 149.124389 -201.733846) (xy 149.081521 -201.769521)
			(xy 149.033915 -201.798575) (xy 148.982586 -201.820387) (xy 148.928629 -201.834493) (xy 148.873192 -201.840593)
			(xy 148.817458 -201.838556) (xy 148.762615 -201.828426) (xy 148.709831 -201.810419) (xy 148.660231 -201.784918)
			(xy 148.614873 -201.752467) (xy 148.574724 -201.713758) (xy 148.540638 -201.669615) (xy 148.513342 -201.62098)
			(xy 148.493419 -201.568889) (xy 148.481293 -201.514452) (xy 148.477222 -201.45883) (xy 141.656347 -201.45883)
			(xy 141.664742 -201.477216) (xy 141.680096 -201.529516) (xy 141.68785 -201.583468) (xy 141.688312 -201.610722)
			(xy 141.68787 -201.636538) (xy 141.680915 -201.6877) (xy 141.667121 -201.737455) (xy 141.657324 -201.761344)
			(xy 141.651825 -201.775352) (xy 141.648462 -201.805244) (xy 141.653947 -201.83482) (xy 141.667804 -201.861518)
			(xy 141.688833 -201.883026) (xy 141.715213 -201.897481) (xy 141.744658 -201.90363) (xy 141.759686 -201.902822)
			(xy 141.793214 -201.901298) (xy 141.820464 -201.901793) (xy 141.874409 -201.909551) (xy 141.9267 -201.924907)
			(xy 141.976274 -201.947549) (xy 142.022122 -201.977015) (xy 142.063309 -202.012706) (xy 142.098998 -202.053895)
			(xy 142.128461 -202.099744) (xy 142.1511 -202.14932) (xy 142.166453 -202.201612) (xy 142.174208 -202.255557)
			(xy 142.174207 -202.310057) (xy 142.16645 -202.364002) (xy 142.151095 -202.416294) (xy 142.128454 -202.465869)
			(xy 142.098989 -202.511716) (xy 142.063299 -202.552904) (xy 142.02211 -202.588594) (xy 141.976262 -202.618058)
			(xy 141.926687 -202.640698) (xy 141.874394 -202.656052) (xy 141.820449 -202.663808) (xy 141.765949 -202.663808)
			(xy 141.712004 -202.656052) (xy 141.659712 -202.640697) (xy 141.610137 -202.618057) (xy 141.564289 -202.588593)
			(xy 141.523101 -202.552903) (xy 141.48741 -202.511715) (xy 141.457945 -202.465867) (xy 141.435305 -202.416293)
			(xy 141.41995 -202.364001) (xy 141.412193 -202.310056) (xy 141.411706 -202.282806) (xy 141.412123 -202.256989)
			(xy 141.419088 -202.205827) (xy 141.432892 -202.156072) (xy 141.442694 -202.132184) (xy 141.448142 -202.118158)
			(xy 141.451509 -202.088275) (xy 141.446031 -202.058706) (xy 141.432182 -202.032013) (xy 141.411163 -202.010507)
			(xy 141.384792 -201.996052) (xy 141.355356 -201.9899) (xy 141.340332 -201.990706) (xy 141.306804 -201.99223)
			(xy 141.27955 -201.991749) (xy 141.225598 -201.983992) (xy 141.173299 -201.968636) (xy 141.123717 -201.945993)
			(xy 141.077863 -201.916525) (xy 141.036669 -201.88083) (xy 141.000975 -201.839636) (xy 140.971506 -201.793782)
			(xy 140.948864 -201.7442) (xy 140.933508 -201.691901) (xy 140.925751 -201.637949) (xy 140.187691 -201.637949)
			(xy 140.187679 -201.638608) (xy 140.179559 -201.693784) (xy 140.163491 -201.747191) (xy 140.139819 -201.797688)
			(xy 140.109046 -201.844201) (xy 140.071829 -201.885738) (xy 140.028961 -201.921413) (xy 139.981355 -201.950467)
			(xy 139.930026 -201.972279) (xy 139.876069 -201.986385) (xy 139.820632 -201.992485) (xy 139.764898 -201.990448)
			(xy 139.710055 -201.980318) (xy 139.657271 -201.962311) (xy 139.607671 -201.93681) (xy 139.562313 -201.904359)
			(xy 139.522164 -201.86565) (xy 139.488078 -201.821507) (xy 139.460782 -201.772872) (xy 139.440859 -201.720781)
			(xy 139.428733 -201.666344) (xy 139.424662 -201.610722) (xy 138.686979 -201.610722) (xy 138.687809 -201.616364)
			(xy 138.688318 -201.64425) (xy 138.687809 -201.672136) (xy 138.679689 -201.727312) (xy 138.663621 -201.780719)
			(xy 138.639949 -201.831216) (xy 138.609176 -201.877729) (xy 138.571959 -201.919266) (xy 138.529091 -201.954941)
			(xy 138.481485 -201.983995) (xy 138.430156 -202.005807) (xy 138.376199 -202.019913) (xy 138.320762 -202.026013)
			(xy 138.265028 -202.023976) (xy 138.210185 -202.013846) (xy 138.157401 -201.995839) (xy 138.107801 -201.970338)
			(xy 138.062443 -201.937887) (xy 138.022294 -201.899178) (xy 137.988208 -201.855035) (xy 137.960912 -201.8064)
			(xy 137.940989 -201.754309) (xy 137.928863 -201.699872) (xy 137.924792 -201.64425) (xy 137.688255 -201.64425)
			(xy 137.68832 -201.647806) (xy 137.687811 -201.675692) (xy 137.679691 -201.730868) (xy 137.663623 -201.784275)
			(xy 137.639951 -201.834772) (xy 137.609178 -201.881285) (xy 137.571961 -201.922822) (xy 137.529093 -201.958497)
			(xy 137.481487 -201.987551) (xy 137.430158 -202.009363) (xy 137.376201 -202.023469) (xy 137.320764 -202.029569)
			(xy 137.26503 -202.027532) (xy 137.210187 -202.017402) (xy 137.157403 -201.999395) (xy 137.107803 -201.973894)
			(xy 137.062445 -201.941443) (xy 137.022296 -201.902734) (xy 136.98821 -201.858591) (xy 136.960914 -201.809956)
			(xy 136.940991 -201.757865) (xy 136.928865 -201.703428) (xy 136.924794 -201.647806) (xy 135.229274 -201.647806)
			(xy 135.229108 -201.651035) (xy 135.234476 -201.669437) (xy 135.240014 -201.67727) (xy 135.240268 -201.677778)
			(xy 135.25561 -201.698005) (xy 135.281353 -201.741762) (xy 135.301069 -201.788546) (xy 135.314407 -201.837531)
			(xy 135.321133 -201.887852) (xy 135.321548 -201.913236) (xy 135.321062 -201.940487) (xy 135.313306 -201.994435)
			(xy 135.297951 -202.04673) (xy 135.275309 -202.096307) (xy 135.245843 -202.142157) (xy 135.210152 -202.183348)
			(xy 135.168961 -202.219039) (xy 135.123111 -202.248505) (xy 135.073534 -202.271147) (xy 135.021239 -202.286502)
			(xy 134.967291 -202.294258) (xy 134.912789 -202.294258) (xy 134.858841 -202.286502) (xy 134.806546 -202.271147)
			(xy 134.756969 -202.248505) (xy 134.711119 -202.219039) (xy 134.669928 -202.183348) (xy 134.634237 -202.142157)
			(xy 134.604771 -202.096307) (xy 134.582129 -202.04673) (xy 134.566774 -201.994435) (xy 134.559018 -201.940487)
			(xy 134.558532 -201.913236) (xy 132.829154 -201.913236) (xy 132.801769 -201.92574) (xy 132.749469 -201.941091)
			(xy 132.695517 -201.948843) (xy 132.668264 -201.949304) (xy 132.638755 -201.948687) (xy 132.580454 -201.939505)
			(xy 132.552186 -201.931016) (xy 132.545582 -201.928984) (xy 132.532374 -201.928476) (xy 132.525262 -201.93)
			(xy 132.518709 -201.931691) (xy 132.506738 -201.937994) (xy 132.50164 -201.942446) (xy 132.437124 -202.002898)
			(xy 132.432198 -202.007714) (xy 132.424988 -202.019447) (xy 132.4229 -202.026012) (xy 132.4229 -202.026266)
			(xy 132.421248 -202.03269) (xy 132.420988 -202.045946) (xy 132.422392 -202.052428) (xy 132.422392 -202.052682)
			(xy 132.42544 -202.06589) (xy 132.42798 -202.077828) (xy 132.442966 -202.096624) (xy 132.540756 -202.140312)
			(xy 132.564632 -202.139042) (xy 132.5753 -202.132946) (xy 132.597037 -202.120932) (xy 132.642964 -202.102025)
			(xy 132.690958 -202.089241) (xy 132.740205 -202.082797) (xy 132.765038 -202.0824) (xy 132.792288 -202.082872)
			(xy 132.846233 -202.090633) (xy 132.898524 -202.105992) (xy 132.948098 -202.128636) (xy 132.993944 -202.158104)
			(xy 133.035131 -202.193796) (xy 133.070819 -202.234986) (xy 133.100282 -202.280836) (xy 133.122921 -202.330412)
			(xy 133.138275 -202.382704) (xy 133.14603 -202.43665) (xy 133.14603 -202.49115) (xy 133.138275 -202.545096)
			(xy 133.122921 -202.597388) (xy 133.100282 -202.646964) (xy 133.070819 -202.692814) (xy 133.035131 -202.734004)
			(xy 132.993944 -202.769696) (xy 132.948098 -202.799164) (xy 132.898524 -202.821808) (xy 132.846233 -202.837167)
			(xy 132.792288 -202.844928) (xy 132.765038 -202.845416) (xy 132.736182 -202.844839) (xy 132.679126 -202.836151)
			(xy 132.624031 -202.818968) (xy 132.572153 -202.793681) (xy 132.524676 -202.760867) (xy 132.482684 -202.721277)
			(xy 132.447135 -202.675812) (xy 132.41884 -202.625511) (xy 132.398445 -202.571522) (xy 132.391912 -202.54341)
			(xy 132.389372 -202.531472) (xy 132.374386 -202.512676) (xy 132.276596 -202.468988) (xy 132.25272 -202.470258)
			(xy 132.242052 -202.476354) (xy 132.220304 -202.488348) (xy 132.174381 -202.50726) (xy 132.126391 -202.520049)
			(xy 132.077146 -202.526499) (xy 132.052314 -202.5269) (xy 132.02506 -202.526454) (xy 131.971106 -202.518698)
			(xy 131.918806 -202.503343) (xy 131.869223 -202.480701) (xy 131.823367 -202.451233) (xy 131.782172 -202.415538)
			(xy 131.746476 -202.374344) (xy 131.717006 -202.328489) (xy 131.694362 -202.278907) (xy 131.679005 -202.226607)
			(xy 131.671247 -202.172654) (xy 127.45974 -202.172654) (xy 127.45974 -203.411074) (xy 147.827236 -203.411074)
			(xy 147.831307 -203.355452) (xy 147.843433 -203.301015) (xy 147.863356 -203.248924) (xy 147.890652 -203.200289)
			(xy 147.924738 -203.156146) (xy 147.964887 -203.117437) (xy 148.010245 -203.084986) (xy 148.059845 -203.059485)
			(xy 148.112629 -203.041478) (xy 148.167472 -203.031348) (xy 148.223206 -203.029311) (xy 148.278643 -203.035411)
			(xy 148.3326 -203.049517) (xy 148.383929 -203.071329) (xy 148.431535 -203.100383) (xy 148.474403 -203.136058)
			(xy 148.51162 -203.177595) (xy 148.542393 -203.224108) (xy 148.566065 -203.274605) (xy 148.582133 -203.328012)
			(xy 148.590253 -203.383188) (xy 148.590762 -203.411074) (xy 148.590253 -203.43896) (xy 148.582133 -203.494136)
			(xy 148.566065 -203.547543) (xy 148.542393 -203.59804) (xy 148.51162 -203.644553) (xy 148.474403 -203.68609)
			(xy 148.431535 -203.721765) (xy 148.383929 -203.750819) (xy 148.3326 -203.772631) (xy 148.278643 -203.786737)
			(xy 148.223206 -203.792837) (xy 148.167472 -203.7908) (xy 148.112629 -203.78067) (xy 148.059845 -203.762663)
			(xy 148.010245 -203.737162) (xy 147.964887 -203.704711) (xy 147.924738 -203.666002) (xy 147.890652 -203.621859)
			(xy 147.863356 -203.573224) (xy 147.843433 -203.521133) (xy 147.831307 -203.466696) (xy 147.827236 -203.411074)
			(xy 127.45974 -203.411074) (xy 127.45974 -204.236347) (xy 131.23092 -204.236347) (xy 131.23092 -204.181853)
			(xy 131.238675 -204.127913) (xy 131.254027 -204.075626) (xy 131.276665 -204.026056) (xy 131.306125 -203.980211)
			(xy 131.341811 -203.939026) (xy 131.382994 -203.903339) (xy 131.428836 -203.873875) (xy 131.478405 -203.851235)
			(xy 131.530691 -203.83588) (xy 131.584631 -203.828122) (xy 131.611878 -203.827634) (xy 131.638791 -203.828041)
			(xy 131.692078 -203.835629) (xy 131.743772 -203.850629) (xy 131.792844 -203.872743) (xy 131.838323 -203.901534)
			(xy 131.879305 -203.936429) (xy 131.914977 -203.976736) (xy 131.944632 -204.021656) (xy 131.967681 -204.070297)
			(xy 131.976114 -204.095858) (xy 131.979416 -204.106526) (xy 131.993386 -204.122528) (xy 132.072634 -204.158596)
			(xy 132.082511 -204.162612) (xy 132.103813 -204.162884) (xy 132.113782 -204.159104) (xy 132.11429 -204.15885)
			(xy 132.114544 -204.158596) (xy 132.138854 -204.148368) (xy 132.189599 -204.133989) (xy 132.241843 -204.126759)
			(xy 132.268214 -204.126338) (xy 132.295468 -204.126733) (xy 132.349421 -204.134492) (xy 132.40172 -204.14985)
			(xy 132.451301 -204.172495) (xy 132.497156 -204.201965) (xy 132.538349 -204.237661) (xy 132.552373 -204.253846)
			(xy 138.236196 -204.253846) (xy 138.240267 -204.198224) (xy 138.252393 -204.143787) (xy 138.272316 -204.091696)
			(xy 138.299612 -204.043061) (xy 138.333698 -203.998918) (xy 138.373847 -203.960209) (xy 138.419205 -203.927758)
			(xy 138.468805 -203.902257) (xy 138.521589 -203.88425) (xy 138.576432 -203.87412) (xy 138.632166 -203.872083)
			(xy 138.687603 -203.878183) (xy 138.74156 -203.892289) (xy 138.792889 -203.914101) (xy 138.840495 -203.943155)
			(xy 138.883363 -203.97883) (xy 138.92058 -204.020367) (xy 138.951353 -204.06688) (xy 138.975025 -204.117377)
			(xy 138.991093 -204.170784) (xy 138.999213 -204.22596) (xy 138.999722 -204.253846) (xy 138.999213 -204.281732)
			(xy 138.991093 -204.336908) (xy 138.975025 -204.390315) (xy 138.951353 -204.440812) (xy 138.92058 -204.487325)
			(xy 138.883363 -204.528862) (xy 138.840495 -204.564537) (xy 138.792889 -204.593591) (xy 138.74156 -204.615403)
			(xy 138.687603 -204.629509) (xy 138.632166 -204.635609) (xy 138.576432 -204.633572) (xy 138.521589 -204.623442)
			(xy 138.468805 -204.605435) (xy 138.419205 -204.579934) (xy 138.373847 -204.547483) (xy 138.333698 -204.508774)
			(xy 138.299612 -204.464631) (xy 138.272316 -204.415996) (xy 138.252393 -204.363905) (xy 138.240267 -204.309468)
			(xy 138.236196 -204.253846) (xy 132.552373 -204.253846) (xy 132.574043 -204.278856) (xy 132.603512 -204.324711)
			(xy 132.626155 -204.374293) (xy 132.641511 -204.426593) (xy 132.649268 -204.480546) (xy 132.649268 -204.535054)
			(xy 132.641511 -204.589007) (xy 132.626155 -204.641307) (xy 132.603512 -204.690889) (xy 132.574043 -204.736744)
			(xy 132.538349 -204.777939) (xy 132.497156 -204.813635) (xy 132.451301 -204.843105) (xy 132.40172 -204.86575)
			(xy 132.349421 -204.881108) (xy 132.295614 -204.888846) (xy 134.823198 -204.888846) (xy 134.827269 -204.833224)
			(xy 134.839395 -204.778787) (xy 134.859318 -204.726696) (xy 134.886614 -204.678061) (xy 134.9207 -204.633918)
			(xy 134.960849 -204.595209) (xy 135.006207 -204.562758) (xy 135.055807 -204.537257) (xy 135.108591 -204.51925)
			(xy 135.163434 -204.50912) (xy 135.219168 -204.507083) (xy 135.274605 -204.513183) (xy 135.328562 -204.527289)
			(xy 135.379891 -204.549101) (xy 135.427497 -204.578155) (xy 135.470365 -204.61383) (xy 135.507582 -204.655367)
			(xy 135.538355 -204.70188) (xy 135.562027 -204.752377) (xy 135.578095 -204.805784) (xy 135.586215 -204.86096)
			(xy 135.586724 -204.888846) (xy 135.586215 -204.916732) (xy 135.581348 -204.949806) (xy 142.112746 -204.949806)
			(xy 142.113281 -204.920905) (xy 142.121993 -204.863763) (xy 142.139233 -204.808592) (xy 142.164606 -204.756657)
			(xy 142.197531 -204.709148) (xy 142.237251 -204.667156) (xy 142.282857 -204.631643) (xy 142.307818 -204.617066)
			(xy 142.320744 -204.609132) (xy 142.341656 -204.587188) (xy 142.355216 -204.560078) (xy 142.360231 -204.530184)
			(xy 142.356262 -204.500133) (xy 142.343657 -204.472567) (xy 142.323523 -204.449907) (xy 142.310866 -204.441552)
			(xy 142.287296 -204.426632) (xy 142.244404 -204.390967) (xy 142.207164 -204.349435) (xy 142.176371 -204.302921)
			(xy 142.152682 -204.252418) (xy 142.136601 -204.199003) (xy 142.128472 -204.143815) (xy 142.127986 -204.115924)
			(xy 142.128472 -204.088673) (xy 142.136228 -204.034725) (xy 142.151583 -203.98243) (xy 142.174225 -203.932853)
			(xy 142.203691 -203.887003) (xy 142.239382 -203.845812) (xy 142.280573 -203.810121) (xy 142.326423 -203.780655)
			(xy 142.376 -203.758013) (xy 142.428295 -203.742658) (xy 142.482243 -203.734902) (xy 142.536745 -203.734902)
			(xy 142.590693 -203.742658) (xy 142.642988 -203.758013) (xy 142.692565 -203.780655) (xy 142.738415 -203.810121)
			(xy 142.779606 -203.845812) (xy 142.815297 -203.887003) (xy 142.844763 -203.932853) (xy 142.867405 -203.98243)
			(xy 142.88276 -204.034725) (xy 142.890516 -204.088673) (xy 142.891002 -204.115924) (xy 142.890466 -204.144825)
			(xy 142.881751 -204.201965) (xy 142.864509 -204.257135) (xy 142.839136 -204.309069) (xy 142.806212 -204.356578)
			(xy 142.766493 -204.398571) (xy 142.72089 -204.434086) (xy 142.69593 -204.448664) (xy 142.682972 -204.456555)
			(xy 142.662048 -204.478504) (xy 142.648483 -204.505624) (xy 142.643468 -204.535531) (xy 142.647445 -204.565593)
			(xy 142.660064 -204.593166) (xy 142.680215 -204.615826) (xy 142.692882 -204.624178) (xy 142.716477 -204.63906)
			(xy 142.759366 -204.674734) (xy 142.796603 -204.716273) (xy 142.827392 -204.762793) (xy 142.835881 -204.780896)
			(xy 143.716756 -204.780896) (xy 143.717147 -204.754953) (xy 143.72418 -204.703546) (xy 143.738115 -204.653566)
			(xy 143.758696 -204.605936) (xy 143.785543 -204.561536) (xy 143.81816 -204.521184) (xy 143.855945 -204.485625)
			(xy 143.898201 -204.455515) (xy 143.920972 -204.443076) (xy 143.933789 -204.435839) (xy 143.954848 -204.415288)
			(xy 143.969177 -204.389588) (xy 143.975588 -204.36087) (xy 143.973549 -204.331516) (xy 143.963229 -204.30396)
			(xy 143.945484 -204.280488) (xy 143.933926 -204.271372) (xy 143.910266 -204.253256) (xy 143.868345 -204.210911)
			(xy 143.833515 -204.162565) (xy 143.806622 -204.109392) (xy 143.78832 -204.052687) (xy 143.779053 -203.993825)
			(xy 143.778478 -203.964032) (xy 143.778964 -203.936781) (xy 143.78672 -203.882833) (xy 143.802075 -203.830538)
			(xy 143.824717 -203.780961) (xy 143.854183 -203.735111) (xy 143.889874 -203.69392) (xy 143.931065 -203.658229)
			(xy 143.976915 -203.628763) (xy 144.026492 -203.606121) (xy 144.078787 -203.590766) (xy 144.132735 -203.58301)
			(xy 144.187237 -203.58301) (xy 144.241185 -203.590766) (xy 144.29348 -203.606121) (xy 144.343057 -203.628763)
			(xy 144.388907 -203.658229) (xy 144.430098 -203.69392) (xy 144.465789 -203.735111) (xy 144.495255 -203.780961)
			(xy 144.517897 -203.830538) (xy 144.533252 -203.882833) (xy 144.541008 -203.936781) (xy 144.541494 -203.964032)
			(xy 144.541018 -203.989972) (xy 144.533996 -204.041374) (xy 144.520071 -204.091351) (xy 144.499502 -204.138979)
			(xy 144.472667 -204.183379) (xy 144.440062 -204.223733) (xy 144.402288 -204.259295) (xy 144.360043 -204.28941)
			(xy 144.337278 -204.301852) (xy 144.324522 -204.309189) (xy 144.30346 -204.329716) (xy 144.289124 -204.355395)
			(xy 144.282703 -204.384096) (xy 144.284731 -204.413436) (xy 144.295039 -204.440981) (xy 144.312772 -204.464444)
			(xy 144.324324 -204.473556) (xy 144.347986 -204.491669) (xy 144.38991 -204.534013) (xy 144.424742 -204.582359)
			(xy 144.451635 -204.635533) (xy 144.469935 -204.69224) (xy 144.479199 -204.751102) (xy 144.479772 -204.780896)
			(xy 144.479286 -204.808147) (xy 144.47153 -204.862095) (xy 144.456175 -204.91439) (xy 144.433533 -204.963967)
			(xy 144.404067 -205.009817) (xy 144.368376 -205.051008) (xy 144.327185 -205.086699) (xy 144.281335 -205.116165)
			(xy 144.231758 -205.138807) (xy 144.179463 -205.154162) (xy 144.125515 -205.161918) (xy 144.071013 -205.161918)
			(xy 144.017065 -205.154162) (xy 143.96477 -205.138807) (xy 143.915193 -205.116165) (xy 143.869343 -205.086699)
			(xy 143.828152 -205.051008) (xy 143.792461 -205.009817) (xy 143.762995 -204.963967) (xy 143.740353 -204.91439)
			(xy 143.724998 -204.862095) (xy 143.717242 -204.808147) (xy 143.716756 -204.780896) (xy 142.835881 -204.780896)
			(xy 142.851077 -204.813302) (xy 142.867153 -204.866721) (xy 142.875278 -204.921913) (xy 142.875762 -204.949806)
			(xy 142.875276 -204.977057) (xy 142.86752 -205.031005) (xy 142.852165 -205.0833) (xy 142.829523 -205.132877)
			(xy 142.800057 -205.178727) (xy 142.764366 -205.219918) (xy 142.723175 -205.255609) (xy 142.677325 -205.285075)
			(xy 142.627748 -205.307717) (xy 142.575453 -205.323072) (xy 142.521505 -205.330828) (xy 142.467003 -205.330828)
			(xy 142.413055 -205.323072) (xy 142.36076 -205.307717) (xy 142.311183 -205.285075) (xy 142.265333 -205.255609)
			(xy 142.224142 -205.219918) (xy 142.188451 -205.178727) (xy 142.158985 -205.132877) (xy 142.136343 -205.0833)
			(xy 142.120988 -205.031005) (xy 142.113232 -204.977057) (xy 142.112746 -204.949806) (xy 135.581348 -204.949806)
			(xy 135.578095 -204.971908) (xy 135.562027 -205.025315) (xy 135.538355 -205.075812) (xy 135.507582 -205.122325)
			(xy 135.470365 -205.163862) (xy 135.427497 -205.199537) (xy 135.379891 -205.228591) (xy 135.328562 -205.250403)
			(xy 135.274605 -205.264509) (xy 135.219168 -205.270609) (xy 135.163434 -205.268572) (xy 135.108591 -205.258442)
			(xy 135.055807 -205.240435) (xy 135.006207 -205.214934) (xy 134.960849 -205.182483) (xy 134.9207 -205.143774)
			(xy 134.886614 -205.099631) (xy 134.859318 -205.050996) (xy 134.839395 -204.998905) (xy 134.827269 -204.944468)
			(xy 134.823198 -204.888846) (xy 132.295614 -204.888846) (xy 132.295468 -204.888867) (xy 132.268214 -204.889354)
			(xy 132.241304 -204.888893) (xy 132.188021 -204.881306) (xy 132.136333 -204.866309) (xy 132.087263 -204.844199)
			(xy 132.041787 -204.815415) (xy 132.000805 -204.780528) (xy 131.965131 -204.74023) (xy 131.935472 -204.695319)
			(xy 131.912416 -204.646687) (xy 131.903978 -204.62113) (xy 131.900676 -204.610462) (xy 131.886706 -204.59446)
			(xy 131.807458 -204.558392) (xy 131.797582 -204.554371) (xy 131.77628 -204.554103) (xy 131.76631 -204.557884)
			(xy 131.765802 -204.558138) (xy 131.765548 -204.558392) (xy 131.741226 -204.568591) (xy 131.690488 -204.582981)
			(xy 131.638248 -204.590223) (xy 131.611878 -204.59065) (xy 131.584631 -204.590078) (xy 131.530691 -204.58232)
			(xy 131.478405 -204.566965) (xy 131.428836 -204.544325) (xy 131.382994 -204.514861) (xy 131.341811 -204.479174)
			(xy 131.306125 -204.437989) (xy 131.276665 -204.392144) (xy 131.254027 -204.342574) (xy 131.238675 -204.290287)
			(xy 131.23092 -204.236347) (xy 127.45974 -204.236347) (xy 127.45974 -205.650846) (xy 137.982196 -205.650846)
			(xy 137.986267 -205.595224) (xy 137.998393 -205.540787) (xy 138.018316 -205.488696) (xy 138.045612 -205.440061)
			(xy 138.079698 -205.395918) (xy 138.119847 -205.357209) (xy 138.165205 -205.324758) (xy 138.214805 -205.299257)
			(xy 138.267589 -205.28125) (xy 138.322432 -205.27112) (xy 138.378166 -205.269083) (xy 138.433603 -205.275183)
			(xy 138.48756 -205.289289) (xy 138.538889 -205.311101) (xy 138.586495 -205.340155) (xy 138.629363 -205.37583)
			(xy 138.66658 -205.417367) (xy 138.697353 -205.46388) (xy 138.721025 -205.514377) (xy 138.737093 -205.567784)
			(xy 138.745213 -205.62296) (xy 138.745722 -205.650846) (xy 138.745213 -205.678732) (xy 138.737093 -205.733908)
			(xy 138.721025 -205.787315) (xy 138.697353 -205.837812) (xy 138.66658 -205.884325) (xy 138.629363 -205.925862)
			(xy 138.586495 -205.961537) (xy 138.538889 -205.990591) (xy 138.48756 -206.012403) (xy 138.433603 -206.026509)
			(xy 138.378166 -206.032609) (xy 138.322432 -206.030572) (xy 138.267589 -206.020442) (xy 138.214805 -206.002435)
			(xy 138.165205 -205.976934) (xy 138.119847 -205.944483) (xy 138.079698 -205.905774) (xy 138.045612 -205.861631)
			(xy 138.018316 -205.812996) (xy 137.998393 -205.760905) (xy 137.986267 -205.706468) (xy 137.982196 -205.650846)
			(xy 127.45974 -205.650846) (xy 127.45974 -206.25816) (xy 127.720596 -206.25816) (xy 127.724667 -206.202538)
			(xy 127.736793 -206.148101) (xy 127.756716 -206.09601) (xy 127.784012 -206.047375) (xy 127.818098 -206.003232)
			(xy 127.858247 -205.964523) (xy 127.903605 -205.932072) (xy 127.953205 -205.906571) (xy 128.005989 -205.888564)
			(xy 128.060832 -205.878434) (xy 128.116566 -205.876397) (xy 128.172003 -205.882497) (xy 128.22596 -205.896603)
			(xy 128.277289 -205.918415) (xy 128.324895 -205.947469) (xy 128.367763 -205.983144) (xy 128.40498 -206.024681)
			(xy 128.435753 -206.071194) (xy 128.459425 -206.121691) (xy 128.475493 -206.175098) (xy 128.483613 -206.230274)
			(xy 128.484122 -206.25816) (xy 128.483936 -206.268347) (xy 131.334444 -206.268347) (xy 131.334445 -206.213838)
			(xy 131.342204 -206.159885) (xy 131.357562 -206.107584) (xy 131.380208 -206.058002) (xy 131.409679 -206.012147)
			(xy 131.445376 -205.970954) (xy 131.486573 -205.93526) (xy 131.53243 -205.905792) (xy 131.582014 -205.883151)
			(xy 131.634316 -205.867797) (xy 131.68827 -205.860043) (xy 131.742779 -205.860047) (xy 131.796732 -205.867808)
			(xy 131.849032 -205.883169) (xy 131.898613 -205.905816) (xy 131.944467 -205.935289) (xy 131.985659 -205.970989)
			(xy 132.021351 -206.012187) (xy 132.050816 -206.058045) (xy 132.056134 -206.069692) (xy 140.301216 -206.069692)
			(xy 140.305287 -206.01407) (xy 140.317413 -205.959633) (xy 140.337336 -205.907542) (xy 140.364632 -205.858907)
			(xy 140.398718 -205.814764) (xy 140.438867 -205.776055) (xy 140.484225 -205.743604) (xy 140.533825 -205.718103)
			(xy 140.586609 -205.700096) (xy 140.641452 -205.689966) (xy 140.697186 -205.687929) (xy 140.752623 -205.694029)
			(xy 140.80658 -205.708135) (xy 140.857909 -205.729947) (xy 140.905515 -205.759001) (xy 140.948383 -205.794676)
			(xy 140.9856 -205.836213) (xy 141.016373 -205.882726) (xy 141.040045 -205.933223) (xy 141.056113 -205.98663)
			(xy 141.064233 -206.041806) (xy 141.064482 -206.055468) (xy 142.213836 -206.055468) (xy 142.217907 -205.999846)
			(xy 142.230033 -205.945409) (xy 142.249956 -205.893318) (xy 142.277252 -205.844683) (xy 142.311338 -205.80054)
			(xy 142.351487 -205.761831) (xy 142.396845 -205.72938) (xy 142.446445 -205.703879) (xy 142.499229 -205.685872)
			(xy 142.554072 -205.675742) (xy 142.609806 -205.673705) (xy 142.665243 -205.679805) (xy 142.7192 -205.693911)
			(xy 142.770529 -205.715723) (xy 142.818135 -205.744777) (xy 142.861003 -205.780452) (xy 142.89822 -205.821989)
			(xy 142.928993 -205.868502) (xy 142.952665 -205.918999) (xy 142.968733 -205.972406) (xy 142.976853 -206.027582)
			(xy 142.977362 -206.055468) (xy 142.976853 -206.083354) (xy 142.968733 -206.13853) (xy 142.952665 -206.191937)
			(xy 142.928993 -206.242434) (xy 142.89822 -206.288947) (xy 142.861003 -206.330484) (xy 142.818135 -206.366159)
			(xy 142.770529 -206.395213) (xy 142.7192 -206.417025) (xy 142.665243 -206.431131) (xy 142.609806 -206.437231)
			(xy 142.554072 -206.435194) (xy 142.499229 -206.425064) (xy 142.446445 -206.407057) (xy 142.396845 -206.381556)
			(xy 142.351487 -206.349105) (xy 142.311338 -206.310396) (xy 142.277252 -206.266253) (xy 142.249956 -206.217618)
			(xy 142.230033 -206.165527) (xy 142.217907 -206.11109) (xy 142.213836 -206.055468) (xy 141.064482 -206.055468)
			(xy 141.064742 -206.069692) (xy 141.064233 -206.097578) (xy 141.056113 -206.152754) (xy 141.040045 -206.206161)
			(xy 141.016373 -206.256658) (xy 140.9856 -206.303171) (xy 140.948383 -206.344708) (xy 140.905515 -206.380383)
			(xy 140.857909 -206.409437) (xy 140.80658 -206.431249) (xy 140.752623 -206.445355) (xy 140.697186 -206.451455)
			(xy 140.641452 -206.449418) (xy 140.586609 -206.439288) (xy 140.533825 -206.421281) (xy 140.484225 -206.39578)
			(xy 140.438867 -206.363329) (xy 140.398718 -206.32462) (xy 140.364632 -206.280477) (xy 140.337336 -206.231842)
			(xy 140.317413 -206.179751) (xy 140.305287 -206.125314) (xy 140.301216 -206.069692) (xy 132.056134 -206.069692)
			(xy 132.073455 -206.10763) (xy 132.088806 -206.159933) (xy 132.096558 -206.213888) (xy 132.097018 -206.241142)
			(xy 132.096927 -206.254841) (xy 132.095021 -206.282173) (xy 132.093208 -206.295752) (xy 132.09159 -206.310987)
			(xy 132.09644 -206.341221) (xy 132.110027 -206.368663) (xy 132.131132 -206.390848) (xy 132.157862 -206.405787)
			(xy 132.187817 -206.412138) (xy 132.218309 -206.409332) (xy 132.232654 -206.403956) (xy 132.255926 -206.394713)
			(xy 132.304279 -206.381699) (xy 132.353921 -206.37514) (xy 132.378958 -206.374746) (xy 132.379212 -206.374746)
			(xy 132.406464 -206.375268) (xy 132.460414 -206.383027) (xy 132.512711 -206.398385) (xy 132.56229 -206.421029)
			(xy 132.608141 -206.450498) (xy 132.623607 -206.4639) (xy 134.571994 -206.4639) (xy 134.57248 -206.436649)
			(xy 134.580236 -206.382701) (xy 134.595591 -206.330406) (xy 134.618233 -206.280829) (xy 134.647699 -206.234979)
			(xy 134.68339 -206.193788) (xy 134.724581 -206.158097) (xy 134.770431 -206.128631) (xy 134.820008 -206.105989)
			(xy 134.872303 -206.090634) (xy 134.926251 -206.082878) (xy 134.980753 -206.082878) (xy 135.034701 -206.090634)
			(xy 135.086996 -206.105989) (xy 135.136573 -206.128631) (xy 135.182423 -206.158097) (xy 135.223614 -206.193788)
			(xy 135.259305 -206.234979) (xy 135.288771 -206.280829) (xy 135.311413 -206.330406) (xy 135.326768 -206.382701)
			(xy 135.334524 -206.436649) (xy 135.33501 -206.4639) (xy 143.777968 -206.4639) (xy 143.782039 -206.408278)
			(xy 143.794165 -206.353841) (xy 143.814088 -206.30175) (xy 143.841384 -206.253115) (xy 143.87547 -206.208972)
			(xy 143.915619 -206.170263) (xy 143.960977 -206.137812) (xy 144.010577 -206.112311) (xy 144.063361 -206.094304)
			(xy 144.118204 -206.084174) (xy 144.173938 -206.082137) (xy 144.229375 -206.088237) (xy 144.283332 -206.102343)
			(xy 144.334661 -206.124155) (xy 144.382267 -206.153209) (xy 144.425135 -206.188884) (xy 144.462352 -206.230421)
			(xy 144.493125 -206.276934) (xy 144.516797 -206.327431) (xy 144.532865 -206.380838) (xy 144.540985 -206.436014)
			(xy 144.541494 -206.4639) (xy 144.540985 -206.491786) (xy 144.532865 -206.546962) (xy 144.516797 -206.600369)
			(xy 144.493125 -206.650866) (xy 144.462352 -206.697379) (xy 144.425135 -206.738916) (xy 144.382267 -206.774591)
			(xy 144.361538 -206.787242) (xy 147.192746 -206.787242) (xy 147.193207 -206.760638) (xy 147.200584 -206.707945)
			(xy 147.215214 -206.656788) (xy 147.236814 -206.608163) (xy 147.264965 -206.563012) (xy 147.299118 -206.522213)
			(xy 147.338612 -206.486558) (xy 147.360386 -206.471266) (xy 147.371875 -206.462942) (xy 147.390082 -206.441197)
			(xy 147.4016 -206.415281) (xy 147.405539 -206.387195) (xy 147.401597 -206.35911) (xy 147.390077 -206.333195)
			(xy 147.371868 -206.311452) (xy 147.360386 -206.303118) (xy 147.338626 -206.287809) (xy 147.299144 -206.252147)
			(xy 147.264999 -206.211346) (xy 147.236851 -206.166199) (xy 147.215247 -206.117579) (xy 147.200605 -206.06643)
			(xy 147.19321 -206.013744) (xy 147.192746 -205.987142) (xy 147.193232 -205.959891) (xy 147.200988 -205.905943)
			(xy 147.216343 -205.853648) (xy 147.238985 -205.804071) (xy 147.268451 -205.758221) (xy 147.304142 -205.71703)
			(xy 147.345333 -205.681339) (xy 147.391183 -205.651873) (xy 147.44076 -205.629231) (xy 147.493055 -205.613876)
			(xy 147.547003 -205.60612) (xy 147.601505 -205.60612) (xy 147.655453 -205.613876) (xy 147.707748 -205.629231)
			(xy 147.757325 -205.651873) (xy 147.803175 -205.681339) (xy 147.844366 -205.71703) (xy 147.880057 -205.758221)
			(xy 147.909523 -205.804071) (xy 147.932165 -205.853648) (xy 147.94752 -205.905943) (xy 147.955276 -205.959891)
			(xy 147.955762 -205.987142) (xy 147.955286 -206.013745) (xy 147.947911 -206.066438) (xy 147.933283 -206.117594)
			(xy 147.911685 -206.166219) (xy 147.883538 -206.21137) (xy 147.849386 -206.252169) (xy 147.809895 -206.287825)
			(xy 147.788122 -206.303118) (xy 147.776648 -206.311461) (xy 147.75844 -206.333201) (xy 147.746921 -206.359113)
			(xy 147.742978 -206.387195) (xy 147.746918 -206.415278) (xy 147.758436 -206.441191) (xy 147.776641 -206.462933)
			(xy 147.788122 -206.471266) (xy 147.809877 -206.486582) (xy 147.849358 -206.522244) (xy 147.883504 -206.563043)
			(xy 147.911652 -206.608189) (xy 147.933257 -206.656807) (xy 147.9479 -206.707955) (xy 147.955297 -206.760641)
			(xy 147.955762 -206.787242) (xy 147.955276 -206.814493) (xy 147.94752 -206.868441) (xy 147.932165 -206.920736)
			(xy 147.909523 -206.970313) (xy 147.880057 -207.016163) (xy 147.844366 -207.057354) (xy 147.803175 -207.093045)
			(xy 147.757325 -207.122511) (xy 147.707748 -207.145153) (xy 147.655453 -207.160508) (xy 147.601505 -207.168264)
			(xy 147.547003 -207.168264) (xy 147.493055 -207.160508) (xy 147.44076 -207.145153) (xy 147.391183 -207.122511)
			(xy 147.345333 -207.093045) (xy 147.304142 -207.057354) (xy 147.268451 -207.016163) (xy 147.238985 -206.970313)
			(xy 147.216343 -206.920736) (xy 147.200988 -206.868441) (xy 147.193232 -206.814493) (xy 147.192746 -206.787242)
			(xy 144.361538 -206.787242) (xy 144.334661 -206.803645) (xy 144.283332 -206.825457) (xy 144.229375 -206.839563)
			(xy 144.173938 -206.845663) (xy 144.118204 -206.843626) (xy 144.063361 -206.833496) (xy 144.010577 -206.815489)
			(xy 143.960977 -206.789988) (xy 143.915619 -206.757537) (xy 143.87547 -206.718828) (xy 143.841384 -206.674685)
			(xy 143.814088 -206.62605) (xy 143.794165 -206.573959) (xy 143.782039 -206.519522) (xy 143.777968 -206.4639)
			(xy 135.33501 -206.4639) (xy 135.334491 -206.49226) (xy 135.326099 -206.548355) (xy 135.309486 -206.602586)
			(xy 135.28502 -206.653757) (xy 135.253239 -206.700736) (xy 135.234426 -206.721964) (xy 135.22706 -206.730092)
			(xy 135.220202 -206.751174) (xy 135.23214 -206.850234) (xy 135.243824 -206.86903) (xy 135.253222 -206.87538)
			(xy 135.275462 -206.890573) (xy 135.315799 -206.926268) (xy 135.350716 -206.96728) (xy 135.379521 -207.012793)
			(xy 135.401641 -207.061904) (xy 135.416636 -207.113637) (xy 135.424209 -207.166965) (xy 135.424672 -207.193896)
			(xy 135.424186 -207.221147) (xy 135.41643 -207.275095) (xy 135.401075 -207.32739) (xy 135.378433 -207.376967)
			(xy 135.360273 -207.405224) (xy 136.98296 -207.405224) (xy 136.987031 -207.349602) (xy 136.999157 -207.295165)
			(xy 137.01908 -207.243074) (xy 137.046376 -207.194439) (xy 137.080462 -207.150296) (xy 137.120611 -207.111587)
			(xy 137.165969 -207.079136) (xy 137.215569 -207.053635) (xy 137.268353 -207.035628) (xy 137.323196 -207.025498)
			(xy 137.37893 -207.023461) (xy 137.434367 -207.029561) (xy 137.488324 -207.043667) (xy 137.539653 -207.065479)
			(xy 137.587259 -207.094533) (xy 137.630127 -207.130208) (xy 137.667344 -207.171745) (xy 137.698117 -207.218258)
			(xy 137.721789 -207.268755) (xy 137.737857 -207.322162) (xy 137.740848 -207.342486) (xy 138.016994 -207.342486)
			(xy 138.021065 -207.286864) (xy 138.033191 -207.232427) (xy 138.053114 -207.180336) (xy 138.08041 -207.131701)
			(xy 138.114496 -207.087558) (xy 138.154645 -207.048849) (xy 138.200003 -207.016398) (xy 138.249603 -206.990897)
			(xy 138.302387 -206.97289) (xy 138.35723 -206.96276) (xy 138.412964 -206.960723) (xy 138.468401 -206.966823)
			(xy 138.522358 -206.980929) (xy 138.573687 -207.002741) (xy 138.621293 -207.031795) (xy 138.664161 -207.06747)
			(xy 138.701378 -207.109007) (xy 138.732151 -207.15552) (xy 138.755823 -207.206017) (xy 138.771891 -207.259424)
			(xy 138.780011 -207.3146) (xy 138.78052 -207.342486) (xy 138.780011 -207.370372) (xy 138.771891 -207.425548)
			(xy 138.755823 -207.478955) (xy 138.732151 -207.529452) (xy 138.701378 -207.575965) (xy 138.664161 -207.617502)
			(xy 138.621293 -207.653177) (xy 138.573687 -207.682231) (xy 138.522358 -207.704043) (xy 138.468401 -207.718149)
			(xy 138.412964 -207.724249) (xy 138.35723 -207.722212) (xy 138.302387 -207.712082) (xy 138.249603 -207.694075)
			(xy 138.200003 -207.668574) (xy 138.154645 -207.636123) (xy 138.114496 -207.597414) (xy 138.08041 -207.553271)
			(xy 138.053114 -207.504636) (xy 138.033191 -207.452545) (xy 138.021065 -207.398108) (xy 138.016994 -207.342486)
			(xy 137.740848 -207.342486) (xy 137.745977 -207.377338) (xy 137.746486 -207.405224) (xy 137.745977 -207.43311)
			(xy 137.737857 -207.488286) (xy 137.721789 -207.541693) (xy 137.698117 -207.59219) (xy 137.667344 -207.638703)
			(xy 137.630127 -207.68024) (xy 137.587259 -207.715915) (xy 137.539653 -207.744969) (xy 137.488324 -207.766781)
			(xy 137.434367 -207.780887) (xy 137.37893 -207.786987) (xy 137.323196 -207.78495) (xy 137.268353 -207.77482)
			(xy 137.215569 -207.756813) (xy 137.165969 -207.731312) (xy 137.120611 -207.698861) (xy 137.080462 -207.660152)
			(xy 137.046376 -207.616009) (xy 137.01908 -207.567374) (xy 136.999157 -207.515283) (xy 136.987031 -207.460846)
			(xy 136.98296 -207.405224) (xy 135.360273 -207.405224) (xy 135.348967 -207.422817) (xy 135.313276 -207.464008)
			(xy 135.272085 -207.499699) (xy 135.226235 -207.529165) (xy 135.176658 -207.551807) (xy 135.124363 -207.567162)
			(xy 135.070415 -207.574918) (xy 135.015913 -207.574918) (xy 134.961965 -207.567162) (xy 134.90967 -207.551807)
			(xy 134.860093 -207.529165) (xy 134.814243 -207.499699) (xy 134.773052 -207.464008) (xy 134.737361 -207.422817)
			(xy 134.707895 -207.376967) (xy 134.685253 -207.32739) (xy 134.669898 -207.275095) (xy 134.662142 -207.221147)
			(xy 134.661656 -207.193896) (xy 134.662182 -207.165537) (xy 134.670573 -207.109442) (xy 134.687185 -207.055211)
			(xy 134.71165 -207.00404) (xy 134.743428 -206.95706) (xy 134.76224 -206.935832) (xy 134.769606 -206.927704)
			(xy 134.776464 -206.906622) (xy 134.764526 -206.807562) (xy 134.752842 -206.788766) (xy 134.743444 -206.782416)
			(xy 134.721194 -206.767236) (xy 134.680859 -206.731538) (xy 134.645944 -206.690523) (xy 134.617141 -206.645008)
			(xy 134.595023 -206.595895) (xy 134.580029 -206.54416) (xy 134.572457 -206.490832) (xy 134.571994 -206.4639)
			(xy 132.623607 -206.4639) (xy 132.649332 -206.486193) (xy 132.685023 -206.527387) (xy 132.714488 -206.573241)
			(xy 132.737128 -206.622822) (xy 132.752481 -206.67512) (xy 132.760234 -206.729071) (xy 132.760231 -206.783576)
			(xy 132.752471 -206.837526) (xy 132.737111 -206.889822) (xy 132.714466 -206.9394) (xy 132.684995 -206.98525)
			(xy 132.649299 -207.02644) (xy 132.608104 -207.06213) (xy 132.562249 -207.091594) (xy 132.512667 -207.114232)
			(xy 132.460369 -207.129583) (xy 132.406418 -207.137335) (xy 132.351913 -207.13733) (xy 132.297963 -207.129568)
			(xy 132.245668 -207.114207) (xy 132.19609 -207.09156) (xy 132.150241 -207.062088) (xy 132.109052 -207.02639)
			(xy 132.073364 -206.985195) (xy 132.043901 -206.939339) (xy 132.021264 -206.889757) (xy 132.005915 -206.837458)
			(xy 131.998164 -206.783507) (xy 131.997704 -206.756254) (xy 131.997796 -206.742555) (xy 131.999701 -206.715223)
			(xy 132.001514 -206.701644) (xy 132.003105 -206.686408) (xy 131.998256 -206.656179) (xy 131.984671 -206.628743)
			(xy 131.963571 -206.60656) (xy 131.936848 -206.591621) (xy 131.906899 -206.585267) (xy 131.876412 -206.588068)
			(xy 131.862068 -206.59344) (xy 131.838805 -206.602707) (xy 131.790447 -206.615711) (xy 131.740802 -206.622261)
			(xy 131.715764 -206.62265) (xy 131.71551 -206.62265) (xy 131.688256 -206.622156) (xy 131.634301 -206.6144)
			(xy 131.582 -206.599044) (xy 131.532417 -206.576401) (xy 131.486561 -206.546931) (xy 131.445366 -206.511236)
			(xy 131.40967 -206.470041) (xy 131.380201 -206.424185) (xy 131.357557 -206.374602) (xy 131.342201 -206.322301)
			(xy 131.334444 -206.268347) (xy 128.483936 -206.268347) (xy 128.483613 -206.286046) (xy 128.475493 -206.341222)
			(xy 128.459425 -206.394629) (xy 128.435753 -206.445126) (xy 128.40498 -206.491639) (xy 128.367763 -206.533176)
			(xy 128.324895 -206.568851) (xy 128.277289 -206.597905) (xy 128.22596 -206.619717) (xy 128.172003 -206.633823)
			(xy 128.116566 -206.639923) (xy 128.060832 -206.637886) (xy 128.005989 -206.627756) (xy 127.953205 -206.609749)
			(xy 127.903605 -206.584248) (xy 127.858247 -206.551797) (xy 127.818098 -206.513088) (xy 127.784012 -206.468945)
			(xy 127.756716 -206.42031) (xy 127.736793 -206.368219) (xy 127.724667 -206.313782) (xy 127.720596 -206.25816)
			(xy 127.45974 -206.25816) (xy 127.45974 -206.955136) (xy 128.420112 -206.955136) (xy 128.424183 -206.899514)
			(xy 128.436309 -206.845077) (xy 128.456232 -206.792986) (xy 128.483528 -206.744351) (xy 128.517614 -206.700208)
			(xy 128.557763 -206.661499) (xy 128.603121 -206.629048) (xy 128.652721 -206.603547) (xy 128.705505 -206.58554)
			(xy 128.760348 -206.57541) (xy 128.816082 -206.573373) (xy 128.871519 -206.579473) (xy 128.925476 -206.593579)
			(xy 128.976805 -206.615391) (xy 129.024411 -206.644445) (xy 129.067279 -206.68012) (xy 129.104496 -206.721657)
			(xy 129.135269 -206.76817) (xy 129.158941 -206.818667) (xy 129.175009 -206.872074) (xy 129.183129 -206.92725)
			(xy 129.183638 -206.955136) (xy 129.183129 -206.983022) (xy 129.175009 -207.038198) (xy 129.158941 -207.091605)
			(xy 129.135269 -207.142102) (xy 129.104496 -207.188615) (xy 129.067279 -207.230152) (xy 129.024411 -207.265827)
			(xy 128.976805 -207.294881) (xy 128.925476 -207.316693) (xy 128.871519 -207.330799) (xy 128.816082 -207.336899)
			(xy 128.760348 -207.334862) (xy 128.705505 -207.324732) (xy 128.652721 -207.306725) (xy 128.603121 -207.281224)
			(xy 128.557763 -207.248773) (xy 128.517614 -207.210064) (xy 128.483528 -207.165921) (xy 128.456232 -207.117286)
			(xy 128.436309 -207.065195) (xy 128.424183 -207.010758) (xy 128.420112 -206.955136) (xy 127.45974 -206.955136)
			(xy 127.45974 -208.516474) (xy 132.095492 -208.516474) (xy 132.099563 -208.460852) (xy 132.111689 -208.406415)
			(xy 132.131612 -208.354324) (xy 132.158908 -208.305689) (xy 132.192994 -208.261546) (xy 132.233143 -208.222837)
			(xy 132.278501 -208.190386) (xy 132.328101 -208.164885) (xy 132.380885 -208.146878) (xy 132.435728 -208.136748)
			(xy 132.491462 -208.134711) (xy 132.546899 -208.140811) (xy 132.600856 -208.154917) (xy 132.652185 -208.176729)
			(xy 132.699791 -208.205783) (xy 132.742659 -208.241458) (xy 132.779876 -208.282995) (xy 132.802933 -208.317846)
			(xy 141.030196 -208.317846) (xy 141.034267 -208.262224) (xy 141.046393 -208.207787) (xy 141.066316 -208.155696)
			(xy 141.093612 -208.107061) (xy 141.127698 -208.062918) (xy 141.167847 -208.024209) (xy 141.213205 -207.991758)
			(xy 141.262805 -207.966257) (xy 141.315589 -207.94825) (xy 141.370432 -207.93812) (xy 141.426166 -207.936083)
			(xy 141.481603 -207.942183) (xy 141.53556 -207.956289) (xy 141.586889 -207.978101) (xy 141.623754 -208.0006)
			(xy 142.467582 -208.0006) (xy 142.471653 -207.944978) (xy 142.483779 -207.890541) (xy 142.503702 -207.83845)
			(xy 142.530998 -207.789815) (xy 142.565084 -207.745672) (xy 142.605233 -207.706963) (xy 142.650591 -207.674512)
			(xy 142.700191 -207.649011) (xy 142.752975 -207.631004) (xy 142.807818 -207.620874) (xy 142.863552 -207.618837)
			(xy 142.918989 -207.624937) (xy 142.972946 -207.639043) (xy 143.024275 -207.660855) (xy 143.071881 -207.689909)
			(xy 143.095136 -207.709262) (xy 146.876514 -207.709262) (xy 146.880585 -207.65364) (xy 146.892711 -207.599203)
			(xy 146.912634 -207.547112) (xy 146.93993 -207.498477) (xy 146.974016 -207.454334) (xy 147.014165 -207.415625)
			(xy 147.059523 -207.383174) (xy 147.109123 -207.357673) (xy 147.161907 -207.339666) (xy 147.21675 -207.329536)
			(xy 147.272484 -207.327499) (xy 147.327921 -207.333599) (xy 147.381878 -207.347705) (xy 147.433207 -207.369517)
			(xy 147.480813 -207.398571) (xy 147.523681 -207.434246) (xy 147.560898 -207.475783) (xy 147.591671 -207.522296)
			(xy 147.615343 -207.572793) (xy 147.631411 -207.6262) (xy 147.639531 -207.681376) (xy 147.64004 -207.709262)
			(xy 147.639531 -207.737148) (xy 147.631411 -207.792324) (xy 147.615343 -207.845731) (xy 147.591671 -207.896228)
			(xy 147.560898 -207.942741) (xy 147.523681 -207.984278) (xy 147.480813 -208.019953) (xy 147.433207 -208.049007)
			(xy 147.381878 -208.070819) (xy 147.327921 -208.084925) (xy 147.272484 -208.091025) (xy 147.21675 -208.088988)
			(xy 147.161907 -208.078858) (xy 147.109123 -208.060851) (xy 147.059523 -208.03535) (xy 147.014165 -208.002899)
			(xy 146.974016 -207.96419) (xy 146.93993 -207.920047) (xy 146.912634 -207.871412) (xy 146.892711 -207.819321)
			(xy 146.880585 -207.764884) (xy 146.876514 -207.709262) (xy 143.095136 -207.709262) (xy 143.114749 -207.725584)
			(xy 143.151966 -207.767121) (xy 143.182739 -207.813634) (xy 143.206411 -207.864131) (xy 143.222479 -207.917538)
			(xy 143.230599 -207.972714) (xy 143.231108 -208.0006) (xy 143.230599 -208.028486) (xy 143.222479 -208.083662)
			(xy 143.206411 -208.137069) (xy 143.182739 -208.187566) (xy 143.151966 -208.234079) (xy 143.149282 -208.237074)
			(xy 147.63318 -208.237074) (xy 147.637251 -208.181452) (xy 147.649377 -208.127015) (xy 147.6693 -208.074924)
			(xy 147.696596 -208.026289) (xy 147.730682 -207.982146) (xy 147.770831 -207.943437) (xy 147.816189 -207.910986)
			(xy 147.865789 -207.885485) (xy 147.918573 -207.867478) (xy 147.973416 -207.857348) (xy 148.02915 -207.855311)
			(xy 148.084587 -207.861411) (xy 148.138544 -207.875517) (xy 148.189873 -207.897329) (xy 148.237479 -207.926383)
			(xy 148.280347 -207.962058) (xy 148.317564 -208.003595) (xy 148.348337 -208.050108) (xy 148.372009 -208.100605)
			(xy 148.388077 -208.154012) (xy 148.396197 -208.209188) (xy 148.396706 -208.237074) (xy 148.396197 -208.26496)
			(xy 148.388077 -208.320136) (xy 148.372009 -208.373543) (xy 148.348337 -208.42404) (xy 148.317564 -208.470553)
			(xy 148.280347 -208.51209) (xy 148.237479 -208.547765) (xy 148.189873 -208.576819) (xy 148.138544 -208.598631)
			(xy 148.084587 -208.612737) (xy 148.02915 -208.618837) (xy 147.973416 -208.6168) (xy 147.918573 -208.60667)
			(xy 147.865789 -208.588663) (xy 147.816189 -208.563162) (xy 147.770831 -208.530711) (xy 147.730682 -208.492002)
			(xy 147.696596 -208.447859) (xy 147.6693 -208.399224) (xy 147.649377 -208.347133) (xy 147.637251 -208.292696)
			(xy 147.63318 -208.237074) (xy 143.149282 -208.237074) (xy 143.114749 -208.275616) (xy 143.071881 -208.311291)
			(xy 143.024275 -208.340345) (xy 142.972946 -208.362157) (xy 142.918989 -208.376263) (xy 142.863552 -208.382363)
			(xy 142.807818 -208.380326) (xy 142.752975 -208.370196) (xy 142.700191 -208.352189) (xy 142.650591 -208.326688)
			(xy 142.605233 -208.294237) (xy 142.565084 -208.255528) (xy 142.530998 -208.211385) (xy 142.503702 -208.16275)
			(xy 142.483779 -208.110659) (xy 142.471653 -208.056222) (xy 142.467582 -208.0006) (xy 141.623754 -208.0006)
			(xy 141.634495 -208.007155) (xy 141.677363 -208.04283) (xy 141.71458 -208.084367) (xy 141.745353 -208.13088)
			(xy 141.769025 -208.181377) (xy 141.785093 -208.234784) (xy 141.793213 -208.28996) (xy 141.793722 -208.317846)
			(xy 141.793213 -208.345732) (xy 141.785093 -208.400908) (xy 141.769025 -208.454315) (xy 141.745353 -208.504812)
			(xy 141.71458 -208.551325) (xy 141.677363 -208.592862) (xy 141.634495 -208.628537) (xy 141.586889 -208.657591)
			(xy 141.53556 -208.679403) (xy 141.481603 -208.693509) (xy 141.426166 -208.699609) (xy 141.370432 -208.697572)
			(xy 141.315589 -208.687442) (xy 141.262805 -208.669435) (xy 141.213205 -208.643934) (xy 141.167847 -208.611483)
			(xy 141.127698 -208.572774) (xy 141.093612 -208.528631) (xy 141.066316 -208.479996) (xy 141.046393 -208.427905)
			(xy 141.034267 -208.373468) (xy 141.030196 -208.317846) (xy 132.802933 -208.317846) (xy 132.810649 -208.329508)
			(xy 132.834321 -208.380005) (xy 132.850389 -208.433412) (xy 132.858509 -208.488588) (xy 132.859018 -208.516474)
			(xy 132.858509 -208.54436) (xy 132.850389 -208.599536) (xy 132.834321 -208.652943) (xy 132.810649 -208.70344)
			(xy 132.779876 -208.749953) (xy 132.742659 -208.79149) (xy 132.699791 -208.827165) (xy 132.652185 -208.856219)
			(xy 132.600856 -208.878031) (xy 132.546899 -208.892137) (xy 132.491462 -208.898237) (xy 132.435728 -208.8962)
			(xy 132.380885 -208.88607) (xy 132.328101 -208.868063) (xy 132.278501 -208.842562) (xy 132.233143 -208.810111)
			(xy 132.192994 -208.771402) (xy 132.158908 -208.727259) (xy 132.131612 -208.678624) (xy 132.111689 -208.626533)
			(xy 132.099563 -208.572096) (xy 132.095492 -208.516474) (xy 127.45974 -208.516474) (xy 127.45974 -208.964022)
			(xy 134.571484 -208.964022) (xy 134.575555 -208.9084) (xy 134.587681 -208.853963) (xy 134.607604 -208.801872)
			(xy 134.6349 -208.753237) (xy 134.668986 -208.709094) (xy 134.709135 -208.670385) (xy 134.754493 -208.637934)
			(xy 134.804093 -208.612433) (xy 134.856877 -208.594426) (xy 134.91172 -208.584296) (xy 134.967454 -208.582259)
			(xy 135.022891 -208.588359) (xy 135.076848 -208.602465) (xy 135.128177 -208.624277) (xy 135.175783 -208.653331)
			(xy 135.218651 -208.689006) (xy 135.255868 -208.730543) (xy 135.286641 -208.777056) (xy 135.310313 -208.827553)
			(xy 135.326381 -208.88096) (xy 135.334501 -208.936136) (xy 135.33501 -208.964022) (xy 135.334501 -208.991908)
			(xy 135.326381 -209.047084) (xy 135.316524 -209.079846) (xy 137.982196 -209.079846) (xy 137.986267 -209.024224)
			(xy 137.998393 -208.969787) (xy 138.018316 -208.917696) (xy 138.045612 -208.869061) (xy 138.079698 -208.824918)
			(xy 138.119847 -208.786209) (xy 138.165205 -208.753758) (xy 138.214805 -208.728257) (xy 138.267589 -208.71025)
			(xy 138.322432 -208.70012) (xy 138.378166 -208.698083) (xy 138.433603 -208.704183) (xy 138.48756 -208.718289)
			(xy 138.538889 -208.740101) (xy 138.586495 -208.769155) (xy 138.629363 -208.80483) (xy 138.66658 -208.846367)
			(xy 138.697353 -208.89288) (xy 138.721025 -208.943377) (xy 138.737093 -208.996784) (xy 138.745213 -209.05196)
			(xy 138.745722 -209.079846) (xy 138.74569 -209.081624) (xy 138.927838 -209.081624) (xy 138.931909 -209.026002)
			(xy 138.944035 -208.971565) (xy 138.963958 -208.919474) (xy 138.991254 -208.870839) (xy 139.02534 -208.826696)
			(xy 139.065489 -208.787987) (xy 139.110847 -208.755536) (xy 139.160447 -208.730035) (xy 139.213231 -208.712028)
			(xy 139.268074 -208.701898) (xy 139.323808 -208.699861) (xy 139.379245 -208.705961) (xy 139.433202 -208.720067)
			(xy 139.484531 -208.741879) (xy 139.532137 -208.770933) (xy 139.575005 -208.806608) (xy 139.592242 -208.825846)
			(xy 141.792196 -208.825846) (xy 141.796267 -208.770224) (xy 141.808393 -208.715787) (xy 141.828316 -208.663696)
			(xy 141.855612 -208.615061) (xy 141.889698 -208.570918) (xy 141.929847 -208.532209) (xy 141.975205 -208.499758)
			(xy 142.024805 -208.474257) (xy 142.077589 -208.45625) (xy 142.132432 -208.44612) (xy 142.188166 -208.444083)
			(xy 142.243603 -208.450183) (xy 142.29756 -208.464289) (xy 142.348889 -208.486101) (xy 142.396495 -208.515155)
			(xy 142.439363 -208.55083) (xy 142.47658 -208.592367) (xy 142.507353 -208.63888) (xy 142.531025 -208.689377)
			(xy 142.547093 -208.742784) (xy 142.555213 -208.79796) (xy 142.555722 -208.825846) (xy 142.555213 -208.853732)
			(xy 142.547093 -208.908908) (xy 142.531025 -208.962315) (xy 142.507353 -209.012812) (xy 142.47658 -209.059325)
			(xy 142.439363 -209.100862) (xy 142.396495 -209.136537) (xy 142.348889 -209.165591) (xy 142.29756 -209.187403)
			(xy 142.243603 -209.201509) (xy 142.188166 -209.207609) (xy 142.132432 -209.205572) (xy 142.077589 -209.195442)
			(xy 142.024805 -209.177435) (xy 141.975205 -209.151934) (xy 141.929847 -209.119483) (xy 141.889698 -209.080774)
			(xy 141.855612 -209.036631) (xy 141.828316 -208.987996) (xy 141.808393 -208.935905) (xy 141.796267 -208.881468)
			(xy 141.792196 -208.825846) (xy 139.592242 -208.825846) (xy 139.612222 -208.848145) (xy 139.642995 -208.894658)
			(xy 139.666667 -208.945155) (xy 139.682735 -208.998562) (xy 139.690855 -209.053738) (xy 139.691364 -209.081624)
			(xy 139.690855 -209.10951) (xy 139.682735 -209.164686) (xy 139.666667 -209.218093) (xy 139.642995 -209.26859)
			(xy 139.612222 -209.315103) (xy 139.575005 -209.35664) (xy 139.532137 -209.392315) (xy 139.484531 -209.421369)
			(xy 139.433202 -209.443181) (xy 139.379245 -209.457287) (xy 139.323808 -209.463387) (xy 139.268074 -209.46135)
			(xy 139.213231 -209.45122) (xy 139.160447 -209.433213) (xy 139.110847 -209.407712) (xy 139.065489 -209.375261)
			(xy 139.02534 -209.336552) (xy 138.991254 -209.292409) (xy 138.963958 -209.243774) (xy 138.944035 -209.191683)
			(xy 138.931909 -209.137246) (xy 138.927838 -209.081624) (xy 138.74569 -209.081624) (xy 138.745213 -209.107732)
			(xy 138.737093 -209.162908) (xy 138.721025 -209.216315) (xy 138.697353 -209.266812) (xy 138.66658 -209.313325)
			(xy 138.629363 -209.354862) (xy 138.586495 -209.390537) (xy 138.538889 -209.419591) (xy 138.48756 -209.441403)
			(xy 138.433603 -209.455509) (xy 138.378166 -209.461609) (xy 138.322432 -209.459572) (xy 138.267589 -209.449442)
			(xy 138.214805 -209.431435) (xy 138.165205 -209.405934) (xy 138.119847 -209.373483) (xy 138.079698 -209.334774)
			(xy 138.045612 -209.290631) (xy 138.018316 -209.241996) (xy 137.998393 -209.189905) (xy 137.986267 -209.135468)
			(xy 137.982196 -209.079846) (xy 135.316524 -209.079846) (xy 135.310313 -209.100491) (xy 135.286641 -209.150988)
			(xy 135.255868 -209.197501) (xy 135.218651 -209.239038) (xy 135.175783 -209.274713) (xy 135.128177 -209.303767)
			(xy 135.076848 -209.325579) (xy 135.022891 -209.339685) (xy 134.967454 -209.345785) (xy 134.91172 -209.343748)
			(xy 134.856877 -209.333618) (xy 134.804093 -209.315611) (xy 134.754493 -209.29011) (xy 134.709135 -209.257659)
			(xy 134.668986 -209.21895) (xy 134.6349 -209.174807) (xy 134.607604 -209.126172) (xy 134.587681 -209.074081)
			(xy 134.575555 -209.019644) (xy 134.571484 -208.964022) (xy 127.45974 -208.964022) (xy 127.45974 -209.471006)
			(xy 128.204466 -209.471006) (xy 128.208537 -209.415384) (xy 128.220663 -209.360947) (xy 128.240586 -209.308856)
			(xy 128.267882 -209.260221) (xy 128.301968 -209.216078) (xy 128.342117 -209.177369) (xy 128.387475 -209.144918)
			(xy 128.437075 -209.119417) (xy 128.489859 -209.10141) (xy 128.544702 -209.09128) (xy 128.600436 -209.089243)
			(xy 128.655873 -209.095343) (xy 128.70983 -209.109449) (xy 128.761159 -209.131261) (xy 128.808765 -209.160315)
			(xy 128.851633 -209.19599) (xy 128.88885 -209.237527) (xy 128.919623 -209.28404) (xy 128.943295 -209.334537)
			(xy 128.959363 -209.387944) (xy 128.964971 -209.426048) (xy 129.072892 -209.426048) (xy 129.076963 -209.370426)
			(xy 129.089089 -209.315989) (xy 129.109012 -209.263898) (xy 129.136308 -209.215263) (xy 129.170394 -209.17112)
			(xy 129.210543 -209.132411) (xy 129.255901 -209.09996) (xy 129.305501 -209.074459) (xy 129.358285 -209.056452)
			(xy 129.413128 -209.046322) (xy 129.468862 -209.044285) (xy 129.524299 -209.050385) (xy 129.578256 -209.064491)
			(xy 129.629585 -209.086303) (xy 129.677191 -209.115357) (xy 129.720059 -209.151032) (xy 129.757276 -209.192569)
			(xy 129.788049 -209.239082) (xy 129.811721 -209.289579) (xy 129.827789 -209.342986) (xy 129.835909 -209.398162)
			(xy 129.836418 -209.426048) (xy 129.835909 -209.453934) (xy 129.834443 -209.463894) (xy 132.328156 -209.463894)
			(xy 132.332227 -209.408272) (xy 132.344353 -209.353835) (xy 132.364276 -209.301744) (xy 132.391572 -209.253109)
			(xy 132.425658 -209.208966) (xy 132.465807 -209.170257) (xy 132.511165 -209.137806) (xy 132.560765 -209.112305)
			(xy 132.613549 -209.094298) (xy 132.668392 -209.084168) (xy 132.724126 -209.082131) (xy 132.779563 -209.088231)
			(xy 132.83352 -209.102337) (xy 132.884849 -209.124149) (xy 132.932455 -209.153203) (xy 132.975323 -209.188878)
			(xy 133.01254 -209.230415) (xy 133.043313 -209.276928) (xy 133.066985 -209.327425) (xy 133.083053 -209.380832)
			(xy 133.091173 -209.436008) (xy 133.091682 -209.463894) (xy 133.091173 -209.49178) (xy 133.083053 -209.546956)
			(xy 133.066985 -209.600363) (xy 133.043313 -209.65086) (xy 133.01254 -209.697373) (xy 132.975323 -209.73891)
			(xy 132.932455 -209.774585) (xy 132.884849 -209.803639) (xy 132.83352 -209.825451) (xy 132.779563 -209.839557)
			(xy 132.724126 -209.845657) (xy 132.668392 -209.84362) (xy 132.613549 -209.83349) (xy 132.560765 -209.815483)
			(xy 132.511165 -209.789982) (xy 132.465807 -209.757531) (xy 132.425658 -209.718822) (xy 132.391572 -209.674679)
			(xy 132.364276 -209.626044) (xy 132.344353 -209.573953) (xy 132.332227 -209.519516) (xy 132.328156 -209.463894)
			(xy 129.834443 -209.463894) (xy 129.827789 -209.50911) (xy 129.811721 -209.562517) (xy 129.788049 -209.613014)
			(xy 129.757276 -209.659527) (xy 129.720059 -209.701064) (xy 129.677191 -209.736739) (xy 129.629585 -209.765793)
			(xy 129.578256 -209.787605) (xy 129.524299 -209.801711) (xy 129.468862 -209.807811) (xy 129.413128 -209.805774)
			(xy 129.358285 -209.795644) (xy 129.305501 -209.777637) (xy 129.255901 -209.752136) (xy 129.210543 -209.719685)
			(xy 129.170394 -209.680976) (xy 129.136308 -209.636833) (xy 129.109012 -209.588198) (xy 129.089089 -209.536107)
			(xy 129.076963 -209.48167) (xy 129.072892 -209.426048) (xy 128.964971 -209.426048) (xy 128.967483 -209.44312)
			(xy 128.967992 -209.471006) (xy 128.967483 -209.498892) (xy 128.959363 -209.554068) (xy 128.943295 -209.607475)
			(xy 128.919623 -209.657972) (xy 128.88885 -209.704485) (xy 128.851633 -209.746022) (xy 128.808765 -209.781697)
			(xy 128.761159 -209.810751) (xy 128.70983 -209.832563) (xy 128.655873 -209.846669) (xy 128.600436 -209.852769)
			(xy 128.544702 -209.850732) (xy 128.489859 -209.840602) (xy 128.437075 -209.822595) (xy 128.387475 -209.797094)
			(xy 128.342117 -209.764643) (xy 128.301968 -209.725934) (xy 128.267882 -209.681791) (xy 128.240586 -209.633156)
			(xy 128.220663 -209.581065) (xy 128.208537 -209.526628) (xy 128.204466 -209.471006) (xy 127.45974 -209.471006)
			(xy 127.45974 -209.9564) (xy 131.11429 -209.9564) (xy 131.118361 -209.900778) (xy 131.130487 -209.846341)
			(xy 131.15041 -209.79425) (xy 131.177706 -209.745615) (xy 131.211792 -209.701472) (xy 131.251941 -209.662763)
			(xy 131.297299 -209.630312) (xy 131.346899 -209.604811) (xy 131.399683 -209.586804) (xy 131.454526 -209.576674)
			(xy 131.51026 -209.574637) (xy 131.565697 -209.580737) (xy 131.619654 -209.594843) (xy 131.670983 -209.616655)
			(xy 131.718589 -209.645709) (xy 131.761457 -209.681384) (xy 131.798674 -209.722921) (xy 131.829447 -209.769434)
			(xy 131.853119 -209.819931) (xy 131.869187 -209.873338) (xy 131.877307 -209.928514) (xy 131.877816 -209.9564)
			(xy 131.877677 -209.96402) (xy 134.571484 -209.96402) (xy 134.575555 -209.908398) (xy 134.587681 -209.853961)
			(xy 134.607604 -209.80187) (xy 134.6349 -209.753235) (xy 134.668986 -209.709092) (xy 134.709135 -209.670383)
			(xy 134.754493 -209.637932) (xy 134.804093 -209.612431) (xy 134.856877 -209.594424) (xy 134.91172 -209.584294)
			(xy 134.967454 -209.582257) (xy 135.022891 -209.588357) (xy 135.076848 -209.602463) (xy 135.128177 -209.624275)
			(xy 135.175783 -209.653329) (xy 135.218651 -209.689004) (xy 135.255868 -209.730541) (xy 135.286641 -209.777054)
			(xy 135.310313 -209.827551) (xy 135.326381 -209.880958) (xy 135.334501 -209.936134) (xy 135.33501 -209.96402)
			(xy 135.334501 -209.991906) (xy 135.326381 -210.047082) (xy 135.310313 -210.100489) (xy 135.286641 -210.150986)
			(xy 135.255868 -210.197499) (xy 135.218651 -210.239036) (xy 135.175783 -210.274711) (xy 135.128177 -210.303765)
			(xy 135.076848 -210.325577) (xy 135.022891 -210.339683) (xy 134.967454 -210.345783) (xy 134.91172 -210.343746)
			(xy 134.856877 -210.333616) (xy 134.804093 -210.315609) (xy 134.754493 -210.290108) (xy 134.709135 -210.257657)
			(xy 134.668986 -210.218948) (xy 134.6349 -210.174805) (xy 134.607604 -210.12617) (xy 134.587681 -210.074079)
			(xy 134.575555 -210.019642) (xy 134.571484 -209.96402) (xy 131.877677 -209.96402) (xy 131.877307 -209.984286)
			(xy 131.869187 -210.039462) (xy 131.853119 -210.092869) (xy 131.829447 -210.143366) (xy 131.798674 -210.189879)
			(xy 131.761457 -210.231416) (xy 131.718589 -210.267091) (xy 131.670983 -210.296145) (xy 131.619654 -210.317957)
			(xy 131.565697 -210.332063) (xy 131.51026 -210.338163) (xy 131.454526 -210.336126) (xy 131.399683 -210.325996)
			(xy 131.346899 -210.307989) (xy 131.297299 -210.282488) (xy 131.251941 -210.250037) (xy 131.211792 -210.211328)
			(xy 131.177706 -210.167185) (xy 131.15041 -210.11855) (xy 131.130487 -210.066459) (xy 131.118361 -210.012022)
			(xy 131.11429 -209.9564) (xy 127.45974 -209.9564) (xy 127.45974 -210.39709) (xy 137.064748 -210.39709)
			(xy 137.068819 -210.341468) (xy 137.080945 -210.287031) (xy 137.100868 -210.23494) (xy 137.128164 -210.186305)
			(xy 137.16225 -210.142162) (xy 137.202399 -210.103453) (xy 137.247757 -210.071002) (xy 137.297357 -210.045501)
			(xy 137.350141 -210.027494) (xy 137.404984 -210.017364) (xy 137.460718 -210.015327) (xy 137.516155 -210.021427)
			(xy 137.570112 -210.035533) (xy 137.621441 -210.057345) (xy 137.669047 -210.086399) (xy 137.711915 -210.122074)
			(xy 137.749132 -210.163611) (xy 137.779905 -210.210124) (xy 137.794799 -210.241896) (xy 143.716756 -210.241896)
			(xy 143.717306 -210.214112) (xy 143.725348 -210.159129) (xy 143.74129 -210.105898) (xy 143.764794 -210.055546)
			(xy 143.795362 -210.009141) (xy 143.832345 -209.967668) (xy 143.874959 -209.932006) (xy 143.898366 -209.91703)
			(xy 143.909807 -209.909486) (xy 143.928518 -209.889481) (xy 143.941234 -209.865219) (xy 143.94704 -209.838449)
			(xy 143.945516 -209.811099) (xy 143.936772 -209.785139) (xy 143.921439 -209.76244) (xy 143.91132 -209.7532)
			(xy 143.890865 -209.734994) (xy 143.854862 -209.693735) (xy 143.82513 -209.647751) (xy 143.80228 -209.597988)
			(xy 143.78678 -209.545469) (xy 143.77895 -209.491273) (xy 143.778478 -209.463894) (xy 143.778964 -209.436643)
			(xy 143.78672 -209.382695) (xy 143.802075 -209.3304) (xy 143.824717 -209.280823) (xy 143.854183 -209.234973)
			(xy 143.889874 -209.193782) (xy 143.931065 -209.158091) (xy 143.976915 -209.128625) (xy 144.026492 -209.105983)
			(xy 144.078787 -209.090628) (xy 144.132735 -209.082872) (xy 144.187237 -209.082872) (xy 144.241185 -209.090628)
			(xy 144.29348 -209.105983) (xy 144.343057 -209.128625) (xy 144.388907 -209.158091) (xy 144.393582 -209.162142)
			(xy 147.232114 -209.162142) (xy 147.236185 -209.10652) (xy 147.248311 -209.052083) (xy 147.268234 -208.999992)
			(xy 147.29553 -208.951357) (xy 147.329616 -208.907214) (xy 147.369765 -208.868505) (xy 147.415123 -208.836054)
			(xy 147.464723 -208.810553) (xy 147.517507 -208.792546) (xy 147.57235 -208.782416) (xy 147.628084 -208.780379)
			(xy 147.683521 -208.786479) (xy 147.737478 -208.800585) (xy 147.788807 -208.822397) (xy 147.836413 -208.851451)
			(xy 147.879281 -208.887126) (xy 147.916498 -208.928663) (xy 147.947271 -208.975176) (xy 147.970943 -209.025673)
			(xy 147.987011 -209.07908) (xy 147.995131 -209.134256) (xy 147.99564 -209.162142) (xy 147.995131 -209.190028)
			(xy 147.987011 -209.245204) (xy 147.970943 -209.298611) (xy 147.947271 -209.349108) (xy 147.916498 -209.395621)
			(xy 147.879281 -209.437158) (xy 147.836413 -209.472833) (xy 147.788807 -209.501887) (xy 147.737478 -209.523699)
			(xy 147.683521 -209.537805) (xy 147.628084 -209.543905) (xy 147.57235 -209.541868) (xy 147.517507 -209.531738)
			(xy 147.464723 -209.513731) (xy 147.415123 -209.48823) (xy 147.369765 -209.455779) (xy 147.329616 -209.41707)
			(xy 147.29553 -209.372927) (xy 147.268234 -209.324292) (xy 147.248311 -209.272201) (xy 147.236185 -209.217764)
			(xy 147.232114 -209.162142) (xy 144.393582 -209.162142) (xy 144.430098 -209.193782) (xy 144.465789 -209.234973)
			(xy 144.495255 -209.280823) (xy 144.517897 -209.3304) (xy 144.533252 -209.382695) (xy 144.541008 -209.436643)
			(xy 144.541494 -209.463894) (xy 144.541038 -209.491682) (xy 144.532982 -209.546669) (xy 144.517025 -209.599904)
			(xy 144.493506 -209.650257) (xy 144.462924 -209.696661) (xy 144.425926 -209.73813) (xy 144.383298 -209.773787)
			(xy 144.359884 -209.78876) (xy 144.348452 -209.796318) (xy 144.329733 -209.816317) (xy 144.31701 -209.840577)
			(xy 144.311201 -209.867346) (xy 144.312724 -209.894697) (xy 144.32147 -209.920656) (xy 144.336808 -209.943352)
			(xy 144.34693 -209.95259) (xy 144.36737 -209.970812) (xy 144.403376 -210.012066) (xy 144.433111 -210.058046)
			(xy 144.455965 -210.107806) (xy 144.471467 -210.160323) (xy 144.479299 -210.214517) (xy 144.479772 -210.241896)
			(xy 144.479286 -210.269147) (xy 144.47153 -210.323095) (xy 144.456175 -210.37539) (xy 144.433533 -210.424967)
			(xy 144.404067 -210.470817) (xy 144.368376 -210.512008) (xy 144.327185 -210.547699) (xy 144.281335 -210.577165)
			(xy 144.231758 -210.599807) (xy 144.179463 -210.615162) (xy 144.125515 -210.622918) (xy 144.071013 -210.622918)
			(xy 144.017065 -210.615162) (xy 143.96477 -210.599807) (xy 143.915193 -210.577165) (xy 143.869343 -210.547699)
			(xy 143.828152 -210.512008) (xy 143.792461 -210.470817) (xy 143.762995 -210.424967) (xy 143.740353 -210.37539)
			(xy 143.724998 -210.323095) (xy 143.717242 -210.269147) (xy 143.716756 -210.241896) (xy 137.794799 -210.241896)
			(xy 137.803577 -210.260621) (xy 137.819645 -210.314028) (xy 137.827765 -210.369204) (xy 137.828274 -210.39709)
			(xy 137.827765 -210.424976) (xy 137.819645 -210.480152) (xy 137.803577 -210.533559) (xy 137.779905 -210.584056)
			(xy 137.749132 -210.630569) (xy 137.711915 -210.672106) (xy 137.669047 -210.707781) (xy 137.621441 -210.736835)
			(xy 137.570112 -210.758647) (xy 137.516155 -210.772753) (xy 137.460718 -210.778853) (xy 137.404984 -210.776816)
			(xy 137.350141 -210.766686) (xy 137.297357 -210.748679) (xy 137.247757 -210.723178) (xy 137.202399 -210.690727)
			(xy 137.16225 -210.652018) (xy 137.128164 -210.607875) (xy 137.100868 -210.55924) (xy 137.080945 -210.507149)
			(xy 137.068819 -210.452712) (xy 137.064748 -210.39709) (xy 127.45974 -210.39709) (xy 127.45974 -210.834247)
			(xy 138.520224 -210.834247) (xy 138.520224 -210.779753) (xy 138.527979 -210.725815) (xy 138.543331 -210.673529)
			(xy 138.565967 -210.62396) (xy 138.595427 -210.578116) (xy 138.631111 -210.536932) (xy 138.672292 -210.501245)
			(xy 138.718133 -210.471781) (xy 138.767701 -210.449141) (xy 138.819986 -210.433785) (xy 138.873923 -210.426026)
			(xy 138.90117 -210.425538) (xy 138.927933 -210.425945) (xy 138.980932 -210.43343) (xy 139.032366 -210.448244)
			(xy 139.081227 -210.470097) (xy 139.126558 -210.498559) (xy 139.167468 -210.533074) (xy 139.203158 -210.572965)
			(xy 139.218416 -210.594956) (xy 139.227117 -210.606883) (xy 139.249879 -210.625655) (xy 139.277057 -210.637138)
			(xy 139.306384 -210.640372) (xy 139.335411 -210.635089) (xy 139.361717 -210.621729) (xy 139.383107 -210.601407)
			(xy 139.390882 -210.58886) (xy 139.405539 -210.564222) (xy 139.441142 -210.519289) (xy 139.483066 -210.480188)
			(xy 139.530367 -210.447799) (xy 139.581982 -210.422851) (xy 139.636749 -210.405906) (xy 139.693434 -210.397344)
			(xy 139.722098 -210.396836) (xy 139.749354 -210.397211) (xy 139.803312 -210.404968) (xy 139.855616 -210.420326)
			(xy 139.905202 -210.442971) (xy 139.951061 -210.472443) (xy 139.992258 -210.50814) (xy 140.027956 -210.549338)
			(xy 140.057428 -210.595196) (xy 140.080073 -210.644782) (xy 140.095431 -210.697087) (xy 140.103189 -210.751044)
			(xy 140.103189 -210.805556) (xy 140.101514 -210.817206) (xy 140.924786 -210.817206) (xy 140.928857 -210.761584)
			(xy 140.940983 -210.707147) (xy 140.960906 -210.655056) (xy 140.988202 -210.606421) (xy 141.022288 -210.562278)
			(xy 141.062437 -210.523569) (xy 141.107795 -210.491118) (xy 141.157395 -210.465617) (xy 141.210179 -210.44761)
			(xy 141.265022 -210.43748) (xy 141.320756 -210.435443) (xy 141.376193 -210.441543) (xy 141.43015 -210.455649)
			(xy 141.481479 -210.477461) (xy 141.529085 -210.506515) (xy 141.571953 -210.54219) (xy 141.60917 -210.583727)
			(xy 141.639943 -210.63024) (xy 141.663615 -210.680737) (xy 141.679683 -210.734144) (xy 141.687803 -210.78932)
			(xy 141.688312 -210.817206) (xy 141.687815 -210.844453) (xy 141.925761 -210.844453) (xy 141.925761 -210.789947)
			(xy 141.933518 -210.735997) (xy 141.948874 -210.6837) (xy 141.971516 -210.634121) (xy 142.000984 -210.588268)
			(xy 142.036677 -210.547076) (xy 142.07787 -210.511383) (xy 142.123722 -210.481915) (xy 142.173302 -210.459273)
			(xy 142.225599 -210.443918) (xy 142.279549 -210.436161) (xy 142.306802 -210.435698) (xy 142.333057 -210.436163)
			(xy 142.385073 -210.443349) (xy 142.435613 -210.457597) (xy 142.483722 -210.478638) (xy 142.528493 -210.506077)
			(xy 142.569079 -210.539393) (xy 142.587218 -210.55838) (xy 142.594584 -210.566508) (xy 142.614396 -210.57489)
			(xy 142.711932 -210.573366) (xy 142.731236 -210.564222) (xy 142.738602 -210.556094) (xy 142.75682 -210.53578)
			(xy 142.798028 -210.500012) (xy 142.843905 -210.470471) (xy 142.89352 -210.44776) (xy 142.945861 -210.43234)
			(xy 142.999864 -210.424526) (xy 143.027146 -210.424014) (xy 143.054397 -210.424459) (xy 143.108343 -210.432221)
			(xy 143.160635 -210.447581) (xy 143.210209 -210.470226) (xy 143.256056 -210.499696) (xy 143.297243 -210.535389)
			(xy 143.332932 -210.576581) (xy 143.362396 -210.622431) (xy 143.385035 -210.672008) (xy 143.398656 -210.7184)
			(xy 145.236182 -210.7184) (xy 145.240253 -210.662778) (xy 145.252379 -210.608341) (xy 145.272302 -210.55625)
			(xy 145.299598 -210.507615) (xy 145.333684 -210.463472) (xy 145.373833 -210.424763) (xy 145.419191 -210.392312)
			(xy 145.468791 -210.366811) (xy 145.521575 -210.348804) (xy 145.576418 -210.338674) (xy 145.632152 -210.336637)
			(xy 145.687589 -210.342737) (xy 145.741546 -210.356843) (xy 145.792875 -210.378655) (xy 145.840481 -210.407709)
			(xy 145.883349 -210.443384) (xy 145.920566 -210.484921) (xy 145.951339 -210.531434) (xy 145.975011 -210.581931)
			(xy 145.991079 -210.635338) (xy 145.999199 -210.690514) (xy 145.999708 -210.7184) (xy 145.999199 -210.746286)
			(xy 145.991079 -210.801462) (xy 145.975011 -210.854869) (xy 145.951339 -210.905366) (xy 145.920566 -210.951879)
			(xy 145.883349 -210.993416) (xy 145.840481 -211.029091) (xy 145.792875 -211.058145) (xy 145.741546 -211.079957)
			(xy 145.687589 -211.094063) (xy 145.632152 -211.100163) (xy 145.576418 -211.098126) (xy 145.521575 -211.087996)
			(xy 145.468791 -211.069989) (xy 145.419191 -211.044488) (xy 145.373833 -211.012037) (xy 145.333684 -210.973328)
			(xy 145.299598 -210.929185) (xy 145.272302 -210.88055) (xy 145.252379 -210.828459) (xy 145.240253 -210.774022)
			(xy 145.236182 -210.7184) (xy 143.398656 -210.7184) (xy 143.400389 -210.724302) (xy 143.408144 -210.778249)
			(xy 143.408144 -210.832751) (xy 143.400389 -210.886698) (xy 143.385035 -210.938992) (xy 143.362396 -210.988569)
			(xy 143.332932 -211.034419) (xy 143.297243 -211.075611) (xy 143.256056 -211.111304) (xy 143.210209 -211.140774)
			(xy 143.160635 -211.163419) (xy 143.108343 -211.178779) (xy 143.054397 -211.186541) (xy 143.027146 -211.18703)
			(xy 143.000889 -211.186622) (xy 142.94887 -211.179429) (xy 142.898328 -211.165171) (xy 142.850218 -211.144118)
			(xy 142.805449 -211.116669) (xy 142.764866 -211.08334) (xy 142.74673 -211.064348) (xy 142.739364 -211.05622)
			(xy 142.719552 -211.047838) (xy 142.622016 -211.049362) (xy 142.602712 -211.058506) (xy 142.595346 -211.066634)
			(xy 142.577109 -211.086931) (xy 142.535905 -211.122699) (xy 142.490031 -211.152241) (xy 142.44042 -211.174955)
			(xy 142.388083 -211.190379) (xy 142.334083 -211.198199) (xy 142.306802 -211.198714) (xy 142.279549 -211.198239)
			(xy 142.225599 -211.190482) (xy 142.173302 -211.175127) (xy 142.123722 -211.152485) (xy 142.07787 -211.123017)
			(xy 142.036677 -211.087324) (xy 142.000984 -211.046132) (xy 141.971516 -211.000279) (xy 141.948874 -210.9507)
			(xy 141.933518 -210.898403) (xy 141.925761 -210.844453) (xy 141.687815 -210.844453) (xy 141.687803 -210.845092)
			(xy 141.679683 -210.900268) (xy 141.663615 -210.953675) (xy 141.639943 -211.004172) (xy 141.60917 -211.050685)
			(xy 141.571953 -211.092222) (xy 141.529085 -211.127897) (xy 141.481479 -211.156951) (xy 141.43015 -211.178763)
			(xy 141.376193 -211.192869) (xy 141.320756 -211.198969) (xy 141.265022 -211.196932) (xy 141.210179 -211.186802)
			(xy 141.157395 -211.168795) (xy 141.107795 -211.143294) (xy 141.062437 -211.110843) (xy 141.022288 -211.072134)
			(xy 140.988202 -211.027991) (xy 140.960906 -210.979356) (xy 140.940983 -210.927265) (xy 140.928857 -210.872828)
			(xy 140.924786 -210.817206) (xy 140.101514 -210.817206) (xy 140.095431 -210.859513) (xy 140.080073 -210.911818)
			(xy 140.057428 -210.961404) (xy 140.027956 -211.007262) (xy 139.992258 -211.04846) (xy 139.951061 -211.084157)
			(xy 139.905202 -211.113629) (xy 139.855616 -211.136274) (xy 139.803312 -211.151632) (xy 139.749354 -211.159389)
			(xy 139.722098 -211.159852) (xy 139.695337 -211.159398) (xy 139.64234 -211.151922) (xy 139.590906 -211.137116)
			(xy 139.542045 -211.115271) (xy 139.496714 -211.086816) (xy 139.455802 -211.052308) (xy 139.420111 -211.012423)
			(xy 139.404852 -210.990434) (xy 139.396191 -210.978476) (xy 139.373419 -210.959705) (xy 139.346232 -210.948225)
			(xy 139.316899 -210.944995) (xy 139.287865 -210.950284) (xy 139.261555 -210.963651) (xy 139.240162 -210.98398)
			(xy 139.232386 -210.99653) (xy 139.217678 -211.021136) (xy 139.182084 -211.066069) (xy 139.140168 -211.105172)
			(xy 139.092875 -211.137564) (xy 139.041269 -211.162518) (xy 138.98651 -211.179471) (xy 138.929832 -211.188041)
			(xy 138.90117 -211.188554) (xy 138.873923 -211.187974) (xy 138.819986 -211.180215) (xy 138.767701 -211.164859)
			(xy 138.718133 -211.142219) (xy 138.672292 -211.112755) (xy 138.631111 -211.077068) (xy 138.595427 -211.035884)
			(xy 138.565967 -210.99004) (xy 138.543331 -210.940471) (xy 138.527979 -210.888185) (xy 138.520224 -210.834247)
			(xy 127.45974 -210.834247) (xy 127.45974 -211.977732) (xy 131.14731 -211.977732) (xy 131.151381 -211.92211)
			(xy 131.163507 -211.867673) (xy 131.18343 -211.815582) (xy 131.210726 -211.766947) (xy 131.244812 -211.722804)
			(xy 131.284961 -211.684095) (xy 131.330319 -211.651644) (xy 131.379919 -211.626143) (xy 131.432703 -211.608136)
			(xy 131.487546 -211.598006) (xy 131.54328 -211.595969) (xy 131.598717 -211.602069) (xy 131.652674 -211.616175)
			(xy 131.704003 -211.637987) (xy 131.751609 -211.667041) (xy 131.794477 -211.702716) (xy 131.831694 -211.744253)
			(xy 131.83341 -211.746846) (xy 134.826246 -211.746846) (xy 134.830317 -211.691224) (xy 134.842443 -211.636787)
			(xy 134.862366 -211.584696) (xy 134.889662 -211.536061) (xy 134.923748 -211.491918) (xy 134.963897 -211.453209)
			(xy 135.009255 -211.420758) (xy 135.058855 -211.395257) (xy 135.111639 -211.37725) (xy 135.166482 -211.36712)
			(xy 135.222216 -211.365083) (xy 135.277653 -211.371183) (xy 135.33161 -211.385289) (xy 135.382939 -211.407101)
			(xy 135.430545 -211.436155) (xy 135.473413 -211.47183) (xy 135.51063 -211.513367) (xy 135.541403 -211.55988)
			(xy 135.565075 -211.610377) (xy 135.581143 -211.663784) (xy 135.589263 -211.71896) (xy 135.589772 -211.746846)
			(xy 135.589263 -211.774732) (xy 135.581143 -211.829908) (xy 135.565075 -211.883315) (xy 135.541403 -211.933812)
			(xy 135.51063 -211.980325) (xy 135.473413 -212.021862) (xy 135.430545 -212.057537) (xy 135.382939 -212.086591)
			(xy 135.33161 -212.108403) (xy 135.277653 -212.122509) (xy 135.222216 -212.128609) (xy 135.166482 -212.126572)
			(xy 135.111639 -212.116442) (xy 135.058855 -212.098435) (xy 135.009255 -212.072934) (xy 134.963897 -212.040483)
			(xy 134.923748 -212.001774) (xy 134.889662 -211.957631) (xy 134.862366 -211.908996) (xy 134.842443 -211.856905)
			(xy 134.830317 -211.802468) (xy 134.826246 -211.746846) (xy 131.83341 -211.746846) (xy 131.862467 -211.790766)
			(xy 131.886139 -211.841263) (xy 131.902207 -211.89467) (xy 131.910327 -211.949846) (xy 131.910836 -211.977732)
			(xy 131.910327 -212.005618) (xy 131.902207 -212.060794) (xy 131.886139 -212.114201) (xy 131.862467 -212.164698)
			(xy 131.831694 -212.211211) (xy 131.794477 -212.252748) (xy 131.751609 -212.288423) (xy 131.704003 -212.317477)
			(xy 131.652674 -212.339289) (xy 131.598717 -212.353395) (xy 131.54328 -212.359495) (xy 131.487546 -212.357458)
			(xy 131.432703 -212.347328) (xy 131.379919 -212.329321) (xy 131.330319 -212.30382) (xy 131.284961 -212.271369)
			(xy 131.244812 -212.23266) (xy 131.210726 -212.188517) (xy 131.18343 -212.139882) (xy 131.163507 -212.087791)
			(xy 131.151381 -212.033354) (xy 131.14731 -211.977732) (xy 127.45974 -211.977732) (xy 127.45974 -213.016846)
			(xy 135.924796 -213.016846) (xy 135.928867 -212.961224) (xy 135.940993 -212.906787) (xy 135.960916 -212.854696)
			(xy 135.988212 -212.806061) (xy 136.022298 -212.761918) (xy 136.062447 -212.723209) (xy 136.107805 -212.690758)
			(xy 136.157405 -212.665257) (xy 136.210189 -212.64725) (xy 136.265032 -212.63712) (xy 136.320766 -212.635083)
			(xy 136.376203 -212.641183) (xy 136.43016 -212.655289) (xy 136.481489 -212.677101) (xy 136.529095 -212.706155)
			(xy 136.571963 -212.74183) (xy 136.60918 -212.783367) (xy 136.639953 -212.82988) (xy 136.663625 -212.880377)
			(xy 136.679693 -212.933784) (xy 136.687813 -212.98896) (xy 136.688322 -213.016846) (xy 136.687813 -213.044732)
			(xy 136.683843 -213.07171) (xy 137.064748 -213.07171) (xy 137.068819 -213.016088) (xy 137.080945 -212.961651)
			(xy 137.100868 -212.90956) (xy 137.128164 -212.860925) (xy 137.16225 -212.816782) (xy 137.202399 -212.778073)
			(xy 137.247757 -212.745622) (xy 137.297357 -212.720121) (xy 137.350141 -212.702114) (xy 137.404984 -212.691984)
			(xy 137.460718 -212.689947) (xy 137.516155 -212.696047) (xy 137.570112 -212.710153) (xy 137.621441 -212.731965)
			(xy 137.669047 -212.761019) (xy 137.711915 -212.796694) (xy 137.749132 -212.838231) (xy 137.779905 -212.884744)
			(xy 137.803577 -212.935241) (xy 137.819645 -212.988648) (xy 137.827765 -213.043824) (xy 137.828274 -213.07171)
			(xy 137.827765 -213.099596) (xy 137.819645 -213.154772) (xy 137.803577 -213.208179) (xy 137.779905 -213.258676)
			(xy 137.749132 -213.305189) (xy 137.711915 -213.346726) (xy 137.669047 -213.382401) (xy 137.621441 -213.411455)
			(xy 137.570112 -213.433267) (xy 137.516155 -213.447373) (xy 137.460718 -213.453473) (xy 137.404984 -213.451436)
			(xy 137.350141 -213.441306) (xy 137.297357 -213.423299) (xy 137.247757 -213.397798) (xy 137.202399 -213.365347)
			(xy 137.16225 -213.326638) (xy 137.128164 -213.282495) (xy 137.100868 -213.23386) (xy 137.080945 -213.181769)
			(xy 137.068819 -213.127332) (xy 137.064748 -213.07171) (xy 136.683843 -213.07171) (xy 136.679693 -213.099908)
			(xy 136.663625 -213.153315) (xy 136.639953 -213.203812) (xy 136.60918 -213.250325) (xy 136.571963 -213.291862)
			(xy 136.529095 -213.327537) (xy 136.481489 -213.356591) (xy 136.43016 -213.378403) (xy 136.376203 -213.392509)
			(xy 136.320766 -213.398609) (xy 136.265032 -213.396572) (xy 136.210189 -213.386442) (xy 136.157405 -213.368435)
			(xy 136.107805 -213.342934) (xy 136.062447 -213.310483) (xy 136.022298 -213.271774) (xy 135.988212 -213.227631)
			(xy 135.960916 -213.178996) (xy 135.940993 -213.126905) (xy 135.928867 -213.072468) (xy 135.924796 -213.016846)
			(xy 127.45974 -213.016846) (xy 127.45974 -213.712552) (xy 139.125196 -213.712552) (xy 139.129267 -213.65693)
			(xy 139.141393 -213.602493) (xy 139.161316 -213.550402) (xy 139.188612 -213.501767) (xy 139.222698 -213.457624)
			(xy 139.262847 -213.418915) (xy 139.308205 -213.386464) (xy 139.357805 -213.360963) (xy 139.410589 -213.342956)
			(xy 139.465432 -213.332826) (xy 139.521166 -213.330789) (xy 139.576603 -213.336889) (xy 139.63056 -213.350995)
			(xy 139.681889 -213.372807) (xy 139.729495 -213.401861) (xy 139.772363 -213.437536) (xy 139.80958 -213.479073)
			(xy 139.82726 -213.505796) (xy 142.064484 -213.505796) (xy 142.068555 -213.450174) (xy 142.080681 -213.395737)
			(xy 142.100604 -213.343646) (xy 142.1279 -213.295011) (xy 142.161986 -213.250868) (xy 142.202135 -213.212159)
			(xy 142.247493 -213.179708) (xy 142.297093 -213.154207) (xy 142.349877 -213.1362) (xy 142.40472 -213.12607)
			(xy 142.460454 -213.124033) (xy 142.515891 -213.130133) (xy 142.569848 -213.144239) (xy 142.621177 -213.166051)
			(xy 142.668783 -213.195105) (xy 142.711651 -213.23078) (xy 142.748868 -213.272317) (xy 142.779641 -213.31883)
			(xy 142.803313 -213.369327) (xy 142.819381 -213.422734) (xy 142.827501 -213.47791) (xy 142.82801 -213.505796)
			(xy 142.827501 -213.533682) (xy 142.819381 -213.588858) (xy 142.803313 -213.642265) (xy 142.779641 -213.692762)
			(xy 142.748868 -213.739275) (xy 142.711651 -213.780812) (xy 142.668783 -213.816487) (xy 142.621177 -213.845541)
			(xy 142.569848 -213.867353) (xy 142.515891 -213.881459) (xy 142.460454 -213.887559) (xy 142.40472 -213.885522)
			(xy 142.349877 -213.875392) (xy 142.297093 -213.857385) (xy 142.247493 -213.831884) (xy 142.202135 -213.799433)
			(xy 142.161986 -213.760724) (xy 142.1279 -213.716581) (xy 142.100604 -213.667946) (xy 142.080681 -213.615855)
			(xy 142.068555 -213.561418) (xy 142.064484 -213.505796) (xy 139.82726 -213.505796) (xy 139.840353 -213.525586)
			(xy 139.864025 -213.576083) (xy 139.880093 -213.62949) (xy 139.888213 -213.684666) (xy 139.888722 -213.712552)
			(xy 139.888213 -213.740438) (xy 139.880093 -213.795614) (xy 139.864025 -213.849021) (xy 139.840353 -213.899518)
			(xy 139.80958 -213.946031) (xy 139.800752 -213.955884) (xy 144.949926 -213.955884) (xy 144.950412 -213.928633)
			(xy 144.958168 -213.874685) (xy 144.973523 -213.82239) (xy 144.996165 -213.772813) (xy 145.025631 -213.726963)
			(xy 145.061322 -213.685772) (xy 145.102513 -213.650081) (xy 145.148363 -213.620615) (xy 145.19794 -213.597973)
			(xy 145.250235 -213.582618) (xy 145.304183 -213.574862) (xy 145.358685 -213.574862) (xy 145.412633 -213.582618)
			(xy 145.464928 -213.597973) (xy 145.514505 -213.620615) (xy 145.560355 -213.650081) (xy 145.601546 -213.685772)
			(xy 145.637237 -213.726963) (xy 145.666703 -213.772813) (xy 145.689345 -213.82239) (xy 145.7047 -213.874685)
			(xy 145.712456 -213.928633) (xy 145.712942 -213.955884) (xy 145.712434 -213.984697) (xy 145.703781 -214.041669)
			(xy 145.686654 -214.096691) (xy 145.661445 -214.14851) (xy 145.628725 -214.195946) (xy 145.589241 -214.23792)
			(xy 145.566892 -214.256112) (xy 145.555627 -214.265392) (xy 145.538637 -214.289116) (xy 145.52905 -214.316677)
			(xy 145.52765 -214.345823) (xy 145.53455 -214.374176) (xy 145.549188 -214.399419) (xy 145.570368 -214.419492)
			(xy 145.583148 -214.426546) (xy 145.60623 -214.438854) (xy 145.649072 -214.46887) (xy 145.687409 -214.504461)
			(xy 145.720521 -214.544959) (xy 145.747786 -214.589602) (xy 145.768693 -214.637554) (xy 145.782848 -214.687913)
			(xy 145.789987 -214.739734) (xy 145.790412 -214.76589) (xy 145.789926 -214.793141) (xy 145.78217 -214.847089)
			(xy 145.766815 -214.899384) (xy 145.744173 -214.948961) (xy 145.714707 -214.994811) (xy 145.679016 -215.036002)
			(xy 145.637825 -215.071693) (xy 145.591975 -215.101159) (xy 145.542398 -215.123801) (xy 145.490103 -215.139156)
			(xy 145.436155 -215.146912) (xy 145.381653 -215.146912) (xy 145.327705 -215.139156) (xy 145.27541 -215.123801)
			(xy 145.225833 -215.101159) (xy 145.179983 -215.071693) (xy 145.138792 -215.036002) (xy 145.103101 -214.994811)
			(xy 145.073635 -214.948961) (xy 145.050993 -214.899384) (xy 145.035638 -214.847089) (xy 145.027882 -214.793141)
			(xy 145.027396 -214.76589) (xy 145.027909 -214.737077) (xy 145.036565 -214.680106) (xy 145.053692 -214.625085)
			(xy 145.0789 -214.573267) (xy 145.111618 -214.525831) (xy 145.151098 -214.483856) (xy 145.173446 -214.465662)
			(xy 145.184624 -214.456288) (xy 145.201607 -214.432585) (xy 145.211195 -214.405048) (xy 145.212605 -214.375923)
			(xy 145.205722 -214.347588) (xy 145.191109 -214.322356) (xy 145.169956 -214.302285) (xy 145.15719 -214.295228)
			(xy 145.134124 -214.282891) (xy 145.091286 -214.252876) (xy 145.052951 -214.217287) (xy 145.01984 -214.176794)
			(xy 144.992574 -214.132155) (xy 144.971664 -214.084209) (xy 144.957503 -214.033855) (xy 144.950356 -213.982038)
			(xy 144.949926 -213.955884) (xy 139.800752 -213.955884) (xy 139.772363 -213.987568) (xy 139.729495 -214.023243)
			(xy 139.681889 -214.052297) (xy 139.63056 -214.074109) (xy 139.576603 -214.088215) (xy 139.521166 -214.094315)
			(xy 139.465432 -214.092278) (xy 139.410589 -214.082148) (xy 139.357805 -214.064141) (xy 139.308205 -214.03864)
			(xy 139.262847 -214.006189) (xy 139.222698 -213.96748) (xy 139.188612 -213.923337) (xy 139.161316 -213.874702)
			(xy 139.141393 -213.822611) (xy 139.129267 -213.768174) (xy 139.125196 -213.712552) (xy 127.45974 -213.712552)
			(xy 127.45974 -214.149251) (xy 135.254978 -214.149251) (xy 135.254978 -214.094749) (xy 135.262734 -214.040801)
			(xy 135.278089 -213.988506) (xy 135.300731 -213.938929) (xy 135.330197 -213.893079) (xy 135.365888 -213.851888)
			(xy 135.407079 -213.816197) (xy 135.452929 -213.786731) (xy 135.502506 -213.764089) (xy 135.554801 -213.748734)
			(xy 135.608749 -213.740978) (xy 135.636 -213.740492) (xy 135.663825 -213.740971) (xy 135.718883 -213.749062)
			(xy 135.772179 -213.765071) (xy 135.822582 -213.788659) (xy 135.86902 -213.819325) (xy 135.910506 -213.856416)
			(xy 135.946158 -213.899145) (xy 135.96112 -213.92261) (xy 135.969512 -213.935406) (xy 135.992504 -213.955584)
			(xy 136.020437 -213.968059) (xy 136.050809 -213.971713) (xy 136.080903 -213.96622) (xy 136.108025 -213.952071)
			(xy 136.129749 -213.930533) (xy 136.137396 -213.917276) (xy 136.151785 -213.89153) (xy 136.187195 -213.844367)
			(xy 136.229437 -213.803212) (xy 136.277506 -213.769044) (xy 136.330259 -213.742676) (xy 136.38644 -213.724735)
			(xy 136.444712 -213.715649) (xy 136.4742 -213.715092) (xy 136.501451 -213.715578) (xy 136.555399 -213.723334)
			(xy 136.607694 -213.738689) (xy 136.657271 -213.761331) (xy 136.703121 -213.790797) (xy 136.744312 -213.826488)
			(xy 136.780003 -213.867679) (xy 136.809469 -213.913529) (xy 136.832111 -213.963106) (xy 136.847466 -214.015401)
			(xy 136.855222 -214.069349) (xy 136.855222 -214.123851) (xy 136.847466 -214.177799) (xy 136.832111 -214.230094)
			(xy 136.809469 -214.279671) (xy 136.780003 -214.325521) (xy 136.744312 -214.366712) (xy 136.703121 -214.402403)
			(xy 136.657271 -214.431869) (xy 136.607694 -214.454511) (xy 136.555399 -214.469866) (xy 136.501451 -214.477622)
			(xy 136.4742 -214.478108) (xy 136.446375 -214.477629) (xy 136.391317 -214.469538) (xy 136.338021 -214.453529)
			(xy 136.287618 -214.429941) (xy 136.24118 -214.399275) (xy 136.199694 -214.362184) (xy 136.164042 -214.319455)
			(xy 136.14908 -214.29599) (xy 136.140688 -214.283194) (xy 136.117696 -214.263016) (xy 136.089763 -214.250541)
			(xy 136.059391 -214.246887) (xy 136.029297 -214.25238) (xy 136.002175 -214.266529) (xy 135.980451 -214.288067)
			(xy 135.972804 -214.301324) (xy 135.958415 -214.32707) (xy 135.923005 -214.374233) (xy 135.880763 -214.415388)
			(xy 135.832694 -214.449556) (xy 135.779941 -214.475924) (xy 135.72376 -214.493865) (xy 135.665488 -214.502951)
			(xy 135.636 -214.503508) (xy 135.608749 -214.503022) (xy 135.554801 -214.495266) (xy 135.502506 -214.479911)
			(xy 135.452929 -214.457269) (xy 135.407079 -214.427803) (xy 135.365888 -214.392112) (xy 135.330197 -214.350921)
			(xy 135.300731 -214.305071) (xy 135.278089 -214.255494) (xy 135.262734 -214.203199) (xy 135.254978 -214.149251)
			(xy 127.45974 -214.149251) (xy 127.45974 -215.09482) (xy 127.568196 -215.09482) (xy 127.572267 -215.039198)
			(xy 127.584393 -214.984761) (xy 127.604316 -214.93267) (xy 127.631612 -214.884035) (xy 127.665698 -214.839892)
			(xy 127.705847 -214.801183) (xy 127.751205 -214.768732) (xy 127.800805 -214.743231) (xy 127.853589 -214.725224)
			(xy 127.908432 -214.715094) (xy 127.964166 -214.713057) (xy 128.019603 -214.719157) (xy 128.07356 -214.733263)
			(xy 128.124889 -214.755075) (xy 128.172495 -214.784129) (xy 128.215363 -214.819804) (xy 128.25258 -214.861341)
			(xy 128.283353 -214.907854) (xy 128.288007 -214.917782) (xy 131.880862 -214.917782) (xy 131.884933 -214.86216)
			(xy 131.897059 -214.807723) (xy 131.916982 -214.755632) (xy 131.944278 -214.706997) (xy 131.978364 -214.662854)
			(xy 132.018513 -214.624145) (xy 132.063871 -214.591694) (xy 132.113471 -214.566193) (xy 132.166255 -214.548186)
			(xy 132.221098 -214.538056) (xy 132.276832 -214.536019) (xy 132.332269 -214.542119) (xy 132.386226 -214.556225)
			(xy 132.437555 -214.578037) (xy 132.485161 -214.607091) (xy 132.528029 -214.642766) (xy 132.550501 -214.667846)
			(xy 132.902196 -214.667846) (xy 132.906267 -214.612224) (xy 132.918393 -214.557787) (xy 132.938316 -214.505696)
			(xy 132.965612 -214.457061) (xy 132.999698 -214.412918) (xy 133.039847 -214.374209) (xy 133.085205 -214.341758)
			(xy 133.134805 -214.316257) (xy 133.187589 -214.29825) (xy 133.242432 -214.28812) (xy 133.298166 -214.286083)
			(xy 133.353603 -214.292183) (xy 133.40756 -214.306289) (xy 133.458889 -214.328101) (xy 133.506495 -214.357155)
			(xy 133.549363 -214.39283) (xy 133.58658 -214.434367) (xy 133.617353 -214.48088) (xy 133.641025 -214.531377)
			(xy 133.657093 -214.584784) (xy 133.665213 -214.63996) (xy 133.665722 -214.667846) (xy 134.426196 -214.667846)
			(xy 134.430267 -214.612224) (xy 134.442393 -214.557787) (xy 134.462316 -214.505696) (xy 134.489612 -214.457061)
			(xy 134.523698 -214.412918) (xy 134.563847 -214.374209) (xy 134.609205 -214.341758) (xy 134.658805 -214.316257)
			(xy 134.711589 -214.29825) (xy 134.766432 -214.28812) (xy 134.822166 -214.286083) (xy 134.877603 -214.292183)
			(xy 134.93156 -214.306289) (xy 134.982889 -214.328101) (xy 135.030495 -214.357155) (xy 135.073363 -214.39283)
			(xy 135.11058 -214.434367) (xy 135.141353 -214.48088) (xy 135.165025 -214.531377) (xy 135.181093 -214.584784)
			(xy 135.189213 -214.63996) (xy 135.189722 -214.667846) (xy 135.189213 -214.695732) (xy 135.181093 -214.750908)
			(xy 135.165025 -214.804315) (xy 135.141353 -214.854812) (xy 135.11058 -214.901325) (xy 135.073363 -214.942862)
			(xy 135.030495 -214.978537) (xy 135.0235 -214.982806) (xy 138.297156 -214.982806) (xy 138.301227 -214.927184)
			(xy 138.313353 -214.872747) (xy 138.333276 -214.820656) (xy 138.360572 -214.772021) (xy 138.394658 -214.727878)
			(xy 138.434807 -214.689169) (xy 138.480165 -214.656718) (xy 138.529765 -214.631217) (xy 138.582549 -214.61321)
			(xy 138.637392 -214.60308) (xy 138.693126 -214.601043) (xy 138.748563 -214.607143) (xy 138.80252 -214.621249)
			(xy 138.853849 -214.643061) (xy 138.901455 -214.672115) (xy 138.944323 -214.70779) (xy 138.98154 -214.749327)
			(xy 139.012313 -214.79584) (xy 139.035985 -214.846337) (xy 139.052053 -214.899744) (xy 139.060173 -214.95492)
			(xy 139.060251 -214.959184) (xy 141.653766 -214.959184) (xy 141.657837 -214.903562) (xy 141.669963 -214.849125)
			(xy 141.689886 -214.797034) (xy 141.717182 -214.748399) (xy 141.751268 -214.704256) (xy 141.791417 -214.665547)
			(xy 141.836775 -214.633096) (xy 141.886375 -214.607595) (xy 141.939159 -214.589588) (xy 141.994002 -214.579458)
			(xy 142.049736 -214.577421) (xy 142.105173 -214.583521) (xy 142.15913 -214.597627) (xy 142.210459 -214.619439)
			(xy 142.258065 -214.648493) (xy 142.300933 -214.684168) (xy 142.33815 -214.725705) (xy 142.368923 -214.772218)
			(xy 142.392595 -214.822715) (xy 142.408663 -214.876122) (xy 142.416783 -214.931298) (xy 142.417292 -214.959184)
			(xy 142.416783 -214.98707) (xy 142.408663 -215.042246) (xy 142.392595 -215.095653) (xy 142.368923 -215.14615)
			(xy 142.33815 -215.192663) (xy 142.300933 -215.2342) (xy 142.258065 -215.269875) (xy 142.210459 -215.298929)
			(xy 142.15913 -215.320741) (xy 142.105173 -215.334847) (xy 142.049736 -215.340947) (xy 141.994002 -215.33891)
			(xy 141.939159 -215.32878) (xy 141.886375 -215.310773) (xy 141.836775 -215.285272) (xy 141.791417 -215.252821)
			(xy 141.751268 -215.214112) (xy 141.717182 -215.169969) (xy 141.689886 -215.121334) (xy 141.669963 -215.069243)
			(xy 141.657837 -215.014806) (xy 141.653766 -214.959184) (xy 139.060251 -214.959184) (xy 139.060682 -214.982806)
			(xy 139.060173 -215.010692) (xy 139.052053 -215.065868) (xy 139.035985 -215.119275) (xy 139.012313 -215.169772)
			(xy 138.98154 -215.216285) (xy 138.944323 -215.257822) (xy 138.901455 -215.293497) (xy 138.853849 -215.322551)
			(xy 138.80252 -215.344363) (xy 138.748563 -215.358469) (xy 138.693126 -215.364569) (xy 138.637392 -215.362532)
			(xy 138.582549 -215.352402) (xy 138.529765 -215.334395) (xy 138.480165 -215.308894) (xy 138.434807 -215.276443)
			(xy 138.394658 -215.237734) (xy 138.360572 -215.193591) (xy 138.333276 -215.144956) (xy 138.313353 -215.092865)
			(xy 138.301227 -215.038428) (xy 138.297156 -214.982806) (xy 135.0235 -214.982806) (xy 134.982889 -215.007591)
			(xy 134.93156 -215.029403) (xy 134.877603 -215.043509) (xy 134.822166 -215.049609) (xy 134.766432 -215.047572)
			(xy 134.711589 -215.037442) (xy 134.658805 -215.019435) (xy 134.609205 -214.993934) (xy 134.563847 -214.961483)
			(xy 134.523698 -214.922774) (xy 134.489612 -214.878631) (xy 134.462316 -214.829996) (xy 134.442393 -214.777905)
			(xy 134.430267 -214.723468) (xy 134.426196 -214.667846) (xy 133.665722 -214.667846) (xy 133.665213 -214.695732)
			(xy 133.657093 -214.750908) (xy 133.641025 -214.804315) (xy 133.617353 -214.854812) (xy 133.58658 -214.901325)
			(xy 133.549363 -214.942862) (xy 133.506495 -214.978537) (xy 133.458889 -215.007591) (xy 133.40756 -215.029403)
			(xy 133.353603 -215.043509) (xy 133.298166 -215.049609) (xy 133.242432 -215.047572) (xy 133.187589 -215.037442)
			(xy 133.134805 -215.019435) (xy 133.085205 -214.993934) (xy 133.039847 -214.961483) (xy 132.999698 -214.922774)
			(xy 132.965612 -214.878631) (xy 132.938316 -214.829996) (xy 132.918393 -214.777905) (xy 132.906267 -214.723468)
			(xy 132.902196 -214.667846) (xy 132.550501 -214.667846) (xy 132.565246 -214.684303) (xy 132.596019 -214.730816)
			(xy 132.619691 -214.781313) (xy 132.635759 -214.83472) (xy 132.643879 -214.889896) (xy 132.644388 -214.917782)
			(xy 132.643879 -214.945668) (xy 132.635759 -215.000844) (xy 132.619691 -215.054251) (xy 132.596019 -215.104748)
			(xy 132.56965 -215.144604) (xy 133.662164 -215.144604) (xy 133.666235 -215.088982) (xy 133.678361 -215.034545)
			(xy 133.698284 -214.982454) (xy 133.72558 -214.933819) (xy 133.759666 -214.889676) (xy 133.799815 -214.850967)
			(xy 133.845173 -214.818516) (xy 133.894773 -214.793015) (xy 133.947557 -214.775008) (xy 134.0024 -214.764878)
			(xy 134.058134 -214.762841) (xy 134.113571 -214.768941) (xy 134.167528 -214.783047) (xy 134.218857 -214.804859)
			(xy 134.266463 -214.833913) (xy 134.309331 -214.869588) (xy 134.346548 -214.911125) (xy 134.377321 -214.957638)
			(xy 134.400993 -215.008135) (xy 134.417061 -215.061542) (xy 134.425181 -215.116718) (xy 134.42569 -215.144604)
			(xy 134.425181 -215.17249) (xy 134.417061 -215.227666) (xy 134.400993 -215.281073) (xy 134.377321 -215.33157)
			(xy 134.346548 -215.378083) (xy 134.309331 -215.41962) (xy 134.266463 -215.455295) (xy 134.218857 -215.484349)
			(xy 134.167528 -215.506161) (xy 134.113571 -215.520267) (xy 134.058134 -215.526367) (xy 134.0024 -215.52433)
			(xy 133.947557 -215.5142) (xy 133.894773 -215.496193) (xy 133.845173 -215.470692) (xy 133.799815 -215.438241)
			(xy 133.759666 -215.399532) (xy 133.72558 -215.355389) (xy 133.698284 -215.306754) (xy 133.678361 -215.254663)
			(xy 133.666235 -215.200226) (xy 133.662164 -215.144604) (xy 132.56965 -215.144604) (xy 132.565246 -215.151261)
			(xy 132.528029 -215.192798) (xy 132.485161 -215.228473) (xy 132.437555 -215.257527) (xy 132.386226 -215.279339)
			(xy 132.332269 -215.293445) (xy 132.276832 -215.299545) (xy 132.221098 -215.297508) (xy 132.166255 -215.287378)
			(xy 132.113471 -215.269371) (xy 132.063871 -215.24387) (xy 132.018513 -215.211419) (xy 131.978364 -215.17271)
			(xy 131.944278 -215.128567) (xy 131.916982 -215.079932) (xy 131.897059 -215.027841) (xy 131.884933 -214.973404)
			(xy 131.880862 -214.917782) (xy 128.288007 -214.917782) (xy 128.307025 -214.958351) (xy 128.323093 -215.011758)
			(xy 128.331213 -215.066934) (xy 128.331722 -215.09482) (xy 128.331213 -215.122706) (xy 128.323093 -215.177882)
			(xy 128.307025 -215.231289) (xy 128.283353 -215.281786) (xy 128.25258 -215.328299) (xy 128.215363 -215.369836)
			(xy 128.172495 -215.405511) (xy 128.124889 -215.434565) (xy 128.07356 -215.456377) (xy 128.019603 -215.470483)
			(xy 127.964166 -215.476583) (xy 127.908432 -215.474546) (xy 127.853589 -215.464416) (xy 127.800805 -215.446409)
			(xy 127.751205 -215.420908) (xy 127.705847 -215.388457) (xy 127.665698 -215.349748) (xy 127.631612 -215.305605)
			(xy 127.604316 -215.25697) (xy 127.584393 -215.204879) (xy 127.572267 -215.150442) (xy 127.568196 -215.09482)
			(xy 127.45974 -215.09482) (xy 127.45974 -215.85682) (xy 135.41451 -215.85682) (xy 135.418581 -215.801198)
			(xy 135.430707 -215.746761) (xy 135.45063 -215.69467) (xy 135.477926 -215.646035) (xy 135.512012 -215.601892)
			(xy 135.552161 -215.563183) (xy 135.597519 -215.530732) (xy 135.647119 -215.505231) (xy 135.699903 -215.487224)
			(xy 135.754746 -215.477094) (xy 135.81048 -215.475057) (xy 135.865917 -215.481157) (xy 135.919874 -215.495263)
			(xy 135.971203 -215.517075) (xy 136.018809 -215.546129) (xy 136.061677 -215.581804) (xy 136.098894 -215.623341)
			(xy 136.129667 -215.669854) (xy 136.153339 -215.720351) (xy 136.169407 -215.773758) (xy 136.177527 -215.828934)
			(xy 136.178036 -215.85682) (xy 136.177527 -215.884706) (xy 136.169407 -215.939882) (xy 136.157028 -215.981026)
			(xy 138.10818 -215.981026) (xy 138.112251 -215.925404) (xy 138.124377 -215.870967) (xy 138.1443 -215.818876)
			(xy 138.171596 -215.770241) (xy 138.205682 -215.726098) (xy 138.245831 -215.687389) (xy 138.291189 -215.654938)
			(xy 138.340789 -215.629437) (xy 138.393573 -215.61143) (xy 138.448416 -215.6013) (xy 138.50415 -215.599263)
			(xy 138.559587 -215.605363) (xy 138.613544 -215.619469) (xy 138.664873 -215.641281) (xy 138.712479 -215.670335)
			(xy 138.755347 -215.70601) (xy 138.792564 -215.747547) (xy 138.823337 -215.79406) (xy 138.847009 -215.844557)
			(xy 138.863077 -215.897964) (xy 138.871197 -215.95314) (xy 138.871706 -215.981026) (xy 138.871335 -216.001346)
			(xy 138.978892 -216.001346) (xy 138.982963 -215.945724) (xy 138.995089 -215.891287) (xy 139.015012 -215.839196)
			(xy 139.042308 -215.790561) (xy 139.076394 -215.746418) (xy 139.116543 -215.707709) (xy 139.161901 -215.675258)
			(xy 139.211501 -215.649757) (xy 139.264285 -215.63175) (xy 139.319128 -215.62162) (xy 139.374862 -215.619583)
			(xy 139.430299 -215.625683) (xy 139.484256 -215.639789) (xy 139.535585 -215.661601) (xy 139.583191 -215.690655)
			(xy 139.626059 -215.72633) (xy 139.663276 -215.767867) (xy 139.694049 -215.81438) (xy 139.717721 -215.864877)
			(xy 139.733789 -215.918284) (xy 139.741909 -215.97346) (xy 139.742418 -216.001346) (xy 139.741909 -216.029232)
			(xy 139.733789 -216.084408) (xy 139.717721 -216.137815) (xy 139.694049 -216.188312) (xy 139.663276 -216.234825)
			(xy 139.626059 -216.276362) (xy 139.583191 -216.312037) (xy 139.56371 -216.323926) (xy 141.308326 -216.323926)
			(xy 141.312397 -216.268304) (xy 141.324523 -216.213867) (xy 141.344446 -216.161776) (xy 141.371742 -216.113141)
			(xy 141.405828 -216.068998) (xy 141.445977 -216.030289) (xy 141.491335 -215.997838) (xy 141.540935 -215.972337)
			(xy 141.593719 -215.95433) (xy 141.648562 -215.9442) (xy 141.704296 -215.942163) (xy 141.759733 -215.948263)
			(xy 141.81369 -215.962369) (xy 141.865019 -215.984181) (xy 141.912625 -216.013235) (xy 141.955493 -216.04891)
			(xy 141.99271 -216.090447) (xy 142.023483 -216.13696) (xy 142.047155 -216.187457) (xy 142.063223 -216.240864)
			(xy 142.071343 -216.29604) (xy 142.071852 -216.323926) (xy 142.071343 -216.351812) (xy 142.063223 -216.406988)
			(xy 142.047155 -216.460395) (xy 142.023483 -216.510892) (xy 141.99271 -216.557405) (xy 141.955493 -216.598942)
			(xy 141.912625 -216.634617) (xy 141.865019 -216.663671) (xy 141.81369 -216.685483) (xy 141.759733 -216.699589)
			(xy 141.704296 -216.705689) (xy 141.648562 -216.703652) (xy 141.593719 -216.693522) (xy 141.540935 -216.675515)
			(xy 141.491335 -216.650014) (xy 141.445977 -216.617563) (xy 141.405828 -216.578854) (xy 141.371742 -216.534711)
			(xy 141.344446 -216.486076) (xy 141.324523 -216.433985) (xy 141.312397 -216.379548) (xy 141.308326 -216.323926)
			(xy 139.56371 -216.323926) (xy 139.535585 -216.341091) (xy 139.484256 -216.362903) (xy 139.430299 -216.377009)
			(xy 139.374862 -216.383109) (xy 139.319128 -216.381072) (xy 139.264285 -216.370942) (xy 139.211501 -216.352935)
			(xy 139.161901 -216.327434) (xy 139.116543 -216.294983) (xy 139.076394 -216.256274) (xy 139.042308 -216.212131)
			(xy 139.015012 -216.163496) (xy 138.995089 -216.111405) (xy 138.982963 -216.056968) (xy 138.978892 -216.001346)
			(xy 138.871335 -216.001346) (xy 138.871197 -216.008912) (xy 138.863077 -216.064088) (xy 138.847009 -216.117495)
			(xy 138.823337 -216.167992) (xy 138.792564 -216.214505) (xy 138.755347 -216.256042) (xy 138.712479 -216.291717)
			(xy 138.664873 -216.320771) (xy 138.613544 -216.342583) (xy 138.559587 -216.356689) (xy 138.50415 -216.362789)
			(xy 138.448416 -216.360752) (xy 138.393573 -216.350622) (xy 138.340789 -216.332615) (xy 138.291189 -216.307114)
			(xy 138.245831 -216.274663) (xy 138.205682 -216.235954) (xy 138.171596 -216.191811) (xy 138.1443 -216.143176)
			(xy 138.124377 -216.091085) (xy 138.112251 -216.036648) (xy 138.10818 -215.981026) (xy 136.157028 -215.981026)
			(xy 136.153339 -215.993289) (xy 136.129667 -216.043786) (xy 136.098894 -216.090299) (xy 136.061677 -216.131836)
			(xy 136.018809 -216.167511) (xy 135.971203 -216.196565) (xy 135.919874 -216.218377) (xy 135.865917 -216.232483)
			(xy 135.81048 -216.238583) (xy 135.754746 -216.236546) (xy 135.699903 -216.226416) (xy 135.647119 -216.208409)
			(xy 135.597519 -216.182908) (xy 135.552161 -216.150457) (xy 135.512012 -216.111748) (xy 135.477926 -216.067605)
			(xy 135.45063 -216.01897) (xy 135.430707 -215.966879) (xy 135.418581 -215.912442) (xy 135.41451 -215.85682)
			(xy 127.45974 -215.85682) (xy 127.45974 -218.827858) (xy 127.460132 -218.837349) (xy 127.467022 -218.855038)
			(xy 127.479846 -218.869034) (xy 127.488188 -218.873578) (xy 127.56642 -218.911932) (xy 127.574194 -218.915373)
			(xy 127.591061 -218.917439) (xy 127.59944 -218.915996) (xy 127.603504 -218.915234) (xy 127.624078 -218.907868)
			(xy 127.630174 -218.903296) (xy 127.655122 -218.885333) (xy 127.709559 -218.856777) (xy 127.76787 -218.837318)
			(xy 127.828546 -218.82746) (xy 127.859282 -218.826842) (xy 127.884936 -218.827604) (xy 127.892048 -218.828366)
			(xy 127.892556 -218.828366) (xy 127.920709 -218.831353) (xy 127.975756 -218.84458) (xy 128.028244 -218.865794)
			(xy 128.077022 -218.894531) (xy 128.121019 -218.930159) (xy 128.159269 -218.971896) (xy 128.190933 -219.018826)
			(xy 128.215316 -219.06992) (xy 128.231882 -219.124055) (xy 128.240269 -219.180044) (xy 128.24079 -219.20835)
			(xy 128.24033 -219.235605) (xy 128.232579 -219.28956) (xy 128.217227 -219.341863) (xy 128.194587 -219.391448)
			(xy 128.16512 -219.437306) (xy 128.129426 -219.478503) (xy 128.088232 -219.514201) (xy 128.042376 -219.543672)
			(xy 127.992793 -219.566316) (xy 127.940491 -219.581672) (xy 127.886537 -219.589428) (xy 127.859282 -219.589858)
			(xy 127.858774 -219.589858) (xy 127.828082 -219.589243) (xy 127.767488 -219.579416) (xy 127.709248 -219.56002)
			(xy 127.654862 -219.531555) (xy 127.62992 -219.513658) (xy 127.62357 -219.508832) (xy 127.606806 -219.502736)
			(xy 127.59707 -219.49975) (xy 127.576756 -219.50092) (xy 127.567436 -219.505022) (xy 127.488442 -219.543122)
			(xy 127.480043 -219.547623) (xy 127.467103 -219.561595) (xy 127.460145 -219.579321) (xy 127.45974 -219.588842)
			(xy 127.45974 -220.799914) (xy 142.146018 -220.799914) (xy 142.150089 -220.744292) (xy 142.162215 -220.689855)
			(xy 142.182138 -220.637764) (xy 142.209434 -220.589129) (xy 142.24352 -220.544986) (xy 142.283669 -220.506277)
			(xy 142.329027 -220.473826) (xy 142.378627 -220.448325) (xy 142.431411 -220.430318) (xy 142.486254 -220.420188)
			(xy 142.541988 -220.418151) (xy 142.597425 -220.424251) (xy 142.651382 -220.438357) (xy 142.702711 -220.460169)
			(xy 142.750317 -220.489223) (xy 142.793185 -220.524898) (xy 142.830402 -220.566435) (xy 142.861175 -220.612948)
			(xy 142.884847 -220.663445) (xy 142.900915 -220.716852) (xy 142.909035 -220.772028) (xy 142.909544 -220.799914)
			(xy 142.909035 -220.8278) (xy 142.900915 -220.882976) (xy 142.884847 -220.936383) (xy 142.861175 -220.98688)
			(xy 142.830402 -221.033393) (xy 142.793185 -221.07493) (xy 142.750317 -221.110605) (xy 142.702711 -221.139659)
			(xy 142.651382 -221.161471) (xy 142.597425 -221.175577) (xy 142.541988 -221.181677) (xy 142.486254 -221.17964)
			(xy 142.431411 -221.16951) (xy 142.378627 -221.151503) (xy 142.329027 -221.126002) (xy 142.283669 -221.093551)
			(xy 142.24352 -221.054842) (xy 142.209434 -221.010699) (xy 142.182138 -220.962064) (xy 142.162215 -220.909973)
			(xy 142.150089 -220.855536) (xy 142.146018 -220.799914) (xy 127.45974 -220.799914) (xy 127.45974 -221.332806)
			(xy 138.540742 -221.332806) (xy 138.544813 -221.277184) (xy 138.556939 -221.222747) (xy 138.576862 -221.170656)
			(xy 138.604158 -221.122021) (xy 138.638244 -221.077878) (xy 138.678393 -221.039169) (xy 138.723751 -221.006718)
			(xy 138.773351 -220.981217) (xy 138.826135 -220.96321) (xy 138.880978 -220.95308) (xy 138.936712 -220.951043)
			(xy 138.992149 -220.957143) (xy 139.046106 -220.971249) (xy 139.097435 -220.993061) (xy 139.145041 -221.022115)
			(xy 139.187909 -221.05779) (xy 139.225126 -221.099327) (xy 139.255899 -221.14584) (xy 139.279571 -221.196337)
			(xy 139.295639 -221.249744) (xy 139.303759 -221.30492) (xy 139.304268 -221.332806) (xy 139.303759 -221.360692)
			(xy 139.295639 -221.415868) (xy 139.279571 -221.469275) (xy 139.255899 -221.519772) (xy 139.225126 -221.566285)
			(xy 139.187909 -221.607822) (xy 139.145041 -221.643497) (xy 139.097435 -221.672551) (xy 139.046106 -221.694363)
			(xy 138.992149 -221.708469) (xy 138.936712 -221.714569) (xy 138.880978 -221.712532) (xy 138.826135 -221.702402)
			(xy 138.773351 -221.684395) (xy 138.723751 -221.658894) (xy 138.678393 -221.626443) (xy 138.638244 -221.587734)
			(xy 138.604158 -221.543591) (xy 138.576862 -221.494956) (xy 138.556939 -221.442865) (xy 138.544813 -221.388428)
			(xy 138.540742 -221.332806) (xy 127.45974 -221.332806) (xy 127.45974 -221.823026) (xy 128.712974 -221.823026)
			(xy 128.717045 -221.767404) (xy 128.729171 -221.712967) (xy 128.749094 -221.660876) (xy 128.77639 -221.612241)
			(xy 128.810476 -221.568098) (xy 128.850625 -221.529389) (xy 128.895983 -221.496938) (xy 128.945583 -221.471437)
			(xy 128.998367 -221.45343) (xy 129.05321 -221.4433) (xy 129.108944 -221.441263) (xy 129.164381 -221.447363)
			(xy 129.218338 -221.461469) (xy 129.269667 -221.483281) (xy 129.317273 -221.512335) (xy 129.360141 -221.54801)
			(xy 129.397358 -221.589547) (xy 129.428131 -221.63606) (xy 129.451803 -221.686557) (xy 129.467871 -221.739964)
			(xy 129.475991 -221.79514) (xy 129.4765 -221.823026) (xy 129.475991 -221.850912) (xy 129.467871 -221.906088)
			(xy 129.451803 -221.959495) (xy 129.428131 -222.009992) (xy 129.397358 -222.056505) (xy 129.360141 -222.098042)
			(xy 129.317273 -222.133717) (xy 129.269667 -222.162771) (xy 129.247299 -222.172276) (xy 131.918962 -222.172276)
			(xy 131.923033 -222.116654) (xy 131.935159 -222.062217) (xy 131.955082 -222.010126) (xy 131.982378 -221.961491)
			(xy 132.016464 -221.917348) (xy 132.056613 -221.878639) (xy 132.101971 -221.846188) (xy 132.151571 -221.820687)
			(xy 132.204355 -221.80268) (xy 132.259198 -221.79255) (xy 132.314932 -221.790513) (xy 132.370369 -221.796613)
			(xy 132.424326 -221.810719) (xy 132.475655 -221.832531) (xy 132.523261 -221.861585) (xy 132.566129 -221.89726)
			(xy 132.603346 -221.938797) (xy 132.629116 -221.977748) (xy 133.151412 -221.977748) (xy 133.151412 -221.923252)
			(xy 133.159167 -221.869312) (xy 133.17452 -221.817024) (xy 133.197157 -221.767453) (xy 133.226618 -221.721608)
			(xy 133.262303 -221.680423) (xy 133.303486 -221.644734) (xy 133.349329 -221.61527) (xy 133.398898 -221.592629)
			(xy 133.451185 -221.577273) (xy 133.505125 -221.569514) (xy 133.532372 -221.569026) (xy 133.56206 -221.569591)
			(xy 133.620719 -221.578786) (xy 133.677245 -221.596959) (xy 133.730273 -221.62367) (xy 133.778522 -221.658275)
			(xy 133.820826 -221.699937) (xy 133.83895 -221.723458) (xy 133.847725 -221.734637) (xy 133.870269 -221.751929)
			(xy 133.896707 -221.762335) (xy 133.924989 -221.765048) (xy 133.952923 -221.759859) (xy 133.978344 -221.74717)
			(xy 133.999281 -221.727963) (xy 134.007098 -221.716092) (xy 134.022101 -221.692637) (xy 134.057797 -221.649912)
			(xy 134.099322 -221.612826) (xy 134.145794 -221.582165) (xy 134.196227 -221.55858) (xy 134.249551 -221.542572)
			(xy 134.304635 -221.534481) (xy 134.332472 -221.533974) (xy 134.359725 -221.534471) (xy 134.413676 -221.542225)
			(xy 134.465975 -221.557578) (xy 134.515556 -221.580217) (xy 134.561411 -221.609683) (xy 134.602605 -221.645375)
			(xy 134.6383 -221.686567) (xy 134.667769 -221.732419) (xy 134.690413 -221.781999) (xy 134.705769 -221.834296)
			(xy 134.713527 -221.888247) (xy 134.713527 -221.942753) (xy 134.705769 -221.996704) (xy 134.690413 -222.049001)
			(xy 134.667769 -222.098581) (xy 134.6383 -222.144433) (xy 134.602605 -222.185625) (xy 134.561411 -222.221317)
			(xy 134.515556 -222.250783) (xy 134.465975 -222.273422) (xy 134.413676 -222.288775) (xy 134.359725 -222.296529)
			(xy 134.332472 -222.29699) (xy 134.302786 -222.296387) (xy 134.244129 -222.287199) (xy 134.187604 -222.269033)
			(xy 134.134576 -222.242329) (xy 134.086326 -222.207731) (xy 134.044019 -222.166076) (xy 134.025894 -222.142558)
			(xy 134.017068 -222.131422) (xy 133.994537 -222.114128) (xy 133.96811 -222.103717) (xy 133.939837 -222.100996)
			(xy 133.91191 -222.106178) (xy 133.886495 -222.118859) (xy 133.865562 -222.138057) (xy 133.857746 -222.149924)
			(xy 133.842752 -222.173385) (xy 133.807057 -222.216114) (xy 133.765532 -222.253203) (xy 133.719059 -222.283865)
			(xy 133.668624 -222.307448) (xy 133.615297 -222.323453) (xy 133.56021 -222.331539) (xy 133.532372 -222.332042)
			(xy 133.505125 -222.331486) (xy 133.451185 -222.323727) (xy 133.398898 -222.308371) (xy 133.349329 -222.28573)
			(xy 133.303486 -222.256266) (xy 133.262303 -222.220577) (xy 133.226618 -222.179392) (xy 133.197157 -222.133547)
			(xy 133.17452 -222.083976) (xy 133.159167 -222.031688) (xy 133.151412 -221.977748) (xy 132.629116 -221.977748)
			(xy 132.634119 -221.98531) (xy 132.657791 -222.035807) (xy 132.673859 -222.089214) (xy 132.681979 -222.14439)
			(xy 132.682488 -222.172276) (xy 132.681979 -222.200162) (xy 132.673859 -222.255338) (xy 132.657791 -222.308745)
			(xy 132.634119 -222.359242) (xy 132.603346 -222.405755) (xy 132.566129 -222.447292) (xy 132.523261 -222.482967)
			(xy 132.475655 -222.512021) (xy 132.424326 -222.533833) (xy 132.370369 -222.547939) (xy 132.314932 -222.554039)
			(xy 132.259198 -222.552002) (xy 132.204355 -222.541872) (xy 132.151571 -222.523865) (xy 132.101971 -222.498364)
			(xy 132.056613 -222.465913) (xy 132.016464 -222.427204) (xy 131.982378 -222.383061) (xy 131.955082 -222.334426)
			(xy 131.935159 -222.282335) (xy 131.923033 -222.227898) (xy 131.918962 -222.172276) (xy 129.247299 -222.172276)
			(xy 129.218338 -222.184583) (xy 129.164381 -222.198689) (xy 129.108944 -222.204789) (xy 129.05321 -222.202752)
			(xy 128.998367 -222.192622) (xy 128.945583 -222.174615) (xy 128.895983 -222.149114) (xy 128.850625 -222.116663)
			(xy 128.810476 -222.077954) (xy 128.77639 -222.033811) (xy 128.749094 -221.985176) (xy 128.729171 -221.933085)
			(xy 128.717045 -221.878648) (xy 128.712974 -221.823026) (xy 127.45974 -221.823026) (xy 127.45974 -222.958406)
			(xy 128.662428 -222.958406) (xy 128.666499 -222.902784) (xy 128.678625 -222.848347) (xy 128.698548 -222.796256)
			(xy 128.725844 -222.747621) (xy 128.75993 -222.703478) (xy 128.800079 -222.664769) (xy 128.845437 -222.632318)
			(xy 128.895037 -222.606817) (xy 128.947821 -222.58881) (xy 129.002664 -222.57868) (xy 129.058398 -222.576643)
			(xy 129.113835 -222.582743) (xy 129.167792 -222.596849) (xy 129.219121 -222.618661) (xy 129.266727 -222.647715)
			(xy 129.309595 -222.68339) (xy 129.346812 -222.724927) (xy 129.377585 -222.77144) (xy 129.401257 -222.821937)
			(xy 129.417325 -222.875344) (xy 129.425445 -222.93052) (xy 129.425954 -222.958406) (xy 129.425445 -222.986292)
			(xy 129.417325 -223.041468) (xy 129.401257 -223.094875) (xy 129.377585 -223.145372) (xy 129.376255 -223.147382)
			(xy 135.118854 -223.147382) (xy 135.122925 -223.09176) (xy 135.135051 -223.037323) (xy 135.154974 -222.985232)
			(xy 135.18227 -222.936597) (xy 135.216356 -222.892454) (xy 135.256505 -222.853745) (xy 135.301863 -222.821294)
			(xy 135.351463 -222.795793) (xy 135.404247 -222.777786) (xy 135.45909 -222.767656) (xy 135.514824 -222.765619)
			(xy 135.570261 -222.771719) (xy 135.624218 -222.785825) (xy 135.675547 -222.807637) (xy 135.723153 -222.836691)
			(xy 135.766021 -222.872366) (xy 135.803238 -222.913903) (xy 135.834011 -222.960416) (xy 135.857683 -223.010913)
			(xy 135.873751 -223.06432) (xy 135.879508 -223.10344) (xy 137.023854 -223.10344) (xy 137.027925 -223.047818)
			(xy 137.040051 -222.993381) (xy 137.059974 -222.94129) (xy 137.08727 -222.892655) (xy 137.121356 -222.848512)
			(xy 137.161505 -222.809803) (xy 137.206863 -222.777352) (xy 137.256463 -222.751851) (xy 137.309247 -222.733844)
			(xy 137.36409 -222.723714) (xy 137.419824 -222.721677) (xy 137.475261 -222.727777) (xy 137.529218 -222.741883)
			(xy 137.580547 -222.763695) (xy 137.628153 -222.792749) (xy 137.671021 -222.828424) (xy 137.708238 -222.869961)
			(xy 137.739011 -222.916474) (xy 137.762683 -222.966971) (xy 137.765455 -222.976186) (xy 138.942826 -222.976186)
			(xy 138.943396 -222.947271) (xy 138.952113 -222.890102) (xy 138.96936 -222.834904) (xy 138.994742 -222.782941)
			(xy 139.027677 -222.735406) (xy 139.06741 -222.693388) (xy 139.089892 -222.675196) (xy 139.097284 -222.66892)
			(xy 139.107075 -222.6522) (xy 139.108942 -222.642684) (xy 139.10945 -222.635064) (xy 139.10945 -222.555308)
			(xy 139.108942 -222.547688) (xy 139.107046 -222.538181) (xy 139.097268 -222.521464) (xy 139.089892 -222.515176)
			(xy 139.067395 -222.497001) (xy 139.027661 -222.454977) (xy 138.994724 -222.407439) (xy 138.969338 -222.355475)
			(xy 138.952085 -222.300275) (xy 138.943359 -222.243103) (xy 138.942826 -222.214186) (xy 138.943312 -222.186935)
			(xy 138.951068 -222.132987) (xy 138.966423 -222.080692) (xy 138.989065 -222.031115) (xy 139.018531 -221.985265)
			(xy 139.054222 -221.944074) (xy 139.095413 -221.908383) (xy 139.141263 -221.878917) (xy 139.19084 -221.856275)
			(xy 139.243135 -221.84092) (xy 139.297083 -221.833164) (xy 139.351585 -221.833164) (xy 139.405533 -221.84092)
			(xy 139.457828 -221.856275) (xy 139.507405 -221.878917) (xy 139.553255 -221.908383) (xy 139.594446 -221.944074)
			(xy 139.630137 -221.985265) (xy 139.659603 -222.031115) (xy 139.682245 -222.080692) (xy 139.6976 -222.132987)
			(xy 139.705356 -222.186935) (xy 139.705842 -222.214186) (xy 139.705336 -222.243104) (xy 139.696607 -222.300276)
			(xy 139.679348 -222.355476) (xy 139.653955 -222.407439) (xy 139.621008 -222.454972) (xy 139.581263 -222.496987)
			(xy 139.558776 -222.515176) (xy 139.551388 -222.521456) (xy 139.541596 -222.538173) (xy 139.539726 -222.547688)
			(xy 139.539218 -222.555308) (xy 139.539218 -222.635064) (xy 139.539726 -222.642684) (xy 139.541599 -222.652196)
			(xy 139.551394 -222.66891) (xy 139.558776 -222.675196) (xy 139.581253 -222.693395) (xy 139.620989 -222.735413)
			(xy 139.65393 -222.782946) (xy 139.67932 -222.834905) (xy 139.696577 -222.890102) (xy 139.705307 -222.94727)
			(xy 139.705842 -222.976186) (xy 139.705356 -223.003437) (xy 139.6976 -223.057385) (xy 139.682245 -223.10968)
			(xy 139.659603 -223.159257) (xy 139.630137 -223.205107) (xy 139.594446 -223.246298) (xy 139.553255 -223.281989)
			(xy 139.507405 -223.311455) (xy 139.457828 -223.334097) (xy 139.405533 -223.349452) (xy 139.351585 -223.357208)
			(xy 139.297083 -223.357208) (xy 139.243135 -223.349452) (xy 139.19084 -223.334097) (xy 139.141263 -223.311455)
			(xy 139.095413 -223.281989) (xy 139.054222 -223.246298) (xy 139.018531 -223.205107) (xy 138.989065 -223.159257)
			(xy 138.966423 -223.10968) (xy 138.951068 -223.057385) (xy 138.943312 -223.003437) (xy 138.942826 -222.976186)
			(xy 137.765455 -222.976186) (xy 137.778751 -223.020378) (xy 137.786871 -223.075554) (xy 137.78738 -223.10344)
			(xy 137.786871 -223.131326) (xy 137.778751 -223.186502) (xy 137.762683 -223.239909) (xy 137.739011 -223.290406)
			(xy 137.708238 -223.336919) (xy 137.671021 -223.378456) (xy 137.628153 -223.414131) (xy 137.580547 -223.443185)
			(xy 137.529218 -223.464997) (xy 137.475261 -223.479103) (xy 137.419824 -223.485203) (xy 137.36409 -223.483166)
			(xy 137.309247 -223.473036) (xy 137.256463 -223.455029) (xy 137.206863 -223.429528) (xy 137.161505 -223.397077)
			(xy 137.121356 -223.358368) (xy 137.08727 -223.314225) (xy 137.059974 -223.26559) (xy 137.040051 -223.213499)
			(xy 137.027925 -223.159062) (xy 137.023854 -223.10344) (xy 135.879508 -223.10344) (xy 135.881871 -223.119496)
			(xy 135.88238 -223.147382) (xy 135.881871 -223.175268) (xy 135.873751 -223.230444) (xy 135.857683 -223.283851)
			(xy 135.834011 -223.334348) (xy 135.803238 -223.380861) (xy 135.766021 -223.422398) (xy 135.723153 -223.458073)
			(xy 135.675547 -223.487127) (xy 135.624218 -223.508939) (xy 135.570261 -223.523045) (xy 135.514824 -223.529145)
			(xy 135.45909 -223.527108) (xy 135.404247 -223.516978) (xy 135.351463 -223.498971) (xy 135.301863 -223.47347)
			(xy 135.256505 -223.441019) (xy 135.216356 -223.40231) (xy 135.18227 -223.358167) (xy 135.154974 -223.309532)
			(xy 135.135051 -223.257441) (xy 135.122925 -223.203004) (xy 135.118854 -223.147382) (xy 129.376255 -223.147382)
			(xy 129.346812 -223.191885) (xy 129.309595 -223.233422) (xy 129.266727 -223.269097) (xy 129.219121 -223.298151)
			(xy 129.167792 -223.319963) (xy 129.113835 -223.334069) (xy 129.058398 -223.340169) (xy 129.002664 -223.338132)
			(xy 128.947821 -223.328002) (xy 128.895037 -223.309995) (xy 128.845437 -223.284494) (xy 128.800079 -223.252043)
			(xy 128.75993 -223.213334) (xy 128.725844 -223.169191) (xy 128.698548 -223.120556) (xy 128.678625 -223.068465)
			(xy 128.666499 -223.014028) (xy 128.662428 -222.958406) (xy 127.45974 -222.958406) (xy 127.45974 -223.537018)
			(xy 132.52907 -223.537018) (xy 132.533141 -223.481396) (xy 132.545267 -223.426959) (xy 132.56519 -223.374868)
			(xy 132.592486 -223.326233) (xy 132.626572 -223.28209) (xy 132.666721 -223.243381) (xy 132.712079 -223.21093)
			(xy 132.761679 -223.185429) (xy 132.814463 -223.167422) (xy 132.869306 -223.157292) (xy 132.92504 -223.155255)
			(xy 132.980477 -223.161355) (xy 133.034434 -223.175461) (xy 133.085763 -223.197273) (xy 133.133369 -223.226327)
			(xy 133.176237 -223.262002) (xy 133.213454 -223.303539) (xy 133.244227 -223.350052) (xy 133.267899 -223.400549)
			(xy 133.283967 -223.453956) (xy 133.292087 -223.509132) (xy 133.292596 -223.537018) (xy 133.292087 -223.564904)
			(xy 133.283967 -223.62008) (xy 133.267899 -223.673487) (xy 133.244227 -223.723984) (xy 133.213454 -223.770497)
			(xy 133.176237 -223.812034) (xy 133.133369 -223.847709) (xy 133.085763 -223.876763) (xy 133.034434 -223.898575)
			(xy 132.980477 -223.912681) (xy 132.92504 -223.918781) (xy 132.869306 -223.916744) (xy 132.814463 -223.906614)
			(xy 132.761679 -223.888607) (xy 132.712079 -223.863106) (xy 132.666721 -223.830655) (xy 132.626572 -223.791946)
			(xy 132.592486 -223.747803) (xy 132.56519 -223.699168) (xy 132.545267 -223.647077) (xy 132.533141 -223.59264)
			(xy 132.52907 -223.537018) (xy 127.45974 -223.537018) (xy 127.45974 -224.010728) (xy 129.104896 -224.010728)
			(xy 129.108967 -223.955106) (xy 129.121093 -223.900669) (xy 129.141016 -223.848578) (xy 129.168312 -223.799943)
			(xy 129.202398 -223.7558) (xy 129.242547 -223.717091) (xy 129.287905 -223.68464) (xy 129.337505 -223.659139)
			(xy 129.390289 -223.641132) (xy 129.445132 -223.631002) (xy 129.500866 -223.628965) (xy 129.556303 -223.635065)
			(xy 129.61026 -223.649171) (xy 129.661589 -223.670983) (xy 129.709195 -223.700037) (xy 129.752063 -223.735712)
			(xy 129.78928 -223.777249) (xy 129.820053 -223.823762) (xy 129.843725 -223.874259) (xy 129.859793 -223.927666)
			(xy 129.867913 -223.982842) (xy 129.868422 -224.010728) (xy 129.867913 -224.038614) (xy 129.859793 -224.09379)
			(xy 129.843725 -224.147197) (xy 129.820053 -224.197694) (xy 129.78928 -224.244207) (xy 129.752063 -224.285744)
			(xy 129.709195 -224.321419) (xy 129.661589 -224.350473) (xy 129.61026 -224.372285) (xy 129.556303 -224.386391)
			(xy 129.500866 -224.392491) (xy 129.445132 -224.390454) (xy 129.390289 -224.380324) (xy 129.337505 -224.362317)
			(xy 129.287905 -224.336816) (xy 129.242547 -224.304365) (xy 129.202398 -224.265656) (xy 129.168312 -224.221513)
			(xy 129.141016 -224.172878) (xy 129.121093 -224.120787) (xy 129.108967 -224.06635) (xy 129.104896 -224.010728)
			(xy 127.45974 -224.010728) (xy 127.45974 -224.56322) (xy 143.847118 -224.56322) (xy 143.847122 -224.508724)
			(xy 143.854881 -224.454785) (xy 143.870238 -224.402498) (xy 143.892879 -224.352929) (xy 143.922344 -224.307086)
			(xy 143.958033 -224.265904) (xy 143.99922 -224.230219) (xy 144.045066 -224.200759) (xy 144.094637 -224.178123)
			(xy 144.146926 -224.162772) (xy 144.200866 -224.155019) (xy 144.255362 -224.155021) (xy 144.309302 -224.162778)
			(xy 144.361589 -224.178133) (xy 144.411159 -224.200772) (xy 144.457003 -224.230236) (xy 144.498187 -224.265923)
			(xy 144.533873 -224.307109) (xy 144.563334 -224.352953) (xy 144.585972 -224.402524) (xy 144.601325 -224.454812)
			(xy 144.60908 -224.508752) (xy 144.609566 -224.536) (xy 146.89404 -224.536) (xy 146.898111 -224.480378)
			(xy 146.910237 -224.425941) (xy 146.93016 -224.37385) (xy 146.957456 -224.325215) (xy 146.991542 -224.281072)
			(xy 147.031691 -224.242363) (xy 147.077049 -224.209912) (xy 147.126649 -224.184411) (xy 147.179433 -224.166404)
			(xy 147.234276 -224.156274) (xy 147.29001 -224.154237) (xy 147.345447 -224.160337) (xy 147.399404 -224.174443)
			(xy 147.450733 -224.196255) (xy 147.498339 -224.225309) (xy 147.541207 -224.260984) (xy 147.578424 -224.302521)
			(xy 147.609197 -224.349034) (xy 147.632869 -224.399531) (xy 147.648937 -224.452938) (xy 147.657057 -224.508114)
			(xy 147.657566 -224.536) (xy 147.657057 -224.563886) (xy 147.648937 -224.619062) (xy 147.632869 -224.672469)
			(xy 147.609197 -224.722966) (xy 147.578424 -224.769479) (xy 147.541207 -224.811016) (xy 147.498339 -224.846691)
			(xy 147.450733 -224.875745) (xy 147.399404 -224.897557) (xy 147.345447 -224.911663) (xy 147.29001 -224.917763)
			(xy 147.234276 -224.915726) (xy 147.179433 -224.905596) (xy 147.126649 -224.887589) (xy 147.077049 -224.862088)
			(xy 147.031691 -224.829637) (xy 146.991542 -224.790928) (xy 146.957456 -224.746785) (xy 146.93016 -224.69815)
			(xy 146.910237 -224.646059) (xy 146.898111 -224.591622) (xy 146.89404 -224.536) (xy 144.609566 -224.536)
			(xy 144.609566 -224.536508) (xy 144.6091 -224.56335) (xy 144.601542 -224.616499) (xy 144.586606 -224.668063)
			(xy 144.564585 -224.717024) (xy 144.550638 -224.739962) (xy 144.543483 -224.752063) (xy 144.535511 -224.779014)
			(xy 144.535196 -224.807116) (xy 144.542559 -224.834239) (xy 144.557044 -224.858323) (xy 144.57755 -224.877542)
			(xy 144.602522 -224.890436) (xy 144.630064 -224.896028) (xy 144.64411 -224.89541) (xy 144.672558 -224.894394)
			(xy 144.699815 -224.89481) (xy 144.753773 -224.902562) (xy 144.80608 -224.917915) (xy 144.855669 -224.940555)
			(xy 144.901531 -224.970023) (xy 144.942733 -225.005717) (xy 144.978435 -225.046912) (xy 145.007911 -225.092769)
			(xy 145.03056 -225.142354) (xy 145.045923 -225.194657) (xy 145.053685 -225.248615) (xy 145.053689 -225.303128)
			(xy 145.045935 -225.357087) (xy 145.03058 -225.409392) (xy 145.007938 -225.458981) (xy 144.978469 -225.504842)
			(xy 144.942773 -225.546042) (xy 144.901577 -225.581743) (xy 144.855719 -225.611217) (xy 144.806134 -225.633865)
			(xy 144.75383 -225.649226) (xy 144.699872 -225.656986) (xy 144.645359 -225.656988) (xy 144.5914 -225.649232)
			(xy 144.539095 -225.633876) (xy 144.489508 -225.611232) (xy 144.443648 -225.581761) (xy 144.402449 -225.546064)
			(xy 144.366749 -225.504866) (xy 144.337277 -225.459008) (xy 144.31463 -225.409421) (xy 144.299272 -225.357117)
			(xy 144.291513 -225.303158) (xy 144.29105 -225.275902) (xy 144.29105 -225.275394) (xy 144.29153 -225.248553)
			(xy 144.299086 -225.195404) (xy 144.314018 -225.14384) (xy 144.336034 -225.094879) (xy 144.349978 -225.07194)
			(xy 144.357117 -225.05983) (xy 144.365086 -225.032883) (xy 144.365401 -225.004784) (xy 144.358039 -224.977665)
			(xy 144.343557 -224.953584) (xy 144.323055 -224.934366) (xy 144.298088 -224.921471) (xy 144.27055 -224.915876)
			(xy 144.256506 -224.916492) (xy 144.228058 -224.917508) (xy 144.20081 -224.916977) (xy 144.146871 -224.909216)
			(xy 144.094585 -224.893857) (xy 144.045016 -224.871214) (xy 143.999175 -224.841747) (xy 143.957994 -224.806057)
			(xy 143.922311 -224.764869) (xy 143.892852 -224.719022) (xy 143.870218 -224.66945) (xy 143.854869 -224.617161)
			(xy 143.847118 -224.56322) (xy 127.45974 -224.56322) (xy 127.45974 -225.65106) (xy 129.012694 -225.65106)
			(xy 129.016765 -225.595438) (xy 129.028891 -225.541001) (xy 129.048814 -225.48891) (xy 129.07611 -225.440275)
			(xy 129.110196 -225.396132) (xy 129.150345 -225.357423) (xy 129.195703 -225.324972) (xy 129.245303 -225.299471)
			(xy 129.298087 -225.281464) (xy 129.35293 -225.271334) (xy 129.408664 -225.269297) (xy 129.464101 -225.275397)
			(xy 129.518058 -225.289503) (xy 129.569387 -225.311315) (xy 129.616993 -225.340369) (xy 129.659861 -225.376044)
			(xy 129.697078 -225.417581) (xy 129.727851 -225.464094) (xy 129.751523 -225.514591) (xy 129.767591 -225.567998)
			(xy 129.775711 -225.623174) (xy 129.775724 -225.623882) (xy 134.483854 -225.623882) (xy 134.487925 -225.56826)
			(xy 134.500051 -225.513823) (xy 134.519974 -225.461732) (xy 134.54727 -225.413097) (xy 134.581356 -225.368954)
			(xy 134.621505 -225.330245) (xy 134.666863 -225.297794) (xy 134.716463 -225.272293) (xy 134.769247 -225.254286)
			(xy 134.82409 -225.244156) (xy 134.879824 -225.242119) (xy 134.935261 -225.248219) (xy 134.989218 -225.262325)
			(xy 135.040547 -225.284137) (xy 135.088153 -225.313191) (xy 135.131021 -225.348866) (xy 135.168238 -225.390403)
			(xy 135.199011 -225.436916) (xy 135.222683 -225.487413) (xy 135.238751 -225.54082) (xy 135.24163 -225.560382)
			(xy 136.388854 -225.560382) (xy 136.392925 -225.50476) (xy 136.405051 -225.450323) (xy 136.424974 -225.398232)
			(xy 136.45227 -225.349597) (xy 136.486356 -225.305454) (xy 136.526505 -225.266745) (xy 136.571863 -225.234294)
			(xy 136.621463 -225.208793) (xy 136.674247 -225.190786) (xy 136.72909 -225.180656) (xy 136.784824 -225.178619)
			(xy 136.840261 -225.184719) (xy 136.894218 -225.198825) (xy 136.945547 -225.220637) (xy 136.993153 -225.249691)
			(xy 137.036021 -225.285366) (xy 137.073238 -225.326903) (xy 137.104011 -225.373416) (xy 137.127683 -225.423913)
			(xy 137.143751 -225.47732) (xy 137.151871 -225.532496) (xy 137.15238 -225.560382) (xy 137.151871 -225.588268)
			(xy 137.143751 -225.643444) (xy 137.127683 -225.696851) (xy 137.104011 -225.747348) (xy 137.073238 -225.793861)
			(xy 137.036021 -225.835398) (xy 136.993153 -225.871073) (xy 136.945547 -225.900127) (xy 136.894218 -225.921939)
			(xy 136.840261 -225.936045) (xy 136.784824 -225.942145) (xy 136.72909 -225.940108) (xy 136.674247 -225.929978)
			(xy 136.621463 -225.911971) (xy 136.571863 -225.88647) (xy 136.526505 -225.854019) (xy 136.486356 -225.81531)
			(xy 136.45227 -225.771167) (xy 136.424974 -225.722532) (xy 136.405051 -225.670441) (xy 136.392925 -225.616004)
			(xy 136.388854 -225.560382) (xy 135.24163 -225.560382) (xy 135.246871 -225.595996) (xy 135.24738 -225.623882)
			(xy 135.246871 -225.651768) (xy 135.238751 -225.706944) (xy 135.222683 -225.760351) (xy 135.199011 -225.810848)
			(xy 135.168238 -225.857361) (xy 135.131021 -225.898898) (xy 135.088153 -225.934573) (xy 135.040547 -225.963627)
			(xy 134.989218 -225.985439) (xy 134.935261 -225.999545) (xy 134.879824 -226.005645) (xy 134.82409 -226.003608)
			(xy 134.769247 -225.993478) (xy 134.716463 -225.975471) (xy 134.666863 -225.94997) (xy 134.621505 -225.917519)
			(xy 134.581356 -225.87881) (xy 134.54727 -225.834667) (xy 134.519974 -225.786032) (xy 134.500051 -225.733941)
			(xy 134.487925 -225.679504) (xy 134.483854 -225.623882) (xy 129.775724 -225.623882) (xy 129.77622 -225.65106)
			(xy 129.775711 -225.678946) (xy 129.767591 -225.734122) (xy 129.751523 -225.787529) (xy 129.727851 -225.838026)
			(xy 129.697078 -225.884539) (xy 129.659861 -225.926076) (xy 129.616993 -225.961751) (xy 129.569387 -225.990805)
			(xy 129.518058 -226.012617) (xy 129.464101 -226.026723) (xy 129.408664 -226.032823) (xy 129.35293 -226.030786)
			(xy 129.298087 -226.020656) (xy 129.245303 -226.002649) (xy 129.195703 -225.977148) (xy 129.150345 -225.944697)
			(xy 129.110196 -225.905988) (xy 129.07611 -225.861845) (xy 129.048814 -225.81321) (xy 129.028891 -225.761119)
			(xy 129.016765 -225.706682) (xy 129.012694 -225.65106) (xy 127.45974 -225.65106) (xy 127.45974 -226.568)
			(xy 147.02104 -226.568) (xy 147.025111 -226.512378) (xy 147.037237 -226.457941) (xy 147.05716 -226.40585)
			(xy 147.084456 -226.357215) (xy 147.118542 -226.313072) (xy 147.158691 -226.274363) (xy 147.204049 -226.241912)
			(xy 147.253649 -226.216411) (xy 147.306433 -226.198404) (xy 147.361276 -226.188274) (xy 147.41701 -226.186237)
			(xy 147.472447 -226.192337) (xy 147.526404 -226.206443) (xy 147.577733 -226.228255) (xy 147.625339 -226.257309)
			(xy 147.668207 -226.292984) (xy 147.705424 -226.334521) (xy 147.736197 -226.381034) (xy 147.759869 -226.431531)
			(xy 147.775937 -226.484938) (xy 147.784057 -226.540114) (xy 147.784566 -226.568) (xy 147.784057 -226.595886)
			(xy 147.775937 -226.651062) (xy 147.759869 -226.704469) (xy 147.736197 -226.754966) (xy 147.705424 -226.801479)
			(xy 147.668207 -226.843016) (xy 147.625339 -226.878691) (xy 147.577733 -226.907745) (xy 147.526404 -226.929557)
			(xy 147.472447 -226.943663) (xy 147.41701 -226.949763) (xy 147.361276 -226.947726) (xy 147.306433 -226.937596)
			(xy 147.253649 -226.919589) (xy 147.204049 -226.894088) (xy 147.158691 -226.861637) (xy 147.118542 -226.822928)
			(xy 147.084456 -226.778785) (xy 147.05716 -226.73015) (xy 147.037237 -226.678059) (xy 147.025111 -226.623622)
			(xy 147.02104 -226.568) (xy 127.45974 -226.568) (xy 127.45974 -227.180394) (xy 142.915892 -227.180394)
			(xy 142.919963 -227.124772) (xy 142.932089 -227.070335) (xy 142.952012 -227.018244) (xy 142.979308 -226.969609)
			(xy 143.013394 -226.925466) (xy 143.053543 -226.886757) (xy 143.098901 -226.854306) (xy 143.148501 -226.828805)
			(xy 143.201285 -226.810798) (xy 143.256128 -226.800668) (xy 143.311862 -226.798631) (xy 143.367299 -226.804731)
			(xy 143.421256 -226.818837) (xy 143.472585 -226.840649) (xy 143.520191 -226.869703) (xy 143.563059 -226.905378)
			(xy 143.600276 -226.946915) (xy 143.631049 -226.993428) (xy 143.654721 -227.043925) (xy 143.670789 -227.097332)
			(xy 143.678909 -227.152508) (xy 143.679418 -227.180394) (xy 143.678909 -227.20828) (xy 143.670789 -227.263456)
			(xy 143.654721 -227.316863) (xy 143.631049 -227.36736) (xy 143.600276 -227.413873) (xy 143.563059 -227.45541)
			(xy 143.520191 -227.491085) (xy 143.472585 -227.520139) (xy 143.421256 -227.541951) (xy 143.367299 -227.556057)
			(xy 143.311862 -227.562157) (xy 143.256128 -227.56012) (xy 143.201285 -227.54999) (xy 143.148501 -227.531983)
			(xy 143.098901 -227.506482) (xy 143.053543 -227.474031) (xy 143.013394 -227.435322) (xy 142.979308 -227.391179)
			(xy 142.952012 -227.342544) (xy 142.932089 -227.290453) (xy 142.919963 -227.236016) (xy 142.915892 -227.180394)
			(xy 127.45974 -227.180394) (xy 127.45974 -227.965) (xy 131.981192 -227.965) (xy 131.985263 -227.909378)
			(xy 131.997389 -227.854941) (xy 132.017312 -227.80285) (xy 132.044608 -227.754215) (xy 132.078694 -227.710072)
			(xy 132.118843 -227.671363) (xy 132.164201 -227.638912) (xy 132.213801 -227.613411) (xy 132.266585 -227.595404)
			(xy 132.321428 -227.585274) (xy 132.377162 -227.583237) (xy 132.432599 -227.589337) (xy 132.486556 -227.603443)
			(xy 132.537885 -227.625255) (xy 132.585491 -227.654309) (xy 132.628359 -227.689984) (xy 132.665576 -227.731521)
			(xy 132.696349 -227.778034) (xy 132.720021 -227.828531) (xy 132.736089 -227.881938) (xy 132.744209 -227.937114)
			(xy 132.744718 -227.965) (xy 132.744209 -227.992886) (xy 132.736089 -228.048062) (xy 132.720021 -228.101469)
			(xy 132.696349 -228.151966) (xy 132.677878 -228.179884) (xy 133.977632 -228.179884) (xy 133.981703 -228.124262)
			(xy 133.993829 -228.069825) (xy 134.013752 -228.017734) (xy 134.041048 -227.969099) (xy 134.075134 -227.924956)
			(xy 134.115283 -227.886247) (xy 134.160641 -227.853796) (xy 134.210241 -227.828295) (xy 134.263025 -227.810288)
			(xy 134.317868 -227.800158) (xy 134.373602 -227.798121) (xy 134.429039 -227.804221) (xy 134.482996 -227.818327)
			(xy 134.534325 -227.840139) (xy 134.581931 -227.869193) (xy 134.624799 -227.904868) (xy 134.662016 -227.946405)
			(xy 134.692789 -227.992918) (xy 134.716461 -228.043415) (xy 134.724201 -228.06914) (xy 135.036304 -228.06914)
			(xy 135.040375 -228.013518) (xy 135.052501 -227.959081) (xy 135.072424 -227.90699) (xy 135.09972 -227.858355)
			(xy 135.133806 -227.814212) (xy 135.173955 -227.775503) (xy 135.219313 -227.743052) (xy 135.268913 -227.717551)
			(xy 135.321697 -227.699544) (xy 135.37654 -227.689414) (xy 135.432274 -227.687377) (xy 135.487711 -227.693477)
			(xy 135.541668 -227.707583) (xy 135.592997 -227.729395) (xy 135.640603 -227.758449) (xy 135.683471 -227.794124)
			(xy 135.720688 -227.835661) (xy 135.751461 -227.882174) (xy 135.775133 -227.932671) (xy 135.791201 -227.986078)
			(xy 135.799321 -228.041254) (xy 135.79983 -228.06914) (xy 135.799677 -228.077522) (xy 136.086848 -228.077522)
			(xy 136.090919 -228.0219) (xy 136.103045 -227.967463) (xy 136.122968 -227.915372) (xy 136.150264 -227.866737)
			(xy 136.18435 -227.822594) (xy 136.224499 -227.783885) (xy 136.269857 -227.751434) (xy 136.319457 -227.725933)
			(xy 136.372241 -227.707926) (xy 136.427084 -227.697796) (xy 136.482818 -227.695759) (xy 136.538255 -227.701859)
			(xy 136.592212 -227.715965) (xy 136.643541 -227.737777) (xy 136.691147 -227.766831) (xy 136.734015 -227.802506)
			(xy 136.771232 -227.844043) (xy 136.802005 -227.890556) (xy 136.825677 -227.941053) (xy 136.82715 -227.94595)
			(xy 141.658338 -227.94595) (xy 141.662409 -227.890328) (xy 141.674535 -227.835891) (xy 141.694458 -227.7838)
			(xy 141.721754 -227.735165) (xy 141.75584 -227.691022) (xy 141.795989 -227.652313) (xy 141.841347 -227.619862)
			(xy 141.890947 -227.594361) (xy 141.943731 -227.576354) (xy 141.998574 -227.566224) (xy 142.054308 -227.564187)
			(xy 142.109745 -227.570287) (xy 142.163702 -227.584393) (xy 142.215031 -227.606205) (xy 142.262637 -227.635259)
			(xy 142.305505 -227.670934) (xy 142.342722 -227.712471) (xy 142.373495 -227.758984) (xy 142.397167 -227.809481)
			(xy 142.413235 -227.862888) (xy 142.421355 -227.918064) (xy 142.421864 -227.94595) (xy 142.421355 -227.973836)
			(xy 142.413235 -228.029012) (xy 142.397167 -228.082419) (xy 142.373495 -228.132916) (xy 142.342722 -228.179429)
			(xy 142.305505 -228.220966) (xy 142.262637 -228.256641) (xy 142.215031 -228.285695) (xy 142.163702 -228.307507)
			(xy 142.109745 -228.321613) (xy 142.054308 -228.327713) (xy 141.998574 -228.325676) (xy 141.943731 -228.315546)
			(xy 141.890947 -228.297539) (xy 141.841347 -228.272038) (xy 141.795989 -228.239587) (xy 141.75584 -228.200878)
			(xy 141.721754 -228.156735) (xy 141.694458 -228.1081) (xy 141.674535 -228.056009) (xy 141.662409 -228.001572)
			(xy 141.658338 -227.94595) (xy 136.82715 -227.94595) (xy 136.841745 -227.99446) (xy 136.849865 -228.049636)
			(xy 136.850374 -228.077522) (xy 136.849865 -228.105408) (xy 136.841745 -228.160584) (xy 136.825677 -228.213991)
			(xy 136.802005 -228.264488) (xy 136.771232 -228.311001) (xy 136.734015 -228.352538) (xy 136.691147 -228.388213)
			(xy 136.668753 -228.40188) (xy 137.995404 -228.40188) (xy 137.999475 -228.346258) (xy 138.011601 -228.291821)
			(xy 138.031524 -228.23973) (xy 138.05882 -228.191095) (xy 138.092906 -228.146952) (xy 138.133055 -228.108243)
			(xy 138.178413 -228.075792) (xy 138.228013 -228.050291) (xy 138.280797 -228.032284) (xy 138.33564 -228.022154)
			(xy 138.391374 -228.020117) (xy 138.446811 -228.026217) (xy 138.500768 -228.040323) (xy 138.552097 -228.062135)
			(xy 138.599703 -228.091189) (xy 138.642571 -228.126864) (xy 138.679788 -228.168401) (xy 138.710561 -228.214914)
			(xy 138.734233 -228.265411) (xy 138.750301 -228.318818) (xy 138.758421 -228.373994) (xy 138.75893 -228.40188)
			(xy 138.758421 -228.429766) (xy 138.750301 -228.484942) (xy 138.734233 -228.538349) (xy 138.710561 -228.588846)
			(xy 138.679788 -228.635359) (xy 138.642571 -228.676896) (xy 138.599703 -228.712571) (xy 138.552097 -228.741625)
			(xy 138.500768 -228.763437) (xy 138.446811 -228.777543) (xy 138.391374 -228.783643) (xy 138.33564 -228.781606)
			(xy 138.280797 -228.771476) (xy 138.228013 -228.753469) (xy 138.178413 -228.727968) (xy 138.133055 -228.695517)
			(xy 138.092906 -228.656808) (xy 138.05882 -228.612665) (xy 138.031524 -228.56403) (xy 138.011601 -228.511939)
			(xy 137.999475 -228.457502) (xy 137.995404 -228.40188) (xy 136.668753 -228.40188) (xy 136.643541 -228.417267)
			(xy 136.592212 -228.439079) (xy 136.538255 -228.453185) (xy 136.482818 -228.459285) (xy 136.427084 -228.457248)
			(xy 136.372241 -228.447118) (xy 136.319457 -228.429111) (xy 136.269857 -228.40361) (xy 136.224499 -228.371159)
			(xy 136.18435 -228.33245) (xy 136.150264 -228.288307) (xy 136.122968 -228.239672) (xy 136.103045 -228.187581)
			(xy 136.090919 -228.133144) (xy 136.086848 -228.077522) (xy 135.799677 -228.077522) (xy 135.799321 -228.097026)
			(xy 135.791201 -228.152202) (xy 135.775133 -228.205609) (xy 135.751461 -228.256106) (xy 135.720688 -228.302619)
			(xy 135.683471 -228.344156) (xy 135.640603 -228.379831) (xy 135.592997 -228.408885) (xy 135.541668 -228.430697)
			(xy 135.487711 -228.444803) (xy 135.432274 -228.450903) (xy 135.37654 -228.448866) (xy 135.321697 -228.438736)
			(xy 135.268913 -228.420729) (xy 135.219313 -228.395228) (xy 135.173955 -228.362777) (xy 135.133806 -228.324068)
			(xy 135.09972 -228.279925) (xy 135.072424 -228.23129) (xy 135.052501 -228.179199) (xy 135.040375 -228.124762)
			(xy 135.036304 -228.06914) (xy 134.724201 -228.06914) (xy 134.732529 -228.096822) (xy 134.740649 -228.151998)
			(xy 134.741158 -228.179884) (xy 134.740649 -228.20777) (xy 134.732529 -228.262946) (xy 134.716461 -228.316353)
			(xy 134.692789 -228.36685) (xy 134.662016 -228.413363) (xy 134.624799 -228.4549) (xy 134.581931 -228.490575)
			(xy 134.534325 -228.519629) (xy 134.482996 -228.541441) (xy 134.429039 -228.555547) (xy 134.373602 -228.561647)
			(xy 134.317868 -228.55961) (xy 134.263025 -228.54948) (xy 134.210241 -228.531473) (xy 134.160641 -228.505972)
			(xy 134.115283 -228.473521) (xy 134.075134 -228.434812) (xy 134.041048 -228.390669) (xy 134.013752 -228.342034)
			(xy 133.993829 -228.289943) (xy 133.981703 -228.235506) (xy 133.977632 -228.179884) (xy 132.677878 -228.179884)
			(xy 132.665576 -228.198479) (xy 132.628359 -228.240016) (xy 132.585491 -228.275691) (xy 132.537885 -228.304745)
			(xy 132.486556 -228.326557) (xy 132.432599 -228.340663) (xy 132.377162 -228.346763) (xy 132.321428 -228.344726)
			(xy 132.266585 -228.334596) (xy 132.213801 -228.316589) (xy 132.164201 -228.291088) (xy 132.118843 -228.258637)
			(xy 132.078694 -228.219928) (xy 132.044608 -228.175785) (xy 132.017312 -228.12715) (xy 131.997389 -228.075059)
			(xy 131.985263 -228.020622) (xy 131.981192 -227.965) (xy 127.45974 -227.965) (xy 127.45974 -228.67493)
			(xy 129.074924 -228.67493) (xy 129.078995 -228.619308) (xy 129.091121 -228.564871) (xy 129.111044 -228.51278)
			(xy 129.13834 -228.464145) (xy 129.172426 -228.420002) (xy 129.212575 -228.381293) (xy 129.257933 -228.348842)
			(xy 129.307533 -228.323341) (xy 129.360317 -228.305334) (xy 129.41516 -228.295204) (xy 129.470894 -228.293167)
			(xy 129.526331 -228.299267) (xy 129.580288 -228.313373) (xy 129.631617 -228.335185) (xy 129.679223 -228.364239)
			(xy 129.722091 -228.399914) (xy 129.759308 -228.441451) (xy 129.790081 -228.487964) (xy 129.813753 -228.538461)
			(xy 129.829821 -228.591868) (xy 129.837941 -228.647044) (xy 129.83845 -228.67493) (xy 129.837941 -228.702816)
			(xy 129.829821 -228.757992) (xy 129.813753 -228.811399) (xy 129.791163 -228.859588) (xy 142.064738 -228.859588)
			(xy 142.068809 -228.803966) (xy 142.080935 -228.749529) (xy 142.100858 -228.697438) (xy 142.128154 -228.648803)
			(xy 142.16224 -228.60466) (xy 142.202389 -228.565951) (xy 142.247747 -228.5335) (xy 142.297347 -228.507999)
			(xy 142.350131 -228.489992) (xy 142.404974 -228.479862) (xy 142.460708 -228.477825) (xy 142.516145 -228.483925)
			(xy 142.570102 -228.498031) (xy 142.621431 -228.519843) (xy 142.669037 -228.548897) (xy 142.711905 -228.584572)
			(xy 142.749122 -228.626109) (xy 142.779895 -228.672622) (xy 142.803567 -228.723119) (xy 142.819635 -228.776526)
			(xy 142.827755 -228.831702) (xy 142.828264 -228.859588) (xy 142.827755 -228.887474) (xy 142.819635 -228.94265)
			(xy 142.803567 -228.996057) (xy 142.779895 -229.046554) (xy 142.749122 -229.093067) (xy 142.711905 -229.134604)
			(xy 142.669037 -229.170279) (xy 142.621431 -229.199333) (xy 142.570102 -229.221145) (xy 142.516145 -229.235251)
			(xy 142.460708 -229.241351) (xy 142.404974 -229.239314) (xy 142.350131 -229.229184) (xy 142.297347 -229.211177)
			(xy 142.247747 -229.185676) (xy 142.202389 -229.153225) (xy 142.16224 -229.114516) (xy 142.128154 -229.070373)
			(xy 142.100858 -229.021738) (xy 142.080935 -228.969647) (xy 142.068809 -228.91521) (xy 142.064738 -228.859588)
			(xy 129.791163 -228.859588) (xy 129.790081 -228.861896) (xy 129.759308 -228.908409) (xy 129.722091 -228.949946)
			(xy 129.679223 -228.985621) (xy 129.631617 -229.014675) (xy 129.580288 -229.036487) (xy 129.526331 -229.050593)
			(xy 129.470894 -229.056693) (xy 129.41516 -229.054656) (xy 129.360317 -229.044526) (xy 129.307533 -229.026519)
			(xy 129.257933 -229.001018) (xy 129.212575 -228.968567) (xy 129.172426 -228.929858) (xy 129.13834 -228.885715)
			(xy 129.111044 -228.83708) (xy 129.091121 -228.784989) (xy 129.078995 -228.730552) (xy 129.074924 -228.67493)
			(xy 127.45974 -228.67493) (xy 127.45974 -229.454456) (xy 146.747736 -229.454456) (xy 146.751807 -229.398834)
			(xy 146.763933 -229.344397) (xy 146.783856 -229.292306) (xy 146.811152 -229.243671) (xy 146.845238 -229.199528)
			(xy 146.885387 -229.160819) (xy 146.930745 -229.128368) (xy 146.980345 -229.102867) (xy 147.033129 -229.08486)
			(xy 147.087972 -229.07473) (xy 147.143706 -229.072693) (xy 147.199143 -229.078793) (xy 147.2531 -229.092899)
			(xy 147.304429 -229.114711) (xy 147.352035 -229.143765) (xy 147.394903 -229.17944) (xy 147.43212 -229.220977)
			(xy 147.462893 -229.26749) (xy 147.486565 -229.317987) (xy 147.502633 -229.371394) (xy 147.510753 -229.42657)
			(xy 147.510937 -229.436676) (xy 147.716492 -229.436676) (xy 147.720563 -229.381054) (xy 147.732689 -229.326617)
			(xy 147.752612 -229.274526) (xy 147.779908 -229.225891) (xy 147.813994 -229.181748) (xy 147.854143 -229.143039)
			(xy 147.899501 -229.110588) (xy 147.949101 -229.085087) (xy 148.001885 -229.06708) (xy 148.056728 -229.05695)
			(xy 148.112462 -229.054913) (xy 148.167899 -229.061013) (xy 148.221856 -229.075119) (xy 148.273185 -229.096931)
			(xy 148.320791 -229.125985) (xy 148.363659 -229.16166) (xy 148.400876 -229.203197) (xy 148.431649 -229.24971)
			(xy 148.455321 -229.300207) (xy 148.471389 -229.353614) (xy 148.479509 -229.40879) (xy 148.480018 -229.436676)
			(xy 148.479509 -229.464562) (xy 148.471389 -229.519738) (xy 148.455321 -229.573145) (xy 148.431649 -229.623642)
			(xy 148.400876 -229.670155) (xy 148.363659 -229.711692) (xy 148.320791 -229.747367) (xy 148.273185 -229.776421)
			(xy 148.221856 -229.798233) (xy 148.167899 -229.812339) (xy 148.112462 -229.818439) (xy 148.056728 -229.816402)
			(xy 148.001885 -229.806272) (xy 147.949101 -229.788265) (xy 147.899501 -229.762764) (xy 147.854143 -229.730313)
			(xy 147.813994 -229.691604) (xy 147.779908 -229.647461) (xy 147.752612 -229.598826) (xy 147.732689 -229.546735)
			(xy 147.720563 -229.492298) (xy 147.716492 -229.436676) (xy 147.510937 -229.436676) (xy 147.511262 -229.454456)
			(xy 147.510753 -229.482342) (xy 147.502633 -229.537518) (xy 147.486565 -229.590925) (xy 147.462893 -229.641422)
			(xy 147.43212 -229.687935) (xy 147.394903 -229.729472) (xy 147.352035 -229.765147) (xy 147.304429 -229.794201)
			(xy 147.2531 -229.816013) (xy 147.199143 -229.830119) (xy 147.143706 -229.836219) (xy 147.087972 -229.834182)
			(xy 147.033129 -229.824052) (xy 146.980345 -229.806045) (xy 146.930745 -229.780544) (xy 146.885387 -229.748093)
			(xy 146.845238 -229.709384) (xy 146.811152 -229.665241) (xy 146.783856 -229.616606) (xy 146.763933 -229.564515)
			(xy 146.751807 -229.510078) (xy 146.747736 -229.454456) (xy 127.45974 -229.454456) (xy 127.45974 -229.94493)
			(xy 128.9083 -229.94493) (xy 128.912371 -229.889308) (xy 128.924497 -229.834871) (xy 128.94442 -229.78278)
			(xy 128.971716 -229.734145) (xy 129.005802 -229.690002) (xy 129.045951 -229.651293) (xy 129.091309 -229.618842)
			(xy 129.140909 -229.593341) (xy 129.193693 -229.575334) (xy 129.248536 -229.565204) (xy 129.30427 -229.563167)
			(xy 129.359707 -229.569267) (xy 129.413664 -229.583373) (xy 129.464993 -229.605185) (xy 129.512599 -229.634239)
			(xy 129.555467 -229.669914) (xy 129.592684 -229.711451) (xy 129.623457 -229.757964) (xy 129.647129 -229.808461)
			(xy 129.663197 -229.861868) (xy 129.671317 -229.917044) (xy 129.671826 -229.94493) (xy 138.89304 -229.94493)
			(xy 138.897111 -229.889308) (xy 138.909237 -229.834871) (xy 138.92916 -229.78278) (xy 138.956456 -229.734145)
			(xy 138.990542 -229.690002) (xy 139.030691 -229.651293) (xy 139.076049 -229.618842) (xy 139.125649 -229.593341)
			(xy 139.178433 -229.575334) (xy 139.233276 -229.565204) (xy 139.28901 -229.563167) (xy 139.344447 -229.569267)
			(xy 139.398404 -229.583373) (xy 139.449733 -229.605185) (xy 139.497339 -229.634239) (xy 139.540207 -229.669914)
			(xy 139.577424 -229.711451) (xy 139.608197 -229.757964) (xy 139.631869 -229.808461) (xy 139.647937 -229.861868)
			(xy 139.656057 -229.917044) (xy 139.656566 -229.94493) (xy 139.656057 -229.972816) (xy 139.647937 -230.027992)
			(xy 139.631869 -230.081399) (xy 139.608197 -230.131896) (xy 139.577424 -230.178409) (xy 139.540207 -230.219946)
			(xy 139.497339 -230.255621) (xy 139.449733 -230.284675) (xy 139.398404 -230.306487) (xy 139.344447 -230.320593)
			(xy 139.28901 -230.326693) (xy 139.233276 -230.324656) (xy 139.178433 -230.314526) (xy 139.125649 -230.296519)
			(xy 139.076049 -230.271018) (xy 139.030691 -230.238567) (xy 138.990542 -230.199858) (xy 138.956456 -230.155715)
			(xy 138.92916 -230.10708) (xy 138.909237 -230.054989) (xy 138.897111 -230.000552) (xy 138.89304 -229.94493)
			(xy 129.671826 -229.94493) (xy 129.671317 -229.972816) (xy 129.663197 -230.027992) (xy 129.647129 -230.081399)
			(xy 129.623457 -230.131896) (xy 129.592684 -230.178409) (xy 129.555467 -230.219946) (xy 129.512599 -230.255621)
			(xy 129.464993 -230.284675) (xy 129.413664 -230.306487) (xy 129.359707 -230.320593) (xy 129.30427 -230.326693)
			(xy 129.248536 -230.324656) (xy 129.193693 -230.314526) (xy 129.140909 -230.296519) (xy 129.091309 -230.271018)
			(xy 129.045951 -230.238567) (xy 129.005802 -230.199858) (xy 128.971716 -230.155715) (xy 128.94442 -230.10708)
			(xy 128.924497 -230.054989) (xy 128.912371 -230.000552) (xy 128.9083 -229.94493) (xy 127.45974 -229.94493)
			(xy 127.45974 -231.506522) (xy 129.418332 -231.506522) (xy 129.422403 -231.4509) (xy 129.434529 -231.396463)
			(xy 129.454452 -231.344372) (xy 129.481748 -231.295737) (xy 129.515834 -231.251594) (xy 129.555983 -231.212885)
			(xy 129.601341 -231.180434) (xy 129.650941 -231.154933) (xy 129.703725 -231.136926) (xy 129.758568 -231.126796)
			(xy 129.814302 -231.124759) (xy 129.869739 -231.130859) (xy 129.923696 -231.144965) (xy 129.975025 -231.166777)
			(xy 130.022631 -231.195831) (xy 130.032151 -231.203754) (xy 130.91109 -231.203754) (xy 130.915161 -231.148132)
			(xy 130.927287 -231.093695) (xy 130.94721 -231.041604) (xy 130.974506 -230.992969) (xy 131.008592 -230.948826)
			(xy 131.048741 -230.910117) (xy 131.094099 -230.877666) (xy 131.143699 -230.852165) (xy 131.196483 -230.834158)
			(xy 131.251326 -230.824028) (xy 131.30706 -230.821991) (xy 131.362497 -230.828091) (xy 131.416454 -230.842197)
			(xy 131.467783 -230.864009) (xy 131.514221 -230.89235) (xy 138.084558 -230.89235) (xy 138.088629 -230.836728)
			(xy 138.100755 -230.782291) (xy 138.120678 -230.7302) (xy 138.147974 -230.681565) (xy 138.18206 -230.637422)
			(xy 138.222209 -230.598713) (xy 138.267567 -230.566262) (xy 138.317167 -230.540761) (xy 138.369951 -230.522754)
			(xy 138.424794 -230.512624) (xy 138.480528 -230.510587) (xy 138.535965 -230.516687) (xy 138.589922 -230.530793)
			(xy 138.641251 -230.552605) (xy 138.688857 -230.581659) (xy 138.731725 -230.617334) (xy 138.768942 -230.658871)
			(xy 138.799715 -230.705384) (xy 138.823387 -230.755881) (xy 138.839455 -230.809288) (xy 138.847575 -230.864464)
			(xy 138.847778 -230.875586) (xy 147.625306 -230.875586) (xy 147.629377 -230.819964) (xy 147.641503 -230.765527)
			(xy 147.661426 -230.713436) (xy 147.688722 -230.664801) (xy 147.722808 -230.620658) (xy 147.762957 -230.581949)
			(xy 147.808315 -230.549498) (xy 147.857915 -230.523997) (xy 147.910699 -230.50599) (xy 147.965542 -230.49586)
			(xy 148.021276 -230.493823) (xy 148.076713 -230.499923) (xy 148.13067 -230.514029) (xy 148.181999 -230.535841)
			(xy 148.229605 -230.564895) (xy 148.272473 -230.60057) (xy 148.30969 -230.642107) (xy 148.340463 -230.68862)
			(xy 148.364135 -230.739117) (xy 148.380203 -230.792524) (xy 148.388323 -230.8477) (xy 148.388721 -230.86949)
			(xy 148.496526 -230.86949) (xy 148.500597 -230.813868) (xy 148.512723 -230.759431) (xy 148.532646 -230.70734)
			(xy 148.559942 -230.658705) (xy 148.594028 -230.614562) (xy 148.634177 -230.575853) (xy 148.679535 -230.543402)
			(xy 148.729135 -230.517901) (xy 148.781919 -230.499894) (xy 148.836762 -230.489764) (xy 148.892496 -230.487727)
			(xy 148.947933 -230.493827) (xy 149.00189 -230.507933) (xy 149.053219 -230.529745) (xy 149.100825 -230.558799)
			(xy 149.143693 -230.594474) (xy 149.18091 -230.636011) (xy 149.211683 -230.682524) (xy 149.235355 -230.733021)
			(xy 149.251423 -230.786428) (xy 149.259543 -230.841604) (xy 149.260052 -230.86949) (xy 149.259543 -230.897376)
			(xy 149.251423 -230.952552) (xy 149.235355 -231.005959) (xy 149.211683 -231.056456) (xy 149.18091 -231.102969)
			(xy 149.143693 -231.144506) (xy 149.100825 -231.180181) (xy 149.053219 -231.209235) (xy 149.00189 -231.231047)
			(xy 148.947933 -231.245153) (xy 148.892496 -231.251253) (xy 148.836762 -231.249216) (xy 148.781919 -231.239086)
			(xy 148.729135 -231.221079) (xy 148.679535 -231.195578) (xy 148.634177 -231.163127) (xy 148.594028 -231.124418)
			(xy 148.559942 -231.080275) (xy 148.532646 -231.03164) (xy 148.512723 -230.979549) (xy 148.500597 -230.925112)
			(xy 148.496526 -230.86949) (xy 148.388721 -230.86949) (xy 148.388832 -230.875586) (xy 148.388323 -230.903472)
			(xy 148.380203 -230.958648) (xy 148.364135 -231.012055) (xy 148.340463 -231.062552) (xy 148.30969 -231.109065)
			(xy 148.272473 -231.150602) (xy 148.229605 -231.186277) (xy 148.181999 -231.215331) (xy 148.13067 -231.237143)
			(xy 148.076713 -231.251249) (xy 148.021276 -231.257349) (xy 147.965542 -231.255312) (xy 147.910699 -231.245182)
			(xy 147.857915 -231.227175) (xy 147.808315 -231.201674) (xy 147.762957 -231.169223) (xy 147.722808 -231.130514)
			(xy 147.688722 -231.086371) (xy 147.661426 -231.037736) (xy 147.641503 -230.985645) (xy 147.629377 -230.931208)
			(xy 147.625306 -230.875586) (xy 138.847778 -230.875586) (xy 138.848084 -230.89235) (xy 138.847575 -230.920236)
			(xy 138.839455 -230.975412) (xy 138.823387 -231.028819) (xy 138.799715 -231.079316) (xy 138.768942 -231.125829)
			(xy 138.731725 -231.167366) (xy 138.688857 -231.203041) (xy 138.641251 -231.232095) (xy 138.589922 -231.253907)
			(xy 138.535965 -231.268013) (xy 138.480528 -231.274113) (xy 138.424794 -231.272076) (xy 138.369951 -231.261946)
			(xy 138.317167 -231.243939) (xy 138.267567 -231.218438) (xy 138.222209 -231.185987) (xy 138.18206 -231.147278)
			(xy 138.147974 -231.103135) (xy 138.120678 -231.0545) (xy 138.100755 -231.002409) (xy 138.088629 -230.947972)
			(xy 138.084558 -230.89235) (xy 131.514221 -230.89235) (xy 131.515389 -230.893063) (xy 131.558257 -230.928738)
			(xy 131.595474 -230.970275) (xy 131.626247 -231.016788) (xy 131.649919 -231.067285) (xy 131.665987 -231.120692)
			(xy 131.674107 -231.175868) (xy 131.674616 -231.203754) (xy 131.674107 -231.23164) (xy 131.665987 -231.286816)
			(xy 131.649919 -231.340223) (xy 131.626247 -231.39072) (xy 131.595474 -231.437233) (xy 131.558257 -231.47877)
			(xy 131.515389 -231.514445) (xy 131.467783 -231.543499) (xy 131.416454 -231.565311) (xy 131.362497 -231.579417)
			(xy 131.30706 -231.585517) (xy 131.251326 -231.58348) (xy 131.196483 -231.57335) (xy 131.143699 -231.555343)
			(xy 131.094099 -231.529842) (xy 131.048741 -231.497391) (xy 131.008592 -231.458682) (xy 130.974506 -231.414539)
			(xy 130.94721 -231.365904) (xy 130.927287 -231.313813) (xy 130.915161 -231.259376) (xy 130.91109 -231.203754)
			(xy 130.032151 -231.203754) (xy 130.065499 -231.231506) (xy 130.102716 -231.273043) (xy 130.133489 -231.319556)
			(xy 130.157161 -231.370053) (xy 130.173229 -231.42346) (xy 130.181349 -231.478636) (xy 130.181858 -231.506522)
			(xy 130.181349 -231.534408) (xy 130.173229 -231.589584) (xy 130.157161 -231.642991) (xy 130.133489 -231.693488)
			(xy 130.102716 -231.740001) (xy 130.065499 -231.781538) (xy 130.022631 -231.817213) (xy 129.975025 -231.846267)
			(xy 129.923696 -231.868079) (xy 129.869739 -231.882185) (xy 129.814302 -231.888285) (xy 129.758568 -231.886248)
			(xy 129.703725 -231.876118) (xy 129.650941 -231.858111) (xy 129.601341 -231.83261) (xy 129.555983 -231.800159)
			(xy 129.515834 -231.76145) (xy 129.481748 -231.717307) (xy 129.454452 -231.668672) (xy 129.434529 -231.616581)
			(xy 129.422403 -231.562144) (xy 129.418332 -231.506522) (xy 127.45974 -231.506522) (xy 127.45974 -232.082564)
			(xy 133.009326 -232.082564) (xy 133.017081 -232.028608) (xy 133.032435 -231.976305) (xy 133.055078 -231.92672)
			(xy 133.084546 -231.880861) (xy 133.120241 -231.839664) (xy 133.161435 -231.803966) (xy 133.207291 -231.774493)
			(xy 133.256874 -231.751847) (xy 133.309176 -231.736488) (xy 133.363131 -231.728728) (xy 133.390386 -231.728264)
			(xy 133.408017 -231.7285) (xy 133.443125 -231.731806) (xy 133.46049 -231.734868) (xy 133.475012 -231.737124)
			(xy 133.504236 -231.734123) (xy 133.531396 -231.722925) (xy 133.554245 -231.704459) (xy 133.57089 -231.680251)
			(xy 133.579954 -231.652307) (xy 133.580688 -231.622938) (xy 133.57733 -231.60863) (xy 133.57129 -231.584505)
			(xy 133.564793 -231.535198) (xy 133.564376 -231.510332) (xy 133.564821 -231.483076) (xy 133.572574 -231.429119)
			(xy 133.587928 -231.376814) (xy 133.610569 -231.327226) (xy 133.640038 -231.281366) (xy 133.675733 -231.240166)
			(xy 133.716928 -231.204466) (xy 133.762784 -231.174992) (xy 133.812369 -231.152345) (xy 133.864672 -231.136984)
			(xy 133.918628 -231.129224) (xy 133.97314 -231.129222) (xy 134.027097 -231.136978) (xy 134.079401 -231.152334)
			(xy 134.128988 -231.174977) (xy 134.174847 -231.204447) (xy 134.216045 -231.240144) (xy 134.251743 -231.28134)
			(xy 134.281215 -231.327198) (xy 134.303861 -231.376784) (xy 134.319219 -231.429087) (xy 134.326977 -231.483044)
			(xy 134.326977 -231.537556) (xy 134.319219 -231.591513) (xy 134.303861 -231.643816) (xy 134.281215 -231.693402)
			(xy 134.251743 -231.73926) (xy 134.216045 -231.780456) (xy 134.174847 -231.816153) (xy 134.128988 -231.845623)
			(xy 134.079401 -231.868266) (xy 134.027097 -231.883622) (xy 133.97314 -231.891378) (xy 133.945884 -231.89184)
			(xy 133.928253 -231.891608) (xy 133.893145 -231.8883) (xy 133.87578 -231.885236) (xy 133.861248 -231.883045)
			(xy 133.832029 -231.88603) (xy 133.80487 -231.897213) (xy 133.782021 -231.915669) (xy 133.765375 -231.939869)
			(xy 133.762004 -231.95026) (xy 134.511286 -231.95026) (xy 134.515357 -231.894638) (xy 134.527483 -231.840201)
			(xy 134.547406 -231.78811) (xy 134.574702 -231.739475) (xy 134.608788 -231.695332) (xy 134.648937 -231.656623)
			(xy 134.694295 -231.624172) (xy 134.743895 -231.598671) (xy 134.796679 -231.580664) (xy 134.851522 -231.570534)
			(xy 134.907256 -231.568497) (xy 134.962693 -231.574597) (xy 135.01665 -231.588703) (xy 135.067979 -231.610515)
			(xy 135.115585 -231.639569) (xy 135.158453 -231.675244) (xy 135.19567 -231.716781) (xy 135.226443 -231.763294)
			(xy 135.250115 -231.813791) (xy 135.266183 -231.867198) (xy 135.274303 -231.922374) (xy 135.274812 -231.95026)
			(xy 135.274303 -231.978146) (xy 135.266183 -232.033322) (xy 135.250115 -232.086729) (xy 135.226443 -232.137226)
			(xy 135.19567 -232.183739) (xy 135.158453 -232.225276) (xy 135.115585 -232.260951) (xy 135.067979 -232.290005)
			(xy 135.01665 -232.311817) (xy 134.962693 -232.325923) (xy 134.907256 -232.332023) (xy 134.851522 -232.329986)
			(xy 134.796679 -232.319856) (xy 134.743895 -232.301849) (xy 134.694295 -232.276348) (xy 134.648937 -232.243897)
			(xy 134.608788 -232.205188) (xy 134.574702 -232.161045) (xy 134.547406 -232.11241) (xy 134.527483 -232.060319)
			(xy 134.515357 -232.005882) (xy 134.511286 -231.95026) (xy 133.762004 -231.95026) (xy 133.756312 -231.967807)
			(xy 133.755581 -231.997169) (xy 133.75894 -232.011474) (xy 133.764982 -232.035599) (xy 133.771477 -232.084906)
			(xy 133.771894 -232.109772) (xy 133.771475 -232.137027) (xy 133.763721 -232.190983) (xy 133.748368 -232.243286)
			(xy 133.725727 -232.292872) (xy 133.69626 -232.338731) (xy 133.660566 -232.379929) (xy 133.619372 -232.415629)
			(xy 133.573517 -232.445102) (xy 133.523934 -232.46775) (xy 133.471633 -232.48311) (xy 133.417678 -232.490871)
			(xy 133.363168 -232.490875) (xy 133.309212 -232.48312) (xy 133.256909 -232.467766) (xy 133.207324 -232.445125)
			(xy 133.161465 -232.415657) (xy 133.120267 -232.379963) (xy 133.084568 -232.338768) (xy 133.055095 -232.292913)
			(xy 133.032449 -232.24333) (xy 133.017089 -232.191029) (xy 133.009328 -232.137074) (xy 133.009326 -232.082564)
			(xy 127.45974 -232.082564) (xy 127.45974 -237.517178) (xy 145.922744 -237.517178) (xy 145.926815 -237.461556)
			(xy 145.938941 -237.407119) (xy 145.958864 -237.355028) (xy 145.98616 -237.306393) (xy 146.020246 -237.26225)
			(xy 146.060395 -237.223541) (xy 146.105753 -237.19109) (xy 146.155353 -237.165589) (xy 146.208137 -237.147582)
			(xy 146.26298 -237.137452) (xy 146.318714 -237.135415) (xy 146.374151 -237.141515) (xy 146.428108 -237.155621)
			(xy 146.479437 -237.177433) (xy 146.527043 -237.206487) (xy 146.569911 -237.242162) (xy 146.607128 -237.283699)
			(xy 146.637901 -237.330212) (xy 146.661573 -237.380709) (xy 146.677641 -237.434116) (xy 146.685761 -237.489292)
			(xy 146.68627 -237.517178) (xy 146.685761 -237.545064) (xy 146.677641 -237.60024) (xy 146.661573 -237.653647)
			(xy 146.637901 -237.704144) (xy 146.607128 -237.750657) (xy 146.569911 -237.792194) (xy 146.527043 -237.827869)
			(xy 146.479437 -237.856923) (xy 146.428108 -237.878735) (xy 146.374151 -237.892841) (xy 146.318714 -237.898941)
			(xy 146.26298 -237.896904) (xy 146.208137 -237.886774) (xy 146.155353 -237.868767) (xy 146.105753 -237.843266)
			(xy 146.060395 -237.810815) (xy 146.020246 -237.772106) (xy 145.98616 -237.727963) (xy 145.958864 -237.679328)
			(xy 145.938941 -237.627237) (xy 145.926815 -237.5728) (xy 145.922744 -237.517178) (xy 127.45974 -237.517178)
			(xy 127.45974 -237.9218) (xy 127.459315 -237.931869) (xy 127.452213 -237.948978) (xy 143.128744 -237.948978)
			(xy 143.132815 -237.893356) (xy 143.144941 -237.838919) (xy 143.164864 -237.786828) (xy 143.19216 -237.738193)
			(xy 143.226246 -237.69405) (xy 143.266395 -237.655341) (xy 143.311753 -237.62289) (xy 143.361353 -237.597389)
			(xy 143.414137 -237.579382) (xy 143.46898 -237.569252) (xy 143.524714 -237.567215) (xy 143.580151 -237.573315)
			(xy 143.634108 -237.587421) (xy 143.685437 -237.609233) (xy 143.733043 -237.638287) (xy 143.775911 -237.673962)
			(xy 143.813128 -237.715499) (xy 143.843901 -237.762012) (xy 143.867573 -237.812509) (xy 143.883641 -237.865916)
			(xy 143.891761 -237.921092) (xy 143.89227 -237.948978) (xy 144.017744 -237.948978) (xy 144.021815 -237.893356)
			(xy 144.033941 -237.838919) (xy 144.053864 -237.786828) (xy 144.08116 -237.738193) (xy 144.115246 -237.69405)
			(xy 144.155395 -237.655341) (xy 144.200753 -237.62289) (xy 144.250353 -237.597389) (xy 144.303137 -237.579382)
			(xy 144.35798 -237.569252) (xy 144.413714 -237.567215) (xy 144.469151 -237.573315) (xy 144.523108 -237.587421)
			(xy 144.574437 -237.609233) (xy 144.622043 -237.638287) (xy 144.664911 -237.673962) (xy 144.702128 -237.715499)
			(xy 144.732901 -237.762012) (xy 144.756573 -237.812509) (xy 144.772641 -237.865916) (xy 144.780761 -237.921092)
			(xy 144.78127 -237.948978) (xy 144.780761 -237.976864) (xy 144.772641 -238.03204) (xy 144.756573 -238.085447)
			(xy 144.732901 -238.135944) (xy 144.702128 -238.182457) (xy 144.664911 -238.223994) (xy 144.622043 -238.259669)
			(xy 144.574437 -238.288723) (xy 144.523108 -238.310535) (xy 144.469151 -238.324641) (xy 144.413714 -238.330741)
			(xy 144.35798 -238.328704) (xy 144.303137 -238.318574) (xy 144.250353 -238.300567) (xy 144.200753 -238.275066)
			(xy 144.155395 -238.242615) (xy 144.115246 -238.203906) (xy 144.08116 -238.159763) (xy 144.053864 -238.111128)
			(xy 144.033941 -238.059037) (xy 144.021815 -238.0046) (xy 144.017744 -237.948978) (xy 143.89227 -237.948978)
			(xy 143.891761 -237.976864) (xy 143.883641 -238.03204) (xy 143.867573 -238.085447) (xy 143.843901 -238.135944)
			(xy 143.813128 -238.182457) (xy 143.775911 -238.223994) (xy 143.733043 -238.259669) (xy 143.685437 -238.288723)
			(xy 143.634108 -238.310535) (xy 143.580151 -238.324641) (xy 143.524714 -238.330741) (xy 143.46898 -238.328704)
			(xy 143.414137 -238.318574) (xy 143.361353 -238.300567) (xy 143.311753 -238.275066) (xy 143.266395 -238.242615)
			(xy 143.226246 -238.203906) (xy 143.19216 -238.159763) (xy 143.164864 -238.111128) (xy 143.144941 -238.059037)
			(xy 143.132815 -238.0046) (xy 143.128744 -237.948978) (xy 127.452213 -237.948978) (xy 127.451594 -237.950468)
			(xy 127.444754 -237.957868) (xy 126.856744 -238.545878) (xy 130.747006 -238.545878) (xy 130.751077 -238.490256)
			(xy 130.763203 -238.435819) (xy 130.783126 -238.383728) (xy 130.810422 -238.335093) (xy 130.844508 -238.29095)
			(xy 130.884657 -238.252241) (xy 130.930015 -238.21979) (xy 130.979615 -238.194289) (xy 131.032399 -238.176282)
			(xy 131.087242 -238.166152) (xy 131.142976 -238.164115) (xy 131.198413 -238.170215) (xy 131.25237 -238.184321)
			(xy 131.303699 -238.206133) (xy 131.351305 -238.235187) (xy 131.394173 -238.270862) (xy 131.43139 -238.312399)
			(xy 131.462163 -238.358912) (xy 131.485835 -238.409409) (xy 131.501903 -238.462816) (xy 131.510023 -238.517992)
			(xy 131.510532 -238.545878) (xy 131.510023 -238.573764) (xy 131.506979 -238.594449) (xy 131.736092 -238.594449)
			(xy 131.736092 -238.539951) (xy 131.743848 -238.486006) (xy 131.759202 -238.433715) (xy 131.781841 -238.38414)
			(xy 131.811305 -238.338293) (xy 131.846993 -238.297104) (xy 131.88818 -238.261414) (xy 131.934026 -238.231949)
			(xy 131.9836 -238.209307) (xy 132.035891 -238.193951) (xy 132.089835 -238.186193) (xy 132.117084 -238.185706)
			(xy 132.143203 -238.186155) (xy 132.194952 -238.193287) (xy 132.245247 -238.207406) (xy 132.293147 -238.228249)
			(xy 132.337759 -238.255426) (xy 132.37825 -238.288431) (xy 132.413865 -238.326647) (xy 132.42925 -238.347758)
			(xy 132.437721 -238.359102) (xy 132.459727 -238.376902) (xy 132.485776 -238.387974) (xy 132.513863 -238.391469)
			(xy 132.54183 -238.387116) (xy 132.567527 -238.375251) (xy 132.588978 -238.356786) (xy 132.597144 -238.345218)
			(xy 132.612371 -238.323033) (xy 132.648039 -238.282748) (xy 132.689016 -238.247876) (xy 132.734487 -238.21911)
			(xy 132.78355 -238.19702) (xy 132.83523 -238.182045) (xy 132.888503 -238.174483) (xy 132.915406 -238.174022)
			(xy 132.942659 -238.174448) (xy 132.99661 -238.182206) (xy 133.048909 -238.197563) (xy 133.098489 -238.220206)
			(xy 133.144342 -238.249675) (xy 133.185535 -238.285369) (xy 133.221229 -238.326563) (xy 133.250697 -238.372416)
			(xy 133.273339 -238.421997) (xy 133.288695 -238.474295) (xy 133.296452 -238.528247) (xy 133.296452 -238.582753)
			(xy 133.288695 -238.636705) (xy 133.273339 -238.689003) (xy 133.250697 -238.738584) (xy 133.221229 -238.784437)
			(xy 133.185535 -238.825631) (xy 133.144342 -238.861325) (xy 133.098489 -238.890794) (xy 133.048909 -238.913437)
			(xy 132.99661 -238.928794) (xy 132.942659 -238.936552) (xy 132.915406 -238.937038) (xy 132.889286 -238.93662)
			(xy 132.837534 -238.929485) (xy 132.787238 -238.915363) (xy 132.739337 -238.894515) (xy 132.694725 -238.867333)
			(xy 132.654235 -238.834322) (xy 132.618624 -238.7961) (xy 132.60324 -238.774986) (xy 132.594777 -238.763638)
			(xy 132.572766 -238.745848) (xy 132.546717 -238.734783) (xy 132.518631 -238.731292) (xy 132.490666 -238.735644)
			(xy 132.464969 -238.747504) (xy 132.443515 -238.765962) (xy 132.435346 -238.777526) (xy 132.420108 -238.799703)
			(xy 132.384443 -238.839991) (xy 132.34347 -238.874865) (xy 132.298001 -238.903634) (xy 132.248939 -238.925725)
			(xy 132.197259 -238.9407) (xy 132.143987 -238.948261) (xy 132.117084 -238.948722) (xy 132.089835 -238.948207)
			(xy 132.035891 -238.940449) (xy 131.9836 -238.925093) (xy 131.934026 -238.902451) (xy 131.88818 -238.872986)
			(xy 131.846993 -238.837296) (xy 131.811305 -238.796107) (xy 131.781841 -238.75026) (xy 131.759202 -238.700685)
			(xy 131.743848 -238.648394) (xy 131.736092 -238.594449) (xy 131.506979 -238.594449) (xy 131.501903 -238.62894)
			(xy 131.485835 -238.682347) (xy 131.462163 -238.732844) (xy 131.43139 -238.779357) (xy 131.394173 -238.820894)
			(xy 131.351305 -238.856569) (xy 131.303699 -238.885623) (xy 131.25237 -238.907435) (xy 131.198413 -238.921541)
			(xy 131.142976 -238.927641) (xy 131.087242 -238.925604) (xy 131.032399 -238.915474) (xy 130.979615 -238.897467)
			(xy 130.930015 -238.871966) (xy 130.884657 -238.839515) (xy 130.844508 -238.800806) (xy 130.810422 -238.756663)
			(xy 130.783126 -238.708028) (xy 130.763203 -238.655937) (xy 130.751077 -238.6015) (xy 130.747006 -238.545878)
			(xy 126.856744 -238.545878) (xy 126.310644 -239.091978) (xy 145.186144 -239.091978) (xy 145.190215 -239.036356)
			(xy 145.202341 -238.981919) (xy 145.222264 -238.929828) (xy 145.24956 -238.881193) (xy 145.283646 -238.83705)
			(xy 145.323795 -238.798341) (xy 145.369153 -238.76589) (xy 145.418753 -238.740389) (xy 145.471537 -238.722382)
			(xy 145.52638 -238.712252) (xy 145.582114 -238.710215) (xy 145.637551 -238.716315) (xy 145.691508 -238.730421)
			(xy 145.742837 -238.752233) (xy 145.790443 -238.781287) (xy 145.833311 -238.816962) (xy 145.870528 -238.858499)
			(xy 145.901301 -238.905012) (xy 145.924973 -238.955509) (xy 145.935464 -238.990378) (xy 146.405344 -238.990378)
			(xy 146.409415 -238.934756) (xy 146.421541 -238.880319) (xy 146.441464 -238.828228) (xy 146.46876 -238.779593)
			(xy 146.502846 -238.73545) (xy 146.542995 -238.696741) (xy 146.588353 -238.66429) (xy 146.637953 -238.638789)
			(xy 146.690737 -238.620782) (xy 146.74558 -238.610652) (xy 146.801314 -238.608615) (xy 146.856751 -238.614715)
			(xy 146.910708 -238.628821) (xy 146.962037 -238.650633) (xy 147.009643 -238.679687) (xy 147.052511 -238.715362)
			(xy 147.089728 -238.756899) (xy 147.120501 -238.803412) (xy 147.144173 -238.853909) (xy 147.160241 -238.907316)
			(xy 147.168361 -238.962492) (xy 147.16887 -238.990378) (xy 147.168361 -239.018264) (xy 147.160241 -239.07344)
			(xy 147.144173 -239.126847) (xy 147.120501 -239.177344) (xy 147.089728 -239.223857) (xy 147.052511 -239.265394)
			(xy 147.009643 -239.301069) (xy 146.962037 -239.330123) (xy 146.910708 -239.351935) (xy 146.856751 -239.366041)
			(xy 146.801314 -239.372141) (xy 146.74558 -239.370104) (xy 146.690737 -239.359974) (xy 146.637953 -239.341967)
			(xy 146.588353 -239.316466) (xy 146.542995 -239.284015) (xy 146.502846 -239.245306) (xy 146.46876 -239.201163)
			(xy 146.441464 -239.152528) (xy 146.421541 -239.100437) (xy 146.409415 -239.046) (xy 146.405344 -238.990378)
			(xy 145.935464 -238.990378) (xy 145.941041 -239.008916) (xy 145.949161 -239.064092) (xy 145.94967 -239.091978)
			(xy 145.949161 -239.119864) (xy 145.941041 -239.17504) (xy 145.924973 -239.228447) (xy 145.901301 -239.278944)
			(xy 145.870528 -239.325457) (xy 145.833311 -239.366994) (xy 145.790443 -239.402669) (xy 145.742837 -239.431723)
			(xy 145.691508 -239.453535) (xy 145.637551 -239.467641) (xy 145.582114 -239.473741) (xy 145.52638 -239.471704)
			(xy 145.471537 -239.461574) (xy 145.418753 -239.443567) (xy 145.369153 -239.418066) (xy 145.323795 -239.385615)
			(xy 145.283646 -239.346906) (xy 145.24956 -239.302763) (xy 145.222264 -239.254128) (xy 145.202341 -239.202037)
			(xy 145.190215 -239.1476) (xy 145.186144 -239.091978) (xy 126.310644 -239.091978) (xy 123.546616 -241.856006)
			(xy 130.399026 -241.856006) (xy 130.403097 -241.800384) (xy 130.415223 -241.745947) (xy 130.435146 -241.693856)
			(xy 130.462442 -241.645221) (xy 130.496528 -241.601078) (xy 130.536677 -241.562369) (xy 130.582035 -241.529918)
			(xy 130.631635 -241.504417) (xy 130.684419 -241.48641) (xy 130.739262 -241.47628) (xy 130.794996 -241.474243)
			(xy 130.850433 -241.480343) (xy 130.90439 -241.494449) (xy 130.955719 -241.516261) (xy 131.003325 -241.545315)
			(xy 131.046193 -241.58099) (xy 131.08341 -241.622527) (xy 131.114183 -241.66904) (xy 131.137855 -241.719537)
			(xy 131.153923 -241.772944) (xy 131.162043 -241.82812) (xy 131.162552 -241.856006) (xy 131.162043 -241.883892)
			(xy 131.159253 -241.902852) (xy 132.042642 -241.902852) (xy 132.042642 -241.848348) (xy 132.050398 -241.794398)
			(xy 132.065753 -241.742102) (xy 132.088393 -241.692522) (xy 132.117859 -241.64667) (xy 132.153549 -241.605476)
			(xy 132.194739 -241.569782) (xy 132.240589 -241.540311) (xy 132.290166 -241.517666) (xy 132.342461 -241.502306)
			(xy 132.39641 -241.494544) (xy 132.423662 -241.494056) (xy 132.450108 -241.494482) (xy 132.502492 -241.501796)
			(xy 132.553364 -241.516274) (xy 132.601748 -241.53764) (xy 132.646718 -241.565484) (xy 132.687411 -241.599272)
			(xy 132.723048 -241.638357) (xy 132.738368 -241.659918) (xy 132.746583 -241.671285) (xy 132.768106 -241.689257)
			(xy 132.793704 -241.7007) (xy 132.82145 -241.704752) (xy 132.849252 -241.701108) (xy 132.875016 -241.690042)
			(xy 132.896801 -241.672388) (xy 132.905246 -241.661188) (xy 132.92067 -241.640218) (xy 132.956252 -241.602225)
			(xy 132.996667 -241.56942) (xy 133.041167 -241.542412) (xy 133.088924 -241.521704) (xy 133.139053 -241.507679)
			(xy 133.190623 -241.500597) (xy 133.21665 -241.500152) (xy 133.243902 -241.500692) (xy 133.297853 -241.508442)
			(xy 133.350151 -241.523792) (xy 133.399733 -241.54643) (xy 133.445587 -241.575893) (xy 133.486782 -241.611583)
			(xy 133.522477 -241.652773) (xy 133.551946 -241.698623) (xy 133.57459 -241.748202) (xy 133.589947 -241.800498)
			(xy 133.597705 -241.854448) (xy 133.597705 -241.856006) (xy 133.699248 -241.856006) (xy 133.703319 -241.800384)
			(xy 133.715445 -241.745947) (xy 133.735368 -241.693856) (xy 133.762664 -241.645221) (xy 133.79675 -241.601078)
			(xy 133.836899 -241.562369) (xy 133.882257 -241.529918) (xy 133.931857 -241.504417) (xy 133.984641 -241.48641)
			(xy 134.039484 -241.47628) (xy 134.095218 -241.474243) (xy 134.150655 -241.480343) (xy 134.204612 -241.494449)
			(xy 134.255941 -241.516261) (xy 134.303547 -241.545315) (xy 134.346415 -241.58099) (xy 134.383632 -241.622527)
			(xy 134.414405 -241.66904) (xy 134.438077 -241.719537) (xy 134.454145 -241.772944) (xy 134.456103 -241.786251)
			(xy 142.647156 -241.786251) (xy 142.647156 -241.731749) (xy 142.654912 -241.677801) (xy 142.670266 -241.625507)
			(xy 142.692905 -241.575929) (xy 142.72237 -241.530078) (xy 142.758059 -241.488886) (xy 142.799247 -241.453193)
			(xy 142.845096 -241.423724) (xy 142.894671 -241.401079) (xy 142.946964 -241.38572) (xy 143.000911 -241.377958)
			(xy 143.028162 -241.37747) (xy 143.055419 -241.377968) (xy 143.109378 -241.38573) (xy 143.161684 -241.401088)
			(xy 143.211275 -241.42373) (xy 143.257141 -241.453194) (xy 143.298349 -241.488882) (xy 143.334063 -241.530069)
			(xy 143.349218 -241.55273) (xy 143.354044 -241.559718) (xy 143.367364 -241.570237) (xy 143.383403 -241.57579)
			(xy 143.39189 -241.576098) (xy 143.477234 -241.576098) (xy 143.485714 -241.575783) (xy 143.501729 -241.57019)
			(xy 143.515053 -241.559693) (xy 143.519906 -241.55273) (xy 143.535039 -241.530052) (xy 143.570749 -241.488855)
			(xy 143.611958 -241.45316) (xy 143.657827 -241.423693) (xy 143.707423 -241.401053) (xy 143.759737 -241.385702)
			(xy 143.813702 -241.377952) (xy 143.840962 -241.37747) (xy 143.866939 -241.377857) (xy 143.918413 -241.384909)
			(xy 143.968452 -241.398887) (xy 144.016129 -241.419531) (xy 144.06056 -241.44646) (xy 144.100921 -241.479174)
			(xy 144.136465 -241.517068) (xy 144.151858 -241.537998) (xy 144.153382 -241.54003) (xy 144.160999 -241.548596)
			(xy 144.181567 -241.558634) (xy 144.193006 -241.559334) (xy 144.19326 -241.559334) (xy 144.276318 -241.559334)
			(xy 144.287789 -241.558762) (xy 144.308416 -241.548707) (xy 144.315942 -241.54003) (xy 144.317466 -241.537998)
			(xy 144.332855 -241.517069) (xy 144.368412 -241.479195) (xy 144.40878 -241.446497) (xy 144.453212 -241.41958)
			(xy 144.500886 -241.398943) (xy 144.55092 -241.384967) (xy 144.602387 -241.377911) (xy 144.628362 -241.37747)
			(xy 144.655615 -241.377975) (xy 144.709567 -241.385727) (xy 144.761866 -241.401079) (xy 144.811448 -241.423718)
			(xy 144.857304 -241.453183) (xy 144.898499 -241.488875) (xy 144.934194 -241.530066) (xy 144.963664 -241.575918)
			(xy 144.986308 -241.625498) (xy 145.001665 -241.677796) (xy 145.009423 -241.731747) (xy 145.009423 -241.786253)
			(xy 145.001665 -241.840204) (xy 144.986308 -241.892502) (xy 144.963664 -241.942082) (xy 144.934194 -241.987934)
			(xy 144.898499 -242.029125) (xy 144.857304 -242.064817) (xy 144.811448 -242.094282) (xy 144.761866 -242.116921)
			(xy 144.709567 -242.132273) (xy 144.655615 -242.140025) (xy 144.628362 -242.140486) (xy 144.602386 -242.140057)
			(xy 144.550915 -242.13301) (xy 144.500878 -242.119038) (xy 144.453202 -242.098399) (xy 144.408771 -242.071477)
			(xy 144.368408 -242.03877) (xy 144.332861 -242.000885) (xy 144.317466 -241.979958) (xy 144.315942 -241.977926)
			(xy 144.308322 -241.969364) (xy 144.287756 -241.959326) (xy 144.276318 -241.958622) (xy 144.276064 -241.958622)
			(xy 144.193006 -241.958622) (xy 144.181539 -241.959223) (xy 144.160913 -241.969259) (xy 144.153382 -241.977926)
			(xy 144.151858 -241.979958) (xy 144.136441 -242.000866) (xy 144.100891 -242.038743) (xy 144.060528 -242.071444)
			(xy 144.016101 -242.098364) (xy 143.968431 -242.119004) (xy 143.9184 -242.132984) (xy 143.866935 -242.140043)
			(xy 143.840962 -242.140486) (xy 143.813707 -242.139944) (xy 143.759751 -242.132186) (xy 143.707447 -242.116834)
			(xy 143.657857 -242.094199) (xy 143.611991 -242.064742) (xy 143.570781 -242.029062) (xy 143.535063 -241.987883)
			(xy 143.519906 -241.965226) (xy 143.515078 -241.95824) (xy 143.501757 -241.947724) (xy 143.48572 -241.942169)
			(xy 143.477234 -241.941858) (xy 143.39189 -241.941858) (xy 143.383414 -241.942209) (xy 143.367402 -241.947788)
			(xy 143.354075 -241.958271) (xy 143.349218 -241.965226) (xy 143.334088 -241.987906) (xy 143.298375 -242.0291)
			(xy 143.257165 -242.064793) (xy 143.211295 -242.094259) (xy 143.161699 -242.116899) (xy 143.109386 -242.132251)
			(xy 143.055421 -242.140003) (xy 143.028162 -242.140486) (xy 143.000911 -242.140042) (xy 142.946964 -242.13228)
			(xy 142.894671 -242.116921) (xy 142.845096 -242.094276) (xy 142.799247 -242.064807) (xy 142.758059 -242.029114)
			(xy 142.72237 -241.987922) (xy 142.692905 -241.942071) (xy 142.670266 -241.892493) (xy 142.654912 -241.840199)
			(xy 142.647156 -241.786251) (xy 134.456103 -241.786251) (xy 134.462265 -241.82812) (xy 134.462774 -241.856006)
			(xy 134.462265 -241.883892) (xy 134.454145 -241.939068) (xy 134.438077 -241.992475) (xy 134.414405 -242.042972)
			(xy 134.383632 -242.089485) (xy 134.346415 -242.131022) (xy 134.303547 -242.166697) (xy 134.255941 -242.195751)
			(xy 134.204612 -242.217563) (xy 134.150655 -242.231669) (xy 134.095218 -242.237769) (xy 134.039484 -242.235732)
			(xy 133.984641 -242.225602) (xy 133.931857 -242.207595) (xy 133.882257 -242.182094) (xy 133.836899 -242.149643)
			(xy 133.79675 -242.110934) (xy 133.762664 -242.066791) (xy 133.735368 -242.018156) (xy 133.715445 -241.966065)
			(xy 133.703319 -241.911628) (xy 133.699248 -241.856006) (xy 133.597705 -241.856006) (xy 133.597705 -241.908952)
			(xy 133.589947 -241.962902) (xy 133.57459 -242.015198) (xy 133.551946 -242.064777) (xy 133.522477 -242.110627)
			(xy 133.486782 -242.151817) (xy 133.445587 -242.187507) (xy 133.399733 -242.21697) (xy 133.350151 -242.239608)
			(xy 133.297853 -242.254958) (xy 133.243902 -242.262708) (xy 133.21665 -242.263168) (xy 133.190205 -242.262722)
			(xy 133.137822 -242.255411) (xy 133.086951 -242.240935) (xy 133.038567 -242.219572) (xy 132.993597 -242.191731)
			(xy 132.952903 -242.157947) (xy 132.917265 -242.118866) (xy 132.901944 -242.097306) (xy 132.893716 -242.085948)
			(xy 132.872197 -242.067972) (xy 132.846601 -242.056526) (xy 132.818857 -242.052471) (xy 132.791055 -242.056114)
			(xy 132.765292 -242.06718) (xy 132.743509 -242.084835) (xy 132.735066 -242.096036) (xy 132.719642 -242.117005)
			(xy 132.684059 -242.154998) (xy 132.643643 -242.187802) (xy 132.599144 -242.214809) (xy 132.551387 -242.235518)
			(xy 132.501258 -242.249544) (xy 132.449689 -242.256626) (xy 132.423662 -242.257072) (xy 132.39641 -242.256656)
			(xy 132.342461 -242.248894) (xy 132.290166 -242.233534) (xy 132.240589 -242.210889) (xy 132.194739 -242.181418)
			(xy 132.153549 -242.145724) (xy 132.117859 -242.10453) (xy 132.088393 -242.058678) (xy 132.065753 -242.009098)
			(xy 132.050398 -241.956802) (xy 132.042642 -241.902852) (xy 131.159253 -241.902852) (xy 131.153923 -241.939068)
			(xy 131.137855 -241.992475) (xy 131.114183 -242.042972) (xy 131.08341 -242.089485) (xy 131.046193 -242.131022)
			(xy 131.003325 -242.166697) (xy 130.955719 -242.195751) (xy 130.90439 -242.217563) (xy 130.850433 -242.231669)
			(xy 130.794996 -242.237769) (xy 130.739262 -242.235732) (xy 130.684419 -242.225602) (xy 130.631635 -242.207595)
			(xy 130.582035 -242.182094) (xy 130.536677 -242.149643) (xy 130.496528 -242.110934) (xy 130.462442 -242.066791)
			(xy 130.435146 -242.018156) (xy 130.415223 -241.966065) (xy 130.403097 -241.911628) (xy 130.399026 -241.856006)
			(xy 123.546616 -241.856006) (xy 123.01093 -242.391692) (xy 123.003528 -242.398528) (xy 122.98493 -242.406238)
			(xy 122.974862 -242.406678) (xy 104.121458 -242.406678) (xy 104.111391 -242.407108) (xy 104.092795 -242.414831)
			(xy 104.08539 -242.421664) (xy 104.062276 -242.444778) (xy 146.252944 -242.444778) (xy 146.257015 -242.389156)
			(xy 146.269141 -242.334719) (xy 146.289064 -242.282628) (xy 146.31636 -242.233993) (xy 146.350446 -242.18985)
			(xy 146.390595 -242.151141) (xy 146.435953 -242.11869) (xy 146.485553 -242.093189) (xy 146.538337 -242.075182)
			(xy 146.59318 -242.065052) (xy 146.648914 -242.063015) (xy 146.704351 -242.069115) (xy 146.758308 -242.083221)
			(xy 146.809637 -242.105033) (xy 146.857243 -242.134087) (xy 146.900111 -242.169762) (xy 146.937328 -242.211299)
			(xy 146.968101 -242.257812) (xy 146.991773 -242.308309) (xy 147.007841 -242.361716) (xy 147.015961 -242.416892)
			(xy 147.01647 -242.444778) (xy 147.421344 -242.444778) (xy 147.425415 -242.389156) (xy 147.437541 -242.334719)
			(xy 147.457464 -242.282628) (xy 147.48476 -242.233993) (xy 147.518846 -242.18985) (xy 147.558995 -242.151141)
			(xy 147.604353 -242.11869) (xy 147.653953 -242.093189) (xy 147.706737 -242.075182) (xy 147.76158 -242.065052)
			(xy 147.817314 -242.063015) (xy 147.872751 -242.069115) (xy 147.926708 -242.083221) (xy 147.978037 -242.105033)
			(xy 148.025643 -242.134087) (xy 148.068511 -242.169762) (xy 148.105728 -242.211299) (xy 148.136501 -242.257812)
			(xy 148.160173 -242.308309) (xy 148.176241 -242.361716) (xy 148.184361 -242.416892) (xy 148.18487 -242.444778)
			(xy 148.184361 -242.472664) (xy 148.176241 -242.52784) (xy 148.160173 -242.581247) (xy 148.136501 -242.631744)
			(xy 148.105728 -242.678257) (xy 148.068511 -242.719794) (xy 148.025643 -242.755469) (xy 147.978037 -242.784523)
			(xy 147.926708 -242.806335) (xy 147.872751 -242.820441) (xy 147.817314 -242.826541) (xy 147.76158 -242.824504)
			(xy 147.706737 -242.814374) (xy 147.653953 -242.796367) (xy 147.604353 -242.770866) (xy 147.558995 -242.738415)
			(xy 147.518846 -242.699706) (xy 147.48476 -242.655563) (xy 147.457464 -242.606928) (xy 147.437541 -242.554837)
			(xy 147.425415 -242.5004) (xy 147.421344 -242.444778) (xy 147.01647 -242.444778) (xy 147.015961 -242.472664)
			(xy 147.007841 -242.52784) (xy 146.991773 -242.581247) (xy 146.968101 -242.631744) (xy 146.937328 -242.678257)
			(xy 146.900111 -242.719794) (xy 146.857243 -242.755469) (xy 146.809637 -242.784523) (xy 146.758308 -242.806335)
			(xy 146.704351 -242.820441) (xy 146.648914 -242.826541) (xy 146.59318 -242.824504) (xy 146.538337 -242.814374)
			(xy 146.485553 -242.796367) (xy 146.435953 -242.770866) (xy 146.390595 -242.738415) (xy 146.350446 -242.699706)
			(xy 146.31636 -242.655563) (xy 146.289064 -242.606928) (xy 146.269141 -242.554837) (xy 146.257015 -242.5004)
			(xy 146.252944 -242.444778) (xy 104.062276 -242.444778) (xy 103.215694 -243.29136) (xy 103.209422 -243.298277)
			(xy 103.201924 -243.315236) (xy 127.416558 -243.315236) (xy 127.420629 -243.259614) (xy 127.432755 -243.205177)
			(xy 127.452678 -243.153086) (xy 127.479974 -243.104451) (xy 127.51406 -243.060308) (xy 127.554209 -243.021599)
			(xy 127.599567 -242.989148) (xy 127.649167 -242.963647) (xy 127.701951 -242.94564) (xy 127.756794 -242.93551)
			(xy 127.812528 -242.933473) (xy 127.867965 -242.939573) (xy 127.921922 -242.953679) (xy 127.973251 -242.975491)
			(xy 128.020857 -243.004545) (xy 128.063725 -243.04022) (xy 128.100942 -243.081757) (xy 128.131715 -243.12827)
			(xy 128.144704 -243.155978) (xy 142.449294 -243.155978) (xy 142.453365 -243.100356) (xy 142.465491 -243.045919)
			(xy 142.485414 -242.993828) (xy 142.51271 -242.945193) (xy 142.546796 -242.90105) (xy 142.586945 -242.862341)
			(xy 142.632303 -242.82989) (xy 142.681903 -242.804389) (xy 142.734687 -242.786382) (xy 142.78953 -242.776252)
			(xy 142.845264 -242.774215) (xy 142.900701 -242.780315) (xy 142.954658 -242.794421) (xy 143.005987 -242.816233)
			(xy 143.053593 -242.845287) (xy 143.096461 -242.880962) (xy 143.133678 -242.922499) (xy 143.164451 -242.969012)
			(xy 143.188123 -243.019509) (xy 143.204191 -243.072916) (xy 143.212311 -243.128092) (xy 143.212356 -243.130578)
			(xy 144.551144 -243.130578) (xy 144.555215 -243.074956) (xy 144.567341 -243.020519) (xy 144.587264 -242.968428)
			(xy 144.61456 -242.919793) (xy 144.648646 -242.87565) (xy 144.688795 -242.836941) (xy 144.734153 -242.80449)
			(xy 144.783753 -242.778989) (xy 144.836537 -242.760982) (xy 144.89138 -242.750852) (xy 144.947114 -242.748815)
			(xy 145.002551 -242.754915) (xy 145.056508 -242.769021) (xy 145.107837 -242.790833) (xy 145.155443 -242.819887)
			(xy 145.198311 -242.855562) (xy 145.235528 -242.897099) (xy 145.266301 -242.943612) (xy 145.289973 -242.994109)
			(xy 145.306041 -243.047516) (xy 145.309742 -243.072666) (xy 149.923498 -243.072666) (xy 149.927569 -243.017044)
			(xy 149.939695 -242.962607) (xy 149.959618 -242.910516) (xy 149.986914 -242.861881) (xy 150.021 -242.817738)
			(xy 150.061149 -242.779029) (xy 150.106507 -242.746578) (xy 150.156107 -242.721077) (xy 150.208891 -242.70307)
			(xy 150.263734 -242.69294) (xy 150.319468 -242.690903) (xy 150.374905 -242.697003) (xy 150.428862 -242.711109)
			(xy 150.480191 -242.732921) (xy 150.527797 -242.761975) (xy 150.570665 -242.79765) (xy 150.607882 -242.839187)
			(xy 150.638655 -242.8857) (xy 150.662327 -242.936197) (xy 150.678395 -242.989604) (xy 150.686515 -243.04478)
			(xy 150.687024 -243.072666) (xy 150.686515 -243.100552) (xy 150.678395 -243.155728) (xy 150.662327 -243.209135)
			(xy 150.638655 -243.259632) (xy 150.607882 -243.306145) (xy 150.570665 -243.347682) (xy 150.527797 -243.383357)
			(xy 150.480191 -243.412411) (xy 150.428862 -243.434223) (xy 150.374905 -243.448329) (xy 150.319468 -243.454429)
			(xy 150.263734 -243.452392) (xy 150.208891 -243.442262) (xy 150.156107 -243.424255) (xy 150.106507 -243.398754)
			(xy 150.061149 -243.366303) (xy 150.021 -243.327594) (xy 149.986914 -243.283451) (xy 149.959618 -243.234816)
			(xy 149.939695 -243.182725) (xy 149.927569 -243.128288) (xy 149.923498 -243.072666) (xy 145.309742 -243.072666)
			(xy 145.314161 -243.102692) (xy 145.31467 -243.130578) (xy 145.314161 -243.158464) (xy 145.306041 -243.21364)
			(xy 145.289973 -243.267047) (xy 145.266301 -243.317544) (xy 145.235528 -243.364057) (xy 145.198311 -243.405594)
			(xy 145.155443 -243.441269) (xy 145.107837 -243.470323) (xy 145.056508 -243.492135) (xy 145.002551 -243.506241)
			(xy 144.947114 -243.512341) (xy 144.89138 -243.510304) (xy 144.836537 -243.500174) (xy 144.783753 -243.482167)
			(xy 144.734153 -243.456666) (xy 144.688795 -243.424215) (xy 144.648646 -243.385506) (xy 144.61456 -243.341363)
			(xy 144.587264 -243.292728) (xy 144.567341 -243.240637) (xy 144.555215 -243.1862) (xy 144.551144 -243.130578)
			(xy 143.212356 -243.130578) (xy 143.21282 -243.155978) (xy 143.212311 -243.183864) (xy 143.204191 -243.23904)
			(xy 143.188123 -243.292447) (xy 143.164451 -243.342944) (xy 143.133678 -243.389457) (xy 143.096461 -243.430994)
			(xy 143.053593 -243.466669) (xy 143.005987 -243.495723) (xy 142.954658 -243.517535) (xy 142.900701 -243.531641)
			(xy 142.845264 -243.537741) (xy 142.78953 -243.535704) (xy 142.734687 -243.525574) (xy 142.681903 -243.507567)
			(xy 142.632303 -243.482066) (xy 142.586945 -243.449615) (xy 142.546796 -243.410906) (xy 142.51271 -243.366763)
			(xy 142.485414 -243.318128) (xy 142.465491 -243.266037) (xy 142.453365 -243.2116) (xy 142.449294 -243.155978)
			(xy 128.144704 -243.155978) (xy 128.155387 -243.178767) (xy 128.171455 -243.232174) (xy 128.179575 -243.28735)
			(xy 128.180084 -243.315236) (xy 128.179575 -243.343122) (xy 128.171455 -243.398298) (xy 128.155387 -243.451705)
			(xy 128.131715 -243.502202) (xy 128.100942 -243.548715) (xy 128.063725 -243.590252) (xy 128.037703 -243.611908)
			(xy 139.886434 -243.611908) (xy 139.890505 -243.556286) (xy 139.902631 -243.501849) (xy 139.922554 -243.449758)
			(xy 139.94985 -243.401123) (xy 139.983936 -243.35698) (xy 140.024085 -243.318271) (xy 140.069443 -243.28582)
			(xy 140.119043 -243.260319) (xy 140.171827 -243.242312) (xy 140.22667 -243.232182) (xy 140.282404 -243.230145)
			(xy 140.337841 -243.236245) (xy 140.391798 -243.250351) (xy 140.443127 -243.272163) (xy 140.490733 -243.301217)
			(xy 140.533601 -243.336892) (xy 140.570818 -243.378429) (xy 140.601591 -243.424942) (xy 140.625263 -243.475439)
			(xy 140.641331 -243.528846) (xy 140.649451 -243.584022) (xy 140.64996 -243.611908) (xy 140.649451 -243.639794)
			(xy 140.641331 -243.69497) (xy 140.625263 -243.748377) (xy 140.601591 -243.798874) (xy 140.570818 -243.845387)
			(xy 140.533601 -243.886924) (xy 140.490733 -243.922599) (xy 140.443127 -243.951653) (xy 140.391798 -243.973465)
			(xy 140.337841 -243.987571) (xy 140.282404 -243.993671) (xy 140.22667 -243.991634) (xy 140.171827 -243.981504)
			(xy 140.119043 -243.963497) (xy 140.069443 -243.937996) (xy 140.024085 -243.905545) (xy 139.983936 -243.866836)
			(xy 139.94985 -243.822693) (xy 139.922554 -243.774058) (xy 139.902631 -243.721967) (xy 139.890505 -243.66753)
			(xy 139.886434 -243.611908) (xy 128.037703 -243.611908) (xy 128.020857 -243.625927) (xy 127.973251 -243.654981)
			(xy 127.921922 -243.676793) (xy 127.867965 -243.690899) (xy 127.812528 -243.696999) (xy 127.756794 -243.694962)
			(xy 127.701951 -243.684832) (xy 127.649167 -243.666825) (xy 127.599567 -243.641324) (xy 127.554209 -243.608873)
			(xy 127.51406 -243.570164) (xy 127.479974 -243.526021) (xy 127.452678 -243.477386) (xy 127.432755 -243.425295)
			(xy 127.420629 -243.370858) (xy 127.416558 -243.315236) (xy 103.201924 -243.315236) (xy 103.201878 -243.315341)
			(xy 103.200962 -243.324634) (xy 103.200888 -243.333896) (xy 103.206609 -243.351494) (xy 103.212138 -243.358924)
			(xy 103.212138 -243.359178) (xy 103.228109 -243.379623) (xy 103.25496 -243.424015) (xy 103.275542 -243.471638)
			(xy 103.289476 -243.521612) (xy 103.296504 -243.573014) (xy 103.296974 -243.598954) (xy 103.296514 -243.626208)
			(xy 103.288762 -243.680162) (xy 103.27341 -243.732464) (xy 103.250769 -243.782047) (xy 103.221302 -243.827904)
			(xy 103.185608 -243.869099) (xy 103.144413 -243.904795) (xy 103.098558 -243.934263) (xy 103.048975 -243.956905)
			(xy 102.996674 -243.972259) (xy 102.94272 -243.980013) (xy 102.915466 -243.980462) (xy 102.889525 -243.980023)
			(xy 102.838124 -243.972983) (xy 102.788152 -243.959038) (xy 102.740533 -243.938445) (xy 102.696146 -243.911585)
			(xy 102.67569 -243.895626) (xy 102.66045 -243.883434) (xy 102.621588 -243.885466) (xy 102.22865 -244.278404)
			(xy 102.228179 -244.278912) (xy 134.358124 -244.278912) (xy 134.362195 -244.22329) (xy 134.374321 -244.168853)
			(xy 134.394244 -244.116762) (xy 134.42154 -244.068127) (xy 134.455626 -244.023984) (xy 134.495775 -243.985275)
			(xy 134.541133 -243.952824) (xy 134.590733 -243.927323) (xy 134.643517 -243.909316) (xy 134.69836 -243.899186)
			(xy 134.754094 -243.897149) (xy 134.809531 -243.903249) (xy 134.863488 -243.917355) (xy 134.914817 -243.939167)
			(xy 134.962423 -243.968221) (xy 135.005291 -244.003896) (xy 135.042508 -244.045433) (xy 135.073281 -244.091946)
			(xy 135.096953 -244.142443) (xy 135.113021 -244.19585) (xy 135.121141 -244.251026) (xy 135.12165 -244.278912)
			(xy 135.121284 -244.298978) (xy 148.488144 -244.298978) (xy 148.492215 -244.243356) (xy 148.504341 -244.188919)
			(xy 148.524264 -244.136828) (xy 148.55156 -244.088193) (xy 148.585646 -244.04405) (xy 148.625795 -244.005341)
			(xy 148.671153 -243.97289) (xy 148.720753 -243.947389) (xy 148.773537 -243.929382) (xy 148.82838 -243.919252)
			(xy 148.884114 -243.917215) (xy 148.939551 -243.923315) (xy 148.993508 -243.937421) (xy 149.044837 -243.959233)
			(xy 149.092443 -243.988287) (xy 149.135311 -244.023962) (xy 149.172528 -244.065499) (xy 149.203301 -244.112012)
			(xy 149.226973 -244.162509) (xy 149.243041 -244.215916) (xy 149.251161 -244.271092) (xy 149.25167 -244.298978)
			(xy 149.251161 -244.326864) (xy 149.243041 -244.38204) (xy 149.226973 -244.435447) (xy 149.203301 -244.485944)
			(xy 149.172528 -244.532457) (xy 149.135311 -244.573994) (xy 149.092443 -244.609669) (xy 149.044837 -244.638723)
			(xy 148.993508 -244.660535) (xy 148.939551 -244.674641) (xy 148.884114 -244.680741) (xy 148.82838 -244.678704)
			(xy 148.773537 -244.668574) (xy 148.720753 -244.650567) (xy 148.671153 -244.625066) (xy 148.625795 -244.592615)
			(xy 148.585646 -244.553906) (xy 148.55156 -244.509763) (xy 148.524264 -244.461128) (xy 148.504341 -244.409037)
			(xy 148.492215 -244.3546) (xy 148.488144 -244.298978) (xy 135.121284 -244.298978) (xy 135.121141 -244.306798)
			(xy 135.113021 -244.361974) (xy 135.096953 -244.415381) (xy 135.073281 -244.465878) (xy 135.042508 -244.512391)
			(xy 135.005291 -244.553928) (xy 134.962423 -244.589603) (xy 134.914817 -244.618657) (xy 134.863488 -244.640469)
			(xy 134.809531 -244.654575) (xy 134.754094 -244.660675) (xy 134.69836 -244.658638) (xy 134.643517 -244.648508)
			(xy 134.590733 -244.630501) (xy 134.541133 -244.605) (xy 134.495775 -244.572549) (xy 134.455626 -244.53384)
			(xy 134.42154 -244.489697) (xy 134.394244 -244.441062) (xy 134.374321 -244.388971) (xy 134.362195 -244.334534)
			(xy 134.358124 -244.278912) (xy 102.228179 -244.278912) (xy 102.221799 -244.2858) (xy 102.214058 -244.304399)
			(xy 102.213664 -244.314472) (xy 102.213664 -244.846602) (xy 126.515112 -244.846602) (xy 126.519183 -244.79098)
			(xy 126.531309 -244.736543) (xy 126.551232 -244.684452) (xy 126.578528 -244.635817) (xy 126.612614 -244.591674)
			(xy 126.652763 -244.552965) (xy 126.698121 -244.520514) (xy 126.747721 -244.495013) (xy 126.800505 -244.477006)
			(xy 126.855348 -244.466876) (xy 126.911082 -244.464839) (xy 126.966519 -244.470939) (xy 127.020476 -244.485045)
			(xy 127.071805 -244.506857) (xy 127.119411 -244.535911) (xy 127.162279 -244.571586) (xy 127.199496 -244.613123)
			(xy 127.230269 -244.659636) (xy 127.253941 -244.710133) (xy 127.270009 -244.76354) (xy 127.278129 -244.818716)
			(xy 127.278638 -244.846602) (xy 127.278129 -244.874488) (xy 127.270009 -244.929664) (xy 127.253941 -244.983071)
			(xy 127.230269 -245.033568) (xy 127.204741 -245.072154) (xy 133.901178 -245.072154) (xy 133.905249 -245.016532)
			(xy 133.917375 -244.962095) (xy 133.937298 -244.910004) (xy 133.964594 -244.861369) (xy 133.99868 -244.817226)
			(xy 134.038829 -244.778517) (xy 134.084187 -244.746066) (xy 134.133787 -244.720565) (xy 134.186571 -244.702558)
			(xy 134.241414 -244.692428) (xy 134.297148 -244.690391) (xy 134.352585 -244.696491) (xy 134.406542 -244.710597)
			(xy 134.457871 -244.732409) (xy 134.505477 -244.761463) (xy 134.548345 -244.797138) (xy 134.585562 -244.838675)
			(xy 134.616335 -244.885188) (xy 134.640007 -244.935685) (xy 134.656075 -244.989092) (xy 134.664195 -245.044268)
			(xy 134.664704 -245.072154) (xy 134.664195 -245.10004) (xy 134.656075 -245.155216) (xy 134.640007 -245.208623)
			(xy 134.635493 -245.218252) (xy 145.388281 -245.218252) (xy 145.388281 -245.163748) (xy 145.396039 -245.109798)
			(xy 145.411395 -245.057501) (xy 145.434038 -245.007922) (xy 145.463507 -244.962071) (xy 145.499201 -244.92088)
			(xy 145.540395 -244.885189) (xy 145.586249 -244.855724) (xy 145.635829 -244.833085) (xy 145.688127 -244.817732)
			(xy 145.742078 -244.809979) (xy 145.76933 -244.809518) (xy 145.796004 -244.809931) (xy 145.848829 -244.817387)
			(xy 145.900103 -244.832122) (xy 145.948827 -244.853849) (xy 145.994053 -244.882146) (xy 146.034902 -244.91646)
			(xy 146.070577 -244.956126) (xy 146.100386 -245.000371) (xy 146.112484 -245.024148) (xy 146.11897 -245.036257)
			(xy 146.137137 -245.056839) (xy 146.160132 -245.071836) (xy 146.186292 -245.080163) (xy 146.213724 -245.08122)
			(xy 146.240447 -245.074928) (xy 146.264526 -245.061743) (xy 146.284222 -245.042619) (xy 146.291554 -245.031006)
			(xy 146.306361 -245.006712) (xy 146.34198 -244.96235) (xy 146.38379 -244.923769) (xy 146.430864 -244.891823)
			(xy 146.482161 -244.86722) (xy 146.536541 -244.850506) (xy 146.592801 -244.842051) (xy 146.621246 -244.841522)
			(xy 146.648497 -244.841951) (xy 146.702444 -244.849713) (xy 146.754738 -244.865074) (xy 146.804313 -244.887719)
			(xy 146.850161 -244.917189) (xy 146.891349 -244.952883) (xy 146.927038 -244.994076) (xy 146.956503 -245.039928)
			(xy 146.979142 -245.089506) (xy 146.994496 -245.141801) (xy 147.002252 -245.195749) (xy 147.002252 -245.250251)
			(xy 146.994496 -245.304199) (xy 146.989691 -245.320566) (xy 151.397206 -245.320566) (xy 151.401277 -245.264944)
			(xy 151.413403 -245.210507) (xy 151.433326 -245.158416) (xy 151.460622 -245.109781) (xy 151.494708 -245.065638)
			(xy 151.534857 -245.026929) (xy 151.580215 -244.994478) (xy 151.629815 -244.968977) (xy 151.682599 -244.95097)
			(xy 151.737442 -244.94084) (xy 151.793176 -244.938803) (xy 151.848613 -244.944903) (xy 151.90257 -244.959009)
			(xy 151.953899 -244.980821) (xy 152.001505 -245.009875) (xy 152.044373 -245.04555) (xy 152.08159 -245.087087)
			(xy 152.112363 -245.1336) (xy 152.136035 -245.184097) (xy 152.152103 -245.237504) (xy 152.160223 -245.29268)
			(xy 152.160732 -245.320566) (xy 152.160223 -245.348452) (xy 152.152103 -245.403628) (xy 152.136035 -245.457035)
			(xy 152.112363 -245.507532) (xy 152.08159 -245.554045) (xy 152.044373 -245.595582) (xy 152.001505 -245.631257)
			(xy 151.953899 -245.660311) (xy 151.90257 -245.682123) (xy 151.848613 -245.696229) (xy 151.793176 -245.702329)
			(xy 151.737442 -245.700292) (xy 151.682599 -245.690162) (xy 151.629815 -245.672155) (xy 151.580215 -245.646654)
			(xy 151.534857 -245.614203) (xy 151.494708 -245.575494) (xy 151.460622 -245.531351) (xy 151.433326 -245.482716)
			(xy 151.413403 -245.430625) (xy 151.401277 -245.376188) (xy 151.397206 -245.320566) (xy 146.989691 -245.320566)
			(xy 146.979142 -245.356494) (xy 146.956503 -245.406072) (xy 146.927038 -245.451924) (xy 146.891349 -245.493117)
			(xy 146.850161 -245.528811) (xy 146.804313 -245.558281) (xy 146.754738 -245.580926) (xy 146.702444 -245.596287)
			(xy 146.648497 -245.604049) (xy 146.621246 -245.604538) (xy 146.594575 -245.604031) (xy 146.541756 -245.596586)
			(xy 146.490486 -245.581864) (xy 146.441764 -245.560149) (xy 146.396537 -245.531866) (xy 146.355687 -245.497565)
			(xy 146.320008 -245.457912) (xy 146.290194 -245.41368) (xy 146.278092 -245.389908) (xy 146.271641 -245.377781)
			(xy 146.253464 -245.357205) (xy 146.230463 -245.342214) (xy 146.204299 -245.333891) (xy 146.176864 -245.332838)
			(xy 146.15014 -245.339131) (xy 146.126057 -245.352315) (xy 146.106357 -245.371437) (xy 146.099022 -245.38305)
			(xy 146.084252 -245.407368) (xy 146.048625 -245.451727) (xy 146.006808 -245.490305) (xy 145.959727 -245.522247)
			(xy 145.908425 -245.546846) (xy 145.85404 -245.563556) (xy 145.797777 -245.572007) (xy 145.76933 -245.572534)
			(xy 145.742078 -245.572021) (xy 145.688127 -245.564268) (xy 145.635829 -245.548915) (xy 145.586249 -245.526276)
			(xy 145.540395 -245.496811) (xy 145.499201 -245.46112) (xy 145.463507 -245.419929) (xy 145.434038 -245.374078)
			(xy 145.411395 -245.324499) (xy 145.396039 -245.272202) (xy 145.388281 -245.218252) (xy 134.635493 -245.218252)
			(xy 134.616335 -245.25912) (xy 134.585562 -245.305633) (xy 134.548345 -245.34717) (xy 134.505477 -245.382845)
			(xy 134.457871 -245.411899) (xy 134.406542 -245.433711) (xy 134.352585 -245.447817) (xy 134.297148 -245.453917)
			(xy 134.241414 -245.45188) (xy 134.186571 -245.44175) (xy 134.133787 -245.423743) (xy 134.084187 -245.398242)
			(xy 134.038829 -245.365791) (xy 133.99868 -245.327082) (xy 133.964594 -245.282939) (xy 133.937298 -245.234304)
			(xy 133.917375 -245.182213) (xy 133.905249 -245.127776) (xy 133.901178 -245.072154) (xy 127.204741 -245.072154)
			(xy 127.199496 -245.080081) (xy 127.162279 -245.121618) (xy 127.119411 -245.157293) (xy 127.071805 -245.186347)
			(xy 127.020476 -245.208159) (xy 126.966519 -245.222265) (xy 126.911082 -245.228365) (xy 126.855348 -245.226328)
			(xy 126.800505 -245.216198) (xy 126.747721 -245.198191) (xy 126.698121 -245.17269) (xy 126.652763 -245.140239)
			(xy 126.612614 -245.10153) (xy 126.578528 -245.057387) (xy 126.551232 -245.008752) (xy 126.531309 -244.956661)
			(xy 126.519183 -244.902224) (xy 126.515112 -244.846602) (xy 102.213664 -244.846602) (xy 102.213664 -247.599753)
			(xy 114.289785 -247.599753) (xy 114.289785 -247.545247) (xy 114.297543 -247.491297) (xy 114.3129 -247.439)
			(xy 114.335543 -247.389421) (xy 114.365013 -247.34357) (xy 114.400708 -247.30238) (xy 114.441902 -247.266689)
			(xy 114.487757 -247.237224) (xy 114.537338 -247.214586) (xy 114.589636 -247.199234) (xy 114.643587 -247.191483)
			(xy 114.67084 -247.191022) (xy 114.699689 -247.191559) (xy 114.756732 -247.200226) (xy 114.811819 -247.217388)
			(xy 114.863691 -247.242653) (xy 114.911166 -247.275443) (xy 114.953159 -247.31501) (xy 114.988713 -247.360452)
			(xy 115.003326 -247.385332) (xy 115.003326 -247.385586) (xy 115.00358 -247.38584) (xy 115.008439 -247.39357)
			(xy 115.022452 -247.405251) (xy 115.039665 -247.411296) (xy 115.048792 -247.411494) (xy 115.152678 -247.409208)
			(xy 115.1763 -247.394476) (xy 115.18265 -247.381776) (xy 115.194935 -247.358523) (xy 115.224882 -247.315293)
			(xy 115.260485 -247.276589) (xy 115.30107 -247.243144) (xy 115.345865 -247.215594) (xy 115.394021 -247.194461)
			(xy 115.444625 -247.180146) (xy 115.496715 -247.17292) (xy 115.52301 -247.17248) (xy 115.552381 -247.172987)
			(xy 115.610427 -247.182) (xy 115.666408 -247.199795) (xy 115.719004 -247.225953) (xy 115.766974 -247.259857)
			(xy 115.809186 -247.300708) (xy 115.844644 -247.347541) (xy 115.859052 -247.37314) (xy 115.865656 -247.385332)
			(xy 115.88877 -247.399556) (xy 116.004594 -247.40235) (xy 116.02847 -247.389142) (xy 116.035582 -247.377458)
			(xy 116.050432 -247.353639) (xy 116.086089 -247.310289) (xy 116.127714 -247.272634) (xy 116.17441 -247.241487)
			(xy 116.225167 -247.217521) (xy 116.278889 -247.201254) (xy 116.334415 -247.193038) (xy 116.36248 -247.192546)
			(xy 116.389731 -247.1931) (xy 116.443677 -247.200854) (xy 116.495971 -247.216206) (xy 116.545548 -247.238845)
			(xy 116.591398 -247.268309) (xy 116.632588 -247.303998) (xy 116.668279 -247.345186) (xy 116.697746 -247.391035)
			(xy 116.720387 -247.44061) (xy 116.735742 -247.492903) (xy 116.743499 -247.54685) (xy 116.743499 -247.60135)
			(xy 116.735742 -247.655297) (xy 116.720387 -247.70759) (xy 116.697746 -247.757165) (xy 116.668279 -247.803014)
			(xy 116.632588 -247.844202) (xy 116.591398 -247.879891) (xy 116.545548 -247.909355) (xy 116.495971 -247.931994)
			(xy 116.443677 -247.947346) (xy 116.389731 -247.9551) (xy 116.36248 -247.955562) (xy 116.333113 -247.95496)
			(xy 116.275072 -247.945963) (xy 116.219094 -247.928183) (xy 116.166499 -247.902039) (xy 116.118528 -247.86815)
			(xy 116.076313 -247.827314) (xy 116.04085 -247.780495) (xy 116.026438 -247.754902) (xy 116.019834 -247.74271)
			(xy 115.99672 -247.728486) (xy 115.880896 -247.725692) (xy 115.85702 -247.7389) (xy 115.849908 -247.750584)
			(xy 115.835044 -247.774394) (xy 115.799392 -247.817747) (xy 115.75777 -247.855405) (xy 115.711076 -247.886554)
			(xy 115.660321 -247.910521) (xy 115.6066 -247.926789) (xy 115.551075 -247.935004) (xy 115.52301 -247.935496)
			(xy 115.49416 -247.93499) (xy 115.437116 -247.926315) (xy 115.382029 -247.909147) (xy 115.330157 -247.883878)
			(xy 115.282683 -247.851083) (xy 115.24069 -247.811512) (xy 115.205137 -247.766067) (xy 115.190524 -247.741186)
			(xy 115.190524 -247.740932) (xy 115.19027 -247.740678) (xy 115.185404 -247.732955) (xy 115.171391 -247.721279)
			(xy 115.154183 -247.715229) (xy 115.145058 -247.715024) (xy 115.041172 -247.71731) (xy 115.01755 -247.732042)
			(xy 115.0112 -247.744742) (xy 114.998961 -247.76802) (xy 114.969007 -247.81125) (xy 114.933396 -247.849954)
			(xy 114.892805 -247.883396) (xy 114.848003 -247.910943) (xy 114.799841 -247.932072) (xy 114.749232 -247.946382)
			(xy 114.697137 -247.953601) (xy 114.67084 -247.954038) (xy 114.643587 -247.953517) (xy 114.589636 -247.945766)
			(xy 114.537338 -247.930414) (xy 114.487757 -247.907776) (xy 114.441902 -247.878311) (xy 114.400708 -247.84262)
			(xy 114.365013 -247.80143) (xy 114.335543 -247.755579) (xy 114.3129 -247.706) (xy 114.297543 -247.653703)
			(xy 114.289785 -247.599753) (xy 102.213664 -247.599753) (xy 102.213664 -248.199402) (xy 123.865384 -248.199402)
			(xy 123.869455 -248.14378) (xy 123.881581 -248.089343) (xy 123.901504 -248.037252) (xy 123.9288 -247.988617)
			(xy 123.962886 -247.944474) (xy 124.003035 -247.905765) (xy 124.048393 -247.873314) (xy 124.097993 -247.847813)
			(xy 124.150777 -247.829806) (xy 124.20562 -247.819676) (xy 124.261354 -247.817639) (xy 124.316791 -247.823739)
			(xy 124.370748 -247.837845) (xy 124.422077 -247.859657) (xy 124.469683 -247.888711) (xy 124.511861 -247.923812)
			(xy 124.852682 -247.923812) (xy 124.856753 -247.86819) (xy 124.868879 -247.813753) (xy 124.888802 -247.761662)
			(xy 124.916098 -247.713027) (xy 124.950184 -247.668884) (xy 124.990333 -247.630175) (xy 125.035691 -247.597724)
			(xy 125.085291 -247.572223) (xy 125.138075 -247.554216) (xy 125.192918 -247.544086) (xy 125.248652 -247.542049)
			(xy 125.304089 -247.548149) (xy 125.358046 -247.562255) (xy 125.409375 -247.584067) (xy 125.456981 -247.613121)
			(xy 125.499849 -247.648796) (xy 125.537066 -247.690333) (xy 125.567839 -247.736846) (xy 125.591511 -247.787343)
			(xy 125.607579 -247.84075) (xy 125.615699 -247.895926) (xy 125.616208 -247.923812) (xy 125.615699 -247.951698)
			(xy 125.607579 -248.006874) (xy 125.591511 -248.060281) (xy 125.567839 -248.110778) (xy 125.537066 -248.157291)
			(xy 125.499849 -248.198828) (xy 125.456981 -248.234503) (xy 125.409375 -248.263557) (xy 125.358046 -248.285369)
			(xy 125.304089 -248.299475) (xy 125.248652 -248.305575) (xy 125.192918 -248.303538) (xy 125.138075 -248.293408)
			(xy 125.085291 -248.275401) (xy 125.035691 -248.2499) (xy 124.990333 -248.217449) (xy 124.950184 -248.17874)
			(xy 124.916098 -248.134597) (xy 124.888802 -248.085962) (xy 124.868879 -248.033871) (xy 124.856753 -247.979434)
			(xy 124.852682 -247.923812) (xy 124.511861 -247.923812) (xy 124.512551 -247.924386) (xy 124.549768 -247.965923)
			(xy 124.580541 -248.012436) (xy 124.604213 -248.062933) (xy 124.620281 -248.11634) (xy 124.628401 -248.171516)
			(xy 124.62891 -248.199402) (xy 124.628401 -248.227288) (xy 124.620281 -248.282464) (xy 124.604213 -248.335871)
			(xy 124.580541 -248.386368) (xy 124.549768 -248.432881) (xy 124.512551 -248.474418) (xy 124.469683 -248.510093)
			(xy 124.422077 -248.539147) (xy 124.370748 -248.560959) (xy 124.316791 -248.575065) (xy 124.261354 -248.581165)
			(xy 124.20562 -248.579128) (xy 124.150777 -248.568998) (xy 124.097993 -248.550991) (xy 124.048393 -248.52549)
			(xy 124.003035 -248.493039) (xy 123.962886 -248.45433) (xy 123.9288 -248.410187) (xy 123.901504 -248.361552)
			(xy 123.881581 -248.309461) (xy 123.869455 -248.255024) (xy 123.865384 -248.199402) (xy 102.213664 -248.199402)
			(xy 102.213664 -248.652538) (xy 128.32029 -248.652538) (xy 128.324361 -248.596916) (xy 128.336487 -248.542479)
			(xy 128.35641 -248.490388) (xy 128.383706 -248.441753) (xy 128.417792 -248.39761) (xy 128.457941 -248.358901)
			(xy 128.503299 -248.32645) (xy 128.552899 -248.300949) (xy 128.605683 -248.282942) (xy 128.660526 -248.272812)
			(xy 128.71626 -248.270775) (xy 128.771697 -248.276875) (xy 128.825654 -248.290981) (xy 128.876983 -248.312793)
			(xy 128.924589 -248.341847) (xy 128.967457 -248.377522) (xy 129.004674 -248.419059) (xy 129.035447 -248.465572)
			(xy 129.059119 -248.516069) (xy 129.075187 -248.569476) (xy 129.083307 -248.624652) (xy 129.083816 -248.652538)
			(xy 129.083307 -248.680424) (xy 129.075187 -248.7356) (xy 129.059119 -248.789007) (xy 129.035447 -248.839504)
			(xy 129.004674 -248.886017) (xy 128.967457 -248.927554) (xy 128.924589 -248.963229) (xy 128.876983 -248.992283)
			(xy 128.825654 -249.014095) (xy 128.771697 -249.028201) (xy 128.71626 -249.034301) (xy 128.660526 -249.032264)
			(xy 128.605683 -249.022134) (xy 128.552899 -249.004127) (xy 128.503299 -248.978626) (xy 128.457941 -248.946175)
			(xy 128.417792 -248.907466) (xy 128.383706 -248.863323) (xy 128.35641 -248.814688) (xy 128.336487 -248.762597)
			(xy 128.324361 -248.70816) (xy 128.32029 -248.652538) (xy 102.213664 -248.652538) (xy 102.213664 -249.273568)
			(xy 127.616964 -249.273568) (xy 127.621035 -249.217946) (xy 127.633161 -249.163509) (xy 127.653084 -249.111418)
			(xy 127.68038 -249.062783) (xy 127.714466 -249.01864) (xy 127.754615 -248.979931) (xy 127.799973 -248.94748)
			(xy 127.849573 -248.921979) (xy 127.902357 -248.903972) (xy 127.9572 -248.893842) (xy 128.012934 -248.891805)
			(xy 128.068371 -248.897905) (xy 128.122328 -248.912011) (xy 128.173657 -248.933823) (xy 128.221263 -248.962877)
			(xy 128.264131 -248.998552) (xy 128.301348 -249.040089) (xy 128.332121 -249.086602) (xy 128.355793 -249.137099)
			(xy 128.371861 -249.190506) (xy 128.379981 -249.245682) (xy 128.38049 -249.273568) (xy 128.379981 -249.301454)
			(xy 128.376011 -249.328432) (xy 129.023616 -249.328432) (xy 129.027687 -249.27281) (xy 129.039813 -249.218373)
			(xy 129.059736 -249.166282) (xy 129.087032 -249.117647) (xy 129.121118 -249.073504) (xy 129.161267 -249.034795)
			(xy 129.206625 -249.002344) (xy 129.256225 -248.976843) (xy 129.309009 -248.958836) (xy 129.363852 -248.948706)
			(xy 129.419586 -248.946669) (xy 129.475023 -248.952769) (xy 129.52898 -248.966875) (xy 129.580309 -248.988687)
			(xy 129.627915 -249.017741) (xy 129.670783 -249.053416) (xy 129.708 -249.094953) (xy 129.738773 -249.141466)
			(xy 129.762445 -249.191963) (xy 129.778513 -249.24537) (xy 129.786633 -249.300546) (xy 129.787142 -249.328432)
			(xy 129.786633 -249.356318) (xy 129.778513 -249.411494) (xy 129.762445 -249.464901) (xy 129.738773 -249.515398)
			(xy 129.708 -249.561911) (xy 129.670783 -249.603448) (xy 129.627915 -249.639123) (xy 129.580309 -249.668177)
			(xy 129.52898 -249.689989) (xy 129.475023 -249.704095) (xy 129.419586 -249.710195) (xy 129.363852 -249.708158)
			(xy 129.309009 -249.698028) (xy 129.256225 -249.680021) (xy 129.206625 -249.65452) (xy 129.161267 -249.622069)
			(xy 129.121118 -249.58336) (xy 129.087032 -249.539217) (xy 129.059736 -249.490582) (xy 129.039813 -249.438491)
			(xy 129.027687 -249.384054) (xy 129.023616 -249.328432) (xy 128.376011 -249.328432) (xy 128.371861 -249.35663)
			(xy 128.355793 -249.410037) (xy 128.332121 -249.460534) (xy 128.301348 -249.507047) (xy 128.264131 -249.548584)
			(xy 128.221263 -249.584259) (xy 128.173657 -249.613313) (xy 128.122328 -249.635125) (xy 128.068371 -249.649231)
			(xy 128.012934 -249.655331) (xy 127.9572 -249.653294) (xy 127.902357 -249.643164) (xy 127.849573 -249.625157)
			(xy 127.799973 -249.599656) (xy 127.754615 -249.567205) (xy 127.714466 -249.528496) (xy 127.68038 -249.484353)
			(xy 127.653084 -249.435718) (xy 127.633161 -249.383627) (xy 127.621035 -249.32919) (xy 127.616964 -249.273568)
			(xy 102.213664 -249.273568) (xy 102.213664 -249.80138) (xy 102.214103 -249.811442) (xy 102.221845 -249.83002)
			(xy 102.22865 -249.837448) (xy 102.449376 -250.058174) (xy 102.456777 -250.065011) (xy 102.475376 -250.072722)
			(xy 102.485444 -250.07316) (xy 127.633222 -250.07316) (xy 127.63754 -250.073414) (xy 127.64008 -250.073668)
			(xy 127.647192 -250.073668) (xy 127.654067 -250.073482) (xy 127.667336 -250.069884) (xy 127.673354 -250.066556)
			(xy 127.693674 -250.054364) (xy 127.699262 -250.051062) (xy 127.708152 -250.042172) (xy 127.711454 -250.036838)
			(xy 127.711708 -250.036584) (xy 127.726527 -250.012907) (xy 127.762003 -249.969765) (xy 127.803394 -249.932259)
			(xy 127.849813 -249.901193) (xy 127.900268 -249.877232) (xy 127.953679 -249.860889) (xy 128.008902 -249.852512)
			(xy 128.036828 -249.851926) (xy 128.038606 -249.851926) (xy 128.068885 -249.852524) (xy 128.128677 -249.862126)
			(xy 128.186201 -249.881058) (xy 128.24001 -249.908841) (xy 128.288752 -249.94478) (xy 128.310386 -249.965972)
			(xy 128.31064 -249.966226) (xy 128.318768 -249.974354) (xy 128.32715 -249.978164) (xy 128.3462 -249.987054)
			(xy 128.351266 -249.989211) (xy 128.362031 -249.991512) (xy 128.367536 -249.991626) (xy 128.420368 -249.991626)
			(xy 128.435862 -249.988324) (xy 128.44653 -249.984768) (xy 128.469644 -249.9741) (xy 128.476248 -249.967242)
			(xy 128.494269 -249.94934) (xy 128.534228 -249.917979) (xy 128.577996 -249.892198) (xy 128.624798 -249.872454)
			(xy 128.673806 -249.859096) (xy 128.724154 -249.852362) (xy 128.749552 -249.851926) (xy 128.777589 -249.852419)
			(xy 128.833059 -249.860627) (xy 128.886728 -249.876874) (xy 128.937438 -249.900807) (xy 128.984094 -249.931912)
			(xy 129.025689 -249.969517) (xy 129.061327 -250.01281) (xy 129.076196 -250.036584) (xy 129.07645 -250.036838)
			(xy 129.079752 -250.042172) (xy 129.08407 -250.04649) (xy 129.09423 -250.054364) (xy 129.114042 -250.066048)
			(xy 129.120009 -250.069336) (xy 129.133141 -250.072946) (xy 129.13995 -250.07316) (xy 129.729992 -250.07316)
			(xy 129.735834 -250.072906) (xy 129.746746 -250.071043) (xy 129.765585 -250.059462) (xy 129.772156 -250.050554)
			(xy 129.774188 -250.047252) (xy 129.787766 -250.023941) (xy 129.820481 -249.981047) (xy 129.858914 -249.943192)
			(xy 129.9023 -249.911132) (xy 129.949771 -249.885507) (xy 130.00038 -249.866829) (xy 130.053117 -249.855472)
			(xy 130.106928 -249.85166) (xy 130.160739 -249.855472) (xy 130.213476 -249.866829) (xy 130.264085 -249.885507)
			(xy 130.311556 -249.911132) (xy 130.354942 -249.943192) (xy 130.393375 -249.981047) (xy 130.42609 -250.023941)
			(xy 130.439668 -250.047252) (xy 130.4417 -250.050554) (xy 130.448279 -250.059451) (xy 130.467116 -250.071018)
			(xy 130.478022 -250.072906) (xy 130.483864 -250.07316) (xy 131.835906 -250.07316) (xy 131.845974 -250.073586)
			(xy 131.864572 -250.081308) (xy 131.871974 -250.088146) (xy 132.94233 -251.158502) (xy 140.060424 -251.158502)
			(xy 140.064495 -251.10288) (xy 140.076621 -251.048443) (xy 140.096544 -250.996352) (xy 140.12384 -250.947717)
			(xy 140.157926 -250.903574) (xy 140.198075 -250.864865) (xy 140.243433 -250.832414) (xy 140.293033 -250.806913)
			(xy 140.345817 -250.788906) (xy 140.40066 -250.778776) (xy 140.456394 -250.776739) (xy 140.511831 -250.782839)
			(xy 140.565788 -250.796945) (xy 140.617117 -250.818757) (xy 140.664723 -250.847811) (xy 140.707591 -250.883486)
			(xy 140.744808 -250.925023) (xy 140.775581 -250.971536) (xy 140.799253 -251.022033) (xy 140.815321 -251.07544)
			(xy 140.823441 -251.130616) (xy 140.82395 -251.158502) (xy 141.076424 -251.158502) (xy 141.080495 -251.10288)
			(xy 141.092621 -251.048443) (xy 141.112544 -250.996352) (xy 141.13984 -250.947717) (xy 141.173926 -250.903574)
			(xy 141.214075 -250.864865) (xy 141.259433 -250.832414) (xy 141.309033 -250.806913) (xy 141.361817 -250.788906)
			(xy 141.41666 -250.778776) (xy 141.472394 -250.776739) (xy 141.527831 -250.782839) (xy 141.581788 -250.796945)
			(xy 141.633117 -250.818757) (xy 141.680723 -250.847811) (xy 141.723591 -250.883486) (xy 141.760808 -250.925023)
			(xy 141.791581 -250.971536) (xy 141.815253 -251.022033) (xy 141.831321 -251.07544) (xy 141.839441 -251.130616)
			(xy 141.83995 -251.158502) (xy 142.092424 -251.158502) (xy 142.096495 -251.10288) (xy 142.108621 -251.048443)
			(xy 142.128544 -250.996352) (xy 142.15584 -250.947717) (xy 142.189926 -250.903574) (xy 142.230075 -250.864865)
			(xy 142.275433 -250.832414) (xy 142.325033 -250.806913) (xy 142.377817 -250.788906) (xy 142.43266 -250.778776)
			(xy 142.488394 -250.776739) (xy 142.543831 -250.782839) (xy 142.597788 -250.796945) (xy 142.649117 -250.818757)
			(xy 142.696723 -250.847811) (xy 142.739591 -250.883486) (xy 142.776808 -250.925023) (xy 142.807581 -250.971536)
			(xy 142.831253 -251.022033) (xy 142.847321 -251.07544) (xy 142.855441 -251.130616) (xy 142.85595 -251.158502)
			(xy 143.108424 -251.158502) (xy 143.112495 -251.10288) (xy 143.124621 -251.048443) (xy 143.144544 -250.996352)
			(xy 143.17184 -250.947717) (xy 143.205926 -250.903574) (xy 143.246075 -250.864865) (xy 143.291433 -250.832414)
			(xy 143.341033 -250.806913) (xy 143.393817 -250.788906) (xy 143.44866 -250.778776) (xy 143.504394 -250.776739)
			(xy 143.559831 -250.782839) (xy 143.613788 -250.796945) (xy 143.665117 -250.818757) (xy 143.712723 -250.847811)
			(xy 143.755591 -250.883486) (xy 143.792808 -250.925023) (xy 143.823581 -250.971536) (xy 143.847253 -251.022033)
			(xy 143.863321 -251.07544) (xy 143.871441 -251.130616) (xy 143.87195 -251.158502) (xy 144.124424 -251.158502)
			(xy 144.128495 -251.10288) (xy 144.140621 -251.048443) (xy 144.160544 -250.996352) (xy 144.18784 -250.947717)
			(xy 144.221926 -250.903574) (xy 144.262075 -250.864865) (xy 144.307433 -250.832414) (xy 144.357033 -250.806913)
			(xy 144.409817 -250.788906) (xy 144.46466 -250.778776) (xy 144.520394 -250.776739) (xy 144.575831 -250.782839)
			(xy 144.629788 -250.796945) (xy 144.681117 -250.818757) (xy 144.728723 -250.847811) (xy 144.771591 -250.883486)
			(xy 144.808808 -250.925023) (xy 144.839581 -250.971536) (xy 144.863253 -251.022033) (xy 144.879321 -251.07544)
			(xy 144.887441 -251.130616) (xy 144.88795 -251.158502) (xy 145.140424 -251.158502) (xy 145.144495 -251.10288)
			(xy 145.156621 -251.048443) (xy 145.176544 -250.996352) (xy 145.20384 -250.947717) (xy 145.237926 -250.903574)
			(xy 145.278075 -250.864865) (xy 145.323433 -250.832414) (xy 145.373033 -250.806913) (xy 145.425817 -250.788906)
			(xy 145.48066 -250.778776) (xy 145.536394 -250.776739) (xy 145.591831 -250.782839) (xy 145.645788 -250.796945)
			(xy 145.697117 -250.818757) (xy 145.744723 -250.847811) (xy 145.787591 -250.883486) (xy 145.824808 -250.925023)
			(xy 145.855581 -250.971536) (xy 145.879253 -251.022033) (xy 145.895321 -251.07544) (xy 145.903441 -251.130616)
			(xy 145.90395 -251.158502) (xy 146.156424 -251.158502) (xy 146.160495 -251.10288) (xy 146.172621 -251.048443)
			(xy 146.192544 -250.996352) (xy 146.21984 -250.947717) (xy 146.253926 -250.903574) (xy 146.294075 -250.864865)
			(xy 146.339433 -250.832414) (xy 146.389033 -250.806913) (xy 146.441817 -250.788906) (xy 146.49666 -250.778776)
			(xy 146.552394 -250.776739) (xy 146.607831 -250.782839) (xy 146.661788 -250.796945) (xy 146.713117 -250.818757)
			(xy 146.760723 -250.847811) (xy 146.803591 -250.883486) (xy 146.840808 -250.925023) (xy 146.871581 -250.971536)
			(xy 146.895253 -251.022033) (xy 146.911321 -251.07544) (xy 146.919441 -251.130616) (xy 146.91995 -251.158502)
			(xy 147.172424 -251.158502) (xy 147.176495 -251.10288) (xy 147.188621 -251.048443) (xy 147.208544 -250.996352)
			(xy 147.23584 -250.947717) (xy 147.269926 -250.903574) (xy 147.310075 -250.864865) (xy 147.355433 -250.832414)
			(xy 147.405033 -250.806913) (xy 147.457817 -250.788906) (xy 147.51266 -250.778776) (xy 147.568394 -250.776739)
			(xy 147.623831 -250.782839) (xy 147.677788 -250.796945) (xy 147.729117 -250.818757) (xy 147.776723 -250.847811)
			(xy 147.819591 -250.883486) (xy 147.856808 -250.925023) (xy 147.887581 -250.971536) (xy 147.911253 -251.022033)
			(xy 147.927321 -251.07544) (xy 147.935441 -251.130616) (xy 147.93595 -251.158502) (xy 148.188424 -251.158502)
			(xy 148.192495 -251.10288) (xy 148.204621 -251.048443) (xy 148.224544 -250.996352) (xy 148.25184 -250.947717)
			(xy 148.285926 -250.903574) (xy 148.326075 -250.864865) (xy 148.371433 -250.832414) (xy 148.421033 -250.806913)
			(xy 148.473817 -250.788906) (xy 148.52866 -250.778776) (xy 148.584394 -250.776739) (xy 148.639831 -250.782839)
			(xy 148.693788 -250.796945) (xy 148.745117 -250.818757) (xy 148.792723 -250.847811) (xy 148.835591 -250.883486)
			(xy 148.872808 -250.925023) (xy 148.903581 -250.971536) (xy 148.927253 -251.022033) (xy 148.943321 -251.07544)
			(xy 148.951441 -251.130616) (xy 148.95195 -251.158502) (xy 149.204424 -251.158502) (xy 149.208495 -251.10288)
			(xy 149.220621 -251.048443) (xy 149.240544 -250.996352) (xy 149.26784 -250.947717) (xy 149.301926 -250.903574)
			(xy 149.342075 -250.864865) (xy 149.387433 -250.832414) (xy 149.437033 -250.806913) (xy 149.489817 -250.788906)
			(xy 149.54466 -250.778776) (xy 149.600394 -250.776739) (xy 149.655831 -250.782839) (xy 149.709788 -250.796945)
			(xy 149.761117 -250.818757) (xy 149.808723 -250.847811) (xy 149.851591 -250.883486) (xy 149.888808 -250.925023)
			(xy 149.919581 -250.971536) (xy 149.943253 -251.022033) (xy 149.959321 -251.07544) (xy 149.967441 -251.130616)
			(xy 149.96795 -251.158502) (xy 150.220424 -251.158502) (xy 150.224495 -251.10288) (xy 150.236621 -251.048443)
			(xy 150.256544 -250.996352) (xy 150.28384 -250.947717) (xy 150.317926 -250.903574) (xy 150.358075 -250.864865)
			(xy 150.403433 -250.832414) (xy 150.453033 -250.806913) (xy 150.505817 -250.788906) (xy 150.56066 -250.778776)
			(xy 150.616394 -250.776739) (xy 150.671831 -250.782839) (xy 150.725788 -250.796945) (xy 150.777117 -250.818757)
			(xy 150.824723 -250.847811) (xy 150.867591 -250.883486) (xy 150.904808 -250.925023) (xy 150.935581 -250.971536)
			(xy 150.959253 -251.022033) (xy 150.975321 -251.07544) (xy 150.983441 -251.130616) (xy 150.98395 -251.158502)
			(xy 151.236424 -251.158502) (xy 151.240495 -251.10288) (xy 151.252621 -251.048443) (xy 151.272544 -250.996352)
			(xy 151.29984 -250.947717) (xy 151.333926 -250.903574) (xy 151.374075 -250.864865) (xy 151.419433 -250.832414)
			(xy 151.469033 -250.806913) (xy 151.521817 -250.788906) (xy 151.57666 -250.778776) (xy 151.632394 -250.776739)
			(xy 151.687831 -250.782839) (xy 151.741788 -250.796945) (xy 151.793117 -250.818757) (xy 151.840723 -250.847811)
			(xy 151.883591 -250.883486) (xy 151.920808 -250.925023) (xy 151.951581 -250.971536) (xy 151.975253 -251.022033)
			(xy 151.991321 -251.07544) (xy 151.999441 -251.130616) (xy 151.99995 -251.158502) (xy 152.252424 -251.158502)
			(xy 152.256495 -251.10288) (xy 152.268621 -251.048443) (xy 152.288544 -250.996352) (xy 152.31584 -250.947717)
			(xy 152.349926 -250.903574) (xy 152.390075 -250.864865) (xy 152.435433 -250.832414) (xy 152.485033 -250.806913)
			(xy 152.537817 -250.788906) (xy 152.59266 -250.778776) (xy 152.648394 -250.776739) (xy 152.703831 -250.782839)
			(xy 152.757788 -250.796945) (xy 152.809117 -250.818757) (xy 152.856723 -250.847811) (xy 152.899591 -250.883486)
			(xy 152.936808 -250.925023) (xy 152.967581 -250.971536) (xy 152.991253 -251.022033) (xy 153.007321 -251.07544)
			(xy 153.015441 -251.130616) (xy 153.01595 -251.158502) (xy 153.268424 -251.158502) (xy 153.272495 -251.10288)
			(xy 153.284621 -251.048443) (xy 153.304544 -250.996352) (xy 153.33184 -250.947717) (xy 153.365926 -250.903574)
			(xy 153.406075 -250.864865) (xy 153.451433 -250.832414) (xy 153.501033 -250.806913) (xy 153.553817 -250.788906)
			(xy 153.60866 -250.778776) (xy 153.664394 -250.776739) (xy 153.719831 -250.782839) (xy 153.773788 -250.796945)
			(xy 153.825117 -250.818757) (xy 153.872723 -250.847811) (xy 153.915591 -250.883486) (xy 153.952808 -250.925023)
			(xy 153.983581 -250.971536) (xy 154.007253 -251.022033) (xy 154.023321 -251.07544) (xy 154.031441 -251.130616)
			(xy 154.03195 -251.158502) (xy 154.284424 -251.158502) (xy 154.288495 -251.10288) (xy 154.300621 -251.048443)
			(xy 154.320544 -250.996352) (xy 154.34784 -250.947717) (xy 154.381926 -250.903574) (xy 154.422075 -250.864865)
			(xy 154.467433 -250.832414) (xy 154.517033 -250.806913) (xy 154.569817 -250.788906) (xy 154.62466 -250.778776)
			(xy 154.680394 -250.776739) (xy 154.735831 -250.782839) (xy 154.789788 -250.796945) (xy 154.841117 -250.818757)
			(xy 154.888723 -250.847811) (xy 154.931591 -250.883486) (xy 154.968808 -250.925023) (xy 154.999581 -250.971536)
			(xy 155.023253 -251.022033) (xy 155.039321 -251.07544) (xy 155.047441 -251.130616) (xy 155.04795 -251.158502)
			(xy 156.316424 -251.158502) (xy 156.320495 -251.10288) (xy 156.332621 -251.048443) (xy 156.352544 -250.996352)
			(xy 156.37984 -250.947717) (xy 156.413926 -250.903574) (xy 156.454075 -250.864865) (xy 156.499433 -250.832414)
			(xy 156.549033 -250.806913) (xy 156.601817 -250.788906) (xy 156.65666 -250.778776) (xy 156.712394 -250.776739)
			(xy 156.767831 -250.782839) (xy 156.821788 -250.796945) (xy 156.873117 -250.818757) (xy 156.920723 -250.847811)
			(xy 156.963591 -250.883486) (xy 157.000808 -250.925023) (xy 157.031581 -250.971536) (xy 157.055253 -251.022033)
			(xy 157.071321 -251.07544) (xy 157.079441 -251.130616) (xy 157.07995 -251.158502) (xy 157.079441 -251.186388)
			(xy 157.071321 -251.241564) (xy 157.055253 -251.294971) (xy 157.031581 -251.345468) (xy 157.000808 -251.391981)
			(xy 156.963591 -251.433518) (xy 156.920723 -251.469193) (xy 156.873117 -251.498247) (xy 156.821788 -251.520059)
			(xy 156.767831 -251.534165) (xy 156.712394 -251.540265) (xy 156.65666 -251.538228) (xy 156.601817 -251.528098)
			(xy 156.549033 -251.510091) (xy 156.499433 -251.48459) (xy 156.454075 -251.452139) (xy 156.413926 -251.41343)
			(xy 156.37984 -251.369287) (xy 156.352544 -251.320652) (xy 156.332621 -251.268561) (xy 156.320495 -251.214124)
			(xy 156.316424 -251.158502) (xy 155.04795 -251.158502) (xy 155.047441 -251.186388) (xy 155.039321 -251.241564)
			(xy 155.023253 -251.294971) (xy 154.999581 -251.345468) (xy 154.968808 -251.391981) (xy 154.931591 -251.433518)
			(xy 154.888723 -251.469193) (xy 154.841117 -251.498247) (xy 154.789788 -251.520059) (xy 154.735831 -251.534165)
			(xy 154.680394 -251.540265) (xy 154.62466 -251.538228) (xy 154.569817 -251.528098) (xy 154.517033 -251.510091)
			(xy 154.467433 -251.48459) (xy 154.422075 -251.452139) (xy 154.381926 -251.41343) (xy 154.34784 -251.369287)
			(xy 154.320544 -251.320652) (xy 154.300621 -251.268561) (xy 154.288495 -251.214124) (xy 154.284424 -251.158502)
			(xy 154.03195 -251.158502) (xy 154.031441 -251.186388) (xy 154.023321 -251.241564) (xy 154.007253 -251.294971)
			(xy 153.983581 -251.345468) (xy 153.952808 -251.391981) (xy 153.915591 -251.433518) (xy 153.872723 -251.469193)
			(xy 153.825117 -251.498247) (xy 153.773788 -251.520059) (xy 153.719831 -251.534165) (xy 153.664394 -251.540265)
			(xy 153.60866 -251.538228) (xy 153.553817 -251.528098) (xy 153.501033 -251.510091) (xy 153.451433 -251.48459)
			(xy 153.406075 -251.452139) (xy 153.365926 -251.41343) (xy 153.33184 -251.369287) (xy 153.304544 -251.320652)
			(xy 153.284621 -251.268561) (xy 153.272495 -251.214124) (xy 153.268424 -251.158502) (xy 153.01595 -251.158502)
			(xy 153.015441 -251.186388) (xy 153.007321 -251.241564) (xy 152.991253 -251.294971) (xy 152.967581 -251.345468)
			(xy 152.936808 -251.391981) (xy 152.899591 -251.433518) (xy 152.856723 -251.469193) (xy 152.809117 -251.498247)
			(xy 152.757788 -251.520059) (xy 152.703831 -251.534165) (xy 152.648394 -251.540265) (xy 152.59266 -251.538228)
			(xy 152.537817 -251.528098) (xy 152.485033 -251.510091) (xy 152.435433 -251.48459) (xy 152.390075 -251.452139)
			(xy 152.349926 -251.41343) (xy 152.31584 -251.369287) (xy 152.288544 -251.320652) (xy 152.268621 -251.268561)
			(xy 152.256495 -251.214124) (xy 152.252424 -251.158502) (xy 151.99995 -251.158502) (xy 151.999441 -251.186388)
			(xy 151.991321 -251.241564) (xy 151.975253 -251.294971) (xy 151.951581 -251.345468) (xy 151.920808 -251.391981)
			(xy 151.883591 -251.433518) (xy 151.840723 -251.469193) (xy 151.793117 -251.498247) (xy 151.741788 -251.520059)
			(xy 151.687831 -251.534165) (xy 151.632394 -251.540265) (xy 151.57666 -251.538228) (xy 151.521817 -251.528098)
			(xy 151.469033 -251.510091) (xy 151.419433 -251.48459) (xy 151.374075 -251.452139) (xy 151.333926 -251.41343)
			(xy 151.29984 -251.369287) (xy 151.272544 -251.320652) (xy 151.252621 -251.268561) (xy 151.240495 -251.214124)
			(xy 151.236424 -251.158502) (xy 150.98395 -251.158502) (xy 150.983441 -251.186388) (xy 150.975321 -251.241564)
			(xy 150.959253 -251.294971) (xy 150.935581 -251.345468) (xy 150.904808 -251.391981) (xy 150.867591 -251.433518)
			(xy 150.824723 -251.469193) (xy 150.777117 -251.498247) (xy 150.725788 -251.520059) (xy 150.671831 -251.534165)
			(xy 150.616394 -251.540265) (xy 150.56066 -251.538228) (xy 150.505817 -251.528098) (xy 150.453033 -251.510091)
			(xy 150.403433 -251.48459) (xy 150.358075 -251.452139) (xy 150.317926 -251.41343) (xy 150.28384 -251.369287)
			(xy 150.256544 -251.320652) (xy 150.236621 -251.268561) (xy 150.224495 -251.214124) (xy 150.220424 -251.158502)
			(xy 149.96795 -251.158502) (xy 149.967441 -251.186388) (xy 149.959321 -251.241564) (xy 149.943253 -251.294971)
			(xy 149.919581 -251.345468) (xy 149.888808 -251.391981) (xy 149.851591 -251.433518) (xy 149.808723 -251.469193)
			(xy 149.761117 -251.498247) (xy 149.709788 -251.520059) (xy 149.655831 -251.534165) (xy 149.600394 -251.540265)
			(xy 149.54466 -251.538228) (xy 149.489817 -251.528098) (xy 149.437033 -251.510091) (xy 149.387433 -251.48459)
			(xy 149.342075 -251.452139) (xy 149.301926 -251.41343) (xy 149.26784 -251.369287) (xy 149.240544 -251.320652)
			(xy 149.220621 -251.268561) (xy 149.208495 -251.214124) (xy 149.204424 -251.158502) (xy 148.95195 -251.158502)
			(xy 148.951441 -251.186388) (xy 148.943321 -251.241564) (xy 148.927253 -251.294971) (xy 148.903581 -251.345468)
			(xy 148.872808 -251.391981) (xy 148.835591 -251.433518) (xy 148.792723 -251.469193) (xy 148.745117 -251.498247)
			(xy 148.693788 -251.520059) (xy 148.639831 -251.534165) (xy 148.584394 -251.540265) (xy 148.52866 -251.538228)
			(xy 148.473817 -251.528098) (xy 148.421033 -251.510091) (xy 148.371433 -251.48459) (xy 148.326075 -251.452139)
			(xy 148.285926 -251.41343) (xy 148.25184 -251.369287) (xy 148.224544 -251.320652) (xy 148.204621 -251.268561)
			(xy 148.192495 -251.214124) (xy 148.188424 -251.158502) (xy 147.93595 -251.158502) (xy 147.935441 -251.186388)
			(xy 147.927321 -251.241564) (xy 147.911253 -251.294971) (xy 147.887581 -251.345468) (xy 147.856808 -251.391981)
			(xy 147.819591 -251.433518) (xy 147.776723 -251.469193) (xy 147.729117 -251.498247) (xy 147.677788 -251.520059)
			(xy 147.623831 -251.534165) (xy 147.568394 -251.540265) (xy 147.51266 -251.538228) (xy 147.457817 -251.528098)
			(xy 147.405033 -251.510091) (xy 147.355433 -251.48459) (xy 147.310075 -251.452139) (xy 147.269926 -251.41343)
			(xy 147.23584 -251.369287) (xy 147.208544 -251.320652) (xy 147.188621 -251.268561) (xy 147.176495 -251.214124)
			(xy 147.172424 -251.158502) (xy 146.91995 -251.158502) (xy 146.919441 -251.186388) (xy 146.911321 -251.241564)
			(xy 146.895253 -251.294971) (xy 146.871581 -251.345468) (xy 146.840808 -251.391981) (xy 146.803591 -251.433518)
			(xy 146.760723 -251.469193) (xy 146.713117 -251.498247) (xy 146.661788 -251.520059) (xy 146.607831 -251.534165)
			(xy 146.552394 -251.540265) (xy 146.49666 -251.538228) (xy 146.441817 -251.528098) (xy 146.389033 -251.510091)
			(xy 146.339433 -251.48459) (xy 146.294075 -251.452139) (xy 146.253926 -251.41343) (xy 146.21984 -251.369287)
			(xy 146.192544 -251.320652) (xy 146.172621 -251.268561) (xy 146.160495 -251.214124) (xy 146.156424 -251.158502)
			(xy 145.90395 -251.158502) (xy 145.903441 -251.186388) (xy 145.895321 -251.241564) (xy 145.879253 -251.294971)
			(xy 145.855581 -251.345468) (xy 145.824808 -251.391981) (xy 145.787591 -251.433518) (xy 145.744723 -251.469193)
			(xy 145.697117 -251.498247) (xy 145.645788 -251.520059) (xy 145.591831 -251.534165) (xy 145.536394 -251.540265)
			(xy 145.48066 -251.538228) (xy 145.425817 -251.528098) (xy 145.373033 -251.510091) (xy 145.323433 -251.48459)
			(xy 145.278075 -251.452139) (xy 145.237926 -251.41343) (xy 145.20384 -251.369287) (xy 145.176544 -251.320652)
			(xy 145.156621 -251.268561) (xy 145.144495 -251.214124) (xy 145.140424 -251.158502) (xy 144.88795 -251.158502)
			(xy 144.887441 -251.186388) (xy 144.879321 -251.241564) (xy 144.863253 -251.294971) (xy 144.839581 -251.345468)
			(xy 144.808808 -251.391981) (xy 144.771591 -251.433518) (xy 144.728723 -251.469193) (xy 144.681117 -251.498247)
			(xy 144.629788 -251.520059) (xy 144.575831 -251.534165) (xy 144.520394 -251.540265) (xy 144.46466 -251.538228)
			(xy 144.409817 -251.528098) (xy 144.357033 -251.510091) (xy 144.307433 -251.48459) (xy 144.262075 -251.452139)
			(xy 144.221926 -251.41343) (xy 144.18784 -251.369287) (xy 144.160544 -251.320652) (xy 144.140621 -251.268561)
			(xy 144.128495 -251.214124) (xy 144.124424 -251.158502) (xy 143.87195 -251.158502) (xy 143.871441 -251.186388)
			(xy 143.863321 -251.241564) (xy 143.847253 -251.294971) (xy 143.823581 -251.345468) (xy 143.792808 -251.391981)
			(xy 143.755591 -251.433518) (xy 143.712723 -251.469193) (xy 143.665117 -251.498247) (xy 143.613788 -251.520059)
			(xy 143.559831 -251.534165) (xy 143.504394 -251.540265) (xy 143.44866 -251.538228) (xy 143.393817 -251.528098)
			(xy 143.341033 -251.510091) (xy 143.291433 -251.48459) (xy 143.246075 -251.452139) (xy 143.205926 -251.41343)
			(xy 143.17184 -251.369287) (xy 143.144544 -251.320652) (xy 143.124621 -251.268561) (xy 143.112495 -251.214124)
			(xy 143.108424 -251.158502) (xy 142.85595 -251.158502) (xy 142.855441 -251.186388) (xy 142.847321 -251.241564)
			(xy 142.831253 -251.294971) (xy 142.807581 -251.345468) (xy 142.776808 -251.391981) (xy 142.739591 -251.433518)
			(xy 142.696723 -251.469193) (xy 142.649117 -251.498247) (xy 142.597788 -251.520059) (xy 142.543831 -251.534165)
			(xy 142.488394 -251.540265) (xy 142.43266 -251.538228) (xy 142.377817 -251.528098) (xy 142.325033 -251.510091)
			(xy 142.275433 -251.48459) (xy 142.230075 -251.452139) (xy 142.189926 -251.41343) (xy 142.15584 -251.369287)
			(xy 142.128544 -251.320652) (xy 142.108621 -251.268561) (xy 142.096495 -251.214124) (xy 142.092424 -251.158502)
			(xy 141.83995 -251.158502) (xy 141.839441 -251.186388) (xy 141.831321 -251.241564) (xy 141.815253 -251.294971)
			(xy 141.791581 -251.345468) (xy 141.760808 -251.391981) (xy 141.723591 -251.433518) (xy 141.680723 -251.469193)
			(xy 141.633117 -251.498247) (xy 141.581788 -251.520059) (xy 141.527831 -251.534165) (xy 141.472394 -251.540265)
			(xy 141.41666 -251.538228) (xy 141.361817 -251.528098) (xy 141.309033 -251.510091) (xy 141.259433 -251.48459)
			(xy 141.214075 -251.452139) (xy 141.173926 -251.41343) (xy 141.13984 -251.369287) (xy 141.112544 -251.320652)
			(xy 141.092621 -251.268561) (xy 141.080495 -251.214124) (xy 141.076424 -251.158502) (xy 140.82395 -251.158502)
			(xy 140.823441 -251.186388) (xy 140.815321 -251.241564) (xy 140.799253 -251.294971) (xy 140.775581 -251.345468)
			(xy 140.744808 -251.391981) (xy 140.707591 -251.433518) (xy 140.664723 -251.469193) (xy 140.617117 -251.498247)
			(xy 140.565788 -251.520059) (xy 140.511831 -251.534165) (xy 140.456394 -251.540265) (xy 140.40066 -251.538228)
			(xy 140.345817 -251.528098) (xy 140.293033 -251.510091) (xy 140.243433 -251.48459) (xy 140.198075 -251.452139)
			(xy 140.157926 -251.41343) (xy 140.12384 -251.369287) (xy 140.096544 -251.320652) (xy 140.076621 -251.268561)
			(xy 140.064495 -251.214124) (xy 140.060424 -251.158502) (xy 132.94233 -251.158502) (xy 135.240268 -253.45644)
			(xy 140.060424 -253.45644) (xy 140.064495 -253.400818) (xy 140.076621 -253.346381) (xy 140.096544 -253.29429)
			(xy 140.12384 -253.245655) (xy 140.157926 -253.201512) (xy 140.198075 -253.162803) (xy 140.243433 -253.130352)
			(xy 140.293033 -253.104851) (xy 140.345817 -253.086844) (xy 140.40066 -253.076714) (xy 140.456394 -253.074677)
			(xy 140.511831 -253.080777) (xy 140.565788 -253.094883) (xy 140.617117 -253.116695) (xy 140.664723 -253.145749)
			(xy 140.707591 -253.181424) (xy 140.744808 -253.222961) (xy 140.775581 -253.269474) (xy 140.799253 -253.319971)
			(xy 140.815321 -253.373378) (xy 140.823441 -253.428554) (xy 140.82395 -253.45644) (xy 141.076424 -253.45644)
			(xy 141.080495 -253.400818) (xy 141.092621 -253.346381) (xy 141.112544 -253.29429) (xy 141.13984 -253.245655)
			(xy 141.173926 -253.201512) (xy 141.214075 -253.162803) (xy 141.259433 -253.130352) (xy 141.309033 -253.104851)
			(xy 141.361817 -253.086844) (xy 141.41666 -253.076714) (xy 141.472394 -253.074677) (xy 141.527831 -253.080777)
			(xy 141.581788 -253.094883) (xy 141.633117 -253.116695) (xy 141.680723 -253.145749) (xy 141.723591 -253.181424)
			(xy 141.760808 -253.222961) (xy 141.791581 -253.269474) (xy 141.815253 -253.319971) (xy 141.831321 -253.373378)
			(xy 141.839441 -253.428554) (xy 141.83995 -253.45644) (xy 142.092424 -253.45644) (xy 142.096495 -253.400818)
			(xy 142.108621 -253.346381) (xy 142.128544 -253.29429) (xy 142.15584 -253.245655) (xy 142.189926 -253.201512)
			(xy 142.230075 -253.162803) (xy 142.275433 -253.130352) (xy 142.325033 -253.104851) (xy 142.377817 -253.086844)
			(xy 142.43266 -253.076714) (xy 142.488394 -253.074677) (xy 142.543831 -253.080777) (xy 142.597788 -253.094883)
			(xy 142.649117 -253.116695) (xy 142.696723 -253.145749) (xy 142.739591 -253.181424) (xy 142.776808 -253.222961)
			(xy 142.807581 -253.269474) (xy 142.831253 -253.319971) (xy 142.847321 -253.373378) (xy 142.855441 -253.428554)
			(xy 142.85595 -253.45644) (xy 143.108424 -253.45644) (xy 143.112495 -253.400818) (xy 143.124621 -253.346381)
			(xy 143.144544 -253.29429) (xy 143.17184 -253.245655) (xy 143.205926 -253.201512) (xy 143.246075 -253.162803)
			(xy 143.291433 -253.130352) (xy 143.341033 -253.104851) (xy 143.393817 -253.086844) (xy 143.44866 -253.076714)
			(xy 143.504394 -253.074677) (xy 143.559831 -253.080777) (xy 143.613788 -253.094883) (xy 143.665117 -253.116695)
			(xy 143.712723 -253.145749) (xy 143.755591 -253.181424) (xy 143.792808 -253.222961) (xy 143.823581 -253.269474)
			(xy 143.847253 -253.319971) (xy 143.863321 -253.373378) (xy 143.871441 -253.428554) (xy 143.87195 -253.45644)
			(xy 144.124424 -253.45644) (xy 144.128495 -253.400818) (xy 144.140621 -253.346381) (xy 144.160544 -253.29429)
			(xy 144.18784 -253.245655) (xy 144.221926 -253.201512) (xy 144.262075 -253.162803) (xy 144.307433 -253.130352)
			(xy 144.357033 -253.104851) (xy 144.409817 -253.086844) (xy 144.46466 -253.076714) (xy 144.520394 -253.074677)
			(xy 144.575831 -253.080777) (xy 144.629788 -253.094883) (xy 144.681117 -253.116695) (xy 144.728723 -253.145749)
			(xy 144.771591 -253.181424) (xy 144.808808 -253.222961) (xy 144.839581 -253.269474) (xy 144.863253 -253.319971)
			(xy 144.879321 -253.373378) (xy 144.887441 -253.428554) (xy 144.88795 -253.45644) (xy 145.140424 -253.45644)
			(xy 145.144495 -253.400818) (xy 145.156621 -253.346381) (xy 145.176544 -253.29429) (xy 145.20384 -253.245655)
			(xy 145.237926 -253.201512) (xy 145.278075 -253.162803) (xy 145.323433 -253.130352) (xy 145.373033 -253.104851)
			(xy 145.425817 -253.086844) (xy 145.48066 -253.076714) (xy 145.536394 -253.074677) (xy 145.591831 -253.080777)
			(xy 145.645788 -253.094883) (xy 145.697117 -253.116695) (xy 145.744723 -253.145749) (xy 145.787591 -253.181424)
			(xy 145.824808 -253.222961) (xy 145.855581 -253.269474) (xy 145.879253 -253.319971) (xy 145.895321 -253.373378)
			(xy 145.903441 -253.428554) (xy 145.90395 -253.45644) (xy 146.156424 -253.45644) (xy 146.160495 -253.400818)
			(xy 146.172621 -253.346381) (xy 146.192544 -253.29429) (xy 146.21984 -253.245655) (xy 146.253926 -253.201512)
			(xy 146.294075 -253.162803) (xy 146.339433 -253.130352) (xy 146.389033 -253.104851) (xy 146.441817 -253.086844)
			(xy 146.49666 -253.076714) (xy 146.552394 -253.074677) (xy 146.607831 -253.080777) (xy 146.661788 -253.094883)
			(xy 146.713117 -253.116695) (xy 146.760723 -253.145749) (xy 146.803591 -253.181424) (xy 146.840808 -253.222961)
			(xy 146.871581 -253.269474) (xy 146.895253 -253.319971) (xy 146.911321 -253.373378) (xy 146.919441 -253.428554)
			(xy 146.91995 -253.45644) (xy 147.172424 -253.45644) (xy 147.176495 -253.400818) (xy 147.188621 -253.346381)
			(xy 147.208544 -253.29429) (xy 147.23584 -253.245655) (xy 147.269926 -253.201512) (xy 147.310075 -253.162803)
			(xy 147.355433 -253.130352) (xy 147.405033 -253.104851) (xy 147.457817 -253.086844) (xy 147.51266 -253.076714)
			(xy 147.568394 -253.074677) (xy 147.623831 -253.080777) (xy 147.677788 -253.094883) (xy 147.729117 -253.116695)
			(xy 147.776723 -253.145749) (xy 147.819591 -253.181424) (xy 147.856808 -253.222961) (xy 147.887581 -253.269474)
			(xy 147.911253 -253.319971) (xy 147.927321 -253.373378) (xy 147.935441 -253.428554) (xy 147.93595 -253.45644)
			(xy 148.188424 -253.45644) (xy 148.192495 -253.400818) (xy 148.204621 -253.346381) (xy 148.224544 -253.29429)
			(xy 148.25184 -253.245655) (xy 148.285926 -253.201512) (xy 148.326075 -253.162803) (xy 148.371433 -253.130352)
			(xy 148.421033 -253.104851) (xy 148.473817 -253.086844) (xy 148.52866 -253.076714) (xy 148.584394 -253.074677)
			(xy 148.639831 -253.080777) (xy 148.693788 -253.094883) (xy 148.745117 -253.116695) (xy 148.792723 -253.145749)
			(xy 148.835591 -253.181424) (xy 148.872808 -253.222961) (xy 148.903581 -253.269474) (xy 148.927253 -253.319971)
			(xy 148.943321 -253.373378) (xy 148.951441 -253.428554) (xy 148.95195 -253.45644) (xy 149.204424 -253.45644)
			(xy 149.208495 -253.400818) (xy 149.220621 -253.346381) (xy 149.240544 -253.29429) (xy 149.26784 -253.245655)
			(xy 149.301926 -253.201512) (xy 149.342075 -253.162803) (xy 149.387433 -253.130352) (xy 149.437033 -253.104851)
			(xy 149.489817 -253.086844) (xy 149.54466 -253.076714) (xy 149.600394 -253.074677) (xy 149.655831 -253.080777)
			(xy 149.709788 -253.094883) (xy 149.761117 -253.116695) (xy 149.808723 -253.145749) (xy 149.851591 -253.181424)
			(xy 149.888808 -253.222961) (xy 149.919581 -253.269474) (xy 149.943253 -253.319971) (xy 149.959321 -253.373378)
			(xy 149.967441 -253.428554) (xy 149.96795 -253.45644) (xy 150.220424 -253.45644) (xy 150.224495 -253.400818)
			(xy 150.236621 -253.346381) (xy 150.256544 -253.29429) (xy 150.28384 -253.245655) (xy 150.317926 -253.201512)
			(xy 150.358075 -253.162803) (xy 150.403433 -253.130352) (xy 150.453033 -253.104851) (xy 150.505817 -253.086844)
			(xy 150.56066 -253.076714) (xy 150.616394 -253.074677) (xy 150.671831 -253.080777) (xy 150.725788 -253.094883)
			(xy 150.777117 -253.116695) (xy 150.824723 -253.145749) (xy 150.867591 -253.181424) (xy 150.904808 -253.222961)
			(xy 150.935581 -253.269474) (xy 150.959253 -253.319971) (xy 150.975321 -253.373378) (xy 150.983441 -253.428554)
			(xy 150.98395 -253.45644) (xy 151.236424 -253.45644) (xy 151.240495 -253.400818) (xy 151.252621 -253.346381)
			(xy 151.272544 -253.29429) (xy 151.29984 -253.245655) (xy 151.333926 -253.201512) (xy 151.374075 -253.162803)
			(xy 151.419433 -253.130352) (xy 151.469033 -253.104851) (xy 151.521817 -253.086844) (xy 151.57666 -253.076714)
			(xy 151.632394 -253.074677) (xy 151.687831 -253.080777) (xy 151.741788 -253.094883) (xy 151.793117 -253.116695)
			(xy 151.840723 -253.145749) (xy 151.883591 -253.181424) (xy 151.920808 -253.222961) (xy 151.951581 -253.269474)
			(xy 151.975253 -253.319971) (xy 151.991321 -253.373378) (xy 151.999441 -253.428554) (xy 151.99995 -253.45644)
			(xy 152.252424 -253.45644) (xy 152.256495 -253.400818) (xy 152.268621 -253.346381) (xy 152.288544 -253.29429)
			(xy 152.31584 -253.245655) (xy 152.349926 -253.201512) (xy 152.390075 -253.162803) (xy 152.435433 -253.130352)
			(xy 152.485033 -253.104851) (xy 152.537817 -253.086844) (xy 152.59266 -253.076714) (xy 152.648394 -253.074677)
			(xy 152.703831 -253.080777) (xy 152.757788 -253.094883) (xy 152.809117 -253.116695) (xy 152.856723 -253.145749)
			(xy 152.899591 -253.181424) (xy 152.936808 -253.222961) (xy 152.967581 -253.269474) (xy 152.991253 -253.319971)
			(xy 153.007321 -253.373378) (xy 153.015441 -253.428554) (xy 153.01595 -253.45644) (xy 153.268424 -253.45644)
			(xy 153.272495 -253.400818) (xy 153.284621 -253.346381) (xy 153.304544 -253.29429) (xy 153.33184 -253.245655)
			(xy 153.365926 -253.201512) (xy 153.406075 -253.162803) (xy 153.451433 -253.130352) (xy 153.501033 -253.104851)
			(xy 153.553817 -253.086844) (xy 153.60866 -253.076714) (xy 153.664394 -253.074677) (xy 153.719831 -253.080777)
			(xy 153.773788 -253.094883) (xy 153.825117 -253.116695) (xy 153.872723 -253.145749) (xy 153.915591 -253.181424)
			(xy 153.952808 -253.222961) (xy 153.983581 -253.269474) (xy 154.007253 -253.319971) (xy 154.023321 -253.373378)
			(xy 154.031441 -253.428554) (xy 154.03195 -253.45644) (xy 154.284424 -253.45644) (xy 154.288495 -253.400818)
			(xy 154.300621 -253.346381) (xy 154.320544 -253.29429) (xy 154.34784 -253.245655) (xy 154.381926 -253.201512)
			(xy 154.422075 -253.162803) (xy 154.467433 -253.130352) (xy 154.517033 -253.104851) (xy 154.569817 -253.086844)
			(xy 154.62466 -253.076714) (xy 154.680394 -253.074677) (xy 154.735831 -253.080777) (xy 154.789788 -253.094883)
			(xy 154.841117 -253.116695) (xy 154.888723 -253.145749) (xy 154.931591 -253.181424) (xy 154.968808 -253.222961)
			(xy 154.999581 -253.269474) (xy 155.023253 -253.319971) (xy 155.039321 -253.373378) (xy 155.047441 -253.428554)
			(xy 155.04795 -253.45644) (xy 155.300424 -253.45644) (xy 155.304495 -253.400818) (xy 155.316621 -253.346381)
			(xy 155.336544 -253.29429) (xy 155.36384 -253.245655) (xy 155.397926 -253.201512) (xy 155.438075 -253.162803)
			(xy 155.483433 -253.130352) (xy 155.533033 -253.104851) (xy 155.585817 -253.086844) (xy 155.64066 -253.076714)
			(xy 155.696394 -253.074677) (xy 155.751831 -253.080777) (xy 155.805788 -253.094883) (xy 155.857117 -253.116695)
			(xy 155.904723 -253.145749) (xy 155.947591 -253.181424) (xy 155.984808 -253.222961) (xy 156.015581 -253.269474)
			(xy 156.039253 -253.319971) (xy 156.055321 -253.373378) (xy 156.063441 -253.428554) (xy 156.06395 -253.45644)
			(xy 156.316424 -253.45644) (xy 156.320495 -253.400818) (xy 156.332621 -253.346381) (xy 156.352544 -253.29429)
			(xy 156.37984 -253.245655) (xy 156.413926 -253.201512) (xy 156.454075 -253.162803) (xy 156.499433 -253.130352)
			(xy 156.549033 -253.104851) (xy 156.601817 -253.086844) (xy 156.65666 -253.076714) (xy 156.712394 -253.074677)
			(xy 156.767831 -253.080777) (xy 156.821788 -253.094883) (xy 156.873117 -253.116695) (xy 156.920723 -253.145749)
			(xy 156.963591 -253.181424) (xy 157.000808 -253.222961) (xy 157.031581 -253.269474) (xy 157.055253 -253.319971)
			(xy 157.071321 -253.373378) (xy 157.079441 -253.428554) (xy 157.07995 -253.45644) (xy 157.079441 -253.484326)
			(xy 157.071321 -253.539502) (xy 157.055253 -253.592909) (xy 157.031581 -253.643406) (xy 157.000808 -253.689919)
			(xy 156.963591 -253.731456) (xy 156.920723 -253.767131) (xy 156.873117 -253.796185) (xy 156.821788 -253.817997)
			(xy 156.767831 -253.832103) (xy 156.712394 -253.838203) (xy 156.65666 -253.836166) (xy 156.601817 -253.826036)
			(xy 156.549033 -253.808029) (xy 156.499433 -253.782528) (xy 156.454075 -253.750077) (xy 156.413926 -253.711368)
			(xy 156.37984 -253.667225) (xy 156.352544 -253.61859) (xy 156.332621 -253.566499) (xy 156.320495 -253.512062)
			(xy 156.316424 -253.45644) (xy 156.06395 -253.45644) (xy 156.063441 -253.484326) (xy 156.055321 -253.539502)
			(xy 156.039253 -253.592909) (xy 156.015581 -253.643406) (xy 155.984808 -253.689919) (xy 155.947591 -253.731456)
			(xy 155.904723 -253.767131) (xy 155.857117 -253.796185) (xy 155.805788 -253.817997) (xy 155.751831 -253.832103)
			(xy 155.696394 -253.838203) (xy 155.64066 -253.836166) (xy 155.585817 -253.826036) (xy 155.533033 -253.808029)
			(xy 155.483433 -253.782528) (xy 155.438075 -253.750077) (xy 155.397926 -253.711368) (xy 155.36384 -253.667225)
			(xy 155.336544 -253.61859) (xy 155.316621 -253.566499) (xy 155.304495 -253.512062) (xy 155.300424 -253.45644)
			(xy 155.04795 -253.45644) (xy 155.047441 -253.484326) (xy 155.039321 -253.539502) (xy 155.023253 -253.592909)
			(xy 154.999581 -253.643406) (xy 154.968808 -253.689919) (xy 154.931591 -253.731456) (xy 154.888723 -253.767131)
			(xy 154.841117 -253.796185) (xy 154.789788 -253.817997) (xy 154.735831 -253.832103) (xy 154.680394 -253.838203)
			(xy 154.62466 -253.836166) (xy 154.569817 -253.826036) (xy 154.517033 -253.808029) (xy 154.467433 -253.782528)
			(xy 154.422075 -253.750077) (xy 154.381926 -253.711368) (xy 154.34784 -253.667225) (xy 154.320544 -253.61859)
			(xy 154.300621 -253.566499) (xy 154.288495 -253.512062) (xy 154.284424 -253.45644) (xy 154.03195 -253.45644)
			(xy 154.031441 -253.484326) (xy 154.023321 -253.539502) (xy 154.007253 -253.592909) (xy 153.983581 -253.643406)
			(xy 153.952808 -253.689919) (xy 153.915591 -253.731456) (xy 153.872723 -253.767131) (xy 153.825117 -253.796185)
			(xy 153.773788 -253.817997) (xy 153.719831 -253.832103) (xy 153.664394 -253.838203) (xy 153.60866 -253.836166)
			(xy 153.553817 -253.826036) (xy 153.501033 -253.808029) (xy 153.451433 -253.782528) (xy 153.406075 -253.750077)
			(xy 153.365926 -253.711368) (xy 153.33184 -253.667225) (xy 153.304544 -253.61859) (xy 153.284621 -253.566499)
			(xy 153.272495 -253.512062) (xy 153.268424 -253.45644) (xy 153.01595 -253.45644) (xy 153.015441 -253.484326)
			(xy 153.007321 -253.539502) (xy 152.991253 -253.592909) (xy 152.967581 -253.643406) (xy 152.936808 -253.689919)
			(xy 152.899591 -253.731456) (xy 152.856723 -253.767131) (xy 152.809117 -253.796185) (xy 152.757788 -253.817997)
			(xy 152.703831 -253.832103) (xy 152.648394 -253.838203) (xy 152.59266 -253.836166) (xy 152.537817 -253.826036)
			(xy 152.485033 -253.808029) (xy 152.435433 -253.782528) (xy 152.390075 -253.750077) (xy 152.349926 -253.711368)
			(xy 152.31584 -253.667225) (xy 152.288544 -253.61859) (xy 152.268621 -253.566499) (xy 152.256495 -253.512062)
			(xy 152.252424 -253.45644) (xy 151.99995 -253.45644) (xy 151.999441 -253.484326) (xy 151.991321 -253.539502)
			(xy 151.975253 -253.592909) (xy 151.951581 -253.643406) (xy 151.920808 -253.689919) (xy 151.883591 -253.731456)
			(xy 151.840723 -253.767131) (xy 151.793117 -253.796185) (xy 151.741788 -253.817997) (xy 151.687831 -253.832103)
			(xy 151.632394 -253.838203) (xy 151.57666 -253.836166) (xy 151.521817 -253.826036) (xy 151.469033 -253.808029)
			(xy 151.419433 -253.782528) (xy 151.374075 -253.750077) (xy 151.333926 -253.711368) (xy 151.29984 -253.667225)
			(xy 151.272544 -253.61859) (xy 151.252621 -253.566499) (xy 151.240495 -253.512062) (xy 151.236424 -253.45644)
			(xy 150.98395 -253.45644) (xy 150.983441 -253.484326) (xy 150.975321 -253.539502) (xy 150.959253 -253.592909)
			(xy 150.935581 -253.643406) (xy 150.904808 -253.689919) (xy 150.867591 -253.731456) (xy 150.824723 -253.767131)
			(xy 150.777117 -253.796185) (xy 150.725788 -253.817997) (xy 150.671831 -253.832103) (xy 150.616394 -253.838203)
			(xy 150.56066 -253.836166) (xy 150.505817 -253.826036) (xy 150.453033 -253.808029) (xy 150.403433 -253.782528)
			(xy 150.358075 -253.750077) (xy 150.317926 -253.711368) (xy 150.28384 -253.667225) (xy 150.256544 -253.61859)
			(xy 150.236621 -253.566499) (xy 150.224495 -253.512062) (xy 150.220424 -253.45644) (xy 149.96795 -253.45644)
			(xy 149.967441 -253.484326) (xy 149.959321 -253.539502) (xy 149.943253 -253.592909) (xy 149.919581 -253.643406)
			(xy 149.888808 -253.689919) (xy 149.851591 -253.731456) (xy 149.808723 -253.767131) (xy 149.761117 -253.796185)
			(xy 149.709788 -253.817997) (xy 149.655831 -253.832103) (xy 149.600394 -253.838203) (xy 149.54466 -253.836166)
			(xy 149.489817 -253.826036) (xy 149.437033 -253.808029) (xy 149.387433 -253.782528) (xy 149.342075 -253.750077)
			(xy 149.301926 -253.711368) (xy 149.26784 -253.667225) (xy 149.240544 -253.61859) (xy 149.220621 -253.566499)
			(xy 149.208495 -253.512062) (xy 149.204424 -253.45644) (xy 148.95195 -253.45644) (xy 148.951441 -253.484326)
			(xy 148.943321 -253.539502) (xy 148.927253 -253.592909) (xy 148.903581 -253.643406) (xy 148.872808 -253.689919)
			(xy 148.835591 -253.731456) (xy 148.792723 -253.767131) (xy 148.745117 -253.796185) (xy 148.693788 -253.817997)
			(xy 148.639831 -253.832103) (xy 148.584394 -253.838203) (xy 148.52866 -253.836166) (xy 148.473817 -253.826036)
			(xy 148.421033 -253.808029) (xy 148.371433 -253.782528) (xy 148.326075 -253.750077) (xy 148.285926 -253.711368)
			(xy 148.25184 -253.667225) (xy 148.224544 -253.61859) (xy 148.204621 -253.566499) (xy 148.192495 -253.512062)
			(xy 148.188424 -253.45644) (xy 147.93595 -253.45644) (xy 147.935441 -253.484326) (xy 147.927321 -253.539502)
			(xy 147.911253 -253.592909) (xy 147.887581 -253.643406) (xy 147.856808 -253.689919) (xy 147.819591 -253.731456)
			(xy 147.776723 -253.767131) (xy 147.729117 -253.796185) (xy 147.677788 -253.817997) (xy 147.623831 -253.832103)
			(xy 147.568394 -253.838203) (xy 147.51266 -253.836166) (xy 147.457817 -253.826036) (xy 147.405033 -253.808029)
			(xy 147.355433 -253.782528) (xy 147.310075 -253.750077) (xy 147.269926 -253.711368) (xy 147.23584 -253.667225)
			(xy 147.208544 -253.61859) (xy 147.188621 -253.566499) (xy 147.176495 -253.512062) (xy 147.172424 -253.45644)
			(xy 146.91995 -253.45644) (xy 146.919441 -253.484326) (xy 146.911321 -253.539502) (xy 146.895253 -253.592909)
			(xy 146.871581 -253.643406) (xy 146.840808 -253.689919) (xy 146.803591 -253.731456) (xy 146.760723 -253.767131)
			(xy 146.713117 -253.796185) (xy 146.661788 -253.817997) (xy 146.607831 -253.832103) (xy 146.552394 -253.838203)
			(xy 146.49666 -253.836166) (xy 146.441817 -253.826036) (xy 146.389033 -253.808029) (xy 146.339433 -253.782528)
			(xy 146.294075 -253.750077) (xy 146.253926 -253.711368) (xy 146.21984 -253.667225) (xy 146.192544 -253.61859)
			(xy 146.172621 -253.566499) (xy 146.160495 -253.512062) (xy 146.156424 -253.45644) (xy 145.90395 -253.45644)
			(xy 145.903441 -253.484326) (xy 145.895321 -253.539502) (xy 145.879253 -253.592909) (xy 145.855581 -253.643406)
			(xy 145.824808 -253.689919) (xy 145.787591 -253.731456) (xy 145.744723 -253.767131) (xy 145.697117 -253.796185)
			(xy 145.645788 -253.817997) (xy 145.591831 -253.832103) (xy 145.536394 -253.838203) (xy 145.48066 -253.836166)
			(xy 145.425817 -253.826036) (xy 145.373033 -253.808029) (xy 145.323433 -253.782528) (xy 145.278075 -253.750077)
			(xy 145.237926 -253.711368) (xy 145.20384 -253.667225) (xy 145.176544 -253.61859) (xy 145.156621 -253.566499)
			(xy 145.144495 -253.512062) (xy 145.140424 -253.45644) (xy 144.88795 -253.45644) (xy 144.887441 -253.484326)
			(xy 144.879321 -253.539502) (xy 144.863253 -253.592909) (xy 144.839581 -253.643406) (xy 144.808808 -253.689919)
			(xy 144.771591 -253.731456) (xy 144.728723 -253.767131) (xy 144.681117 -253.796185) (xy 144.629788 -253.817997)
			(xy 144.575831 -253.832103) (xy 144.520394 -253.838203) (xy 144.46466 -253.836166) (xy 144.409817 -253.826036)
			(xy 144.357033 -253.808029) (xy 144.307433 -253.782528) (xy 144.262075 -253.750077) (xy 144.221926 -253.711368)
			(xy 144.18784 -253.667225) (xy 144.160544 -253.61859) (xy 144.140621 -253.566499) (xy 144.128495 -253.512062)
			(xy 144.124424 -253.45644) (xy 143.87195 -253.45644) (xy 143.871441 -253.484326) (xy 143.863321 -253.539502)
			(xy 143.847253 -253.592909) (xy 143.823581 -253.643406) (xy 143.792808 -253.689919) (xy 143.755591 -253.731456)
			(xy 143.712723 -253.767131) (xy 143.665117 -253.796185) (xy 143.613788 -253.817997) (xy 143.559831 -253.832103)
			(xy 143.504394 -253.838203) (xy 143.44866 -253.836166) (xy 143.393817 -253.826036) (xy 143.341033 -253.808029)
			(xy 143.291433 -253.782528) (xy 143.246075 -253.750077) (xy 143.205926 -253.711368) (xy 143.17184 -253.667225)
			(xy 143.144544 -253.61859) (xy 143.124621 -253.566499) (xy 143.112495 -253.512062) (xy 143.108424 -253.45644)
			(xy 142.85595 -253.45644) (xy 142.855441 -253.484326) (xy 142.847321 -253.539502) (xy 142.831253 -253.592909)
			(xy 142.807581 -253.643406) (xy 142.776808 -253.689919) (xy 142.739591 -253.731456) (xy 142.696723 -253.767131)
			(xy 142.649117 -253.796185) (xy 142.597788 -253.817997) (xy 142.543831 -253.832103) (xy 142.488394 -253.838203)
			(xy 142.43266 -253.836166) (xy 142.377817 -253.826036) (xy 142.325033 -253.808029) (xy 142.275433 -253.782528)
			(xy 142.230075 -253.750077) (xy 142.189926 -253.711368) (xy 142.15584 -253.667225) (xy 142.128544 -253.61859)
			(xy 142.108621 -253.566499) (xy 142.096495 -253.512062) (xy 142.092424 -253.45644) (xy 141.83995 -253.45644)
			(xy 141.839441 -253.484326) (xy 141.831321 -253.539502) (xy 141.815253 -253.592909) (xy 141.791581 -253.643406)
			(xy 141.760808 -253.689919) (xy 141.723591 -253.731456) (xy 141.680723 -253.767131) (xy 141.633117 -253.796185)
			(xy 141.581788 -253.817997) (xy 141.527831 -253.832103) (xy 141.472394 -253.838203) (xy 141.41666 -253.836166)
			(xy 141.361817 -253.826036) (xy 141.309033 -253.808029) (xy 141.259433 -253.782528) (xy 141.214075 -253.750077)
			(xy 141.173926 -253.711368) (xy 141.13984 -253.667225) (xy 141.112544 -253.61859) (xy 141.092621 -253.566499)
			(xy 141.080495 -253.512062) (xy 141.076424 -253.45644) (xy 140.82395 -253.45644) (xy 140.823441 -253.484326)
			(xy 140.815321 -253.539502) (xy 140.799253 -253.592909) (xy 140.775581 -253.643406) (xy 140.744808 -253.689919)
			(xy 140.707591 -253.731456) (xy 140.664723 -253.767131) (xy 140.617117 -253.796185) (xy 140.565788 -253.817997)
			(xy 140.511831 -253.832103) (xy 140.456394 -253.838203) (xy 140.40066 -253.836166) (xy 140.345817 -253.826036)
			(xy 140.293033 -253.808029) (xy 140.243433 -253.782528) (xy 140.198075 -253.750077) (xy 140.157926 -253.711368)
			(xy 140.12384 -253.667225) (xy 140.096544 -253.61859) (xy 140.076621 -253.566499) (xy 140.064495 -253.512062)
			(xy 140.060424 -253.45644) (xy 135.240268 -253.45644) (xy 136.415272 -254.631444) (xy 136.422115 -254.638843)
			(xy 136.429838 -254.657442) (xy 136.430258 -254.667512) (xy 136.430258 -255.910588) (xy 137.976608 -255.910588)
			(xy 137.980679 -255.854966) (xy 137.992805 -255.800529) (xy 138.012728 -255.748438) (xy 138.040024 -255.699803)
			(xy 138.07411 -255.65566) (xy 138.114259 -255.616951) (xy 138.159617 -255.5845) (xy 138.209217 -255.558999)
			(xy 138.262001 -255.540992) (xy 138.316844 -255.530862) (xy 138.372578 -255.528825) (xy 138.428015 -255.534925)
			(xy 138.481972 -255.549031) (xy 138.533301 -255.570843) (xy 138.580907 -255.599897) (xy 138.623775 -255.635572)
			(xy 138.660992 -255.677109) (xy 138.671803 -255.69345) (xy 138.865595 -255.69345) (xy 138.865595 -255.63895)
			(xy 138.873352 -255.585003) (xy 138.888707 -255.53271) (xy 138.911347 -255.483135) (xy 138.940813 -255.437286)
			(xy 138.976504 -255.396097) (xy 139.017694 -255.360407) (xy 139.063543 -255.330943) (xy 139.11312 -255.308303)
			(xy 139.165413 -255.29295) (xy 139.21936 -255.285195) (xy 139.24661 -255.284732) (xy 139.275563 -255.285266)
			(xy 139.332804 -255.294025) (xy 139.388066 -255.311326) (xy 139.440082 -255.336772) (xy 139.487661 -255.36978)
			(xy 139.52971 -255.409593) (xy 139.565266 -255.455299) (xy 139.579858 -255.480312) (xy 139.587594 -255.493222)
			(xy 139.609263 -255.514091) (xy 139.636073 -255.527742) (xy 139.665697 -255.532988) (xy 139.695565 -255.529375)
			(xy 139.723083 -255.517216) (xy 139.745865 -255.497567) (xy 139.754356 -255.485138) (xy 139.769465 -255.462161)
			(xy 139.805167 -255.420337) (xy 139.846503 -255.38407) (xy 139.892616 -255.354112) (xy 139.942551 -255.331082)
			(xy 139.995275 -255.315459) (xy 140.049695 -255.307565) (xy 140.07719 -255.307084) (xy 140.104443 -255.307563)
			(xy 140.158394 -255.315318) (xy 140.210692 -255.330673) (xy 140.260272 -255.353315) (xy 140.306125 -255.382782)
			(xy 140.347318 -255.418475) (xy 140.383012 -255.459667) (xy 140.412481 -255.505519) (xy 140.435123 -255.555099)
			(xy 140.45048 -255.607397) (xy 140.458237 -255.661347) (xy 140.458237 -255.715853) (xy 140.45048 -255.769803)
			(xy 140.435123 -255.822101) (xy 140.412481 -255.871681) (xy 140.383012 -255.917533) (xy 140.347318 -255.958725)
			(xy 140.306125 -255.994418) (xy 140.260272 -256.023885) (xy 140.210692 -256.046527) (xy 140.158394 -256.061882)
			(xy 140.104443 -256.069637) (xy 140.07719 -256.0701) (xy 140.048235 -256.069601) (xy 139.990991 -256.06084)
			(xy 139.935727 -256.043535) (xy 139.883709 -256.018084) (xy 139.836131 -255.98507) (xy 139.794083 -255.94525)
			(xy 139.758531 -255.899537) (xy 139.743942 -255.87452) (xy 139.736204 -255.861615) (xy 139.71453 -255.840759)
			(xy 139.687721 -255.827118) (xy 139.658103 -255.821876) (xy 139.628241 -255.825486) (xy 139.600725 -255.837636)
			(xy 139.57794 -255.857272) (xy 139.569444 -255.869694) (xy 139.554345 -255.892679) (xy 139.51864 -255.934501)
			(xy 139.477303 -255.970766) (xy 139.431188 -256.000723) (xy 139.381251 -256.023751) (xy 139.328526 -256.039374)
			(xy 139.274105 -256.047267) (xy 139.24661 -256.047748) (xy 139.21936 -256.047205) (xy 139.165413 -256.03945)
			(xy 139.11312 -256.024097) (xy 139.063543 -256.001457) (xy 139.017694 -255.971993) (xy 138.976504 -255.936303)
			(xy 138.940813 -255.895114) (xy 138.911347 -255.849265) (xy 138.888707 -255.79969) (xy 138.873352 -255.747397)
			(xy 138.865595 -255.69345) (xy 138.671803 -255.69345) (xy 138.691765 -255.723622) (xy 138.715437 -255.774119)
			(xy 138.731505 -255.827526) (xy 138.739625 -255.882702) (xy 138.740134 -255.910588) (xy 138.739625 -255.938474)
			(xy 138.731505 -255.99365) (xy 138.715437 -256.047057) (xy 138.691765 -256.097554) (xy 138.660992 -256.144067)
			(xy 138.623775 -256.185604) (xy 138.580907 -256.221279) (xy 138.533301 -256.250333) (xy 138.481972 -256.272145)
			(xy 138.428015 -256.286251) (xy 138.372578 -256.292351) (xy 138.316844 -256.290314) (xy 138.262001 -256.280184)
			(xy 138.209217 -256.262177) (xy 138.159617 -256.236676) (xy 138.114259 -256.204225) (xy 138.07411 -256.165516)
			(xy 138.040024 -256.121373) (xy 138.012728 -256.072738) (xy 137.992805 -256.020647) (xy 137.980679 -255.96621)
			(xy 137.976608 -255.910588) (xy 136.430258 -255.910588) (xy 136.430258 -256.479657) (xy 141.379325 -256.479657)
			(xy 141.379325 -256.425143) (xy 141.387084 -256.371183) (xy 141.402444 -256.318878) (xy 141.425091 -256.26929)
			(xy 141.454566 -256.223431) (xy 141.490268 -256.182234) (xy 141.53147 -256.146537) (xy 141.577332 -256.117068)
			(xy 141.626923 -256.094427) (xy 141.67923 -256.079074) (xy 141.733191 -256.071322) (xy 141.760448 -256.070862)
			(xy 141.760702 -256.070862) (xy 141.786996 -256.071332) (xy 141.839084 -256.078576) (xy 141.889685 -256.092901)
			(xy 141.937841 -256.114035) (xy 141.982641 -256.141577) (xy 142.023237 -256.175007) (xy 142.041372 -256.194052)
			(xy 142.048962 -256.201472) (xy 142.068366 -256.210011) (xy 142.078964 -256.210562) (xy 142.153132 -256.210562)
			(xy 142.163767 -256.210173) (xy 142.183232 -256.201611) (xy 142.190724 -256.194052) (xy 142.208842 -256.174986)
			(xy 142.249425 -256.141528) (xy 142.294223 -256.113969) (xy 142.342386 -256.092831) (xy 142.392997 -256.078517)
			(xy 142.445096 -256.071297) (xy 142.471394 -256.070862) (xy 142.471648 -256.070862) (xy 142.498895 -256.071411)
			(xy 142.552833 -256.079173) (xy 142.605118 -256.094531) (xy 142.613912 -256.098548) (xy 143.98193 -256.098548)
			(xy 143.986001 -256.042926) (xy 143.998127 -255.988489) (xy 144.01805 -255.936398) (xy 144.045346 -255.887763)
			(xy 144.079432 -255.84362) (xy 144.119581 -255.804911) (xy 144.164939 -255.77246) (xy 144.214539 -255.746959)
			(xy 144.267323 -255.728952) (xy 144.322166 -255.718822) (xy 144.3779 -255.716785) (xy 144.433337 -255.722885)
			(xy 144.487294 -255.736991) (xy 144.538623 -255.758803) (xy 144.586229 -255.787857) (xy 144.629097 -255.823532)
			(xy 144.666314 -255.865069) (xy 144.697087 -255.911582) (xy 144.720759 -255.962079) (xy 144.736827 -256.015486)
			(xy 144.744947 -256.070662) (xy 144.745456 -256.098548) (xy 144.744947 -256.126434) (xy 144.736827 -256.18161)
			(xy 144.720759 -256.235017) (xy 144.697087 -256.285514) (xy 144.666314 -256.332027) (xy 144.629097 -256.373564)
			(xy 144.626271 -256.375916) (xy 144.86966 -256.375916) (xy 144.873731 -256.320294) (xy 144.885857 -256.265857)
			(xy 144.90578 -256.213766) (xy 144.933076 -256.165131) (xy 144.967162 -256.120988) (xy 145.007311 -256.082279)
			(xy 145.052669 -256.049828) (xy 145.102269 -256.024327) (xy 145.155053 -256.00632) (xy 145.209896 -255.99619)
			(xy 145.26563 -255.994153) (xy 145.321067 -256.000253) (xy 145.375024 -256.014359) (xy 145.426353 -256.036171)
			(xy 145.473959 -256.065225) (xy 145.516827 -256.1009) (xy 145.554044 -256.142437) (xy 145.584817 -256.18895)
			(xy 145.608489 -256.239447) (xy 145.624557 -256.292854) (xy 145.632677 -256.34803) (xy 145.633186 -256.375916)
			(xy 146.345146 -256.375916) (xy 146.349217 -256.320294) (xy 146.361343 -256.265857) (xy 146.381266 -256.213766)
			(xy 146.408562 -256.165131) (xy 146.442648 -256.120988) (xy 146.482797 -256.082279) (xy 146.528155 -256.049828)
			(xy 146.577755 -256.024327) (xy 146.630539 -256.00632) (xy 146.685382 -255.99619) (xy 146.741116 -255.994153)
			(xy 146.796553 -256.000253) (xy 146.85051 -256.014359) (xy 146.901839 -256.036171) (xy 146.949445 -256.065225)
			(xy 146.992313 -256.1009) (xy 147.02953 -256.142437) (xy 147.060303 -256.18895) (xy 147.083975 -256.239447)
			(xy 147.100043 -256.292854) (xy 147.108163 -256.34803) (xy 147.108672 -256.375916) (xy 147.234146 -256.375916)
			(xy 147.238217 -256.320294) (xy 147.250343 -256.265857) (xy 147.270266 -256.213766) (xy 147.297562 -256.165131)
			(xy 147.331648 -256.120988) (xy 147.371797 -256.082279) (xy 147.417155 -256.049828) (xy 147.466755 -256.024327)
			(xy 147.519539 -256.00632) (xy 147.574382 -255.99619) (xy 147.630116 -255.994153) (xy 147.685553 -256.000253)
			(xy 147.73951 -256.014359) (xy 147.790839 -256.036171) (xy 147.838445 -256.065225) (xy 147.881313 -256.1009)
			(xy 147.91853 -256.142437) (xy 147.949303 -256.18895) (xy 147.972975 -256.239447) (xy 147.989043 -256.292854)
			(xy 147.997163 -256.34803) (xy 147.997672 -256.375916) (xy 147.997163 -256.403802) (xy 147.989043 -256.458978)
			(xy 147.972975 -256.512385) (xy 147.949303 -256.562882) (xy 147.91853 -256.609395) (xy 147.881313 -256.650932)
			(xy 147.838445 -256.686607) (xy 147.790839 -256.715661) (xy 147.73951 -256.737473) (xy 147.685553 -256.751579)
			(xy 147.630116 -256.757679) (xy 147.574382 -256.755642) (xy 147.519539 -256.745512) (xy 147.466755 -256.727505)
			(xy 147.417155 -256.702004) (xy 147.371797 -256.669553) (xy 147.331648 -256.630844) (xy 147.297562 -256.586701)
			(xy 147.270266 -256.538066) (xy 147.250343 -256.485975) (xy 147.238217 -256.431538) (xy 147.234146 -256.375916)
			(xy 147.108672 -256.375916) (xy 147.108163 -256.403802) (xy 147.100043 -256.458978) (xy 147.083975 -256.512385)
			(xy 147.060303 -256.562882) (xy 147.02953 -256.609395) (xy 146.992313 -256.650932) (xy 146.949445 -256.686607)
			(xy 146.901839 -256.715661) (xy 146.85051 -256.737473) (xy 146.796553 -256.751579) (xy 146.741116 -256.757679)
			(xy 146.685382 -256.755642) (xy 146.630539 -256.745512) (xy 146.577755 -256.727505) (xy 146.528155 -256.702004)
			(xy 146.482797 -256.669553) (xy 146.442648 -256.630844) (xy 146.408562 -256.586701) (xy 146.381266 -256.538066)
			(xy 146.361343 -256.485975) (xy 146.349217 -256.431538) (xy 146.345146 -256.375916) (xy 145.633186 -256.375916)
			(xy 145.632677 -256.403802) (xy 145.624557 -256.458978) (xy 145.608489 -256.512385) (xy 145.584817 -256.562882)
			(xy 145.554044 -256.609395) (xy 145.516827 -256.650932) (xy 145.473959 -256.686607) (xy 145.426353 -256.715661)
			(xy 145.375024 -256.737473) (xy 145.321067 -256.751579) (xy 145.26563 -256.757679) (xy 145.209896 -256.755642)
			(xy 145.155053 -256.745512) (xy 145.102269 -256.727505) (xy 145.052669 -256.702004) (xy 145.007311 -256.669553)
			(xy 144.967162 -256.630844) (xy 144.933076 -256.586701) (xy 144.90578 -256.538066) (xy 144.885857 -256.485975)
			(xy 144.873731 -256.431538) (xy 144.86966 -256.375916) (xy 144.626271 -256.375916) (xy 144.586229 -256.409239)
			(xy 144.538623 -256.438293) (xy 144.487294 -256.460105) (xy 144.433337 -256.474211) (xy 144.3779 -256.480311)
			(xy 144.322166 -256.478274) (xy 144.267323 -256.468144) (xy 144.214539 -256.450137) (xy 144.164939 -256.424636)
			(xy 144.119581 -256.392185) (xy 144.079432 -256.353476) (xy 144.045346 -256.309333) (xy 144.01805 -256.260698)
			(xy 143.998127 -256.208607) (xy 143.986001 -256.15417) (xy 143.98193 -256.098548) (xy 142.613912 -256.098548)
			(xy 142.654685 -256.117173) (xy 142.700526 -256.146638) (xy 142.741707 -256.182327) (xy 142.777391 -256.223513)
			(xy 142.80685 -256.269357) (xy 142.829486 -256.318927) (xy 142.844837 -256.371214) (xy 142.852592 -256.425153)
			(xy 142.852592 -256.479647) (xy 142.844837 -256.533586) (xy 142.829486 -256.585873) (xy 142.80685 -256.635443)
			(xy 142.777391 -256.681287) (xy 142.741707 -256.722473) (xy 142.700526 -256.758162) (xy 142.654685 -256.787627)
			(xy 142.605118 -256.810269) (xy 142.552833 -256.825627) (xy 142.498895 -256.833389) (xy 142.471648 -256.833878)
			(xy 142.471394 -256.833878) (xy 142.445099 -256.83343) (xy 142.393009 -256.826184) (xy 142.342407 -256.811856)
			(xy 142.294251 -256.790719) (xy 142.249452 -256.763171) (xy 142.208858 -256.729736) (xy 142.190724 -256.710688)
			(xy 142.183144 -256.703257) (xy 142.163732 -256.694726) (xy 142.153132 -256.694178) (xy 142.078964 -256.694178)
			(xy 142.068332 -256.694583) (xy 142.048868 -256.703136) (xy 142.041372 -256.710688) (xy 142.023264 -256.729764)
			(xy 141.982678 -256.763219) (xy 141.937877 -256.790776) (xy 141.889713 -256.811912) (xy 141.839101 -256.826225)
			(xy 141.787001 -256.833443) (xy 141.760702 -256.833878) (xy 141.760448 -256.833878) (xy 141.733191 -256.833478)
			(xy 141.67923 -256.825726) (xy 141.626923 -256.810373) (xy 141.577332 -256.787732) (xy 141.53147 -256.758263)
			(xy 141.490268 -256.722566) (xy 141.454566 -256.681369) (xy 141.425091 -256.63551) (xy 141.402444 -256.585923)
			(xy 141.387084 -256.533617) (xy 141.379325 -256.479657) (xy 136.430258 -256.479657) (xy 136.430258 -256.987548)
			(xy 143.98193 -256.987548) (xy 143.986001 -256.931926) (xy 143.998127 -256.877489) (xy 144.01805 -256.825398)
			(xy 144.045346 -256.776763) (xy 144.079432 -256.73262) (xy 144.119581 -256.693911) (xy 144.164939 -256.66146)
			(xy 144.214539 -256.635959) (xy 144.267323 -256.617952) (xy 144.322166 -256.607822) (xy 144.3779 -256.605785)
			(xy 144.433337 -256.611885) (xy 144.487294 -256.625991) (xy 144.538623 -256.647803) (xy 144.586229 -256.676857)
			(xy 144.629097 -256.712532) (xy 144.666314 -256.754069) (xy 144.697087 -256.800582) (xy 144.720759 -256.851079)
			(xy 144.736827 -256.904486) (xy 144.744947 -256.959662) (xy 144.745456 -256.987548) (xy 144.744947 -257.015434)
			(xy 144.736827 -257.07061) (xy 144.720759 -257.124017) (xy 144.714243 -257.137916) (xy 150.396194 -257.137916)
			(xy 150.396727 -257.108566) (xy 150.405761 -257.050565) (xy 150.423572 -256.994632) (xy 150.44974 -256.942086)
			(xy 150.483646 -256.894169) (xy 150.524492 -256.85201) (xy 150.547578 -256.833878) (xy 150.547832 -256.833624)
			(xy 150.55723 -256.826258) (xy 150.56231 -256.816098) (xy 150.564821 -256.810916) (xy 150.567636 -256.799753)
			(xy 150.567898 -256.794) (xy 150.569168 -256.701798) (xy 150.559262 -256.680716) (xy 150.550118 -256.67335)
			(xy 150.528267 -256.655147) (xy 150.489727 -256.613328) (xy 150.45782 -256.566252) (xy 150.433253 -256.514962)
			(xy 150.41657 -256.460593) (xy 150.408142 -256.404351) (xy 150.407624 -256.375916) (xy 150.40811 -256.348665)
			(xy 150.415866 -256.294717) (xy 150.431221 -256.242422) (xy 150.453863 -256.192845) (xy 150.483329 -256.146995)
			(xy 150.51902 -256.105804) (xy 150.560211 -256.070113) (xy 150.606061 -256.040647) (xy 150.655638 -256.018005)
			(xy 150.707933 -256.00265) (xy 150.761881 -255.994894) (xy 150.816383 -255.994894) (xy 150.870331 -256.00265)
			(xy 150.922626 -256.018005) (xy 150.972203 -256.040647) (xy 151.018053 -256.070113) (xy 151.059244 -256.105804)
			(xy 151.094935 -256.146995) (xy 151.124401 -256.192845) (xy 151.147043 -256.242422) (xy 151.162398 -256.294717)
			(xy 151.170154 -256.348665) (xy 151.17064 -256.375916) (xy 151.170045 -256.405263) (xy 151.161022 -256.463261)
			(xy 151.143222 -256.519192) (xy 151.117066 -256.571738) (xy 151.083171 -256.619657) (xy 151.042336 -256.661819)
			(xy 151.019256 -256.679954) (xy 151.019002 -256.680208) (xy 151.009604 -256.687574) (xy 151.004524 -256.697734)
			(xy 151.002036 -256.702926) (xy 150.999206 -256.714082) (xy 150.998936 -256.719832) (xy 150.997666 -256.812034)
			(xy 151.007572 -256.833116) (xy 151.016716 -256.840482) (xy 151.038541 -256.858714) (xy 151.077082 -256.900528)
			(xy 151.108991 -256.947598) (xy 151.133562 -256.998883) (xy 151.15025 -257.053245) (xy 151.158687 -257.109483)
			(xy 151.15921 -257.137916) (xy 151.792684 -257.137916) (xy 151.796755 -257.082294) (xy 151.808881 -257.027857)
			(xy 151.828804 -256.975766) (xy 151.8561 -256.927131) (xy 151.890186 -256.882988) (xy 151.930335 -256.844279)
			(xy 151.975693 -256.811828) (xy 152.025293 -256.786327) (xy 152.078077 -256.76832) (xy 152.13292 -256.75819)
			(xy 152.188654 -256.756153) (xy 152.244091 -256.762253) (xy 152.298048 -256.776359) (xy 152.349377 -256.798171)
			(xy 152.396983 -256.827225) (xy 152.439851 -256.8629) (xy 152.477068 -256.904437) (xy 152.507841 -256.95095)
			(xy 152.531513 -257.001447) (xy 152.547581 -257.054854) (xy 152.555701 -257.11003) (xy 152.55621 -257.137916)
			(xy 152.679144 -257.137916) (xy 152.683215 -257.082294) (xy 152.695341 -257.027857) (xy 152.715264 -256.975766)
			(xy 152.74256 -256.927131) (xy 152.776646 -256.882988) (xy 152.816795 -256.844279) (xy 152.862153 -256.811828)
			(xy 152.911753 -256.786327) (xy 152.964537 -256.76832) (xy 153.01938 -256.75819) (xy 153.075114 -256.756153)
			(xy 153.130551 -256.762253) (xy 153.184508 -256.776359) (xy 153.235837 -256.798171) (xy 153.283443 -256.827225)
			(xy 153.326311 -256.8629) (xy 153.363528 -256.904437) (xy 153.394301 -256.95095) (xy 153.417973 -257.001447)
			(xy 153.434041 -257.054854) (xy 153.442161 -257.11003) (xy 153.44267 -257.137916) (xy 153.442161 -257.165802)
			(xy 153.434041 -257.220978) (xy 153.417973 -257.274385) (xy 153.394301 -257.324882) (xy 153.363528 -257.371395)
			(xy 153.326311 -257.412932) (xy 153.283443 -257.448607) (xy 153.235837 -257.477661) (xy 153.184508 -257.499473)
			(xy 153.130551 -257.513579) (xy 153.075114 -257.519679) (xy 153.01938 -257.517642) (xy 152.964537 -257.507512)
			(xy 152.911753 -257.489505) (xy 152.862153 -257.464004) (xy 152.816795 -257.431553) (xy 152.776646 -257.392844)
			(xy 152.74256 -257.348701) (xy 152.715264 -257.300066) (xy 152.695341 -257.247975) (xy 152.683215 -257.193538)
			(xy 152.679144 -257.137916) (xy 152.55621 -257.137916) (xy 152.555701 -257.165802) (xy 152.547581 -257.220978)
			(xy 152.531513 -257.274385) (xy 152.507841 -257.324882) (xy 152.477068 -257.371395) (xy 152.439851 -257.412932)
			(xy 152.396983 -257.448607) (xy 152.349377 -257.477661) (xy 152.298048 -257.499473) (xy 152.244091 -257.513579)
			(xy 152.188654 -257.519679) (xy 152.13292 -257.517642) (xy 152.078077 -257.507512) (xy 152.025293 -257.489505)
			(xy 151.975693 -257.464004) (xy 151.930335 -257.431553) (xy 151.890186 -257.392844) (xy 151.8561 -257.348701)
			(xy 151.828804 -257.300066) (xy 151.808881 -257.247975) (xy 151.796755 -257.193538) (xy 151.792684 -257.137916)
			(xy 151.15921 -257.137916) (xy 151.158724 -257.165167) (xy 151.150968 -257.219115) (xy 151.135613 -257.27141)
			(xy 151.112971 -257.320987) (xy 151.083505 -257.366837) (xy 151.047814 -257.408028) (xy 151.006623 -257.443719)
			(xy 150.960773 -257.473185) (xy 150.911196 -257.495827) (xy 150.858901 -257.511182) (xy 150.804953 -257.518938)
			(xy 150.750451 -257.518938) (xy 150.696503 -257.511182) (xy 150.644208 -257.495827) (xy 150.594631 -257.473185)
			(xy 150.548781 -257.443719) (xy 150.50759 -257.408028) (xy 150.471899 -257.366837) (xy 150.442433 -257.320987)
			(xy 150.419791 -257.27141) (xy 150.404436 -257.219115) (xy 150.39668 -257.165167) (xy 150.396194 -257.137916)
			(xy 144.714243 -257.137916) (xy 144.697087 -257.174514) (xy 144.666314 -257.221027) (xy 144.629097 -257.262564)
			(xy 144.586229 -257.298239) (xy 144.538623 -257.327293) (xy 144.487294 -257.349105) (xy 144.433337 -257.363211)
			(xy 144.3779 -257.369311) (xy 144.322166 -257.367274) (xy 144.267323 -257.357144) (xy 144.214539 -257.339137)
			(xy 144.164939 -257.313636) (xy 144.119581 -257.281185) (xy 144.079432 -257.242476) (xy 144.045346 -257.198333)
			(xy 144.01805 -257.149698) (xy 143.998127 -257.097607) (xy 143.986001 -257.04317) (xy 143.98193 -256.987548)
			(xy 136.430258 -256.987548) (xy 136.430258 -257.474212) (xy 138.071858 -257.474212) (xy 138.075929 -257.41859)
			(xy 138.088055 -257.364153) (xy 138.107978 -257.312062) (xy 138.135274 -257.263427) (xy 138.16936 -257.219284)
			(xy 138.209509 -257.180575) (xy 138.254867 -257.148124) (xy 138.304467 -257.122623) (xy 138.357251 -257.104616)
			(xy 138.412094 -257.094486) (xy 138.467828 -257.092449) (xy 138.523265 -257.098549) (xy 138.577222 -257.112655)
			(xy 138.628551 -257.134467) (xy 138.676157 -257.163521) (xy 138.719025 -257.199196) (xy 138.756242 -257.240733)
			(xy 138.787015 -257.287246) (xy 138.810687 -257.337743) (xy 138.826755 -257.39115) (xy 138.834875 -257.446326)
			(xy 138.835384 -257.474212) (xy 138.834875 -257.502098) (xy 138.826755 -257.557274) (xy 138.810687 -257.610681)
			(xy 138.787015 -257.661178) (xy 138.756242 -257.707691) (xy 138.719025 -257.749228) (xy 138.676157 -257.784903)
			(xy 138.628551 -257.813957) (xy 138.577222 -257.835769) (xy 138.523265 -257.849875) (xy 138.467828 -257.855975)
			(xy 138.412094 -257.853938) (xy 138.357251 -257.843808) (xy 138.304467 -257.825801) (xy 138.254867 -257.8003)
			(xy 138.209509 -257.767849) (xy 138.16936 -257.72914) (xy 138.135274 -257.684997) (xy 138.107978 -257.636362)
			(xy 138.088055 -257.584271) (xy 138.075929 -257.529834) (xy 138.071858 -257.474212) (xy 136.430258 -257.474212)
			(xy 136.430258 -258.783328) (xy 136.43075 -258.793335) (xy 136.438413 -258.811824) (xy 136.452564 -258.825979)
			(xy 136.471051 -258.833647) (xy 136.481058 -258.834128)
		)
		(stroke
			(width 0)
			(type solid)
		)
		(fill yes)
		(layer "In7.Cu")
		(net "P1V8_PEX")
	)
	(gr_poly
		(pts
			(xy 200.481692 -418.081968) (xy 200.538276 -418.081432) (xy 200.651116 -418.072836) (xy 200.76298 -418.055715)
			(xy 200.873227 -418.030169) (xy 200.98122 -417.996343) (xy 201.086341 -417.954433) (xy 201.187984 -417.904678)
			(xy 201.285565 -417.847366) (xy 201.378524 -417.782825) (xy 201.466326 -417.711427) (xy 201.548466 -417.633582)
			(xy 201.586846 -417.592002) (xy 201.634058 -417.54062) (xy 201.733379 -417.442584) (xy 201.837997 -417.350223)
			(xy 201.947589 -417.26382) (xy 202.061814 -417.183644) (xy 202.18032 -417.109943) (xy 202.302741 -417.042944)
			(xy 202.428697 -416.982855) (xy 202.557798 -416.929861) (xy 202.689647 -416.884127) (xy 202.823834 -416.845794)
			(xy 202.959945 -416.81498) (xy 203.097558 -416.791782) (xy 203.236248 -416.77627) (xy 203.375587 -416.768492)
			(xy 203.445364 -416.768026) (xy 271.794732 -416.768026) (xy 271.864502 -416.768512) (xy 272.003824 -416.776289)
			(xy 272.142499 -416.791801) (xy 272.280097 -416.814999) (xy 272.416192 -416.845812) (xy 272.550363 -416.884144)
			(xy 272.682195 -416.929877) (xy 272.811281 -416.982869) (xy 272.937221 -417.042957) (xy 273.059624 -417.109954)
			(xy 273.178113 -417.183654) (xy 273.292321 -417.263827) (xy 273.401895 -417.350227) (xy 273.506495 -417.442585)
			(xy 273.605798 -417.540617) (xy 273.652996 -417.592002) (xy 273.691387 -417.633573) (xy 273.773525 -417.71142)
			(xy 273.861325 -417.782821) (xy 273.954282 -417.847364) (xy 274.051862 -417.90468) (xy 274.153504 -417.954438)
			(xy 274.258623 -417.996352) (xy 274.366616 -418.030181) (xy 274.476862 -418.055732) (xy 274.588726 -418.072856)
			(xy 274.701566 -418.081457) (xy 274.75815 -418.081968) (xy 465.600034 -418.081968) (xy 465.65584 -418.081445)
			(xy 465.767139 -418.073102) (xy 465.877504 -418.056464) (xy 465.986317 -418.031626) (xy 466.092969 -417.998726)
			(xy 466.196865 -417.957947) (xy 466.297422 -417.909518) (xy 466.39408 -417.85371) (xy 466.486296 -417.790835)
			(xy 466.573556 -417.721245) (xy 466.655372 -417.645328) (xy 466.731285 -417.563509) (xy 466.800872 -417.476246)
			(xy 466.863743 -417.384027) (xy 466.919547 -417.287367) (xy 466.967972 -417.186808) (xy 467.008746 -417.082911)
			(xy 467.041642 -416.976257) (xy 467.066476 -416.867443) (xy 467.083109 -416.757078) (xy 467.091447 -416.645778)
			(xy 467.09203 -416.589972) (xy 467.09203 -246.488204) (xy 467.091555 -246.434943) (xy 467.083957 -246.328691)
			(xy 467.068799 -246.223252) (xy 467.046159 -246.119163) (xy 467.016151 -246.016954) (xy 466.97893 -245.917146)
			(xy 466.934683 -245.820247) (xy 466.883638 -245.726751) (xy 466.826053 -245.637134) (xy 466.762223 -245.551854)
			(xy 466.692472 -245.471343) (xy 466.65515 -245.433342) (xy 464.026504 -242.80495) (xy 463.977112 -242.75486)
			(xy 463.883366 -242.649956) (xy 463.795648 -242.539961) (xy 463.714235 -242.425221) (xy 463.639382 -242.306097)
			(xy 463.571326 -242.182964) (xy 463.510281 -242.056209) (xy 463.456438 -241.926231) (xy 463.409967 -241.793439)
			(xy 463.371014 -241.65825) (xy 463.339701 -241.52109) (xy 463.316128 -241.382391) (xy 463.300367 -241.242587)
			(xy 463.29247 -241.10212) (xy 463.291936 -241.031776) (xy 463.291936 -87.588344) (xy 463.292417 -87.517998)
			(xy 463.3003 -87.377526) (xy 463.316048 -87.237717) (xy 463.339614 -87.099011) (xy 463.370921 -86.961846)
			(xy 463.409872 -86.826652) (xy 463.456344 -86.693856) (xy 463.510191 -86.563875) (xy 463.571243 -86.437119)
			(xy 463.639308 -86.313987) (xy 463.714172 -86.194865) (xy 463.7956 -86.08013) (xy 463.883333 -85.970143)
			(xy 463.977098 -85.865249) (xy 464.026504 -85.81517) (xy 466.65515 -83.186524) (xy 466.692477 -83.148543)
			(xy 466.762224 -83.068056) (xy 466.826051 -82.982799) (xy 466.883632 -82.893206) (xy 466.934676 -82.799733)
			(xy 466.978921 -82.702856) (xy 467.016141 -82.60307) (xy 467.046149 -82.500883) (xy 467.068789 -82.396815)
			(xy 467.083947 -82.291397) (xy 467.091547 -82.185167) (xy 467.09203 -82.131916) (xy 467.09203 -1.999996)
			(xy 467.091508 -1.944189) (xy 467.083167 -1.832886) (xy 467.066532 -1.722518) (xy 467.041695 -1.613701)
			(xy 467.008796 -1.507045) (xy 466.968019 -1.403146) (xy 466.919592 -1.302584) (xy 466.863785 -1.205923)
			(xy 466.800911 -1.113702) (xy 466.731321 -1.026437) (xy 466.655404 -0.944617) (xy 466.573586 -0.868699)
			(xy 466.486322 -0.799107) (xy 466.394103 -0.736231) (xy 466.297442 -0.680422) (xy 466.196882 -0.631993)
			(xy 466.092983 -0.591214) (xy 465.986328 -0.558313) (xy 465.877512 -0.533474) (xy 465.767144 -0.516836)
			(xy 465.655841 -0.508493) (xy 465.600034 -0.508) (xy 446.265046 -0.508) (xy 446.209237 -0.508508)
			(xy 446.097932 -0.516845) (xy 445.987561 -0.533478) (xy 445.878741 -0.558312) (xy 445.772082 -0.591209)
			(xy 445.668179 -0.631985) (xy 445.567615 -0.680412) (xy 445.47095 -0.736218) (xy 445.378726 -0.799093)
			(xy 445.291459 -0.868683) (xy 445.209636 -0.944601) (xy 445.133716 -1.026421) (xy 445.064123 -1.113686)
			(xy 445.001245 -1.205908) (xy 444.945435 -1.30257) (xy 444.897005 -1.403134) (xy 444.856226 -1.507035)
			(xy 444.823325 -1.613693) (xy 444.798487 -1.722512) (xy 444.781851 -1.832882) (xy 444.773509 -1.944187)
			(xy 444.77305 -1.999996) (xy 444.77305 -11.850116) (xy 444.772563 -11.904445) (xy 444.764743 -12.01282)
			(xy 444.749144 -12.120352) (xy 444.725847 -12.226483) (xy 444.694973 -12.330662) (xy 444.656682 -12.432349)
			(xy 444.611173 -12.531017) (xy 444.558681 -12.626154) (xy 444.49948 -12.717267) (xy 444.433875 -12.803883)
			(xy 444.3984 -12.845034) (xy 444.3984 -12.869164) (xy 444.399924 -12.870688) (xy 445.002666 -12.870688)
			(xy 445.036079 -12.812735) (xy 445.096046 -12.69314) (xy 445.147945 -12.569831) (xy 445.191548 -12.443349)
			(xy 445.226662 -12.314252) (xy 445.253132 -12.183111) (xy 445.270842 -12.050501) (xy 445.279714 -11.917009)
			(xy 445.280288 -11.850116) (xy 445.280288 -1.999996) (xy 445.280813 -1.954511) (xy 445.289205 -1.86393)
			(xy 445.305918 -1.774509) (xy 445.33081 -1.687012) (xy 445.363666 -1.602183) (xy 445.404209 -1.520748)
			(xy 445.452091 -1.4434) (xy 445.506904 -1.370799) (xy 445.568182 -1.303564) (xy 445.6354 -1.242269)
			(xy 445.707987 -1.187437) (xy 445.785322 -1.139534) (xy 445.866747 -1.098971) (xy 445.951567 -1.066092)
			(xy 446.039058 -1.041178) (xy 446.128474 -1.024441) (xy 446.219053 -1.016025) (xy 446.264538 -1.015492)
			(xy 465.600034 -1.015492) (xy 465.64553 -1.016018) (xy 465.736134 -1.024416) (xy 465.825577 -1.041135)
			(xy 465.913097 -1.066034) (xy 465.997946 -1.0989) (xy 466.079402 -1.139453) (xy 466.15677 -1.187348)
			(xy 466.229389 -1.242176) (xy 466.296641 -1.303468) (xy 466.357952 -1.370703) (xy 466.412799 -1.443308)
			(xy 466.460715 -1.520662) (xy 466.501291 -1.602107) (xy 466.53418 -1.686947) (xy 466.559103 -1.77446)
			(xy 466.575847 -1.863898) (xy 466.584269 -1.9545) (xy 466.584792 -1.999996) (xy 466.584792 -82.131916)
			(xy 466.58434 -82.174869) (xy 466.576857 -82.260449) (xy 466.561942 -82.345051) (xy 466.539707 -82.42803)
			(xy 466.510322 -82.508754) (xy 466.474011 -82.586609) (xy 466.43105 -82.661002) (xy 466.381767 -82.731366)
			(xy 466.326536 -82.797165) (xy 466.296502 -82.827876) (xy 463.667856 -85.456522) (xy 463.612395 -85.512692)
			(xy 463.50675 -85.630005) (xy 463.407391 -85.752687) (xy 463.314588 -85.880401) (xy 463.228597 -86.012797)
			(xy 463.149654 -86.149512) (xy 463.077975 -86.290172) (xy 463.013756 -86.43439) (xy 462.957173 -86.581772)
			(xy 462.908382 -86.731914) (xy 462.867516 -86.884404) (xy 462.834688 -87.038823) (xy 462.809987 -87.194749)
			(xy 462.793481 -87.351755) (xy 462.785215 -87.509409) (xy 462.784698 -87.588344) (xy 462.784444 -87.588344)
			(xy 462.784444 -241.031776) (xy 462.784698 -241.031776) (xy 462.785221 -241.11071) (xy 462.793497 -241.268361)
			(xy 462.810012 -241.425363) (xy 462.834721 -241.581286) (xy 462.867556 -241.735702) (xy 462.908426 -241.888188)
			(xy 462.95722 -242.038326) (xy 463.013805 -242.185705) (xy 463.078025 -242.329921) (xy 463.149704 -242.470579)
			(xy 463.228645 -242.607292) (xy 463.314633 -242.739687) (xy 463.407432 -242.867401) (xy 463.506787 -242.990083)
			(xy 463.612426 -243.107398) (xy 463.667856 -243.163598) (xy 466.296502 -245.79199) (xy 466.326545 -245.822708)
			(xy 466.381767 -245.888545) (xy 466.431041 -245.958944) (xy 466.473992 -246.033368) (xy 466.510295 -246.111253)
			(xy 466.539672 -246.192005) (xy 466.561901 -246.27501) (xy 466.576812 -246.359636) (xy 466.584291 -246.445239)
			(xy 466.584792 -246.488204) (xy 466.584792 -303.727612) (xy 465.7852 -304.527204) (xy 449.2625 -304.527204)
			(xy 449.25243 -304.527627) (xy 449.233826 -304.535342) (xy 449.226432 -304.54219) (xy 448.90817 -304.860198)
			(xy 448.90077 -304.86704) (xy 448.882172 -304.874764) (xy 448.872102 -304.875184) (xy 444.928498 -304.875184)
			(xy 444.918428 -304.875607) (xy 444.899822 -304.88332) (xy 444.89243 -304.89017) (xy 443.854586 -305.928014)
			(xy 443.84722 -305.935126) (xy 443.8396 -305.953922) (xy 443.8396 -306.158646) (xy 459.899002 -306.158646)
			(xy 459.903073 -306.103024) (xy 459.915199 -306.048587) (xy 459.935122 -305.996496) (xy 459.962418 -305.947861)
			(xy 459.996504 -305.903718) (xy 460.036653 -305.865009) (xy 460.082011 -305.832558) (xy 460.131611 -305.807057)
			(xy 460.184395 -305.78905) (xy 460.239238 -305.77892) (xy 460.294972 -305.776883) (xy 460.350409 -305.782983)
			(xy 460.404366 -305.797089) (xy 460.455695 -305.818901) (xy 460.503301 -305.847955) (xy 460.546169 -305.88363)
			(xy 460.583386 -305.925167) (xy 460.614159 -305.97168) (xy 460.637831 -306.022177) (xy 460.653899 -306.075584)
			(xy 460.662019 -306.13076) (xy 460.662528 -306.158646) (xy 460.662019 -306.186532) (xy 460.653899 -306.241708)
			(xy 460.637831 -306.295115) (xy 460.614159 -306.345612) (xy 460.583386 -306.392125) (xy 460.546169 -306.433662)
			(xy 460.503301 -306.469337) (xy 460.455695 -306.498391) (xy 460.404366 -306.520203) (xy 460.350409 -306.534309)
			(xy 460.294972 -306.540409) (xy 460.239238 -306.538372) (xy 460.184395 -306.528242) (xy 460.131611 -306.510235)
			(xy 460.082011 -306.484734) (xy 460.036653 -306.452283) (xy 459.996504 -306.413574) (xy 459.962418 -306.369431)
			(xy 459.935122 -306.320796) (xy 459.915199 -306.268705) (xy 459.903073 -306.214268) (xy 459.899002 -306.158646)
			(xy 443.8396 -306.158646) (xy 443.8396 -306.86756) (xy 452.570594 -306.86756) (xy 452.574665 -306.811938)
			(xy 452.586791 -306.757501) (xy 452.606714 -306.70541) (xy 452.63401 -306.656775) (xy 452.668096 -306.612632)
			(xy 452.708245 -306.573923) (xy 452.753603 -306.541472) (xy 452.803203 -306.515971) (xy 452.855987 -306.497964)
			(xy 452.91083 -306.487834) (xy 452.966564 -306.485797) (xy 453.022001 -306.491897) (xy 453.075958 -306.506003)
			(xy 453.127287 -306.527815) (xy 453.174893 -306.556869) (xy 453.217761 -306.592544) (xy 453.254978 -306.634081)
			(xy 453.285751 -306.680594) (xy 453.309423 -306.731091) (xy 453.325491 -306.784498) (xy 453.333611 -306.839674)
			(xy 453.33412 -306.86756) (xy 453.333611 -306.895446) (xy 453.325491 -306.950622) (xy 453.309423 -307.004029)
			(xy 453.285751 -307.054526) (xy 453.254978 -307.101039) (xy 453.217761 -307.142576) (xy 453.174893 -307.178251)
			(xy 453.127287 -307.207305) (xy 453.075958 -307.229117) (xy 453.022001 -307.243223) (xy 452.966564 -307.249323)
			(xy 452.91083 -307.247286) (xy 452.855987 -307.237156) (xy 452.803203 -307.219149) (xy 452.753603 -307.193648)
			(xy 452.708245 -307.161197) (xy 452.668096 -307.122488) (xy 452.63401 -307.078345) (xy 452.606714 -307.02971)
			(xy 452.586791 -306.977619) (xy 452.574665 -306.923182) (xy 452.570594 -306.86756) (xy 443.8396 -306.86756)
			(xy 443.8396 -307.56987) (xy 457.496162 -307.56987) (xy 457.500233 -307.514248) (xy 457.512359 -307.459811)
			(xy 457.532282 -307.40772) (xy 457.559578 -307.359085) (xy 457.593664 -307.314942) (xy 457.633813 -307.276233)
			(xy 457.679171 -307.243782) (xy 457.728771 -307.218281) (xy 457.781555 -307.200274) (xy 457.836398 -307.190144)
			(xy 457.892132 -307.188107) (xy 457.947569 -307.194207) (xy 458.001526 -307.208313) (xy 458.052855 -307.230125)
			(xy 458.100461 -307.259179) (xy 458.143329 -307.294854) (xy 458.180546 -307.336391) (xy 458.211319 -307.382904)
			(xy 458.234991 -307.433401) (xy 458.251059 -307.486808) (xy 458.259179 -307.541984) (xy 458.259688 -307.56987)
			(xy 458.259179 -307.597756) (xy 458.257713 -307.607716) (xy 462.556604 -307.607716) (xy 462.560677 -307.552057)
			(xy 462.572812 -307.497584) (xy 462.592748 -307.445458) (xy 462.620062 -307.39679) (xy 462.65417 -307.352618)
			(xy 462.694347 -307.313883) (xy 462.739735 -307.281411) (xy 462.789367 -307.255893) (xy 462.842187 -307.237874)
			(xy 462.897066 -307.227737) (xy 462.952837 -307.225699) (xy 463.008311 -307.231802) (xy 463.062304 -307.245918)
			(xy 463.113667 -307.267745) (xy 463.161305 -307.296818) (xy 463.204201 -307.332517) (xy 463.241443 -307.374081)
			(xy 463.272237 -307.420625) (xy 463.295925 -307.471156) (xy 463.312003 -307.524598) (xy 463.320129 -307.579812)
			(xy 463.320638 -307.607716) (xy 463.320129 -307.63562) (xy 463.312003 -307.690834) (xy 463.295925 -307.744276)
			(xy 463.272237 -307.794807) (xy 463.241443 -307.841351) (xy 463.204201 -307.882915) (xy 463.161305 -307.918614)
			(xy 463.113667 -307.947687) (xy 463.062304 -307.969514) (xy 463.008311 -307.98363) (xy 462.952837 -307.989733)
			(xy 462.897066 -307.987695) (xy 462.842187 -307.977558) (xy 462.789367 -307.959539) (xy 462.739735 -307.934021)
			(xy 462.694347 -307.901549) (xy 462.65417 -307.862814) (xy 462.620062 -307.818642) (xy 462.592748 -307.769974)
			(xy 462.572812 -307.717848) (xy 462.560677 -307.663375) (xy 462.556604 -307.607716) (xy 458.257713 -307.607716)
			(xy 458.251059 -307.652932) (xy 458.234991 -307.706339) (xy 458.211319 -307.756836) (xy 458.180546 -307.803349)
			(xy 458.143329 -307.844886) (xy 458.100461 -307.880561) (xy 458.052855 -307.909615) (xy 458.001526 -307.931427)
			(xy 457.947569 -307.945533) (xy 457.892132 -307.951633) (xy 457.836398 -307.949596) (xy 457.781555 -307.939466)
			(xy 457.728771 -307.921459) (xy 457.679171 -307.895958) (xy 457.633813 -307.863507) (xy 457.593664 -307.824798)
			(xy 457.559578 -307.780655) (xy 457.532282 -307.73202) (xy 457.512359 -307.679929) (xy 457.500233 -307.625492)
			(xy 457.496162 -307.56987) (xy 443.8396 -307.56987) (xy 443.8396 -308.525672) (xy 458.554072 -308.525672)
			(xy 458.558143 -308.47005) (xy 458.570269 -308.415613) (xy 458.590192 -308.363522) (xy 458.617488 -308.314887)
			(xy 458.651574 -308.270744) (xy 458.691723 -308.232035) (xy 458.737081 -308.199584) (xy 458.786681 -308.174083)
			(xy 458.839465 -308.156076) (xy 458.894308 -308.145946) (xy 458.950042 -308.143909) (xy 459.005479 -308.150009)
			(xy 459.054046 -308.162706) (xy 465.622892 -308.162706) (xy 465.626963 -308.107084) (xy 465.639089 -308.052647)
			(xy 465.659012 -308.000556) (xy 465.686308 -307.951921) (xy 465.720394 -307.907778) (xy 465.760543 -307.869069)
			(xy 465.805901 -307.836618) (xy 465.855501 -307.811117) (xy 465.908285 -307.79311) (xy 465.963128 -307.78298)
			(xy 466.018862 -307.780943) (xy 466.074299 -307.787043) (xy 466.128256 -307.801149) (xy 466.179585 -307.822961)
			(xy 466.227191 -307.852015) (xy 466.270059 -307.88769) (xy 466.307276 -307.929227) (xy 466.338049 -307.97574)
			(xy 466.361721 -308.026237) (xy 466.377789 -308.079644) (xy 466.385909 -308.13482) (xy 466.386418 -308.162706)
			(xy 466.385909 -308.190592) (xy 466.377789 -308.245768) (xy 466.361721 -308.299175) (xy 466.338049 -308.349672)
			(xy 466.307276 -308.396185) (xy 466.270059 -308.437722) (xy 466.227191 -308.473397) (xy 466.179585 -308.502451)
			(xy 466.128256 -308.524263) (xy 466.074299 -308.538369) (xy 466.018862 -308.544469) (xy 465.963128 -308.542432)
			(xy 465.908285 -308.532302) (xy 465.855501 -308.514295) (xy 465.805901 -308.488794) (xy 465.760543 -308.456343)
			(xy 465.720394 -308.417634) (xy 465.686308 -308.373491) (xy 465.659012 -308.324856) (xy 465.639089 -308.272765)
			(xy 465.626963 -308.218328) (xy 465.622892 -308.162706) (xy 459.054046 -308.162706) (xy 459.059436 -308.164115)
			(xy 459.110765 -308.185927) (xy 459.158371 -308.214981) (xy 459.201239 -308.250656) (xy 459.238456 -308.292193)
			(xy 459.269229 -308.338706) (xy 459.292901 -308.389203) (xy 459.308969 -308.44261) (xy 459.317089 -308.497786)
			(xy 459.317598 -308.525672) (xy 459.317089 -308.553558) (xy 459.308969 -308.608734) (xy 459.292901 -308.662141)
			(xy 459.278765 -308.692296) (xy 462.556604 -308.692296) (xy 462.560677 -308.636637) (xy 462.572812 -308.582164)
			(xy 462.592748 -308.530038) (xy 462.620062 -308.48137) (xy 462.65417 -308.437198) (xy 462.694347 -308.398463)
			(xy 462.739735 -308.365991) (xy 462.789367 -308.340473) (xy 462.842187 -308.322454) (xy 462.897066 -308.312317)
			(xy 462.952837 -308.310279) (xy 463.008311 -308.316382) (xy 463.062304 -308.330498) (xy 463.113667 -308.352325)
			(xy 463.161305 -308.381398) (xy 463.204201 -308.417097) (xy 463.241443 -308.458661) (xy 463.272237 -308.505205)
			(xy 463.295925 -308.555736) (xy 463.312003 -308.609178) (xy 463.320129 -308.664392) (xy 463.320638 -308.692296)
			(xy 463.320129 -308.7202) (xy 463.312003 -308.775414) (xy 463.295925 -308.828856) (xy 463.272237 -308.879387)
			(xy 463.241443 -308.925931) (xy 463.204201 -308.967495) (xy 463.161305 -309.003194) (xy 463.113667 -309.032267)
			(xy 463.062304 -309.054094) (xy 463.008311 -309.06821) (xy 462.952837 -309.074313) (xy 462.897066 -309.072275)
			(xy 462.842187 -309.062138) (xy 462.789367 -309.044119) (xy 462.739735 -309.018601) (xy 462.694347 -308.986129)
			(xy 462.65417 -308.947394) (xy 462.620062 -308.903222) (xy 462.592748 -308.854554) (xy 462.572812 -308.802428)
			(xy 462.560677 -308.747955) (xy 462.556604 -308.692296) (xy 459.278765 -308.692296) (xy 459.269229 -308.712638)
			(xy 459.238456 -308.759151) (xy 459.201239 -308.800688) (xy 459.158371 -308.836363) (xy 459.110765 -308.865417)
			(xy 459.059436 -308.887229) (xy 459.005479 -308.901335) (xy 458.950042 -308.907435) (xy 458.894308 -308.905398)
			(xy 458.839465 -308.895268) (xy 458.786681 -308.877261) (xy 458.737081 -308.85176) (xy 458.691723 -308.819309)
			(xy 458.651574 -308.7806) (xy 458.617488 -308.736457) (xy 458.590192 -308.687822) (xy 458.570269 -308.635731)
			(xy 458.558143 -308.581294) (xy 458.554072 -308.525672) (xy 443.8396 -308.525672) (xy 443.8396 -309.141622)
			(xy 460.562196 -309.141622) (xy 460.566267 -309.086) (xy 460.578393 -309.031563) (xy 460.598316 -308.979472)
			(xy 460.625612 -308.930837) (xy 460.659698 -308.886694) (xy 460.699847 -308.847985) (xy 460.745205 -308.815534)
			(xy 460.794805 -308.790033) (xy 460.847589 -308.772026) (xy 460.902432 -308.761896) (xy 460.958166 -308.759859)
			(xy 461.013603 -308.765959) (xy 461.06756 -308.780065) (xy 461.118889 -308.801877) (xy 461.166495 -308.830931)
			(xy 461.209363 -308.866606) (xy 461.24658 -308.908143) (xy 461.277353 -308.954656) (xy 461.301025 -309.005153)
			(xy 461.317093 -309.05856) (xy 461.325213 -309.113736) (xy 461.325722 -309.141622) (xy 461.325213 -309.169508)
			(xy 461.317093 -309.224684) (xy 461.301025 -309.278091) (xy 461.277353 -309.328588) (xy 461.24658 -309.375101)
			(xy 461.209363 -309.416638) (xy 461.166495 -309.452313) (xy 461.118889 -309.481367) (xy 461.06756 -309.503179)
			(xy 461.013603 -309.517285) (xy 460.958166 -309.523385) (xy 460.902432 -309.521348) (xy 460.847589 -309.511218)
			(xy 460.794805 -309.493211) (xy 460.745205 -309.46771) (xy 460.699847 -309.435259) (xy 460.659698 -309.39655)
			(xy 460.625612 -309.352407) (xy 460.598316 -309.303772) (xy 460.578393 -309.251681) (xy 460.566267 -309.197244)
			(xy 460.562196 -309.141622) (xy 443.8396 -309.141622) (xy 443.8396 -310.031892) (xy 456.942188 -310.031892)
			(xy 456.946259 -309.97627) (xy 456.958385 -309.921833) (xy 456.978308 -309.869742) (xy 457.005604 -309.821107)
			(xy 457.03969 -309.776964) (xy 457.079839 -309.738255) (xy 457.125197 -309.705804) (xy 457.174797 -309.680303)
			(xy 457.227581 -309.662296) (xy 457.282424 -309.652166) (xy 457.338158 -309.650129) (xy 457.393595 -309.656229)
			(xy 457.447552 -309.670335) (xy 457.498881 -309.692147) (xy 457.546487 -309.721201) (xy 457.589355 -309.756876)
			(xy 457.626572 -309.798413) (xy 457.657345 -309.844926) (xy 457.668429 -309.86857) (xy 458.657704 -309.86857)
			(xy 458.661775 -309.812948) (xy 458.673901 -309.758511) (xy 458.693824 -309.70642) (xy 458.72112 -309.657785)
			(xy 458.755206 -309.613642) (xy 458.795355 -309.574933) (xy 458.840713 -309.542482) (xy 458.890313 -309.516981)
			(xy 458.943097 -309.498974) (xy 458.99794 -309.488844) (xy 459.053674 -309.486807) (xy 459.109111 -309.492907)
			(xy 459.163068 -309.507013) (xy 459.214397 -309.528825) (xy 459.262003 -309.557879) (xy 459.304871 -309.593554)
			(xy 459.342088 -309.635091) (xy 459.372861 -309.681604) (xy 459.396533 -309.732101) (xy 459.412601 -309.785508)
			(xy 459.420721 -309.840684) (xy 459.42123 -309.86857) (xy 459.420721 -309.896456) (xy 459.412601 -309.951632)
			(xy 459.396533 -310.005039) (xy 459.372861 -310.055536) (xy 459.342088 -310.102049) (xy 459.304871 -310.143586)
			(xy 459.262003 -310.179261) (xy 459.214397 -310.208315) (xy 459.163068 -310.230127) (xy 459.109111 -310.244233)
			(xy 459.053674 -310.250333) (xy 458.99794 -310.248296) (xy 458.943097 -310.238166) (xy 458.890313 -310.220159)
			(xy 458.840713 -310.194658) (xy 458.795355 -310.162207) (xy 458.755206 -310.123498) (xy 458.72112 -310.079355)
			(xy 458.693824 -310.03072) (xy 458.673901 -309.978629) (xy 458.661775 -309.924192) (xy 458.657704 -309.86857)
			(xy 457.668429 -309.86857) (xy 457.681017 -309.895423) (xy 457.697085 -309.94883) (xy 457.705205 -310.004006)
			(xy 457.705714 -310.031892) (xy 457.705205 -310.059778) (xy 457.697085 -310.114954) (xy 457.681017 -310.168361)
			(xy 457.657345 -310.218858) (xy 457.626572 -310.265371) (xy 457.589355 -310.306908) (xy 457.546487 -310.342583)
			(xy 457.498881 -310.371637) (xy 457.447552 -310.393449) (xy 457.393595 -310.407555) (xy 457.338158 -310.413655)
			(xy 457.282424 -310.411618) (xy 457.227581 -310.401488) (xy 457.174797 -310.383481) (xy 457.125197 -310.35798)
			(xy 457.079839 -310.325529) (xy 457.03969 -310.28682) (xy 457.005604 -310.242677) (xy 456.978308 -310.194042)
			(xy 456.958385 -310.141951) (xy 456.946259 -310.087514) (xy 456.942188 -310.031892) (xy 443.8396 -310.031892)
			(xy 443.8396 -310.087518) (xy 443.84006 -310.097395) (xy 443.847503 -310.115694) (xy 443.854078 -310.123078)
			(xy 445.07023 -311.33923) (xy 458.119986 -311.33923) (xy 458.124057 -311.283608) (xy 458.136183 -311.229171)
			(xy 458.156106 -311.17708) (xy 458.183402 -311.128445) (xy 458.217488 -311.084302) (xy 458.257637 -311.045593)
			(xy 458.302995 -311.013142) (xy 458.352595 -310.987641) (xy 458.405379 -310.969634) (xy 458.460222 -310.959504)
			(xy 458.515956 -310.957467) (xy 458.571393 -310.963567) (xy 458.62535 -310.977673) (xy 458.676679 -310.999485)
			(xy 458.724285 -311.028539) (xy 458.767153 -311.064214) (xy 458.80437 -311.105751) (xy 458.835143 -311.152264)
			(xy 458.858815 -311.202761) (xy 458.874883 -311.256168) (xy 458.883003 -311.311344) (xy 458.883512 -311.33923)
			(xy 458.883003 -311.367116) (xy 458.874883 -311.422292) (xy 458.858815 -311.475699) (xy 458.842059 -311.511442)
			(xy 459.73441 -311.511442) (xy 459.738481 -311.45582) (xy 459.750607 -311.401383) (xy 459.77053 -311.349292)
			(xy 459.797826 -311.300657) (xy 459.831912 -311.256514) (xy 459.872061 -311.217805) (xy 459.917419 -311.185354)
			(xy 459.967019 -311.159853) (xy 460.019803 -311.141846) (xy 460.074646 -311.131716) (xy 460.13038 -311.129679)
			(xy 460.185817 -311.135779) (xy 460.239774 -311.149885) (xy 460.291103 -311.171697) (xy 460.338709 -311.200751)
			(xy 460.381577 -311.236426) (xy 460.418794 -311.277963) (xy 460.449567 -311.324476) (xy 460.473239 -311.374973)
			(xy 460.489307 -311.42838) (xy 460.497427 -311.483556) (xy 460.497936 -311.511442) (xy 460.497427 -311.539328)
			(xy 460.489307 -311.594504) (xy 460.473239 -311.647911) (xy 460.449567 -311.698408) (xy 460.418794 -311.744921)
			(xy 460.381577 -311.786458) (xy 460.338709 -311.822133) (xy 460.291103 -311.851187) (xy 460.239774 -311.872999)
			(xy 460.185817 -311.887105) (xy 460.13038 -311.893205) (xy 460.074646 -311.891168) (xy 460.019803 -311.881038)
			(xy 459.967019 -311.863031) (xy 459.917419 -311.83753) (xy 459.872061 -311.805079) (xy 459.831912 -311.76637)
			(xy 459.797826 -311.722227) (xy 459.77053 -311.673592) (xy 459.750607 -311.621501) (xy 459.738481 -311.567064)
			(xy 459.73441 -311.511442) (xy 458.842059 -311.511442) (xy 458.835143 -311.526196) (xy 458.80437 -311.572709)
			(xy 458.767153 -311.614246) (xy 458.724285 -311.649921) (xy 458.676679 -311.678975) (xy 458.62535 -311.700787)
			(xy 458.571393 -311.714893) (xy 458.515956 -311.720993) (xy 458.460222 -311.718956) (xy 458.405379 -311.708826)
			(xy 458.352595 -311.690819) (xy 458.302995 -311.665318) (xy 458.257637 -311.632867) (xy 458.217488 -311.594158)
			(xy 458.183402 -311.550015) (xy 458.156106 -311.50138) (xy 458.136183 -311.449289) (xy 458.124057 -311.394852)
			(xy 458.119986 -311.33923) (xy 445.07023 -311.33923) (xy 447.854578 -314.123578) (xy 447.861415 -314.13098)
			(xy 447.869124 -314.149578) (xy 447.869564 -314.159646) (xy 447.869564 -317.399924) (xy 447.870072 -317.407036)
			(xy 448.26428 -320.183002) (xy 448.265753 -320.191132) (xy 448.273135 -320.205904) (xy 448.278758 -320.211958)
			(xy 449.006976 -320.940176) (xy 455.509122 -320.940176) (xy 455.509569 -320.912805) (xy 455.51739 -320.858625)
			(xy 455.532884 -320.806121) (xy 455.55573 -320.756375) (xy 455.585459 -320.710409) (xy 455.603102 -320.689478)
			(xy 455.603356 -320.689224) (xy 455.608945 -320.68214) (xy 455.615189 -320.665221) (xy 455.615548 -320.656204)
			(xy 455.615548 -320.589148) (xy 455.615179 -320.580132) (xy 455.608941 -320.563214) (xy 455.603356 -320.556128)
			(xy 455.603102 -320.556128) (xy 455.603102 -320.555874) (xy 455.585484 -320.534925) (xy 455.555769 -320.488957)
			(xy 455.532929 -320.439213) (xy 455.517433 -320.386717) (xy 455.509599 -320.332544) (xy 455.509122 -320.305176)
			(xy 455.509533 -320.277921) (xy 455.517294 -320.223967) (xy 455.532654 -320.171666) (xy 455.555302 -320.122084)
			(xy 455.584775 -320.076229) (xy 455.620474 -320.035036) (xy 455.661673 -319.999343) (xy 455.707531 -319.969876)
			(xy 455.757117 -319.947235) (xy 455.80942 -319.931882) (xy 455.863375 -319.924129) (xy 455.89063 -319.923668)
			(xy 455.918002 -319.9241) (xy 455.972183 -319.931923) (xy 456.024687 -319.94742) (xy 456.074433 -319.970269)
			(xy 456.120398 -320.000002) (xy 456.141328 -320.017648) (xy 456.141582 -320.017902) (xy 456.148669 -320.023487)
			(xy 456.165586 -320.029735) (xy 456.174602 -320.030094) (xy 456.241658 -320.030094) (xy 456.250673 -320.029718)
			(xy 456.26759 -320.023484) (xy 456.274678 -320.017902) (xy 456.274678 -320.017648) (xy 456.274932 -320.017648)
			(xy 456.295865 -320.000007) (xy 456.341833 -319.970283) (xy 456.391579 -319.947437) (xy 456.444081 -319.931941)
			(xy 456.498259 -319.924112) (xy 456.553001 -319.924112) (xy 456.607179 -319.931941) (xy 456.659681 -319.947437)
			(xy 456.709427 -319.970283) (xy 456.755395 -320.000007) (xy 456.776328 -320.017648) (xy 456.776582 -320.017902)
			(xy 456.783669 -320.023487) (xy 456.800586 -320.029735) (xy 456.809602 -320.030094) (xy 456.876658 -320.030094)
			(xy 456.885673 -320.029718) (xy 456.90259 -320.023484) (xy 456.909678 -320.017902) (xy 456.909678 -320.017648)
			(xy 456.909932 -320.017648) (xy 456.930885 -320.000035) (xy 456.976851 -319.970317) (xy 457.026593 -319.947476)
			(xy 457.07909 -319.931979) (xy 457.133262 -319.924145) (xy 457.16063 -319.923668) (xy 457.187881 -319.92415)
			(xy 457.241828 -319.93191) (xy 457.294121 -319.947268) (xy 457.343697 -319.96991) (xy 457.389546 -319.999378)
			(xy 457.430735 -320.035069) (xy 457.466426 -320.076259) (xy 457.495892 -320.122109) (xy 457.518535 -320.171685)
			(xy 457.533891 -320.223978) (xy 457.541651 -320.277925) (xy 457.542138 -320.305176) (xy 457.541673 -320.332546)
			(xy 457.533857 -320.386726) (xy 457.518369 -320.43923) (xy 457.495526 -320.488977) (xy 457.4658 -320.534943)
			(xy 457.448158 -320.555874) (xy 457.447904 -320.556128) (xy 457.442342 -320.563231) (xy 457.43608 -320.580135)
			(xy 457.435712 -320.589148) (xy 457.435712 -320.656204) (xy 457.436064 -320.665221) (xy 457.442315 -320.682138)
			(xy 457.447904 -320.689224) (xy 457.448158 -320.689224) (xy 457.448158 -320.689478) (xy 457.465794 -320.710413)
			(xy 457.495507 -320.756384) (xy 457.518345 -320.806131) (xy 457.533836 -320.858631) (xy 457.541664 -320.912807)
			(xy 457.542138 -320.940176) (xy 457.5416 -320.967425) (xy 457.533847 -321.021369) (xy 457.518496 -321.073661)
			(xy 457.49586 -321.123236) (xy 457.466399 -321.169085) (xy 457.430713 -321.210275) (xy 457.389529 -321.245967)
			(xy 457.343684 -321.275434) (xy 457.294112 -321.298078) (xy 457.241822 -321.313436) (xy 457.187879 -321.321196)
			(xy 457.16063 -321.321684) (xy 457.13326 -321.321204) (xy 457.079082 -321.31339) (xy 457.026578 -321.297905)
			(xy 456.976831 -321.275066) (xy 456.930864 -321.245344) (xy 456.909932 -321.227704) (xy 456.909678 -321.22745)
			(xy 456.902606 -321.221842) (xy 456.885678 -321.215609) (xy 456.876658 -321.215258) (xy 456.809602 -321.215258)
			(xy 456.800584 -321.215604) (xy 456.783666 -321.221858) (xy 456.776582 -321.22745) (xy 456.776328 -321.227704)
			(xy 456.755395 -321.245345) (xy 456.709427 -321.275069) (xy 456.659681 -321.297915) (xy 456.607179 -321.313411)
			(xy 456.553001 -321.32124) (xy 456.498259 -321.32124) (xy 456.444081 -321.313411) (xy 456.391579 -321.297915)
			(xy 456.341833 -321.275069) (xy 456.295865 -321.245345) (xy 456.274932 -321.227704) (xy 456.274678 -321.22745)
			(xy 456.267606 -321.221842) (xy 456.250678 -321.215609) (xy 456.241658 -321.215258) (xy 456.174602 -321.215258)
			(xy 456.165584 -321.215604) (xy 456.148666 -321.221858) (xy 456.141582 -321.22745) (xy 456.141582 -321.227704)
			(xy 456.141328 -321.227704) (xy 456.120397 -321.245344) (xy 456.074424 -321.275056) (xy 456.024676 -321.297891)
			(xy 455.972175 -321.313382) (xy 455.917999 -321.32121) (xy 455.89063 -321.321684) (xy 455.863377 -321.321217)
			(xy 455.809425 -321.313463) (xy 455.757126 -321.29811) (xy 455.707544 -321.275469) (xy 455.661689 -321.246002)
			(xy 455.620496 -321.210308) (xy 455.584802 -321.169115) (xy 455.555334 -321.123261) (xy 455.532692 -321.07368)
			(xy 455.517338 -321.021381) (xy 455.509584 -320.967429) (xy 455.509122 -320.940176) (xy 449.006976 -320.940176)
			(xy 449.641722 -321.574922) (xy 449.648573 -321.582318) (xy 449.656312 -321.600917) (xy 449.656708 -321.61099)
			(xy 449.656708 -329.880976) (xy 459.363064 -329.880976) (xy 459.363527 -329.854662) (xy 459.370764 -329.802534)
			(xy 459.385085 -329.751891) (xy 459.406218 -329.703693) (xy 459.433765 -329.658849) (xy 459.467203 -329.618209)
			(xy 459.486254 -329.600052) (xy 459.493672 -329.592544) (xy 459.502188 -329.573254) (xy 459.502764 -329.562714)
			(xy 459.502764 -329.488038) (xy 459.502238 -329.477488) (xy 459.493702 -329.458192) (xy 459.486254 -329.4507)
			(xy 459.467197 -329.432546) (xy 459.433741 -329.391915) (xy 459.406184 -329.347074) (xy 459.385046 -329.298873)
			(xy 459.370729 -329.248226) (xy 459.363503 -329.196092) (xy 459.363064 -329.169776) (xy 459.363555 -329.142525)
			(xy 459.371314 -329.088579) (xy 459.386671 -329.036286) (xy 459.409313 -328.986711) (xy 459.438779 -328.940862)
			(xy 459.47447 -328.899673) (xy 459.515659 -328.863982) (xy 459.561507 -328.834515) (xy 459.611083 -328.811873)
			(xy 459.663375 -328.796515) (xy 459.717321 -328.788756) (xy 459.744572 -328.788268) (xy 459.770887 -328.788698)
			(xy 459.823017 -328.795942) (xy 459.87366 -328.810269) (xy 459.921858 -328.831408) (xy 459.966701 -328.858961)
			(xy 460.00734 -328.892404) (xy 460.025496 -328.911458) (xy 460.033023 -328.918853) (xy 460.052299 -328.927383)
			(xy 460.062834 -328.927968) (xy 460.13751 -328.927968) (xy 460.148063 -328.927467) (xy 460.167359 -328.918913)
			(xy 460.174848 -328.911458) (xy 460.194668 -328.89067) (xy 460.23944 -328.854695) (xy 460.289098 -328.825835)
			(xy 460.34252 -328.804742) (xy 460.398499 -328.791893) (xy 460.455772 -328.787578) (xy 460.513045 -328.791893)
			(xy 460.569024 -328.804742) (xy 460.622446 -328.825835) (xy 460.672104 -328.854695) (xy 460.716876 -328.89067)
			(xy 460.736696 -328.911458) (xy 460.744223 -328.918853) (xy 460.763499 -328.927383) (xy 460.774034 -328.927968)
			(xy 460.84871 -328.927968) (xy 460.859263 -328.927467) (xy 460.878559 -328.918913) (xy 460.886048 -328.911458)
			(xy 460.904179 -328.892378) (xy 460.944815 -328.858925) (xy 460.989661 -328.83137) (xy 461.037866 -328.810236)
			(xy 461.088517 -328.795924) (xy 461.140655 -328.788704) (xy 461.166972 -328.788268) (xy 461.194223 -328.788781)
			(xy 461.248171 -328.796534) (xy 461.300466 -328.811885) (xy 461.350045 -328.834523) (xy 461.395897 -328.863985)
			(xy 461.437089 -328.899674) (xy 461.472783 -328.940861) (xy 461.502252 -328.986709) (xy 461.524897 -329.036285)
			(xy 461.540255 -329.088578) (xy 461.548015 -329.142525) (xy 461.54848 -329.169776) (xy 461.548003 -329.19609)
			(xy 461.540771 -329.248218) (xy 461.526454 -329.298861) (xy 461.505324 -329.34706) (xy 461.477779 -329.391904)
			(xy 461.444341 -329.432543) (xy 461.42529 -329.4507) (xy 461.417885 -329.458218) (xy 461.409363 -329.477501)
			(xy 461.40878 -329.488038) (xy 461.40878 -329.562714) (xy 461.409294 -329.573265) (xy 461.41784 -329.59256)
			(xy 461.42529 -329.600052) (xy 461.444362 -329.618191) (xy 461.477818 -329.658824) (xy 461.505375 -329.703668)
			(xy 461.526511 -329.751872) (xy 461.540824 -329.802522) (xy 461.548044 -329.854659) (xy 461.54848 -329.880976)
			(xy 461.548022 -329.90823) (xy 461.540268 -329.962182) (xy 461.524913 -330.014482) (xy 461.502272 -330.064064)
			(xy 461.472804 -330.109918) (xy 461.437109 -330.151112) (xy 461.395915 -330.186806) (xy 461.35006 -330.216274)
			(xy 461.300478 -330.238915) (xy 461.248178 -330.254269) (xy 461.194226 -330.262023) (xy 461.166972 -330.262484)
			(xy 461.140657 -330.26204) (xy 461.088527 -330.254801) (xy 461.037884 -330.240478) (xy 460.989685 -330.219341)
			(xy 460.944842 -330.191791) (xy 460.904204 -330.158348) (xy 460.886048 -330.139294) (xy 460.878548 -330.131867)
			(xy 460.859252 -330.123357) (xy 460.84871 -330.122784) (xy 460.774034 -330.122784) (xy 460.763486 -330.123323)
			(xy 460.74419 -330.131852) (xy 460.736696 -330.139294) (xy 460.716876 -330.160082) (xy 460.672104 -330.196057)
			(xy 460.622446 -330.224917) (xy 460.569024 -330.24601) (xy 460.513045 -330.258859) (xy 460.455772 -330.263174)
			(xy 460.398499 -330.258859) (xy 460.34252 -330.24601) (xy 460.289098 -330.224917) (xy 460.23944 -330.196057)
			(xy 460.194668 -330.160082) (xy 460.174848 -330.139294) (xy 460.167348 -330.131867) (xy 460.148052 -330.123357)
			(xy 460.13751 -330.122784) (xy 460.062834 -330.122784) (xy 460.052286 -330.123323) (xy 460.03299 -330.131852)
			(xy 460.025496 -330.139294) (xy 460.007334 -330.158343) (xy 459.966706 -330.191801) (xy 459.921867 -330.219361)
			(xy 459.873667 -330.240501) (xy 459.823021 -330.254819) (xy 459.770888 -330.262045) (xy 459.744572 -330.262484)
			(xy 459.717319 -330.262048) (xy 459.663368 -330.254287) (xy 459.611071 -330.238927) (xy 459.561492 -330.216281)
			(xy 459.515641 -330.18681) (xy 459.47445 -330.151113) (xy 459.438759 -330.109918) (xy 459.409294 -330.064062)
			(xy 459.386654 -330.01448) (xy 459.371302 -329.962181) (xy 459.363548 -329.908229) (xy 459.363064 -329.880976)
			(xy 449.656708 -329.880976) (xy 449.656708 -335.288128) (xy 449.65628 -335.298196) (xy 449.64856 -335.316794)
			(xy 449.641722 -335.324196) (xy 444.744856 -340.221062) (xy 444.738013 -340.228461) (xy 444.730292 -340.24706)
			(xy 444.72987 -340.25713) (xy 444.72987 -362.425488) (xy 444.729448 -362.435559) (xy 444.721734 -362.454163)
			(xy 444.714884 -362.461556) (xy 444.370714 -362.805726) (xy 449.753734 -362.805726) (xy 449.757805 -362.750104)
			(xy 449.769931 -362.695667) (xy 449.789854 -362.643576) (xy 449.81715 -362.594941) (xy 449.851236 -362.550798)
			(xy 449.891385 -362.512089) (xy 449.936743 -362.479638) (xy 449.986343 -362.454137) (xy 450.039127 -362.43613)
			(xy 450.09397 -362.426) (xy 450.149704 -362.423963) (xy 450.205141 -362.430063) (xy 450.259098 -362.444169)
			(xy 450.310427 -362.465981) (xy 450.358033 -362.495035) (xy 450.400901 -362.53071) (xy 450.438118 -362.572247)
			(xy 450.468891 -362.61876) (xy 450.492563 -362.669257) (xy 450.508631 -362.722664) (xy 450.516751 -362.77784)
			(xy 450.51726 -362.805726) (xy 450.516751 -362.833612) (xy 450.508631 -362.888788) (xy 450.492563 -362.942195)
			(xy 450.468891 -362.992692) (xy 450.438118 -363.039205) (xy 450.400901 -363.080742) (xy 450.358033 -363.116417)
			(xy 450.310427 -363.145471) (xy 450.259098 -363.167283) (xy 450.205141 -363.181389) (xy 450.149704 -363.187489)
			(xy 450.09397 -363.185452) (xy 450.039127 -363.175322) (xy 449.986343 -363.157315) (xy 449.936743 -363.131814)
			(xy 449.891385 -363.099363) (xy 449.851236 -363.060654) (xy 449.81715 -363.016511) (xy 449.789854 -362.967876)
			(xy 449.769931 -362.915785) (xy 449.757805 -362.861348) (xy 449.753734 -362.805726) (xy 444.370714 -362.805726)
			(xy 443.289944 -363.886496) (xy 459.91729 -363.886496) (xy 459.921361 -363.830874) (xy 459.933487 -363.776437)
			(xy 459.95341 -363.724346) (xy 459.980706 -363.675711) (xy 460.014792 -363.631568) (xy 460.054941 -363.592859)
			(xy 460.100299 -363.560408) (xy 460.149899 -363.534907) (xy 460.202683 -363.5169) (xy 460.257526 -363.50677)
			(xy 460.31326 -363.504733) (xy 460.368697 -363.510833) (xy 460.422654 -363.524939) (xy 460.473983 -363.546751)
			(xy 460.521589 -363.575805) (xy 460.564457 -363.61148) (xy 460.601674 -363.653017) (xy 460.632447 -363.69953)
			(xy 460.656119 -363.750027) (xy 460.672187 -363.803434) (xy 460.680307 -363.85861) (xy 460.680816 -363.886496)
			(xy 460.680307 -363.914382) (xy 460.672187 -363.969558) (xy 460.656119 -364.022965) (xy 460.632447 -364.073462)
			(xy 460.601674 -364.119975) (xy 460.564457 -364.161512) (xy 460.521589 -364.197187) (xy 460.473983 -364.226241)
			(xy 460.422654 -364.248053) (xy 460.368697 -364.262159) (xy 460.31326 -364.268259) (xy 460.257526 -364.266222)
			(xy 460.202683 -364.256092) (xy 460.149899 -364.238085) (xy 460.100299 -364.212584) (xy 460.054941 -364.180133)
			(xy 460.014792 -364.141424) (xy 459.980706 -364.097281) (xy 459.95341 -364.048646) (xy 459.933487 -363.996555)
			(xy 459.921361 -363.942118) (xy 459.91729 -363.886496) (xy 443.289944 -363.886496) (xy 442.674756 -364.501684)
			(xy 457.804772 -364.501684) (xy 457.808843 -364.446062) (xy 457.820969 -364.391625) (xy 457.840892 -364.339534)
			(xy 457.868188 -364.290899) (xy 457.902274 -364.246756) (xy 457.942423 -364.208047) (xy 457.987781 -364.175596)
			(xy 458.037381 -364.150095) (xy 458.090165 -364.132088) (xy 458.145008 -364.121958) (xy 458.200742 -364.119921)
			(xy 458.256179 -364.126021) (xy 458.310136 -364.140127) (xy 458.361465 -364.161939) (xy 458.409071 -364.190993)
			(xy 458.451939 -364.226668) (xy 458.489156 -364.268205) (xy 458.519929 -364.314718) (xy 458.543601 -364.365215)
			(xy 458.559669 -364.418622) (xy 458.567789 -364.473798) (xy 458.568298 -364.501684) (xy 458.567789 -364.52957)
			(xy 458.559669 -364.584746) (xy 458.543601 -364.638153) (xy 458.519929 -364.68865) (xy 458.489156 -364.735163)
			(xy 458.451939 -364.7767) (xy 458.409071 -364.812375) (xy 458.361465 -364.841429) (xy 458.310136 -364.863241)
			(xy 458.256179 -364.877347) (xy 458.200742 -364.883447) (xy 458.145008 -364.88141) (xy 458.090165 -364.87128)
			(xy 458.037381 -364.853273) (xy 457.987781 -364.827772) (xy 457.942423 -364.795321) (xy 457.902274 -364.756612)
			(xy 457.868188 -364.712469) (xy 457.840892 -364.663834) (xy 457.820969 -364.611743) (xy 457.808843 -364.557306)
			(xy 457.804772 -364.501684) (xy 442.674756 -364.501684) (xy 441.899294 -365.277146) (xy 451.28764 -365.277146)
			(xy 451.291711 -365.221524) (xy 451.303837 -365.167087) (xy 451.32376 -365.114996) (xy 451.351056 -365.066361)
			(xy 451.385142 -365.022218) (xy 451.425291 -364.983509) (xy 451.470649 -364.951058) (xy 451.520249 -364.925557)
			(xy 451.573033 -364.90755) (xy 451.627876 -364.89742) (xy 451.68361 -364.895383) (xy 451.739047 -364.901483)
			(xy 451.793004 -364.915589) (xy 451.844333 -364.937401) (xy 451.891939 -364.966455) (xy 451.934807 -365.00213)
			(xy 451.972024 -365.043667) (xy 452.002797 -365.09018) (xy 452.025073 -365.1377) (xy 452.545194 -365.1377)
			(xy 452.549265 -365.082078) (xy 452.561391 -365.027641) (xy 452.581314 -364.97555) (xy 452.60861 -364.926915)
			(xy 452.642696 -364.882772) (xy 452.682845 -364.844063) (xy 452.728203 -364.811612) (xy 452.777803 -364.786111)
			(xy 452.830587 -364.768104) (xy 452.88543 -364.757974) (xy 452.941164 -364.755937) (xy 452.996601 -364.762037)
			(xy 453.050558 -364.776143) (xy 453.101887 -364.797955) (xy 453.149493 -364.827009) (xy 453.192361 -364.862684)
			(xy 453.229578 -364.904221) (xy 453.260351 -364.950734) (xy 453.284023 -365.001231) (xy 453.300091 -365.054638)
			(xy 453.308211 -365.109814) (xy 453.30872 -365.1377) (xy 453.308211 -365.165586) (xy 453.304278 -365.19231)
			(xy 453.705212 -365.19231) (xy 453.709283 -365.136688) (xy 453.721409 -365.082251) (xy 453.741332 -365.03016)
			(xy 453.768628 -364.981525) (xy 453.802714 -364.937382) (xy 453.842863 -364.898673) (xy 453.888221 -364.866222)
			(xy 453.937821 -364.840721) (xy 453.990605 -364.822714) (xy 454.045448 -364.812584) (xy 454.101182 -364.810547)
			(xy 454.156619 -364.816647) (xy 454.210576 -364.830753) (xy 454.261905 -364.852565) (xy 454.309511 -364.881619)
			(xy 454.352379 -364.917294) (xy 454.389596 -364.958831) (xy 454.420369 -365.005344) (xy 454.444041 -365.055841)
			(xy 454.460109 -365.109248) (xy 454.468229 -365.164424) (xy 454.468738 -365.19231) (xy 454.468229 -365.220196)
			(xy 454.460109 -365.275372) (xy 454.444041 -365.328779) (xy 454.420369 -365.379276) (xy 454.389596 -365.425789)
			(xy 454.352379 -365.467326) (xy 454.309511 -365.503001) (xy 454.261905 -365.532055) (xy 454.210576 -365.553867)
			(xy 454.156619 -365.567973) (xy 454.101182 -365.574073) (xy 454.045448 -365.572036) (xy 453.990605 -365.561906)
			(xy 453.937821 -365.543899) (xy 453.888221 -365.518398) (xy 453.842863 -365.485947) (xy 453.802714 -365.447238)
			(xy 453.768628 -365.403095) (xy 453.741332 -365.35446) (xy 453.721409 -365.302369) (xy 453.709283 -365.247932)
			(xy 453.705212 -365.19231) (xy 453.304278 -365.19231) (xy 453.300091 -365.220762) (xy 453.284023 -365.274169)
			(xy 453.260351 -365.324666) (xy 453.229578 -365.371179) (xy 453.192361 -365.412716) (xy 453.149493 -365.448391)
			(xy 453.101887 -365.477445) (xy 453.050558 -365.499257) (xy 452.996601 -365.513363) (xy 452.941164 -365.519463)
			(xy 452.88543 -365.517426) (xy 452.830587 -365.507296) (xy 452.777803 -365.489289) (xy 452.728203 -365.463788)
			(xy 452.682845 -365.431337) (xy 452.642696 -365.392628) (xy 452.60861 -365.348485) (xy 452.581314 -365.29985)
			(xy 452.561391 -365.247759) (xy 452.549265 -365.193322) (xy 452.545194 -365.1377) (xy 452.025073 -365.1377)
			(xy 452.026469 -365.140677) (xy 452.042537 -365.194084) (xy 452.050657 -365.24926) (xy 452.051166 -365.277146)
			(xy 452.050657 -365.305032) (xy 452.042537 -365.360208) (xy 452.026469 -365.413615) (xy 452.002797 -365.464112)
			(xy 451.972024 -365.510625) (xy 451.934807 -365.552162) (xy 451.891939 -365.587837) (xy 451.844333 -365.616891)
			(xy 451.793004 -365.638703) (xy 451.739047 -365.652809) (xy 451.68361 -365.658909) (xy 451.627876 -365.656872)
			(xy 451.573033 -365.646742) (xy 451.520249 -365.628735) (xy 451.470649 -365.603234) (xy 451.425291 -365.570783)
			(xy 451.385142 -365.532074) (xy 451.351056 -365.487931) (xy 451.32376 -365.439296) (xy 451.303837 -365.387205)
			(xy 451.291711 -365.332768) (xy 451.28764 -365.277146) (xy 441.899294 -365.277146) (xy 440.47283 -366.70361)
			(xy 453.285096 -366.70361) (xy 453.289167 -366.647988) (xy 453.301293 -366.593551) (xy 453.321216 -366.54146)
			(xy 453.348512 -366.492825) (xy 453.382598 -366.448682) (xy 453.422747 -366.409973) (xy 453.468105 -366.377522)
			(xy 453.517705 -366.352021) (xy 453.570489 -366.334014) (xy 453.625332 -366.323884) (xy 453.681066 -366.321847)
			(xy 453.736503 -366.327947) (xy 453.79046 -366.342053) (xy 453.841789 -366.363865) (xy 453.889395 -366.392919)
			(xy 453.932263 -366.428594) (xy 453.96948 -366.470131) (xy 454.000253 -366.516644) (xy 454.023925 -366.567141)
			(xy 454.039993 -366.620548) (xy 454.048113 -366.675724) (xy 454.048622 -366.70361) (xy 454.048113 -366.731496)
			(xy 454.039993 -366.786672) (xy 454.023925 -366.840079) (xy 454.000253 -366.890576) (xy 453.984807 -366.913922)
			(xy 455.642978 -366.913922) (xy 455.647049 -366.8583) (xy 455.659175 -366.803863) (xy 455.679098 -366.751772)
			(xy 455.706394 -366.703137) (xy 455.74048 -366.658994) (xy 455.780629 -366.620285) (xy 455.825987 -366.587834)
			(xy 455.875587 -366.562333) (xy 455.928371 -366.544326) (xy 455.983214 -366.534196) (xy 456.038948 -366.532159)
			(xy 456.094385 -366.538259) (xy 456.148342 -366.552365) (xy 456.199671 -366.574177) (xy 456.247277 -366.603231)
			(xy 456.290145 -366.638906) (xy 456.327362 -366.680443) (xy 456.358135 -366.726956) (xy 456.381807 -366.777453)
			(xy 456.397875 -366.83086) (xy 456.405995 -366.886036) (xy 456.406504 -366.913922) (xy 458.450694 -366.913922)
			(xy 458.454765 -366.8583) (xy 458.466891 -366.803863) (xy 458.486814 -366.751772) (xy 458.51411 -366.703137)
			(xy 458.548196 -366.658994) (xy 458.588345 -366.620285) (xy 458.633703 -366.587834) (xy 458.683303 -366.562333)
			(xy 458.736087 -366.544326) (xy 458.79093 -366.534196) (xy 458.846664 -366.532159) (xy 458.902101 -366.538259)
			(xy 458.956058 -366.552365) (xy 459.007387 -366.574177) (xy 459.054993 -366.603231) (xy 459.097861 -366.638906)
			(xy 459.135078 -366.680443) (xy 459.165851 -366.726956) (xy 459.189523 -366.777453) (xy 459.205591 -366.83086)
			(xy 459.213711 -366.886036) (xy 459.21422 -366.913922) (xy 459.213711 -366.941808) (xy 459.205591 -366.996984)
			(xy 459.189523 -367.050391) (xy 459.165851 -367.100888) (xy 459.135078 -367.147401) (xy 459.097861 -367.188938)
			(xy 459.054993 -367.224613) (xy 459.007387 -367.253667) (xy 458.956058 -367.275479) (xy 458.902101 -367.289585)
			(xy 458.846664 -367.295685) (xy 458.79093 -367.293648) (xy 458.736087 -367.283518) (xy 458.683303 -367.265511)
			(xy 458.633703 -367.24001) (xy 458.588345 -367.207559) (xy 458.548196 -367.16885) (xy 458.51411 -367.124707)
			(xy 458.486814 -367.076072) (xy 458.466891 -367.023981) (xy 458.454765 -366.969544) (xy 458.450694 -366.913922)
			(xy 456.406504 -366.913922) (xy 456.405995 -366.941808) (xy 456.397875 -366.996984) (xy 456.381807 -367.050391)
			(xy 456.358135 -367.100888) (xy 456.327362 -367.147401) (xy 456.290145 -367.188938) (xy 456.247277 -367.224613)
			(xy 456.199671 -367.253667) (xy 456.148342 -367.275479) (xy 456.094385 -367.289585) (xy 456.038948 -367.295685)
			(xy 455.983214 -367.293648) (xy 455.928371 -367.283518) (xy 455.875587 -367.265511) (xy 455.825987 -367.24001)
			(xy 455.780629 -367.207559) (xy 455.74048 -367.16885) (xy 455.706394 -367.124707) (xy 455.679098 -367.076072)
			(xy 455.659175 -367.023981) (xy 455.647049 -366.969544) (xy 455.642978 -366.913922) (xy 453.984807 -366.913922)
			(xy 453.96948 -366.937089) (xy 453.932263 -366.978626) (xy 453.889395 -367.014301) (xy 453.841789 -367.043355)
			(xy 453.79046 -367.065167) (xy 453.736503 -367.079273) (xy 453.681066 -367.085373) (xy 453.625332 -367.083336)
			(xy 453.570489 -367.073206) (xy 453.517705 -367.055199) (xy 453.468105 -367.029698) (xy 453.422747 -366.997247)
			(xy 453.382598 -366.958538) (xy 453.348512 -366.914395) (xy 453.321216 -366.86576) (xy 453.301293 -366.813669)
			(xy 453.289167 -366.759232) (xy 453.285096 -366.70361) (xy 440.47283 -366.70361) (xy 438.261506 -368.914934)
			(xy 438.254664 -368.922334) (xy 438.246941 -368.940932) (xy 438.24652 -368.951002) (xy 438.24652 -368.990118)
			(xy 438.803804 -368.990118) (xy 438.807795 -368.927951) (xy 438.819704 -368.866804) (xy 438.839333 -368.807683)
			(xy 438.866362 -368.751557) (xy 438.900346 -368.699348) (xy 438.940728 -368.651913) (xy 438.986844 -368.610032)
			(xy 439.037936 -368.574392) (xy 439.093167 -368.545578) (xy 439.151629 -368.524064) (xy 439.212363 -368.510202)
			(xy 439.27437 -368.50422) (xy 439.336633 -368.506216) (xy 439.39813 -368.516159) (xy 439.457851 -368.533883)
			(xy 439.514814 -368.5591) (xy 439.568085 -368.591393) (xy 439.61679 -368.630233) (xy 439.660127 -368.674983)
			(xy 439.697387 -368.724907) (xy 439.727956 -368.779186) (xy 439.751334 -368.836929) (xy 439.767135 -368.897187)
			(xy 439.775101 -368.95897) (xy 439.7756 -368.990118) (xy 439.775101 -369.021266) (xy 439.767135 -369.083049)
			(xy 439.751334 -369.143307) (xy 439.727956 -369.20105) (xy 439.697387 -369.255329) (xy 439.660127 -369.305253)
			(xy 439.61679 -369.350003) (xy 439.568085 -369.388843) (xy 439.514814 -369.421136) (xy 439.457851 -369.446353)
			(xy 439.39813 -369.464077) (xy 439.336633 -369.47402) (xy 439.27437 -369.476016) (xy 439.212363 -369.470034)
			(xy 439.151629 -369.456172) (xy 439.093167 -369.434658) (xy 439.037936 -369.405844) (xy 438.986844 -369.370204)
			(xy 438.940728 -369.328323) (xy 438.900346 -369.280888) (xy 438.866362 -369.228679) (xy 438.839333 -369.172553)
			(xy 438.819704 -369.113432) (xy 438.807795 -369.052285) (xy 438.803804 -368.990118) (xy 438.24652 -368.990118)
			(xy 438.24652 -371.590062) (xy 438.803804 -371.590062) (xy 438.807795 -371.527895) (xy 438.819704 -371.466748)
			(xy 438.839333 -371.407627) (xy 438.866362 -371.351501) (xy 438.900346 -371.299292) (xy 438.940728 -371.251857)
			(xy 438.986844 -371.209976) (xy 439.037936 -371.174336) (xy 439.093167 -371.145522) (xy 439.151629 -371.124008)
			(xy 439.212363 -371.110146) (xy 439.27437 -371.104164) (xy 439.336633 -371.10616) (xy 439.39813 -371.116103)
			(xy 439.457851 -371.133827) (xy 439.514814 -371.159044) (xy 439.568085 -371.191337) (xy 439.61679 -371.230177)
			(xy 439.660127 -371.274927) (xy 439.697387 -371.324851) (xy 439.727956 -371.37913) (xy 439.751334 -371.436873)
			(xy 439.767135 -371.497131) (xy 439.775101 -371.558914) (xy 439.7756 -371.590062) (xy 439.775101 -371.62121)
			(xy 439.767135 -371.682993) (xy 439.751334 -371.743251) (xy 439.727956 -371.800994) (xy 439.697387 -371.855273)
			(xy 439.694001 -371.85981) (xy 457.532994 -371.85981) (xy 457.53348 -371.832559) (xy 457.541236 -371.778611)
			(xy 457.556591 -371.726316) (xy 457.579233 -371.676739) (xy 457.608699 -371.630889) (xy 457.64439 -371.589698)
			(xy 457.685581 -371.554007) (xy 457.731431 -371.524541) (xy 457.781008 -371.501899) (xy 457.833303 -371.486544)
			(xy 457.887251 -371.478788) (xy 457.941753 -371.478788) (xy 457.995701 -371.486544) (xy 458.047996 -371.501899)
			(xy 458.097573 -371.524541) (xy 458.143423 -371.554007) (xy 458.184614 -371.589698) (xy 458.220305 -371.630889)
			(xy 458.249771 -371.676739) (xy 458.272413 -371.726316) (xy 458.287768 -371.778611) (xy 458.295524 -371.832559)
			(xy 458.29601 -371.85981) (xy 458.29539 -371.890148) (xy 458.285787 -371.950059) (xy 458.266823 -372.007696)
			(xy 458.238976 -372.061604) (xy 458.202949 -372.110427) (xy 458.18171 -372.132098) (xy 458.17212 -372.141991)
			(xy 458.1583 -372.165823) (xy 458.151349 -372.192479) (xy 458.151771 -372.220024) (xy 458.159536 -372.246455)
			(xy 458.174079 -372.269852) (xy 458.194344 -372.288513) (xy 458.218858 -372.301083) (xy 458.232256 -372.30431)
			(xy 458.260571 -372.310664) (xy 458.314998 -372.330791) (xy 458.365747 -372.358932) (xy 458.411647 -372.394436)
			(xy 458.451638 -372.436485) (xy 458.484797 -372.484106) (xy 458.510358 -372.536202) (xy 458.527732 -372.591569)
			(xy 458.536517 -372.648929) (xy 458.537056 -372.677944) (xy 458.53657 -372.705195) (xy 458.528814 -372.759143)
			(xy 458.513459 -372.811438) (xy 458.490817 -372.861015) (xy 458.461351 -372.906865) (xy 458.42566 -372.948056)
			(xy 458.384469 -372.983747) (xy 458.338619 -373.013213) (xy 458.289042 -373.035855) (xy 458.236747 -373.05121)
			(xy 458.182799 -373.058966) (xy 458.128297 -373.058966) (xy 458.074349 -373.05121) (xy 458.022054 -373.035855)
			(xy 457.972477 -373.013213) (xy 457.926627 -372.983747) (xy 457.885436 -372.948056) (xy 457.849745 -372.906865)
			(xy 457.820279 -372.861015) (xy 457.797637 -372.811438) (xy 457.782282 -372.759143) (xy 457.774526 -372.705195)
			(xy 457.77404 -372.677944) (xy 457.774616 -372.647604) (xy 457.784228 -372.58769) (xy 457.803202 -372.530053)
			(xy 457.831058 -372.476145) (xy 457.867095 -372.427325) (xy 457.88834 -372.405656) (xy 457.897843 -372.395687)
			(xy 457.911655 -372.371873) (xy 457.918606 -372.345236) (xy 457.918191 -372.317709) (xy 457.910439 -372.291294)
			(xy 457.895914 -372.267908) (xy 457.875672 -372.24925) (xy 457.851181 -372.236677) (xy 457.837794 -372.233444)
			(xy 457.809476 -372.227098) (xy 457.755046 -372.206974) (xy 457.704294 -372.178835) (xy 457.658391 -372.143331)
			(xy 457.618399 -372.101281) (xy 457.58524 -372.053657) (xy 457.55968 -372.001559) (xy 457.54231 -371.946188)
			(xy 457.53353 -371.888826) (xy 457.532994 -371.85981) (xy 439.694001 -371.85981) (xy 439.660127 -371.905197)
			(xy 439.61679 -371.949947) (xy 439.568085 -371.988787) (xy 439.514814 -372.02108) (xy 439.457851 -372.046297)
			(xy 439.39813 -372.064021) (xy 439.336633 -372.073964) (xy 439.27437 -372.07596) (xy 439.212363 -372.069978)
			(xy 439.151629 -372.056116) (xy 439.093167 -372.034602) (xy 439.037936 -372.005788) (xy 438.986844 -371.970148)
			(xy 438.940728 -371.928267) (xy 438.900346 -371.880832) (xy 438.866362 -371.828623) (xy 438.839333 -371.772497)
			(xy 438.819704 -371.713376) (xy 438.807795 -371.652229) (xy 438.803804 -371.590062) (xy 438.24652 -371.590062)
			(xy 438.24652 -372.199662) (xy 438.246086 -372.209728) (xy 438.238358 -372.228318) (xy 438.231534 -372.23573)
			(xy 437.642254 -372.82501) (xy 437.638622 -372.828835) (xy 437.632862 -372.83767) (xy 437.630824 -372.842536)
			(xy 437.630824 -372.879112) (xy 437.634126 -372.887748) (xy 437.634937 -372.890034) (xy 438.803804 -372.890034)
			(xy 438.807795 -372.827867) (xy 438.819704 -372.76672) (xy 438.839333 -372.707599) (xy 438.866362 -372.651473)
			(xy 438.900346 -372.599264) (xy 438.940728 -372.551829) (xy 438.986844 -372.509948) (xy 439.037936 -372.474308)
			(xy 439.093167 -372.445494) (xy 439.151629 -372.42398) (xy 439.212363 -372.410118) (xy 439.27437 -372.404136)
			(xy 439.336633 -372.406132) (xy 439.39813 -372.416075) (xy 439.457851 -372.433799) (xy 439.514814 -372.459016)
			(xy 439.568085 -372.491309) (xy 439.61679 -372.530149) (xy 439.660127 -372.574899) (xy 439.697387 -372.624823)
			(xy 439.727956 -372.679102) (xy 439.751334 -372.736845) (xy 439.767135 -372.797103) (xy 439.775101 -372.858886)
			(xy 439.7756 -372.890034) (xy 439.775101 -372.921182) (xy 439.767135 -372.982965) (xy 439.751334 -373.043223)
			(xy 439.727956 -373.100966) (xy 439.697387 -373.155245) (xy 439.660127 -373.205169) (xy 439.61679 -373.249919)
			(xy 439.568085 -373.288759) (xy 439.514814 -373.321052) (xy 439.457851 -373.346269) (xy 439.39813 -373.363993)
			(xy 439.336633 -373.373936) (xy 439.27437 -373.375932) (xy 439.212363 -373.36995) (xy 439.151629 -373.356088)
			(xy 439.093167 -373.334574) (xy 439.037936 -373.30576) (xy 438.986844 -373.27012) (xy 438.940728 -373.228239)
			(xy 438.900346 -373.180804) (xy 438.866362 -373.128595) (xy 438.839333 -373.072469) (xy 438.819704 -373.013348)
			(xy 438.807795 -372.952201) (xy 438.803804 -372.890034) (xy 437.634937 -372.890034) (xy 437.645625 -372.920158)
			(xy 437.661787 -372.987004) (xy 437.669932 -373.055292) (xy 437.670448 -373.089678) (xy 437.670448 -373.090186)
			(xy 437.66994 -373.125278) (xy 437.661482 -373.194951) (xy 437.644687 -373.263097) (xy 437.6198 -373.328721)
			(xy 437.587185 -373.390867) (xy 437.547317 -373.448629) (xy 437.543085 -373.453406) (xy 451.256398 -373.453406)
			(xy 451.260469 -373.397784) (xy 451.272595 -373.343347) (xy 451.292518 -373.291256) (xy 451.319814 -373.242621)
			(xy 451.3539 -373.198478) (xy 451.394049 -373.159769) (xy 451.439407 -373.127318) (xy 451.489007 -373.101817)
			(xy 451.541791 -373.08381) (xy 451.596634 -373.07368) (xy 451.652368 -373.071643) (xy 451.707805 -373.077743)
			(xy 451.761762 -373.091849) (xy 451.813091 -373.113661) (xy 451.860697 -373.142715) (xy 451.903565 -373.17839)
			(xy 451.940782 -373.219927) (xy 451.971555 -373.26644) (xy 451.995227 -373.316937) (xy 452.011295 -373.370344)
			(xy 452.019415 -373.42552) (xy 452.019924 -373.453406) (xy 452.019415 -373.481292) (xy 452.011295 -373.536468)
			(xy 451.995227 -373.589875) (xy 451.971555 -373.640372) (xy 451.940782 -373.686885) (xy 451.903565 -373.728422)
			(xy 451.860697 -373.764097) (xy 451.813091 -373.793151) (xy 451.761762 -373.814963) (xy 451.707805 -373.829069)
			(xy 451.652368 -373.835169) (xy 451.596634 -373.833132) (xy 451.541791 -373.823002) (xy 451.489007 -373.804995)
			(xy 451.439407 -373.779494) (xy 451.394049 -373.747043) (xy 451.3539 -373.708334) (xy 451.319814 -373.664191)
			(xy 451.292518 -373.615556) (xy 451.272595 -373.563465) (xy 451.260469 -373.509028) (xy 451.256398 -373.453406)
			(xy 437.543085 -373.453406) (xy 437.500776 -373.501164) (xy 437.448243 -373.547706) (xy 437.390483 -373.587576)
			(xy 437.328338 -373.620193) (xy 437.262714 -373.645082) (xy 437.194569 -373.661878) (xy 437.124896 -373.670339)
			(xy 437.089804 -373.67083) (xy 437.071848 -373.670663) (xy 437.036007 -373.668378) (xy 437.018176 -373.666258)
			(xy 437.006238 -373.664734) (xy 436.983886 -373.672608) (xy 436.919116 -373.739156) (xy 436.911544 -373.747821)
			(xy 436.904162 -373.769582) (xy 436.904892 -373.781066) (xy 436.905146 -373.782336) (xy 436.905146 -373.782844)
			(xy 436.908448 -373.814594) (xy 436.908956 -373.825262) (xy 436.918608 -373.844058) (xy 436.926736 -373.850662)
			(xy 436.92699 -373.850916) (xy 436.984394 -373.897906) (xy 436.992656 -373.90409) (xy 437.012455 -373.909846)
			(xy 437.022748 -373.909082) (xy 437.023764 -373.909082) (xy 437.040191 -373.906949) (xy 437.07324 -373.904662)
			(xy 437.089804 -373.90451) (xy 437.120745 -373.904996) (xy 437.182125 -373.912856) (xy 437.242009 -373.92845)
			(xy 437.299427 -373.951524) (xy 437.35345 -373.981704) (xy 437.403202 -374.018501) (xy 437.447876 -374.06132)
			(xy 437.48675 -374.109467) (xy 437.519194 -374.162161) (xy 437.544681 -374.21855) (xy 437.5628 -374.277719)
			(xy 437.573256 -374.338711) (xy 437.57588 -374.400536) (xy 437.57063 -374.462195) (xy 437.557591 -374.522686)
			(xy 437.536973 -374.581032) (xy 437.509112 -374.636286) (xy 437.474457 -374.687554) (xy 437.433572 -374.734005)
			(xy 437.387117 -374.774886) (xy 437.335846 -374.809535) (xy 437.28059 -374.837391) (xy 437.222242 -374.858003)
			(xy 437.161749 -374.871037) (xy 437.10009 -374.876281) (xy 437.038265 -374.873651) (xy 436.977275 -374.863189)
			(xy 436.918107 -374.845065) (xy 436.861721 -374.819572) (xy 436.809029 -374.787124) (xy 436.760886 -374.748245)
			(xy 436.718072 -374.703567) (xy 436.681279 -374.653812) (xy 436.651104 -374.599786) (xy 436.628035 -374.542365)
			(xy 436.612448 -374.482479) (xy 436.604593 -374.421099) (xy 436.604156 -374.390158) (xy 436.604156 -374.389396)
			(xy 436.604274 -374.37533) (xy 436.605925 -374.347245) (xy 436.607458 -374.333262) (xy 436.608728 -374.322594)
			(xy 436.602632 -374.302528) (xy 436.548022 -374.238012) (xy 436.544607 -374.23416) (xy 436.536551 -374.227754)
			(xy 436.53202 -374.225312) (xy 436.522114 -374.220486) (xy 436.511192 -374.219978) (xy 436.482239 -374.218184)
			(xy 436.425336 -374.206922) (xy 436.3708 -374.187159) (xy 436.345076 -374.17375) (xy 436.33009 -374.165622)
			(xy 436.296816 -374.170448) (xy 435.314598 -375.15292) (xy 435.307755 -375.16032) (xy 435.300028 -375.178918)
			(xy 435.299612 -375.188988) (xy 435.299612 -375.222008) (xy 435.303168 -375.235216) (xy 435.306724 -375.241312)
			(xy 435.323049 -375.269639) (xy 435.348779 -375.329744) (xy 435.366209 -375.392758) (xy 435.375021 -375.457542)
			(xy 435.375558 -375.490232) (xy 435.375558 -375.506742) (xy 435.374049 -375.537438) (xy 435.364238 -375.598108)
			(xy 435.346843 -375.657053) (xy 435.332325 -375.69013) (xy 436.603656 -375.69013) (xy 436.607647 -375.627963)
			(xy 436.619556 -375.566816) (xy 436.639185 -375.507695) (xy 436.666214 -375.451569) (xy 436.700198 -375.39936)
			(xy 436.74058 -375.351925) (xy 436.786696 -375.310044) (xy 436.837788 -375.274404) (xy 436.893019 -375.24559)
			(xy 436.951481 -375.224076) (xy 437.012215 -375.210214) (xy 437.074222 -375.204232) (xy 437.136485 -375.206228)
			(xy 437.197982 -375.216171) (xy 437.257703 -375.233895) (xy 437.314666 -375.259112) (xy 437.367937 -375.291405)
			(xy 437.416642 -375.330245) (xy 437.459979 -375.374995) (xy 437.497239 -375.424919) (xy 437.527808 -375.479198)
			(xy 437.532275 -375.490232) (xy 438.803804 -375.490232) (xy 438.807795 -375.428065) (xy 438.819704 -375.366918)
			(xy 438.839333 -375.307797) (xy 438.866362 -375.251671) (xy 438.900346 -375.199462) (xy 438.940728 -375.152027)
			(xy 438.986844 -375.110146) (xy 439.037936 -375.074506) (xy 439.093167 -375.045692) (xy 439.151629 -375.024178)
			(xy 439.212363 -375.010316) (xy 439.27437 -375.004334) (xy 439.336633 -375.00633) (xy 439.39813 -375.016273)
			(xy 439.457851 -375.033997) (xy 439.514814 -375.059214) (xy 439.565899 -375.090182) (xy 459.19085 -375.090182)
			(xy 459.194921 -375.03456) (xy 459.207047 -374.980123) (xy 459.22697 -374.928032) (xy 459.254266 -374.879397)
			(xy 459.288352 -374.835254) (xy 459.328501 -374.796545) (xy 459.373859 -374.764094) (xy 459.423459 -374.738593)
			(xy 459.476243 -374.720586) (xy 459.531086 -374.710456) (xy 459.58682 -374.708419) (xy 459.642257 -374.714519)
			(xy 459.696214 -374.728625) (xy 459.747543 -374.750437) (xy 459.795149 -374.779491) (xy 459.838017 -374.815166)
			(xy 459.875234 -374.856703) (xy 459.906007 -374.903216) (xy 459.929679 -374.953713) (xy 459.945747 -375.00712)
			(xy 459.953867 -375.062296) (xy 459.954376 -375.090182) (xy 459.953867 -375.118068) (xy 459.945747 -375.173244)
			(xy 459.929679 -375.226651) (xy 459.906007 -375.277148) (xy 459.875234 -375.323661) (xy 459.838017 -375.365198)
			(xy 459.795149 -375.400873) (xy 459.747543 -375.429927) (xy 459.696214 -375.451739) (xy 459.642257 -375.465845)
			(xy 459.58682 -375.471945) (xy 459.531086 -375.469908) (xy 459.476243 -375.459778) (xy 459.423459 -375.441771)
			(xy 459.373859 -375.41627) (xy 459.328501 -375.383819) (xy 459.288352 -375.34511) (xy 459.254266 -375.300967)
			(xy 459.22697 -375.252332) (xy 459.207047 -375.200241) (xy 459.194921 -375.145804) (xy 459.19085 -375.090182)
			(xy 439.565899 -375.090182) (xy 439.568085 -375.091507) (xy 439.61679 -375.130347) (xy 439.660127 -375.175097)
			(xy 439.697387 -375.225021) (xy 439.727956 -375.2793) (xy 439.751334 -375.337043) (xy 439.767135 -375.397301)
			(xy 439.775101 -375.459084) (xy 439.7756 -375.490232) (xy 439.775101 -375.52138) (xy 439.767135 -375.583163)
			(xy 439.751334 -375.643421) (xy 439.727956 -375.701164) (xy 439.697387 -375.755443) (xy 439.660127 -375.805367)
			(xy 439.61679 -375.850117) (xy 439.568085 -375.888957) (xy 439.514814 -375.92125) (xy 439.457851 -375.946467)
			(xy 439.39813 -375.964191) (xy 439.336633 -375.974134) (xy 439.27437 -375.97613) (xy 439.212363 -375.970148)
			(xy 439.151629 -375.956286) (xy 439.093167 -375.934772) (xy 439.037936 -375.905958) (xy 438.986844 -375.870318)
			(xy 438.940728 -375.828437) (xy 438.900346 -375.781002) (xy 438.866362 -375.728793) (xy 438.839333 -375.672667)
			(xy 438.819704 -375.613546) (xy 438.807795 -375.552399) (xy 438.803804 -375.490232) (xy 437.532275 -375.490232)
			(xy 437.551186 -375.536941) (xy 437.566987 -375.597199) (xy 437.574953 -375.658982) (xy 437.575452 -375.69013)
			(xy 437.574953 -375.721278) (xy 437.566987 -375.783061) (xy 437.551186 -375.843319) (xy 437.527808 -375.901062)
			(xy 437.497239 -375.955341) (xy 437.459979 -376.005265) (xy 437.416642 -376.050015) (xy 437.367937 -376.088855)
			(xy 437.314666 -376.121148) (xy 437.257703 -376.146365) (xy 437.197982 -376.164089) (xy 437.136485 -376.174032)
			(xy 437.074222 -376.176028) (xy 437.012215 -376.170046) (xy 436.951481 -376.156184) (xy 436.893019 -376.13467)
			(xy 436.837788 -376.105856) (xy 436.786696 -376.070216) (xy 436.74058 -376.028335) (xy 436.700198 -375.9809)
			(xy 436.666214 -375.928691) (xy 436.639185 -375.872565) (xy 436.619556 -375.813444) (xy 436.607647 -375.752297)
			(xy 436.603656 -375.69013) (xy 435.332325 -375.69013) (xy 435.322142 -375.713329) (xy 435.306724 -375.739914)
			(xy 435.303408 -375.745939) (xy 435.299793 -375.759202) (xy 435.299612 -375.766076) (xy 435.299612 -376.51182)
			(xy 435.299684 -376.515828) (xy 435.300965 -376.523739) (xy 435.302152 -376.527568) (xy 435.306724 -376.54103)
			(xy 435.309264 -376.545348) (xy 435.325007 -376.57332) (xy 435.349801 -376.632525) (xy 435.366574 -376.694482)
			(xy 435.375035 -376.75811) (xy 435.375034 -376.790204) (xy 438.803804 -376.790204) (xy 438.807795 -376.728037)
			(xy 438.819704 -376.66689) (xy 438.839333 -376.607769) (xy 438.866362 -376.551643) (xy 438.900346 -376.499434)
			(xy 438.940728 -376.451999) (xy 438.986844 -376.410118) (xy 439.037936 -376.374478) (xy 439.093167 -376.345664)
			(xy 439.151629 -376.32415) (xy 439.212363 -376.310288) (xy 439.27437 -376.304306) (xy 439.336633 -376.306302)
			(xy 439.39813 -376.316245) (xy 439.457851 -376.333969) (xy 439.514814 -376.359186) (xy 439.568085 -376.391479)
			(xy 439.61679 -376.430319) (xy 439.660127 -376.475069) (xy 439.697387 -376.524993) (xy 439.727956 -376.579272)
			(xy 439.751334 -376.637015) (xy 439.767135 -376.697273) (xy 439.775101 -376.759056) (xy 439.7756 -376.790204)
			(xy 439.775101 -376.821352) (xy 439.767135 -376.883135) (xy 439.751334 -376.943393) (xy 439.727956 -377.001136)
			(xy 439.697387 -377.055415) (xy 439.660127 -377.105339) (xy 439.61679 -377.150089) (xy 439.568085 -377.188929)
			(xy 439.514814 -377.221222) (xy 439.457851 -377.246439) (xy 439.39813 -377.264163) (xy 439.336633 -377.274106)
			(xy 439.27437 -377.276102) (xy 439.212363 -377.27012) (xy 439.151629 -377.256258) (xy 439.093167 -377.234744)
			(xy 439.037936 -377.20593) (xy 438.986844 -377.17029) (xy 438.940728 -377.128409) (xy 438.900346 -377.080974)
			(xy 438.866362 -377.028765) (xy 438.839333 -376.972639) (xy 438.819704 -376.913518) (xy 438.807795 -376.852371)
			(xy 438.803804 -376.790204) (xy 435.375034 -376.790204) (xy 435.375034 -376.822297) (xy 435.366573 -376.885924)
			(xy 435.349799 -376.947881) (xy 435.325004 -377.007086) (xy 435.309264 -377.03506) (xy 435.306724 -377.039378)
			(xy 435.302152 -377.05284) (xy 435.300994 -377.056675) (xy 435.299725 -377.064584) (xy 435.299612 -377.068588)
			(xy 435.299612 -377.35129) (xy 435.299187 -377.361459) (xy 435.291402 -377.380249) (xy 435.277015 -377.394625)
			(xy 435.25822 -377.402395) (xy 435.24805 -377.402852) (xy 434.53177 -377.402852) (xy 434.521617 -377.402351)
			(xy 434.50286 -377.394571) (xy 434.488506 -377.380207) (xy 434.480741 -377.361443) (xy 434.480208 -377.35129)
			(xy 434.480208 -377.068588) (xy 434.480137 -377.06458) (xy 434.478857 -377.056668) (xy 434.477668 -377.05284)
			(xy 434.473096 -377.039378) (xy 434.470556 -377.03506) (xy 434.454814 -377.007087) (xy 434.430024 -376.947881)
			(xy 434.413252 -376.885924) (xy 434.404792 -376.822297) (xy 434.404792 -376.75811) (xy 434.413251 -376.694483)
			(xy 434.430022 -376.632525) (xy 434.454811 -376.573319) (xy 434.470556 -376.545348) (xy 434.473096 -376.54103)
			(xy 434.477668 -376.527568) (xy 434.478826 -376.523733) (xy 434.480096 -376.515824) (xy 434.480208 -376.51182)
			(xy 434.480208 -375.768616) (xy 434.480139 -375.764608) (xy 434.478864 -375.756694) (xy 434.477668 -375.752868)
			(xy 434.473096 -375.739406) (xy 434.470556 -375.735088) (xy 434.454384 -375.706287) (xy 434.429117 -375.645259)
			(xy 434.412349 -375.58137) (xy 434.407818 -375.548652) (xy 434.405532 -375.529348) (xy 434.37683 -375.503948)
			(xy 433.27066 -375.503948) (xy 433.259644 -375.504495) (xy 433.239634 -375.513717) (xy 433.232052 -375.521728)
			(xy 433.197508 -375.562114) (xy 433.182776 -375.579132) (xy 433.177097 -375.586254) (xy 433.170722 -375.603305)
			(xy 433.17033 -375.612406) (xy 433.17033 -375.62028) (xy 433.170838 -375.623836) (xy 433.174648 -375.661428)
			(xy 433.175664 -375.677938) (xy 433.175664 -375.690384) (xy 433.175114 -375.723146) (xy 433.166278 -375.788072)
			(xy 433.14879 -375.851219) (xy 433.12297 -375.911442) (xy 433.106576 -375.939812) (xy 433.103263 -375.945838)
			(xy 433.099651 -375.9591) (xy 433.099464 -375.965974) (xy 433.099464 -376.25147) (xy 433.099043 -376.261646)
			(xy 433.091264 -376.280451) (xy 433.076878 -376.294846) (xy 433.058077 -376.302637) (xy 433.047902 -376.303032)
			(xy 432.331622 -376.303032) (xy 432.32145 -376.302609) (xy 432.302653 -376.294827) (xy 432.288268 -376.280441)
			(xy 432.280489 -376.261642) (xy 432.28006 -376.25147) (xy 432.28006 -375.968514) (xy 432.279991 -375.964506)
			(xy 432.278714 -375.956593) (xy 432.27752 -375.952766) (xy 432.272948 -375.939304) (xy 432.270408 -375.934986)
			(xy 432.254663 -375.907015) (xy 432.229869 -375.84781) (xy 432.213098 -375.785852) (xy 432.204643 -375.722224)
			(xy 432.204114 -375.69013) (xy 432.204281 -375.672604) (xy 432.206822 -375.637645) (xy 432.209194 -375.62028)
			(xy 432.210718 -375.609104) (xy 432.204622 -375.588276) (xy 432.147218 -375.521474) (xy 432.13966 -375.513572)
			(xy 432.119786 -375.504505) (xy 432.108864 -375.503948) (xy 431.002948 -375.503948) (xy 430.974246 -375.529348)
			(xy 430.97196 -375.548652) (xy 430.967272 -375.582248) (xy 430.949781 -375.647787) (xy 430.923343 -375.710256)
			(xy 430.906428 -375.73966) (xy 430.903118 -375.745686) (xy 430.899515 -375.758949) (xy 430.899316 -375.765822)
			(xy 430.899316 -376.514614) (xy 430.899505 -376.521488) (xy 430.903107 -376.534755) (xy 430.906428 -376.540776)
			(xy 430.92281 -376.569153) (xy 430.948634 -376.629372) (xy 430.966124 -376.692518) (xy 430.974963 -376.757443)
			(xy 430.975516 -376.790204) (xy 430.97498 -376.822925) (xy 430.966187 -376.887774) (xy 430.948761 -376.950854)
			(xy 430.923018 -377.011021) (xy 430.906682 -377.039378) (xy 430.906682 -377.039632) (xy 430.90329 -377.045636)
			(xy 430.899545 -377.058902) (xy 430.899316 -377.065794) (xy 430.899316 -377.208034) (xy 430.89957 -377.35129)
			(xy 430.899083 -377.361418) (xy 430.891357 -377.380143) (xy 430.877072 -377.394505) (xy 430.858388 -377.402328)
			(xy 430.848262 -377.402852) (xy 430.131728 -377.402852) (xy 430.121613 -377.402365) (xy 430.102919 -377.394635)
			(xy 430.088605 -377.380341) (xy 430.08085 -377.361658) (xy 430.08042 -377.351544) (xy 430.08042 -377.065794)
			(xy 430.080233 -377.058919) (xy 430.076635 -377.045651) (xy 430.073308 -377.039632) (xy 430.056924 -377.011256)
			(xy 430.031097 -376.951037) (xy 430.013605 -376.887891) (xy 430.004764 -376.822966) (xy 430.00422 -376.790204)
			(xy 430.004777 -376.757443) (xy 430.013624 -376.692522) (xy 430.031117 -376.629378) (xy 430.056938 -376.569159)
			(xy 430.073308 -376.540776) (xy 430.07662 -376.53475) (xy 430.080231 -376.521487) (xy 430.08042 -376.514614)
			(xy 430.08042 -375.765822) (xy 430.080223 -375.75895) (xy 430.076609 -375.745691) (xy 430.073308 -375.73966)
			(xy 430.056356 -375.710276) (xy 430.029922 -375.6478) (xy 430.012445 -375.582253) (xy 430.007776 -375.548652)
			(xy 430.00549 -375.529348) (xy 429.976788 -375.503948) (xy 428.870872 -375.503948) (xy 428.859855 -375.504492)
			(xy 428.839842 -375.513712) (xy 428.832264 -375.521728) (xy 428.79772 -375.562114) (xy 428.782988 -375.579132)
			(xy 428.777308 -375.586254) (xy 428.770931 -375.603305) (xy 428.770542 -375.612406) (xy 428.770542 -375.62028)
			(xy 428.77105 -375.623836) (xy 428.77486 -375.661428) (xy 428.775876 -375.677938) (xy 428.775876 -375.690384)
			(xy 428.775326 -375.723146) (xy 428.76649 -375.788072) (xy 428.749003 -375.85122) (xy 428.723183 -375.911442)
			(xy 428.706788 -375.939812) (xy 428.703474 -375.945838) (xy 428.699861 -375.9591) (xy 428.699676 -375.965974)
			(xy 428.699676 -376.25147) (xy 428.699255 -376.261647) (xy 428.691476 -376.280454) (xy 428.677091 -376.294852)
			(xy 428.65829 -376.302647) (xy 428.648114 -376.303032) (xy 427.931834 -376.303032) (xy 427.92166 -376.302611)
			(xy 427.902859 -376.294831) (xy 427.888471 -376.280444) (xy 427.880689 -376.261644) (xy 427.880272 -376.25147)
			(xy 427.880272 -375.968514) (xy 427.880203 -375.964506) (xy 427.878926 -375.956593) (xy 427.877732 -375.952766)
			(xy 427.87316 -375.939304) (xy 427.87062 -375.934986) (xy 427.854878 -375.907014) (xy 427.830088 -375.847808)
			(xy 427.81332 -375.785851) (xy 427.804867 -375.722223) (xy 427.804326 -375.69013) (xy 427.804492 -375.672604)
			(xy 427.807033 -375.637645) (xy 427.809406 -375.62028) (xy 427.81093 -375.609104) (xy 427.804834 -375.588276)
			(xy 427.74743 -375.521474) (xy 427.739873 -375.51357) (xy 427.719999 -375.504498) (xy 427.709076 -375.503948)
			(xy 426.602906 -375.503948) (xy 426.574204 -375.529348) (xy 426.571918 -375.548652) (xy 426.567257 -375.582157)
			(xy 426.549846 -375.647524) (xy 426.523518 -375.709836) (xy 426.50664 -375.739152) (xy 426.503329 -375.745178)
			(xy 426.499722 -375.758441) (xy 426.499528 -375.765314) (xy 426.499528 -376.51182) (xy 426.4996 -376.515828)
			(xy 426.500881 -376.523739) (xy 426.502068 -376.527568) (xy 426.50664 -376.54103) (xy 426.50918 -376.545348)
			(xy 426.524923 -376.57332) (xy 426.549716 -376.632526) (xy 426.566489 -376.694483) (xy 426.574949 -376.75811)
			(xy 426.574948 -376.822297) (xy 426.566487 -376.885924) (xy 426.549714 -376.947881) (xy 426.52492 -377.007086)
			(xy 426.50918 -377.03506) (xy 426.50664 -377.039378) (xy 426.502068 -377.05284) (xy 426.50091 -377.056675)
			(xy 426.49964 -377.064584) (xy 426.499528 -377.068588) (xy 426.499528 -377.35129) (xy 426.499103 -377.36146)
			(xy 426.491319 -377.380253) (xy 426.476932 -377.394632) (xy 426.458137 -377.402408) (xy 426.447966 -377.402852)
			(xy 425.731686 -377.402852) (xy 425.721531 -377.402354) (xy 425.702768 -377.394577) (xy 425.68841 -377.380212)
			(xy 425.680641 -377.361445) (xy 425.680124 -377.35129) (xy 425.680124 -377.068588) (xy 425.680053 -377.06458)
			(xy 425.678771 -377.056669) (xy 425.677584 -377.05284) (xy 425.673012 -377.039378) (xy 425.670472 -377.03506)
			(xy 425.65473 -377.007088) (xy 425.629938 -376.947881) (xy 425.613166 -376.885924) (xy 425.604706 -376.822297)
			(xy 425.604706 -376.75811) (xy 425.613165 -376.694483) (xy 425.629936 -376.632525) (xy 425.654727 -376.573319)
			(xy 425.670472 -376.545348) (xy 425.673012 -376.54103) (xy 425.677584 -376.527568) (xy 425.678747 -376.523734)
			(xy 425.680019 -376.515825) (xy 425.680124 -376.51182) (xy 425.680124 -375.768616) (xy 425.680055 -375.764608)
			(xy 425.678778 -375.756695) (xy 425.677584 -375.752868) (xy 425.673012 -375.739406) (xy 425.670472 -375.735088)
			(xy 425.6543 -375.706287) (xy 425.629031 -375.645259) (xy 425.612263 -375.581371) (xy 425.607734 -375.548652)
			(xy 425.605448 -375.529348) (xy 425.576746 -375.503948) (xy 424.47083 -375.503948) (xy 424.459807 -375.504481)
			(xy 424.439776 -375.513686) (xy 424.432222 -375.521728) (xy 424.397678 -375.562114) (xy 424.382946 -375.579132)
			(xy 424.37727 -375.586256) (xy 424.370898 -375.603306) (xy 424.3705 -375.612406) (xy 424.3705 -375.62028)
			(xy 424.371008 -375.623582) (xy 424.373147 -375.640072) (xy 424.375433 -375.673248) (xy 424.37558 -375.689876)
			(xy 424.37558 -375.69013) (xy 424.375042 -375.722851) (xy 424.366245 -375.787698) (xy 424.348815 -375.850776)
			(xy 424.323068 -375.910939) (xy 424.306746 -375.939304) (xy 424.306746 -375.939558) (xy 424.303333 -375.945553)
			(xy 424.299588 -375.958825) (xy 424.29938 -375.96572) (xy 424.29938 -376.108214) (xy 424.299634 -376.25147)
			(xy 424.29915 -376.261598) (xy 424.291427 -376.280324) (xy 424.277139 -376.294683) (xy 424.258452 -376.302499)
			(xy 424.248326 -376.303032) (xy 423.531792 -376.303032) (xy 423.521684 -376.302538) (xy 423.503005 -376.294801)
			(xy 423.488708 -376.280508) (xy 423.480965 -376.261832) (xy 423.480484 -376.251724) (xy 423.480484 -375.96572)
			(xy 423.480287 -375.958848) (xy 423.47667 -375.945591) (xy 423.473372 -375.939558) (xy 423.456987 -375.911182)
			(xy 423.431159 -375.850963) (xy 423.413664 -375.787817) (xy 423.404821 -375.722892) (xy 423.404284 -375.69013)
			(xy 423.404451 -375.672604) (xy 423.406992 -375.637645) (xy 423.409364 -375.62028) (xy 423.410888 -375.609104)
			(xy 423.404792 -375.588276) (xy 423.347388 -375.521474) (xy 423.339828 -375.513577) (xy 423.319954 -375.504521)
			(xy 423.309034 -375.503948) (xy 422.202864 -375.503948) (xy 422.174162 -375.529348) (xy 422.171876 -375.548652)
			(xy 422.167188 -375.582248) (xy 422.149698 -375.647788) (xy 422.12326 -375.710257) (xy 422.106344 -375.73966)
			(xy 422.103033 -375.745686) (xy 422.099428 -375.758949) (xy 422.099232 -375.765822) (xy 422.099232 -376.514614)
			(xy 422.099421 -376.521488) (xy 422.103024 -376.534754) (xy 422.106344 -376.540776) (xy 422.122726 -376.569153)
			(xy 422.148549 -376.629373) (xy 422.166039 -376.692518) (xy 422.174877 -376.757443) (xy 422.175432 -376.790204)
			(xy 422.174896 -376.822925) (xy 422.166103 -376.887775) (xy 422.148678 -376.950855) (xy 422.122935 -377.011022)
			(xy 422.106598 -377.039378) (xy 422.106598 -377.039632) (xy 422.103205 -377.045636) (xy 422.099459 -377.058902)
			(xy 422.099232 -377.065794) (xy 422.099232 -377.208034) (xy 422.099486 -377.35129) (xy 422.098999 -377.361419)
			(xy 422.091274 -377.380148) (xy 422.076989 -377.394513) (xy 422.058305 -377.402342) (xy 422.048178 -377.402852)
			(xy 421.331644 -377.402852) (xy 421.321527 -377.402367) (xy 421.302828 -377.394641) (xy 421.288509 -377.380346)
			(xy 421.28075 -377.36166) (xy 421.280336 -377.351544) (xy 421.280336 -377.065794) (xy 421.280149 -377.058919)
			(xy 421.276552 -377.04565) (xy 421.273224 -377.039632) (xy 421.256842 -377.011255) (xy 421.23102 -376.951035)
			(xy 421.21353 -376.887889) (xy 421.204692 -376.822965) (xy 421.204136 -376.790204) (xy 421.204693 -376.757444)
			(xy 421.21354 -376.692522) (xy 421.231034 -376.629379) (xy 421.256856 -376.56916) (xy 421.273224 -376.540776)
			(xy 421.276536 -376.53475) (xy 421.280145 -376.521487) (xy 421.280336 -376.514614) (xy 421.280336 -375.765822)
			(xy 421.280139 -375.75895) (xy 421.276526 -375.745691) (xy 421.273224 -375.73966) (xy 421.256271 -375.710276)
			(xy 421.229837 -375.647801) (xy 421.212359 -375.582253) (xy 421.207692 -375.548652) (xy 421.205406 -375.529348)
			(xy 421.176704 -375.503948) (xy 420.070788 -375.503948) (xy 420.059769 -375.504489) (xy 420.039751 -375.513705)
			(xy 420.03218 -375.521728) (xy 419.997636 -375.562114) (xy 419.982904 -375.579132) (xy 419.977223 -375.586254)
			(xy 419.970844 -375.603304) (xy 419.970458 -375.612406) (xy 419.970458 -375.62028) (xy 419.970966 -375.623836)
			(xy 419.974776 -375.661428) (xy 419.975792 -375.677938) (xy 419.975792 -375.690384) (xy 419.975241 -375.723146)
			(xy 419.966404 -375.788071) (xy 419.948914 -375.851217) (xy 419.92309 -375.911437) (xy 419.906704 -375.939812)
			(xy 419.903389 -375.945837) (xy 419.899775 -375.9591) (xy 419.899592 -375.965974) (xy 419.899592 -376.25147)
			(xy 419.899102 -376.261634) (xy 419.891334 -376.280419) (xy 419.876969 -376.294801) (xy 419.858193 -376.302591)
			(xy 419.84803 -376.303032) (xy 419.35019 -376.303032) (xy 419.340305 -376.303496) (xy 419.322 -376.310967)
			(xy 419.307872 -376.324799) (xy 419.300016 -376.342942) (xy 419.29939 -376.352816) (xy 419.297358 -376.46864)
			(xy 419.29685 -376.493786) (xy 419.27653 -377.567444) (xy 419.277546 -377.578366) (xy 419.28034 -377.592082)
			(xy 419.282118 -377.596654) (xy 419.282118 -377.596908) (xy 419.286287 -377.607382) (xy 419.293528 -377.628732)
			(xy 419.296596 -377.63958) (xy 419.300914 -377.656344) (xy 419.328092 -377.677172) (xy 419.84803 -377.677172)
			(xy 419.858195 -377.677604) (xy 419.876974 -377.685395) (xy 419.891341 -377.69978) (xy 419.899109 -377.718568)
			(xy 419.899592 -377.728734) (xy 419.899592 -378.01169) (xy 419.899661 -378.015698) (xy 419.900937 -378.023611)
			(xy 419.902132 -378.027438) (xy 419.906704 -378.0409) (xy 419.909244 -378.045218) (xy 419.924987 -378.073191)
			(xy 419.949781 -378.132397) (xy 419.966555 -378.194355) (xy 419.975017 -378.257983) (xy 419.97502 -378.322172)
			(xy 419.966564 -378.385801) (xy 419.949795 -378.44776) (xy 419.925007 -378.506969) (xy 419.909244 -378.53493)
			(xy 419.906704 -378.539248) (xy 419.902132 -378.55271) (xy 419.900973 -378.556545) (xy 419.899699 -378.564453)
			(xy 419.899592 -378.568458) (xy 419.899592 -379.311662) (xy 419.899659 -379.31567) (xy 419.900931 -379.323585)
			(xy 419.902132 -379.32741) (xy 419.906704 -379.340872) (xy 419.909244 -379.34519) (xy 419.924982 -379.373163)
			(xy 419.949766 -379.432368) (xy 419.966532 -379.494323) (xy 419.974985 -379.557948) (xy 419.97498 -379.622132)
			(xy 419.966516 -379.685755) (xy 419.949741 -379.747707) (xy 419.924947 -379.806909) (xy 419.909244 -379.834902)
			(xy 419.906704 -379.83922) (xy 419.902132 -379.852682) (xy 419.90097 -379.856516) (xy 419.899693 -379.864425)
			(xy 419.899592 -379.86843) (xy 419.899592 -380.151386) (xy 419.8991 -380.161548) (xy 419.891329 -380.180327)
			(xy 419.876964 -380.194704) (xy 419.858191 -380.202491) (xy 419.84803 -380.202948) (xy 419.328092 -380.202948)
			(xy 419.300914 -380.223776) (xy 419.296342 -380.24054) (xy 419.289998 -380.262717) (xy 419.272703 -380.305478)
			(xy 419.25038 -380.345844) (xy 419.23716 -380.364746) (xy 419.23716 -380.365) (xy 419.232842 -380.371096)
			(xy 419.225222 -380.392432) (xy 419.22319 -380.400306) (xy 419.222428 -380.408434) (xy 419.217168 -380.69012)
			(xy 421.204136 -380.69012) (xy 421.204697 -380.65739) (xy 421.213556 -380.592532) (xy 421.231047 -380.529452)
			(xy 421.256855 -380.469294) (xy 421.273224 -380.440946) (xy 421.276524 -380.434914) (xy 421.280139 -380.421656)
			(xy 421.280336 -380.414784) (xy 421.280336 -379.665484) (xy 421.280146 -379.658611) (xy 421.276536 -379.645348)
			(xy 421.273224 -379.639322) (xy 421.256869 -379.610967) (xy 421.231064 -379.55081) (xy 421.213572 -379.487732)
			(xy 421.204708 -379.422877) (xy 421.204136 -379.390148) (xy 421.204709 -379.357419) (xy 421.213564 -379.292561)
			(xy 421.231052 -379.229481) (xy 421.256857 -379.169323) (xy 421.273224 -379.140974) (xy 421.27655 -379.134955)
			(xy 421.280148 -379.121687) (xy 421.280336 -379.114812) (xy 421.280336 -378.828554) (xy 421.280789 -378.818425)
			(xy 421.288531 -378.799703) (xy 421.302827 -378.785349) (xy 421.321517 -378.777531) (xy 421.331644 -378.776992)
			(xy 422.047924 -378.776992) (xy 422.058079 -378.777402) (xy 422.07683 -378.785204) (xy 422.091152 -378.799604)
			(xy 422.098853 -378.818397) (xy 422.099232 -378.828554) (xy 422.099232 -379.114812) (xy 422.099416 -379.121686)
			(xy 422.103029 -379.134949) (xy 422.106344 -379.140974) (xy 422.122694 -379.169332) (xy 422.148501 -379.229488)
			(xy 422.165995 -379.292565) (xy 422.17486 -379.35742) (xy 422.175432 -379.390148) (xy 422.174861 -379.422877)
			(xy 422.166006 -379.487735) (xy 422.148517 -379.550815) (xy 422.131689 -379.590046) (xy 423.404284 -379.590046)
			(xy 423.40485 -379.557317) (xy 423.413706 -379.492458) (xy 423.431197 -379.429378) (xy 423.457004 -379.36922)
			(xy 423.473372 -379.340872) (xy 423.476695 -379.334851) (xy 423.480296 -379.321585) (xy 423.480484 -379.31471)
			(xy 423.480484 -378.56541) (xy 423.48029 -378.558537) (xy 423.476683 -378.545274) (xy 423.473372 -378.539248)
			(xy 423.456983 -378.510912) (xy 423.431187 -378.450747) (xy 423.413705 -378.387664) (xy 423.404851 -378.322804)
			(xy 423.404284 -378.290074) (xy 423.404863 -378.257345) (xy 423.413715 -378.192487) (xy 423.431202 -378.129407)
			(xy 423.457005 -378.069249) (xy 423.473372 -378.0409) (xy 423.476685 -378.034874) (xy 423.480292 -378.021611)
			(xy 423.480484 -378.014738) (xy 423.480484 -377.728734) (xy 423.480956 -377.718604) (xy 423.488681 -377.699875)
			(xy 423.502972 -377.685516) (xy 423.521664 -377.677704) (xy 423.531792 -377.677172) (xy 424.248072 -377.677172)
			(xy 424.258221 -377.677644) (xy 424.276967 -377.685425) (xy 424.291291 -377.699806) (xy 424.298996 -377.718584)
			(xy 424.29938 -377.728734) (xy 424.29938 -378.014738) (xy 424.299598 -378.021609) (xy 424.303189 -378.034872)
			(xy 424.306492 -378.0409) (xy 424.322857 -378.06925) (xy 424.348659 -378.129409) (xy 424.366149 -378.192488)
			(xy 424.37501 -378.257345) (xy 424.37558 -378.290074) (xy 424.375028 -378.322797) (xy 427.804911 -378.322797)
			(xy 427.804914 -378.257358) (xy 427.813701 -378.192512) (xy 427.831113 -378.129433) (xy 427.856835 -378.069261)
			(xy 427.87316 -378.0409) (xy 427.876471 -378.034874) (xy 427.88008 -378.021611) (xy 427.880272 -378.014738)
			(xy 427.880272 -377.728734) (xy 427.880693 -377.71856) (xy 427.888473 -377.69976) (xy 427.90286 -377.685373)
			(xy 427.92166 -377.677593) (xy 427.931834 -377.677172) (xy 428.648114 -377.677172) (xy 428.658291 -377.677553)
			(xy 428.677092 -377.685349) (xy 428.691478 -377.699748) (xy 428.699256 -377.718557) (xy 428.699676 -377.728734)
			(xy 428.699676 -378.014738) (xy 428.699895 -378.021609) (xy 428.703485 -378.034872) (xy 428.706788 -378.0409)
			(xy 428.723087 -378.069274) (xy 428.748806 -378.129442) (xy 428.766215 -378.192518) (xy 428.775001 -378.25736)
			(xy 428.775004 -378.322795) (xy 428.775004 -378.322797) (xy 432.2047 -378.322797) (xy 432.204703 -378.257358)
			(xy 432.21349 -378.192512) (xy 432.230902 -378.129433) (xy 432.256624 -378.069261) (xy 432.272948 -378.0409)
			(xy 432.276259 -378.034873) (xy 432.279867 -378.021611) (xy 432.28006 -378.014738) (xy 432.28006 -377.728734)
			(xy 432.280492 -377.718562) (xy 432.28827 -377.699764) (xy 432.302654 -377.685377) (xy 432.32145 -377.677595)
			(xy 432.331622 -377.677172) (xy 433.047902 -377.677172) (xy 433.058078 -377.677563) (xy 433.076879 -377.685355)
			(xy 433.091265 -377.699751) (xy 433.099044 -377.718558) (xy 433.099464 -377.728734) (xy 433.099464 -378.014738)
			(xy 433.099684 -378.021609) (xy 433.103274 -378.034872) (xy 433.106576 -378.0409) (xy 433.122876 -378.069274)
			(xy 433.148595 -378.129442) (xy 433.166005 -378.192518) (xy 433.174791 -378.25736) (xy 433.174792 -378.290074)
			(xy 436.603656 -378.290074) (xy 436.607647 -378.227907) (xy 436.619556 -378.16676) (xy 436.639185 -378.107639)
			(xy 436.666214 -378.051513) (xy 436.700198 -377.999304) (xy 436.74058 -377.951869) (xy 436.786696 -377.909988)
			(xy 436.837788 -377.874348) (xy 436.893019 -377.845534) (xy 436.951481 -377.82402) (xy 437.012215 -377.810158)
			(xy 437.074222 -377.804176) (xy 437.136485 -377.806172) (xy 437.197982 -377.816115) (xy 437.257703 -377.833839)
			(xy 437.314666 -377.859056) (xy 437.367937 -377.891349) (xy 437.416642 -377.930189) (xy 437.459979 -377.974939)
			(xy 437.497239 -378.024863) (xy 437.527808 -378.079142) (xy 437.551186 -378.136885) (xy 437.566987 -378.197143)
			(xy 437.574953 -378.258926) (xy 437.575452 -378.290074) (xy 437.574953 -378.321222) (xy 437.566987 -378.383005)
			(xy 437.551186 -378.443263) (xy 437.527808 -378.501006) (xy 437.497239 -378.555285) (xy 437.459979 -378.605209)
			(xy 437.416642 -378.649959) (xy 437.367937 -378.688799) (xy 437.314666 -378.721092) (xy 437.257703 -378.746309)
			(xy 437.197982 -378.764033) (xy 437.136485 -378.773976) (xy 437.074222 -378.775972) (xy 437.012215 -378.76999)
			(xy 436.951481 -378.756128) (xy 436.893019 -378.734614) (xy 436.837788 -378.7058) (xy 436.786696 -378.67016)
			(xy 436.74058 -378.628279) (xy 436.700198 -378.580844) (xy 436.666214 -378.528635) (xy 436.639185 -378.472509)
			(xy 436.619556 -378.413388) (xy 436.607647 -378.352241) (xy 436.603656 -378.290074) (xy 433.174792 -378.290074)
			(xy 433.174794 -378.322795) (xy 433.166014 -378.387638) (xy 433.148609 -378.450716) (xy 433.122896 -378.510887)
			(xy 433.106576 -378.539248) (xy 433.103243 -378.545263) (xy 433.099649 -378.558534) (xy 433.099464 -378.56541)
			(xy 433.099464 -379.31471) (xy 433.099657 -379.321583) (xy 433.103265 -379.334846) (xy 433.106576 -379.340872)
			(xy 433.122937 -379.369212) (xy 433.14865 -379.429388) (xy 433.166053 -379.492471) (xy 433.174832 -379.55732)
			(xy 433.174826 -379.622759) (xy 433.166037 -379.687606) (xy 433.148624 -379.750686) (xy 433.122901 -379.810859)
			(xy 433.106576 -379.83922) (xy 433.103252 -379.84524) (xy 433.099653 -379.858507) (xy 433.099464 -379.865382)
			(xy 433.099464 -380.151386) (xy 433.099025 -380.161556) (xy 433.091245 -380.180351) (xy 433.076864 -380.194736)
			(xy 433.058072 -380.202522) (xy 433.047902 -380.202948) (xy 432.331622 -380.202948) (xy 432.32145 -380.202518)
			(xy 432.302653 -380.194737) (xy 432.288267 -380.180353) (xy 432.280484 -380.161558) (xy 432.28006 -380.151386)
			(xy 432.28006 -379.865382) (xy 432.27988 -379.858508) (xy 432.276264 -379.845245) (xy 432.272948 -379.83922)
			(xy 432.256664 -379.810837) (xy 432.230943 -379.750671) (xy 432.21353 -379.687597) (xy 432.204741 -379.622756)
			(xy 432.204736 -379.557323) (xy 432.213514 -379.49248) (xy 432.230917 -379.429403) (xy 432.256629 -379.369233)
			(xy 432.272948 -379.340872) (xy 432.276269 -379.33485) (xy 432.279871 -379.321584) (xy 432.28006 -379.31471)
			(xy 432.28006 -378.56541) (xy 432.279869 -378.558537) (xy 432.276261 -378.545274) (xy 432.272948 -378.539248)
			(xy 432.256603 -378.510899) (xy 432.230887 -378.450725) (xy 432.213481 -378.387644) (xy 432.2047 -378.322797)
			(xy 428.775004 -378.322797) (xy 428.766224 -378.387638) (xy 428.74882 -378.450716) (xy 428.723108 -378.510886)
			(xy 428.706788 -378.539248) (xy 428.703455 -378.545264) (xy 428.699861 -378.558534) (xy 428.699676 -378.56541)
			(xy 428.699676 -379.31471) (xy 428.699867 -379.321583) (xy 428.703476 -379.334846) (xy 428.706788 -379.340872)
			(xy 428.723148 -379.369212) (xy 428.748861 -379.429388) (xy 428.766264 -379.492472) (xy 428.775042 -379.55732)
			(xy 428.775037 -379.622759) (xy 428.766248 -379.687606) (xy 428.748835 -379.750686) (xy 428.723112 -379.810858)
			(xy 428.706788 -379.83922) (xy 428.703465 -379.845241) (xy 428.699865 -379.858508) (xy 428.699676 -379.865382)
			(xy 428.699676 -380.151386) (xy 428.699156 -380.161541) (xy 428.691388 -380.180307) (xy 428.677031 -380.194673)
			(xy 428.658269 -380.20245) (xy 428.648114 -380.202948) (xy 427.931834 -380.202948) (xy 427.921663 -380.202508)
			(xy 427.902866 -380.194731) (xy 427.88848 -380.180351) (xy 427.880696 -380.161557) (xy 427.880272 -380.151386)
			(xy 427.880272 -379.865382) (xy 427.88009 -379.858508) (xy 427.876475 -379.845245) (xy 427.87316 -379.83922)
			(xy 427.856876 -379.810837) (xy 427.831154 -379.750672) (xy 427.813741 -379.687597) (xy 427.804952 -379.622756)
			(xy 427.804946 -379.557323) (xy 427.813725 -379.49248) (xy 427.831128 -379.429403) (xy 427.85684 -379.369233)
			(xy 427.87316 -379.340872) (xy 427.876481 -379.334851) (xy 427.880083 -379.321584) (xy 427.880272 -379.31471)
			(xy 427.880272 -378.56541) (xy 427.88008 -378.558537) (xy 427.876472 -378.545274) (xy 427.87316 -378.539248)
			(xy 427.856815 -378.510899) (xy 427.831098 -378.450725) (xy 427.813692 -378.387644) (xy 427.804911 -378.322797)
			(xy 424.375028 -378.322797) (xy 424.375028 -378.322804) (xy 424.366168 -378.387663) (xy 424.348674 -378.450743)
			(xy 424.322863 -378.5109) (xy 424.306492 -378.539248) (xy 424.30316 -378.545264) (xy 424.299565 -378.558534)
			(xy 424.29938 -378.56541) (xy 424.29938 -379.31471) (xy 424.299571 -379.321583) (xy 424.30318 -379.334846)
			(xy 424.306492 -379.340872) (xy 424.322846 -379.369228) (xy 424.348651 -379.429385) (xy 424.366144 -379.492462)
			(xy 424.375008 -379.557318) (xy 424.37558 -379.590046) (xy 424.375015 -379.622776) (xy 424.366159 -379.687634)
			(xy 424.348669 -379.750714) (xy 424.322861 -379.810872) (xy 424.306492 -379.83922) (xy 424.30317 -379.845241)
			(xy 424.299569 -379.858508) (xy 424.29938 -379.865382) (xy 424.29938 -380.151386) (xy 424.298863 -380.161509)
			(xy 424.291143 -380.180226) (xy 424.276866 -380.194583) (xy 424.258193 -380.202406) (xy 424.248072 -380.202948)
			(xy 423.531792 -380.202948) (xy 423.521643 -380.202486) (xy 423.5029 -380.194697) (xy 423.488579 -380.180313)
			(xy 423.480871 -380.161536) (xy 423.480484 -380.151386) (xy 423.480484 -379.865382) (xy 423.480301 -379.858508)
			(xy 423.476687 -379.845245) (xy 423.473372 -379.83922) (xy 423.457012 -379.810868) (xy 423.431209 -379.750709)
			(xy 423.413718 -379.687631) (xy 423.404856 -379.622775) (xy 423.404284 -379.590046) (xy 422.131689 -379.590046)
			(xy 422.122712 -379.610974) (xy 422.106344 -379.639322) (xy 422.103025 -379.645345) (xy 422.099422 -379.65861)
			(xy 422.099232 -379.665484) (xy 422.099232 -380.414784) (xy 422.099426 -380.421657) (xy 422.103033 -380.43492)
			(xy 422.106344 -380.440946) (xy 422.122723 -380.469288) (xy 422.148523 -380.52945) (xy 422.166009 -380.592532)
			(xy 422.174864 -380.65739) (xy 422.174864 -380.6574) (xy 425.604793 -380.6574) (xy 425.613574 -380.592556)
			(xy 425.630978 -380.529479) (xy 425.656692 -380.469308) (xy 425.673012 -380.440946) (xy 425.676311 -380.434914)
			(xy 425.679926 -380.421656) (xy 425.680124 -380.414784) (xy 425.680124 -379.665484) (xy 425.679935 -379.658611)
			(xy 425.676324 -379.645348) (xy 425.673012 -379.639322) (xy 425.656731 -379.610938) (xy 425.631011 -379.550772)
			(xy 425.6136 -379.487698) (xy 425.604812 -379.422858) (xy 425.604806 -379.357425) (xy 425.613583 -379.292583)
			(xy 425.630984 -379.229506) (xy 425.656694 -379.169335) (xy 425.673012 -379.140974) (xy 425.676337 -379.134954)
			(xy 425.679936 -379.121687) (xy 425.680124 -379.114812) (xy 425.680124 -378.828554) (xy 425.680595 -378.818395)
			(xy 425.688382 -378.799628) (xy 425.702754 -378.785264) (xy 425.721527 -378.777489) (xy 425.731686 -378.776992)
			(xy 426.447966 -378.776992) (xy 426.458116 -378.77756) (xy 426.476875 -378.785315) (xy 426.49124 -378.799657)
			(xy 426.499024 -378.818405) (xy 426.499528 -378.828554) (xy 426.499528 -379.114812) (xy 426.499712 -379.121686)
			(xy 426.503325 -379.134949) (xy 426.50664 -379.140974) (xy 426.523004 -379.169313) (xy 426.548718 -379.229489)
			(xy 426.566123 -379.292572) (xy 426.574902 -379.357421) (xy 426.574896 -379.422861) (xy 426.566106 -379.487709)
			(xy 426.548691 -379.550789) (xy 426.522966 -379.610961) (xy 426.50664 -379.639322) (xy 426.503321 -379.645344)
			(xy 426.499718 -379.65861) (xy 426.499528 -379.665484) (xy 426.499528 -380.414784) (xy 426.499723 -380.421657)
			(xy 426.503329 -380.43492) (xy 426.50664 -380.440946) (xy 426.52298 -380.469298) (xy 426.548697 -380.529471)
			(xy 426.566104 -380.592552) (xy 426.574886 -380.657398) (xy 426.574884 -380.69012) (xy 430.00422 -380.69012)
			(xy 430.00477 -380.65739) (xy 430.01363 -380.592531) (xy 430.031125 -380.529451) (xy 430.056937 -380.469293)
			(xy 430.073308 -380.440946) (xy 430.076607 -380.434914) (xy 430.080222 -380.421656) (xy 430.08042 -380.414784)
			(xy 430.08042 -379.665484) (xy 430.080232 -379.658611) (xy 430.076621 -379.645348) (xy 430.073308 -379.639322)
			(xy 430.056952 -379.610968) (xy 430.031148 -379.55081) (xy 430.013655 -379.487732) (xy 430.004792 -379.422877)
			(xy 430.00422 -379.390148) (xy 430.004782 -379.357418) (xy 430.013639 -379.29256) (xy 430.03113 -379.22948)
			(xy 430.056939 -379.169322) (xy 430.073308 -379.140974) (xy 430.076633 -379.134954) (xy 430.080232 -379.121687)
			(xy 430.08042 -379.114812) (xy 430.08042 -378.828554) (xy 430.080888 -378.818427) (xy 430.088628 -378.799708)
			(xy 430.102919 -378.785354) (xy 430.121603 -378.777533) (xy 430.131728 -378.776992) (xy 430.848008 -378.776992)
			(xy 430.858162 -378.777415) (xy 430.876913 -378.785212) (xy 430.891235 -378.799608) (xy 430.898936 -378.818398)
			(xy 430.899316 -378.828554) (xy 430.899316 -379.114812) (xy 430.899501 -379.121686) (xy 430.903114 -379.134949)
			(xy 430.906428 -379.140974) (xy 430.922786 -379.169327) (xy 430.948589 -379.229486) (xy 430.966081 -379.292564)
			(xy 430.974944 -379.357419) (xy 430.975516 -379.390148) (xy 430.974947 -379.422877) (xy 430.966092 -379.487735)
			(xy 430.948602 -379.550816) (xy 430.922796 -379.610974) (xy 430.906428 -379.639322) (xy 430.903107 -379.645344)
			(xy 430.899505 -379.65861) (xy 430.899316 -379.665484) (xy 430.899316 -380.414784) (xy 430.899512 -380.421657)
			(xy 430.903117 -380.43492) (xy 430.906428 -380.440946) (xy 430.922815 -380.469284) (xy 430.948611 -380.529448)
			(xy 430.966094 -380.592531) (xy 430.974949 -380.65739) (xy 430.974949 -380.6574) (xy 434.40488 -380.6574)
			(xy 434.41366 -380.592557) (xy 434.431064 -380.529479) (xy 434.456776 -380.469308) (xy 434.473096 -380.440946)
			(xy 434.476394 -380.434913) (xy 434.48001 -380.421656) (xy 434.480208 -380.414784) (xy 434.480208 -379.665484)
			(xy 434.480021 -379.65861) (xy 434.476409 -379.645348) (xy 434.473096 -379.639322) (xy 434.456816 -379.610938)
			(xy 434.431097 -379.550772) (xy 434.413686 -379.487698) (xy 434.404898 -379.422858) (xy 434.404892 -379.357425)
			(xy 434.413669 -379.292583) (xy 434.431069 -379.229506) (xy 434.456778 -379.169336) (xy 434.473096 -379.140974)
			(xy 434.47642 -379.134954) (xy 434.48002 -379.121687) (xy 434.480208 -379.114812) (xy 434.480208 -378.828554)
			(xy 434.480695 -378.818397) (xy 434.488479 -378.799633) (xy 434.502846 -378.78527) (xy 434.521613 -378.777492)
			(xy 434.53177 -378.776992) (xy 435.24805 -378.776992) (xy 435.258213 -378.777504) (xy 435.276998 -378.785264)
			(xy 435.291383 -378.799622) (xy 435.299177 -378.818392) (xy 435.299612 -378.828554) (xy 435.299612 -379.114812)
			(xy 435.299798 -379.121686) (xy 435.30341 -379.134949) (xy 435.306724 -379.140974) (xy 435.323088 -379.169312)
			(xy 435.348804 -379.229489) (xy 435.366209 -379.292572) (xy 435.374988 -379.357421) (xy 435.374982 -379.422861)
			(xy 435.366192 -379.487709) (xy 435.348777 -379.550789) (xy 435.331993 -379.590046) (xy 436.603656 -379.590046)
			(xy 436.607647 -379.527879) (xy 436.619556 -379.466732) (xy 436.639185 -379.407611) (xy 436.666214 -379.351485)
			(xy 436.700198 -379.299276) (xy 436.74058 -379.251841) (xy 436.786696 -379.20996) (xy 436.837788 -379.17432)
			(xy 436.893019 -379.145506) (xy 436.951481 -379.123992) (xy 437.012215 -379.11013) (xy 437.074222 -379.104148)
			(xy 437.136485 -379.106144) (xy 437.197982 -379.116087) (xy 437.257703 -379.133811) (xy 437.314666 -379.159028)
			(xy 437.367937 -379.191321) (xy 437.416642 -379.230161) (xy 437.459979 -379.274911) (xy 437.497239 -379.324835)
			(xy 437.527808 -379.379114) (xy 437.532275 -379.390148) (xy 438.803804 -379.390148) (xy 438.807795 -379.327981)
			(xy 438.819704 -379.266834) (xy 438.839333 -379.207713) (xy 438.866362 -379.151587) (xy 438.900346 -379.099378)
			(xy 438.940728 -379.051943) (xy 438.986844 -379.010062) (xy 439.037936 -378.974422) (xy 439.093167 -378.945608)
			(xy 439.151629 -378.924094) (xy 439.212363 -378.910232) (xy 439.27437 -378.90425) (xy 439.336633 -378.906246)
			(xy 439.39813 -378.916189) (xy 439.457851 -378.933913) (xy 439.514814 -378.95913) (xy 439.568085 -378.991423)
			(xy 439.61679 -379.030263) (xy 439.660127 -379.075013) (xy 439.697387 -379.124937) (xy 439.727956 -379.179216)
			(xy 439.751334 -379.236959) (xy 439.767135 -379.297217) (xy 439.775101 -379.359) (xy 439.7756 -379.390148)
			(xy 439.775101 -379.421296) (xy 439.767135 -379.483079) (xy 439.751334 -379.543337) (xy 439.727956 -379.60108)
			(xy 439.697387 -379.655359) (xy 439.660127 -379.705283) (xy 439.61679 -379.750033) (xy 439.568085 -379.788873)
			(xy 439.514814 -379.821166) (xy 439.457851 -379.846383) (xy 439.39813 -379.864107) (xy 439.336633 -379.87405)
			(xy 439.27437 -379.876046) (xy 439.212363 -379.870064) (xy 439.151629 -379.856202) (xy 439.093167 -379.834688)
			(xy 439.037936 -379.805874) (xy 438.986844 -379.770234) (xy 438.940728 -379.728353) (xy 438.900346 -379.680918)
			(xy 438.866362 -379.628709) (xy 438.839333 -379.572583) (xy 438.819704 -379.513462) (xy 438.807795 -379.452315)
			(xy 438.803804 -379.390148) (xy 437.532275 -379.390148) (xy 437.551186 -379.436857) (xy 437.566987 -379.497115)
			(xy 437.574953 -379.558898) (xy 437.575452 -379.590046) (xy 437.574953 -379.621194) (xy 437.566987 -379.682977)
			(xy 437.551186 -379.743235) (xy 437.527808 -379.800978) (xy 437.497239 -379.855257) (xy 437.459979 -379.905181)
			(xy 437.416642 -379.949931) (xy 437.367937 -379.988771) (xy 437.314666 -380.021064) (xy 437.257703 -380.046281)
			(xy 437.197982 -380.064005) (xy 437.136485 -380.073948) (xy 437.074222 -380.075944) (xy 437.012215 -380.069962)
			(xy 436.951481 -380.0561) (xy 436.893019 -380.034586) (xy 436.837788 -380.005772) (xy 436.786696 -379.970132)
			(xy 436.74058 -379.928251) (xy 436.700198 -379.880816) (xy 436.666214 -379.828607) (xy 436.639185 -379.772481)
			(xy 436.619556 -379.71336) (xy 436.607647 -379.652213) (xy 436.603656 -379.590046) (xy 435.331993 -379.590046)
			(xy 435.323051 -379.610961) (xy 435.306724 -379.639322) (xy 435.303403 -379.645344) (xy 435.299801 -379.65861)
			(xy 435.299612 -379.665484) (xy 435.299612 -380.414784) (xy 435.299809 -380.421657) (xy 435.303414 -380.43492)
			(xy 435.306724 -380.440946) (xy 435.323064 -380.469298) (xy 435.348782 -380.529471) (xy 435.36619 -380.592551)
			(xy 435.374972 -380.657398) (xy 435.374971 -380.69012) (xy 438.803804 -380.69012) (xy 438.807795 -380.627953)
			(xy 438.819704 -380.566806) (xy 438.839333 -380.507685) (xy 438.866362 -380.451559) (xy 438.900346 -380.39935)
			(xy 438.940728 -380.351915) (xy 438.986844 -380.310034) (xy 439.037936 -380.274394) (xy 439.093167 -380.24558)
			(xy 439.151629 -380.224066) (xy 439.212363 -380.210204) (xy 439.27437 -380.204222) (xy 439.336633 -380.206218)
			(xy 439.39813 -380.216161) (xy 439.457851 -380.233885) (xy 439.514814 -380.259102) (xy 439.568085 -380.291395)
			(xy 439.61679 -380.330235) (xy 439.660127 -380.374985) (xy 439.697387 -380.424909) (xy 439.727956 -380.479188)
			(xy 439.751334 -380.536931) (xy 439.767135 -380.597189) (xy 439.775101 -380.658972) (xy 439.7756 -380.69012)
			(xy 439.775101 -380.721268) (xy 439.767135 -380.783051) (xy 439.751334 -380.843309) (xy 439.727956 -380.901052)
			(xy 439.697387 -380.955331) (xy 439.660127 -381.005255) (xy 439.61679 -381.050005) (xy 439.568085 -381.088845)
			(xy 439.514814 -381.121138) (xy 439.457851 -381.146355) (xy 439.39813 -381.164079) (xy 439.336633 -381.174022)
			(xy 439.27437 -381.176018) (xy 439.212363 -381.170036) (xy 439.151629 -381.156174) (xy 439.093167 -381.13466)
			(xy 439.037936 -381.105846) (xy 438.986844 -381.070206) (xy 438.940728 -381.028325) (xy 438.900346 -380.98089)
			(xy 438.866362 -380.928681) (xy 438.839333 -380.872555) (xy 438.819704 -380.813434) (xy 438.807795 -380.752287)
			(xy 438.803804 -380.69012) (xy 435.374971 -380.69012) (xy 435.37497 -380.722836) (xy 435.366183 -380.787682)
			(xy 435.348771 -380.850762) (xy 435.323049 -380.910933) (xy 435.306724 -380.939294) (xy 435.303413 -380.945321)
			(xy 435.299805 -380.958583) (xy 435.299612 -380.965456) (xy 435.299612 -381.251206) (xy 435.29924 -381.261384)
			(xy 435.291444 -381.280189) (xy 435.277041 -381.294575) (xy 435.258229 -381.302351) (xy 435.24805 -381.302768)
			(xy 434.53177 -381.302768) (xy 434.521611 -381.302291) (xy 434.502842 -381.294508) (xy 434.488478 -381.280138)
			(xy 434.480704 -381.261365) (xy 434.480208 -381.251206) (xy 434.480208 -380.965456) (xy 434.479993 -380.958584)
			(xy 434.4764 -380.945322) (xy 434.473096 -380.939294) (xy 434.456792 -380.910923) (xy 434.431075 -380.850754)
			(xy 434.413667 -380.787677) (xy 434.404882 -380.722835) (xy 434.40488 -380.6574) (xy 430.974949 -380.6574)
			(xy 430.975516 -380.69012) (xy 430.974935 -380.722849) (xy 430.966083 -380.787707) (xy 430.948597 -380.850787)
			(xy 430.922794 -380.910945) (xy 430.906428 -380.939294) (xy 430.903117 -380.945321) (xy 430.899509 -380.958583)
			(xy 430.899316 -380.965456) (xy 430.899316 -381.251206) (xy 430.898877 -381.261338) (xy 430.891139 -381.280068)
			(xy 430.876838 -381.294426) (xy 430.858138 -381.302237) (xy 430.848008 -381.302768) (xy 430.131728 -381.302768)
			(xy 430.121572 -381.302355) (xy 430.102814 -381.294563) (xy 430.088488 -381.280163) (xy 430.080793 -381.261364)
			(xy 430.08042 -381.251206) (xy 430.08042 -380.965456) (xy 430.080204 -380.958585) (xy 430.076612 -380.945322)
			(xy 430.073308 -380.939294) (xy 430.056941 -380.910946) (xy 430.031139 -380.850786) (xy 430.01365 -380.787706)
			(xy 430.00479 -380.722849) (xy 430.00422 -380.69012) (xy 426.574884 -380.69012) (xy 426.574883 -380.722836)
			(xy 426.566097 -380.787682) (xy 426.548686 -380.850762) (xy 426.522964 -380.910933) (xy 426.50664 -380.939294)
			(xy 426.503331 -380.945321) (xy 426.499721 -380.958583) (xy 426.499528 -380.965456) (xy 426.499528 -381.251206)
			(xy 426.49914 -381.261382) (xy 426.491347 -381.280184) (xy 426.47695 -381.294569) (xy 426.458143 -381.302348)
			(xy 426.447966 -381.302768) (xy 425.731686 -381.302768) (xy 425.721528 -381.302278) (xy 425.70276 -381.2945)
			(xy 425.688395 -381.280133) (xy 425.68062 -381.261364) (xy 425.680124 -381.251206) (xy 425.680124 -380.965456)
			(xy 425.679908 -380.958585) (xy 425.676316 -380.945322) (xy 425.673012 -380.939294) (xy 425.656708 -380.910923)
			(xy 425.63099 -380.850754) (xy 425.613581 -380.787677) (xy 425.604796 -380.722835) (xy 425.604793 -380.6574)
			(xy 422.174864 -380.6574) (xy 422.175432 -380.69012) (xy 422.174848 -380.722849) (xy 422.165997 -380.787706)
			(xy 422.148512 -380.850786) (xy 422.12271 -380.910945) (xy 422.106344 -380.939294) (xy 422.103035 -380.945321)
			(xy 422.099425 -380.958583) (xy 422.099232 -380.965456) (xy 422.099232 -381.251206) (xy 422.098777 -381.261337)
			(xy 422.091042 -381.280063) (xy 422.076746 -381.29442) (xy 422.058052 -381.302234) (xy 422.047924 -381.302768)
			(xy 421.331644 -381.302768) (xy 421.321489 -381.302342) (xy 421.302731 -381.294555) (xy 421.288405 -381.280159)
			(xy 421.28071 -381.261363) (xy 421.280336 -381.251206) (xy 421.280336 -380.965456) (xy 421.280118 -380.958585)
			(xy 421.276527 -380.945322) (xy 421.273224 -380.939294) (xy 421.256858 -380.910945) (xy 421.231056 -380.850785)
			(xy 421.213566 -380.787706) (xy 421.204706 -380.722849) (xy 421.204136 -380.69012) (xy 419.217168 -380.69012)
			(xy 419.204902 -381.346964) (xy 419.204886 -381.351695) (xy 419.20642 -381.361029) (xy 419.20795 -381.365506)
			(xy 419.21684 -381.389382) (xy 419.222174 -381.395986) (xy 419.24054 -381.419099) (xy 419.270648 -381.469876)
			(xy 419.282118 -381.497078) (xy 419.286223 -381.507555) (xy 419.293338 -381.528906) (xy 419.296342 -381.53975)
			(xy 419.296342 -381.540258) (xy 419.299817 -381.550801) (xy 419.314151 -381.56772) (xy 419.334276 -381.577032)
			(xy 419.345364 -381.577596) (xy 419.851586 -381.577596) (xy 419.861193 -381.578681) (xy 419.878637 -381.586981)
			(xy 419.891863 -381.601064) (xy 419.899053 -381.618995) (xy 419.899592 -381.62865) (xy 419.899592 -381.911606)
			(xy 419.899662 -381.915614) (xy 419.900941 -381.923526) (xy 419.902132 -381.927354) (xy 419.906704 -381.940816)
			(xy 419.909244 -381.945134) (xy 419.924986 -381.973107) (xy 419.949777 -382.032313) (xy 419.96655 -382.09427)
			(xy 419.97501 -382.157898) (xy 419.975011 -382.222085) (xy 419.966553 -382.285713) (xy 419.949783 -382.347671)
			(xy 419.924994 -382.406878) (xy 419.909244 -382.434846) (xy 419.906704 -382.439164) (xy 419.902132 -382.452626)
			(xy 419.900974 -382.456461) (xy 419.899703 -382.46437) (xy 419.899592 -382.468374) (xy 419.899592 -383.211832)
			(xy 419.899664 -383.215839) (xy 419.900947 -383.223751) (xy 419.902132 -383.22758) (xy 419.906704 -383.241042)
			(xy 419.909244 -383.24536) (xy 419.924984 -383.273333) (xy 419.949772 -383.332539) (xy 419.966541 -383.394495)
			(xy 419.974999 -383.458121) (xy 419.974997 -383.522307) (xy 419.966536 -383.585932) (xy 419.949763 -383.647888)
			(xy 419.924972 -383.707092) (xy 419.909244 -383.735072) (xy 419.906704 -383.73939) (xy 419.902132 -383.752852)
			(xy 419.900968 -383.756686) (xy 419.899686 -383.764595) (xy 419.899592 -383.7686) (xy 419.899592 -384.051556)
			(xy 419.899176 -384.061682) (xy 419.891436 -384.080397) (xy 419.87712 -384.094721) (xy 419.85841 -384.10247)
			(xy 419.848284 -384.102864) (xy 419.468554 -384.102864) (xy 419.45938 -384.103235) (xy 419.442212 -384.109703)
			(xy 419.428463 -384.12185) (xy 419.42385 -384.129788) (xy 419.417246 -384.142234) (xy 419.418516 -384.170174)
			(xy 419.428422 -384.184906) (xy 419.430962 -384.188208) (xy 419.436804 -384.195574) (xy 419.440868 -384.198876)
			(xy 419.448091 -384.204083) (xy 419.464984 -384.209669) (xy 419.473888 -384.209798) (xy 419.48989 -384.209544)
			(xy 419.524284 -384.210051) (xy 419.592591 -384.218176) (xy 419.659459 -384.234313) (xy 419.723953 -384.258237)
			(xy 419.785169 -384.289613) (xy 419.84225 -384.328) (xy 419.894396 -384.372862) (xy 419.940877 -384.42357)
			(xy 419.981043 -384.479414) (xy 420.01433 -384.539611) (xy 420.034863 -384.590036) (xy 421.204136 -384.590036)
			(xy 421.204704 -384.557307) (xy 421.213561 -384.492449) (xy 421.23105 -384.429369) (xy 421.256856 -384.36921)
			(xy 421.273224 -384.340862) (xy 421.276554 -384.334845) (xy 421.28015 -384.321575) (xy 421.280336 -384.3147)
			(xy 421.280336 -383.5654) (xy 421.28014 -383.558527) (xy 421.276534 -383.545265) (xy 421.273224 -383.539238)
			(xy 421.256876 -383.510879) (xy 421.231069 -383.450723) (xy 421.213575 -383.387647) (xy 421.204709 -383.322792)
			(xy 421.204136 -383.290064) (xy 421.204717 -383.257335) (xy 421.213569 -383.192478) (xy 421.231055 -383.129398)
			(xy 421.256858 -383.069239) (xy 421.273224 -383.04089) (xy 421.276544 -383.034868) (xy 421.280146 -383.021602)
			(xy 421.280336 -383.014728) (xy 421.280336 -382.728724) (xy 421.280736 -382.718599) (xy 421.288483 -382.699889)
			(xy 421.302805 -382.685572) (xy 421.321518 -382.677832) (xy 421.331644 -382.677416) (xy 422.047924 -382.677416)
			(xy 422.058036 -382.677866) (xy 422.076718 -382.685614) (xy 422.091013 -382.699922) (xy 422.098744 -382.718611)
			(xy 422.099232 -382.728724) (xy 422.099232 -383.014728) (xy 422.099409 -383.021602) (xy 422.103027 -383.034865)
			(xy 422.106344 -383.04089) (xy 422.1227 -383.069244) (xy 422.148506 -383.129402) (xy 422.165998 -383.19248)
			(xy 422.174861 -383.257335) (xy 422.175432 -383.290064) (xy 422.174868 -383.322794) (xy 422.166011 -383.387652)
			(xy 422.14852 -383.450732) (xy 422.131582 -383.490216) (xy 423.404284 -383.490216) (xy 423.404836 -383.457486)
			(xy 423.413696 -383.392627) (xy 423.431191 -383.329547) (xy 423.457002 -383.26939) (xy 423.473372 -383.241042)
			(xy 423.47667 -383.235009) (xy 423.480287 -383.221752) (xy 423.480484 -383.21488) (xy 423.480484 -382.465326)
			(xy 423.480284 -382.458453) (xy 423.476681 -382.445191) (xy 423.473372 -382.439164) (xy 423.456989 -382.410824)
			(xy 423.431192 -382.350661) (xy 423.413708 -382.287579) (xy 423.404852 -382.22272) (xy 423.404284 -382.18999)
			(xy 423.40487 -382.157261) (xy 423.41372 -382.092404) (xy 423.431205 -382.029324) (xy 423.457006 -381.969165)
			(xy 423.473372 -381.940816) (xy 423.476679 -381.934788) (xy 423.48029 -381.921527) (xy 423.480484 -381.914654)
			(xy 423.480484 -381.628904) (xy 423.480988 -381.618798) (xy 423.488721 -381.600122) (xy 423.503012 -381.585828)
			(xy 423.521686 -381.57809) (xy 423.531792 -381.577596) (xy 424.248072 -381.577596) (xy 424.258192 -381.578039)
			(xy 424.276895 -381.585777) (xy 424.29121 -381.600085) (xy 424.298957 -381.618784) (xy 424.29938 -381.628904)
			(xy 424.29938 -381.914654) (xy 424.299592 -381.921526) (xy 424.303187 -381.934788) (xy 424.306492 -381.940816)
			(xy 424.322863 -381.969162) (xy 424.348664 -382.029323) (xy 424.366152 -382.092403) (xy 424.375011 -382.157261)
			(xy 424.37558 -382.18999) (xy 424.375035 -382.22271) (xy 427.80492 -382.22271) (xy 427.804921 -382.157273)
			(xy 427.813706 -382.092427) (xy 427.831116 -382.029348) (xy 427.856836 -381.969177) (xy 427.87316 -381.940816)
			(xy 427.876466 -381.934787) (xy 427.880077 -381.921527) (xy 427.880272 -381.914654) (xy 427.880272 -381.628904)
			(xy 427.880724 -381.618754) (xy 427.888513 -381.600007) (xy 427.9029 -381.585684) (xy 427.921682 -381.577979)
			(xy 427.931834 -381.577596) (xy 428.648114 -381.577596) (xy 428.658236 -381.578114) (xy 428.676949 -381.585838)
			(xy 428.691303 -381.600114) (xy 428.69913 -381.618785) (xy 428.699676 -381.628904) (xy 428.699676 -381.914654)
			(xy 428.699888 -381.921526) (xy 428.703483 -381.934788) (xy 428.706788 -381.940816) (xy 428.723101 -381.969182)
			(xy 428.748818 -382.029353) (xy 428.766226 -382.09243) (xy 428.77501 -382.157274) (xy 428.775011 -382.222709)
			(xy 428.775011 -382.22271) (xy 432.20471 -382.22271) (xy 432.204711 -382.157273) (xy 432.213496 -382.092428)
			(xy 432.230905 -382.029348) (xy 432.256625 -381.969177) (xy 432.272948 -381.940816) (xy 432.276253 -381.934786)
			(xy 432.279865 -381.921527) (xy 432.28006 -381.914654) (xy 432.28006 -381.628904) (xy 432.280524 -381.618755)
			(xy 432.288311 -381.600011) (xy 432.302694 -381.585689) (xy 432.321471 -381.577981) (xy 432.331622 -381.577596)
			(xy 433.047902 -381.577596) (xy 433.058023 -381.578124) (xy 433.076736 -381.585844) (xy 433.091091 -381.600117)
			(xy 433.098918 -381.618786) (xy 433.099464 -381.628904) (xy 433.099464 -381.914654) (xy 433.099678 -381.921526)
			(xy 433.103272 -381.934788) (xy 433.106576 -381.940816) (xy 433.122889 -381.969182) (xy 433.148607 -382.029352)
			(xy 433.166015 -382.09243) (xy 433.1748 -382.157274) (xy 433.1748 -382.18999) (xy 436.603656 -382.18999)
			(xy 436.607647 -382.127823) (xy 436.619556 -382.066676) (xy 436.639185 -382.007555) (xy 436.666214 -381.951429)
			(xy 436.700198 -381.89922) (xy 436.74058 -381.851785) (xy 436.786696 -381.809904) (xy 436.837788 -381.774264)
			(xy 436.893019 -381.74545) (xy 436.951481 -381.723936) (xy 437.012215 -381.710074) (xy 437.074222 -381.704092)
			(xy 437.136485 -381.706088) (xy 437.197982 -381.716031) (xy 437.257703 -381.733755) (xy 437.314666 -381.758972)
			(xy 437.367937 -381.791265) (xy 437.416642 -381.830105) (xy 437.459979 -381.874855) (xy 437.497239 -381.924779)
			(xy 437.527808 -381.979058) (xy 437.551186 -382.036801) (xy 437.566987 -382.097059) (xy 437.574953 -382.158842)
			(xy 437.575452 -382.18999) (xy 437.574953 -382.221138) (xy 437.566987 -382.282921) (xy 437.551186 -382.343179)
			(xy 437.527808 -382.400922) (xy 437.497239 -382.455201) (xy 437.459979 -382.505125) (xy 437.416642 -382.549875)
			(xy 437.367937 -382.588715) (xy 437.314666 -382.621008) (xy 437.257703 -382.646225) (xy 437.197982 -382.663949)
			(xy 437.136485 -382.673892) (xy 437.074222 -382.675888) (xy 437.012215 -382.669906) (xy 436.951481 -382.656044)
			(xy 436.893019 -382.63453) (xy 436.837788 -382.605716) (xy 436.786696 -382.570076) (xy 436.74058 -382.528195)
			(xy 436.700198 -382.48076) (xy 436.666214 -382.428551) (xy 436.639185 -382.372425) (xy 436.619556 -382.313304)
			(xy 436.607647 -382.252157) (xy 436.603656 -382.18999) (xy 433.1748 -382.18999) (xy 433.174801 -382.222709)
			(xy 433.166019 -382.287553) (xy 433.148613 -382.350631) (xy 433.122897 -382.410803) (xy 433.106576 -382.439164)
			(xy 433.103272 -382.445194) (xy 433.09966 -382.458454) (xy 433.099464 -382.465326) (xy 433.099464 -383.21488)
			(xy 433.099668 -383.221752) (xy 433.103269 -383.235015) (xy 433.106576 -383.241042) (xy 433.122911 -383.269396)
			(xy 433.145729 -383.322788) (xy 434.40485 -383.322788) (xy 434.404854 -383.25735) (xy 434.413641 -383.192504)
			(xy 434.431053 -383.129424) (xy 434.456773 -383.069252) (xy 434.473096 -383.04089) (xy 434.476414 -383.034867)
			(xy 434.480018 -383.021602) (xy 434.480208 -383.014728) (xy 434.480208 -382.728724) (xy 434.480641 -382.71857)
			(xy 434.48843 -382.699817) (xy 434.502824 -382.685492) (xy 434.521614 -382.677793) (xy 434.53177 -382.677416)
			(xy 435.24805 -382.677416) (xy 435.258171 -382.677967) (xy 435.276886 -382.685674) (xy 435.291243 -382.69994)
			(xy 435.299068 -382.718607) (xy 435.299612 -382.728724) (xy 435.299612 -383.014728) (xy 435.299792 -383.021602)
			(xy 435.303408 -383.034865) (xy 435.306724 -383.04089) (xy 435.323017 -383.069268) (xy 435.348739 -383.129435)
			(xy 435.366152 -383.19251) (xy 435.37494 -383.257352) (xy 435.374944 -383.322786) (xy 435.366165 -383.387629)
			(xy 435.34876 -383.450707) (xy 435.331875 -383.490216) (xy 436.603656 -383.490216) (xy 436.607647 -383.428049)
			(xy 436.619556 -383.366902) (xy 436.639185 -383.307781) (xy 436.666214 -383.251655) (xy 436.700198 -383.199446)
			(xy 436.74058 -383.152011) (xy 436.786696 -383.11013) (xy 436.837788 -383.07449) (xy 436.893019 -383.045676)
			(xy 436.951481 -383.024162) (xy 437.012215 -383.0103) (xy 437.074222 -383.004318) (xy 437.136485 -383.006314)
			(xy 437.197982 -383.016257) (xy 437.257703 -383.033981) (xy 437.314666 -383.059198) (xy 437.367937 -383.091491)
			(xy 437.416642 -383.130331) (xy 437.459979 -383.175081) (xy 437.497239 -383.225005) (xy 437.527808 -383.279284)
			(xy 437.532172 -383.290064) (xy 438.803804 -383.290064) (xy 438.807795 -383.227897) (xy 438.819704 -383.16675)
			(xy 438.839333 -383.107629) (xy 438.866362 -383.051503) (xy 438.900346 -382.999294) (xy 438.940728 -382.951859)
			(xy 438.986844 -382.909978) (xy 439.037936 -382.874338) (xy 439.093167 -382.845524) (xy 439.151629 -382.82401)
			(xy 439.212363 -382.810148) (xy 439.27437 -382.804166) (xy 439.336633 -382.806162) (xy 439.39813 -382.816105)
			(xy 439.457851 -382.833829) (xy 439.514814 -382.859046) (xy 439.568085 -382.891339) (xy 439.61679 -382.930179)
			(xy 439.660127 -382.974929) (xy 439.697387 -383.024853) (xy 439.727956 -383.079132) (xy 439.751334 -383.136875)
			(xy 439.767135 -383.197133) (xy 439.775101 -383.258916) (xy 439.7756 -383.290064) (xy 439.775101 -383.321212)
			(xy 439.767135 -383.382995) (xy 439.751334 -383.443253) (xy 439.727956 -383.500996) (xy 439.697387 -383.555275)
			(xy 439.660127 -383.605199) (xy 439.61679 -383.649949) (xy 439.568085 -383.688789) (xy 439.514814 -383.721082)
			(xy 439.457851 -383.746299) (xy 439.39813 -383.764023) (xy 439.336633 -383.773966) (xy 439.27437 -383.775962)
			(xy 439.212363 -383.76998) (xy 439.151629 -383.756118) (xy 439.093167 -383.734604) (xy 439.037936 -383.70579)
			(xy 438.986844 -383.67015) (xy 438.940728 -383.628269) (xy 438.900346 -383.580834) (xy 438.866362 -383.528625)
			(xy 438.839333 -383.472499) (xy 438.819704 -383.413378) (xy 438.807795 -383.352231) (xy 438.803804 -383.290064)
			(xy 437.532172 -383.290064) (xy 437.551186 -383.337027) (xy 437.566987 -383.397285) (xy 437.574953 -383.459068)
			(xy 437.575452 -383.490216) (xy 437.574953 -383.521364) (xy 437.566987 -383.583147) (xy 437.551186 -383.643405)
			(xy 437.527808 -383.701148) (xy 437.497239 -383.755427) (xy 437.459979 -383.805351) (xy 437.416642 -383.850101)
			(xy 437.367937 -383.888941) (xy 437.314666 -383.921234) (xy 437.257703 -383.946451) (xy 437.197982 -383.964175)
			(xy 437.136485 -383.974118) (xy 437.074222 -383.976114) (xy 437.012215 -383.970132) (xy 436.951481 -383.95627)
			(xy 436.893019 -383.934756) (xy 436.837788 -383.905942) (xy 436.786696 -383.870302) (xy 436.74058 -383.828421)
			(xy 436.700198 -383.780986) (xy 436.666214 -383.728777) (xy 436.639185 -383.672651) (xy 436.619556 -383.61353)
			(xy 436.607647 -383.552383) (xy 436.603656 -383.490216) (xy 435.331875 -383.490216) (xy 435.323045 -383.510877)
			(xy 435.306724 -383.539238) (xy 435.303397 -383.545257) (xy 435.299799 -383.558525) (xy 435.299612 -383.5654)
			(xy 435.299612 -384.3147) (xy 435.299803 -384.321573) (xy 435.303412 -384.334836) (xy 435.306724 -384.340862)
			(xy 435.323078 -384.369206) (xy 435.348795 -384.429381) (xy 435.366201 -384.492463) (xy 435.374981 -384.557311)
			(xy 435.374979 -384.590036) (xy 438.803804 -384.590036) (xy 438.807795 -384.527869) (xy 438.819704 -384.466722)
			(xy 438.839333 -384.407601) (xy 438.866362 -384.351475) (xy 438.900346 -384.299266) (xy 438.940728 -384.251831)
			(xy 438.986844 -384.20995) (xy 439.037936 -384.17431) (xy 439.093167 -384.145496) (xy 439.151629 -384.123982)
			(xy 439.212363 -384.11012) (xy 439.27437 -384.104138) (xy 439.336633 -384.106134) (xy 439.39813 -384.116077)
			(xy 439.457851 -384.133801) (xy 439.514814 -384.159018) (xy 439.568085 -384.191311) (xy 439.61679 -384.230151)
			(xy 439.660127 -384.274901) (xy 439.697387 -384.324825) (xy 439.727956 -384.379104) (xy 439.751334 -384.436847)
			(xy 439.767135 -384.497105) (xy 439.775101 -384.558888) (xy 439.7756 -384.590036) (xy 439.775101 -384.621184)
			(xy 439.767135 -384.682967) (xy 439.751334 -384.743225) (xy 439.727956 -384.800968) (xy 439.697387 -384.855247)
			(xy 439.660127 -384.905171) (xy 439.61679 -384.949921) (xy 439.568085 -384.988761) (xy 439.514814 -385.021054)
			(xy 439.457851 -385.046271) (xy 439.39813 -385.063995) (xy 439.336633 -385.073938) (xy 439.27437 -385.075934)
			(xy 439.212363 -385.069952) (xy 439.151629 -385.05609) (xy 439.093167 -385.034576) (xy 439.037936 -385.005762)
			(xy 438.986844 -384.970122) (xy 438.940728 -384.928241) (xy 438.900346 -384.880806) (xy 438.866362 -384.828597)
			(xy 438.839333 -384.772471) (xy 438.819704 -384.71335) (xy 438.807795 -384.652203) (xy 438.803804 -384.590036)
			(xy 435.374979 -384.590036) (xy 435.374977 -384.622751) (xy 435.366188 -384.687598) (xy 435.348774 -384.750678)
			(xy 435.32305 -384.810849) (xy 435.306724 -384.83921) (xy 435.303407 -384.845234) (xy 435.299802 -384.858498)
			(xy 435.299612 -384.865372) (xy 435.299612 -385.151376) (xy 435.299159 -385.161527) (xy 435.291374 -385.180277)
			(xy 435.276987 -385.194601) (xy 435.258203 -385.202303) (xy 435.24805 -385.202684) (xy 434.53177 -385.202684)
			(xy 434.521644 -385.202199) (xy 434.502927 -385.194466) (xy 434.488573 -385.180179) (xy 434.48075 -385.161499)
			(xy 434.480208 -385.151376) (xy 434.480208 -384.865372) (xy 434.480026 -384.858498) (xy 434.476411 -384.845235)
			(xy 434.473096 -384.83921) (xy 434.456806 -384.810831) (xy 434.431087 -384.750664) (xy 434.413678 -384.687589)
			(xy 434.404891 -384.622748) (xy 434.404887 -384.557314) (xy 434.413665 -384.492472) (xy 434.431067 -384.429395)
			(xy 434.456778 -384.369224) (xy 434.473096 -384.340862) (xy 434.476424 -384.334844) (xy 434.480021 -384.321575)
			(xy 434.480208 -384.3147) (xy 434.480208 -383.5654) (xy 434.480015 -383.558527) (xy 434.476408 -383.545264)
			(xy 434.473096 -383.539238) (xy 434.456745 -383.510893) (xy 434.431032 -383.450718) (xy 434.413629 -383.387636)
			(xy 434.40485 -383.322788) (xy 433.145729 -383.322788) (xy 433.148627 -383.329569) (xy 433.166033 -383.392649)
			(xy 433.174815 -383.457495) (xy 433.174813 -383.522933) (xy 433.166027 -383.587778) (xy 433.148618 -383.650857)
			(xy 433.122899 -383.711029) (xy 433.106576 -383.73939) (xy 433.103263 -383.745415) (xy 433.099657 -383.758679)
			(xy 433.099464 -383.765552) (xy 433.099464 -384.051556) (xy 433.099042 -384.061712) (xy 433.091254 -384.08047)
			(xy 433.076856 -384.094796) (xy 433.05806 -384.102491) (xy 433.047902 -384.102864) (xy 432.331622 -384.102864)
			(xy 432.321497 -384.102356) (xy 432.302777 -384.094636) (xy 432.28842 -384.080356) (xy 432.2806 -384.061678)
			(xy 432.28006 -384.051556) (xy 432.28006 -383.765552) (xy 432.279853 -383.75868) (xy 432.276256 -383.745417)
			(xy 432.272948 -383.73939) (xy 432.256639 -383.711021) (xy 432.23092 -383.650852) (xy 432.21351 -383.587775)
			(xy 432.204724 -383.522932) (xy 432.204723 -383.457496) (xy 432.213504 -383.392652) (xy 432.230911 -383.329574)
			(xy 432.256627 -383.269403) (xy 432.272948 -383.241042) (xy 432.276244 -383.235008) (xy 432.279862 -383.221752)
			(xy 432.28006 -383.21488) (xy 432.28006 -382.465326) (xy 432.279863 -382.458453) (xy 432.276259 -382.44519)
			(xy 432.272948 -382.439164) (xy 432.256617 -382.410808) (xy 432.2309 -382.350635) (xy 432.213492 -382.287556)
			(xy 432.20471 -382.22271) (xy 428.775011 -382.22271) (xy 428.766229 -382.287553) (xy 428.748824 -382.350631)
			(xy 428.723109 -382.410802) (xy 428.706788 -382.439164) (xy 428.703485 -382.445194) (xy 428.699872 -382.458454)
			(xy 428.699676 -382.465326) (xy 428.699676 -383.21488) (xy 428.699879 -383.221752) (xy 428.70348 -383.235015)
			(xy 428.706788 -383.241042) (xy 428.723123 -383.269396) (xy 428.748838 -383.329569) (xy 428.766243 -383.392649)
			(xy 428.775025 -383.457495) (xy 428.775023 -383.522932) (xy 428.766238 -383.587778) (xy 428.748829 -383.650857)
			(xy 428.72311 -383.711028) (xy 428.706788 -383.73939) (xy 428.703476 -383.745416) (xy 428.699869 -383.758679)
			(xy 428.699676 -383.765552) (xy 428.699676 -384.051556) (xy 428.699242 -384.06171) (xy 428.691456 -384.080466)
			(xy 428.677063 -384.094792) (xy 428.65827 -384.102489) (xy 428.648114 -384.102864) (xy 427.931834 -384.102864)
			(xy 427.92171 -384.102345) (xy 427.90299 -384.09463) (xy 427.888633 -384.080353) (xy 427.880812 -384.061677)
			(xy 427.880272 -384.051556) (xy 427.880272 -383.765552) (xy 427.880064 -383.75868) (xy 427.876467 -383.745417)
			(xy 427.87316 -383.73939) (xy 427.856851 -383.711021) (xy 427.831131 -383.650852) (xy 427.81372 -383.587775)
			(xy 427.804935 -383.522932) (xy 427.804933 -383.457496) (xy 427.813715 -383.392652) (xy 427.831122 -383.329574)
			(xy 427.856838 -383.269403) (xy 427.87316 -383.241042) (xy 427.876457 -383.235008) (xy 427.880074 -383.221752)
			(xy 427.880272 -383.21488) (xy 427.880272 -382.465326) (xy 427.880074 -382.458453) (xy 427.87647 -382.44519)
			(xy 427.87316 -382.439164) (xy 427.856829 -382.410808) (xy 427.831111 -382.350636) (xy 427.813703 -382.287556)
			(xy 427.80492 -382.22271) (xy 424.375035 -382.22271) (xy 424.375035 -382.22272) (xy 424.366173 -382.287579)
			(xy 424.348677 -382.35066) (xy 424.322863 -382.410817) (xy 424.306492 -382.439164) (xy 424.303189 -382.445195)
			(xy 424.299576 -382.458454) (xy 424.29938 -382.465326) (xy 424.29938 -383.21488) (xy 424.299582 -383.221752)
			(xy 424.303184 -383.235015) (xy 424.306492 -383.241042) (xy 424.322874 -383.269382) (xy 424.345775 -383.322789)
			(xy 425.604764 -383.322789) (xy 425.604768 -383.25735) (xy 425.613555 -383.192504) (xy 425.630967 -383.129424)
			(xy 425.656688 -383.069252) (xy 425.673012 -383.04089) (xy 425.676331 -383.034868) (xy 425.679934 -383.021602)
			(xy 425.680124 -383.014728) (xy 425.680124 -382.728724) (xy 425.680542 -382.718568) (xy 425.688334 -382.699812)
			(xy 425.702732 -382.685487) (xy 425.721528 -382.67779) (xy 425.731686 -382.677416) (xy 426.447966 -382.677416)
			(xy 426.458088 -382.677954) (xy 426.476803 -382.685666) (xy 426.49116 -382.699937) (xy 426.498984 -382.718606)
			(xy 426.499528 -382.728724) (xy 426.499528 -383.014728) (xy 426.499705 -383.021602) (xy 426.503323 -383.034865)
			(xy 426.50664 -383.04089) (xy 426.522932 -383.069268) (xy 426.548654 -383.129435) (xy 426.566066 -383.19251)
			(xy 426.574854 -383.257352) (xy 426.574858 -383.322786) (xy 426.566079 -383.387629) (xy 426.548674 -383.450707)
			(xy 426.52296 -383.510877) (xy 426.50664 -383.539238) (xy 426.503315 -383.545258) (xy 426.499715 -383.558525)
			(xy 426.499528 -383.5654) (xy 426.499528 -384.3147) (xy 426.499717 -384.321574) (xy 426.503327 -384.334836)
			(xy 426.50664 -384.340862) (xy 426.522993 -384.369206) (xy 426.548709 -384.429381) (xy 426.566115 -384.492463)
			(xy 426.574895 -384.557311) (xy 426.574893 -384.590036) (xy 430.00422 -384.590036) (xy 430.004777 -384.557306)
			(xy 430.013635 -384.492447) (xy 430.031128 -384.429367) (xy 430.056938 -384.36921) (xy 430.073308 -384.340862)
			(xy 430.076637 -384.334844) (xy 430.080233 -384.321575) (xy 430.08042 -384.3147) (xy 430.08042 -383.5654)
			(xy 430.080226 -383.558527) (xy 430.076619 -383.545264) (xy 430.073308 -383.539238) (xy 430.056958 -383.51088)
			(xy 430.031152 -383.450724) (xy 430.013658 -383.387647) (xy 430.004793 -383.322792) (xy 430.00422 -383.290064)
			(xy 430.004789 -383.257335) (xy 430.013644 -383.192476) (xy 430.031133 -383.129396) (xy 430.05694 -383.069238)
			(xy 430.073308 -383.04089) (xy 430.076627 -383.034867) (xy 430.08023 -383.021602) (xy 430.08042 -383.014728)
			(xy 430.08042 -382.728724) (xy 430.080836 -382.718601) (xy 430.08858 -382.699894) (xy 430.102897 -382.685578)
			(xy 430.121605 -382.677835) (xy 430.131728 -382.677416) (xy 430.848008 -382.677416) (xy 430.858133 -382.67781)
			(xy 430.87684 -382.685564) (xy 430.891154 -382.699887) (xy 430.898896 -382.718599) (xy 430.899316 -382.728724)
			(xy 430.899316 -383.014728) (xy 430.899495 -383.021602) (xy 430.903112 -383.034865) (xy 430.906428 -383.04089)
			(xy 430.922792 -383.06924) (xy 430.948594 -383.129399) (xy 430.966084 -383.192479) (xy 430.974945 -383.257335)
			(xy 430.975516 -383.290064) (xy 430.974955 -383.322794) (xy 430.966097 -383.387652) (xy 430.948606 -383.450732)
			(xy 430.922797 -383.51089) (xy 430.906428 -383.539238) (xy 430.903102 -383.545257) (xy 430.899503 -383.558525)
			(xy 430.899316 -383.5654) (xy 430.899316 -384.3147) (xy 430.899506 -384.321573) (xy 430.903116 -384.334836)
			(xy 430.906428 -384.340862) (xy 430.922781 -384.369218) (xy 430.948585 -384.429375) (xy 430.966078 -384.492453)
			(xy 430.974943 -384.557308) (xy 430.975516 -384.590036) (xy 430.974942 -384.622765) (xy 430.966088 -384.687623)
			(xy 430.9486 -384.750703) (xy 430.922795 -384.810862) (xy 430.906428 -384.83921) (xy 430.903112 -384.845234)
			(xy 430.899507 -384.858498) (xy 430.899316 -384.865372) (xy 430.899316 -385.151376) (xy 430.898865 -385.161495)
			(xy 430.891128 -385.180195) (xy 430.876822 -385.19451) (xy 430.858127 -385.202259) (xy 430.848008 -385.202684)
			(xy 430.131728 -385.202684) (xy 430.121605 -385.202261) (xy 430.102899 -385.194519) (xy 430.088583 -385.180204)
			(xy 430.08084 -385.161499) (xy 430.08042 -385.151376) (xy 430.08042 -384.865372) (xy 430.080236 -384.858498)
			(xy 430.076622 -384.845236) (xy 430.073308 -384.83921) (xy 430.056947 -384.810858) (xy 430.031144 -384.7507)
			(xy 430.013653 -384.687621) (xy 430.004791 -384.622765) (xy 430.00422 -384.590036) (xy 426.574893 -384.590036)
			(xy 426.574891 -384.622751) (xy 426.566102 -384.687597) (xy 426.548689 -384.750677) (xy 426.522965 -384.810849)
			(xy 426.50664 -384.83921) (xy 426.503325 -384.845235) (xy 426.499719 -384.858498) (xy 426.499528 -384.865372)
			(xy 426.499528 -385.151376) (xy 426.499059 -385.161525) (xy 426.491277 -385.180272) (xy 426.476895 -385.194595)
			(xy 426.458117 -385.202301) (xy 426.447966 -385.202684) (xy 425.731686 -385.202684) (xy 425.721561 -385.202185)
			(xy 425.702845 -385.194457) (xy 425.68849 -385.180175) (xy 425.680667 -385.161498) (xy 425.680124 -385.151376)
			(xy 425.680124 -384.865372) (xy 425.67994 -384.858498) (xy 425.676326 -384.845236) (xy 425.673012 -384.83921)
			(xy 425.656721 -384.810832) (xy 425.631002 -384.750664) (xy 425.613592 -384.687589) (xy 425.604805 -384.622748)
			(xy 425.604801 -384.557314) (xy 425.613579 -384.492472) (xy 425.630982 -384.429394) (xy 425.656693 -384.369223)
			(xy 425.673012 -384.340862) (xy 425.676341 -384.334844) (xy 425.679937 -384.321575) (xy 425.680124 -384.3147)
			(xy 425.680124 -383.5654) (xy 425.679929 -383.558527) (xy 425.676323 -383.545264) (xy 425.673012 -383.539238)
			(xy 425.65666 -383.510893) (xy 425.630947 -383.450718) (xy 425.613543 -383.387636) (xy 425.604764 -383.322789)
			(xy 424.345775 -383.322789) (xy 424.348672 -383.329545) (xy 424.366157 -383.392627) (xy 424.375012 -383.457486)
			(xy 424.37558 -383.490216) (xy 424.375002 -383.522945) (xy 424.36615 -383.587803) (xy 424.348664 -383.650883)
			(xy 424.322859 -383.711042) (xy 424.306492 -383.73939) (xy 424.30318 -383.745416) (xy 424.299573 -383.758679)
			(xy 424.29938 -383.765552) (xy 424.29938 -384.051556) (xy 424.298947 -384.061678) (xy 424.29121 -384.080385)
			(xy 424.276898 -384.094701) (xy 424.258194 -384.102444) (xy 424.248072 -384.102864) (xy 423.531792 -384.102864)
			(xy 423.521665 -384.10249) (xy 423.502954 -384.094732) (xy 423.488639 -384.080402) (xy 423.4809 -384.061684)
			(xy 423.480484 -384.051556) (xy 423.480484 -383.765552) (xy 423.480274 -383.75868) (xy 423.476678 -383.745417)
			(xy 423.473372 -383.73939) (xy 423.457 -383.711044) (xy 423.4312 -383.650883) (xy 423.413713 -383.587803)
			(xy 423.404854 -383.522945) (xy 423.404284 -383.490216) (xy 422.131582 -383.490216) (xy 422.122713 -383.51089)
			(xy 422.106344 -383.539238) (xy 422.103019 -383.545258) (xy 422.099419 -383.558525) (xy 422.099232 -383.5654)
			(xy 422.099232 -384.3147) (xy 422.09942 -384.321574) (xy 422.103031 -384.334836) (xy 422.106344 -384.340862)
			(xy 422.122689 -384.369223) (xy 422.148497 -384.429378) (xy 422.165993 -384.492454) (xy 422.174859 -384.557308)
			(xy 422.175432 -384.590036) (xy 422.174856 -384.622765) (xy 422.166003 -384.687623) (xy 422.148515 -384.750703)
			(xy 422.122711 -384.810862) (xy 422.106344 -384.83921) (xy 422.103029 -384.845235) (xy 422.099423 -384.858498)
			(xy 422.099232 -384.865372) (xy 422.099232 -385.151376) (xy 422.098696 -385.161479) (xy 422.090972 -385.180151)
			(xy 422.076691 -385.194445) (xy 422.058027 -385.202187) (xy 422.047924 -385.202684) (xy 421.331644 -385.202684)
			(xy 421.321522 -385.202247) (xy 421.302817 -385.194511) (xy 421.2885 -385.1802) (xy 421.280756 -385.161497)
			(xy 421.280336 -385.151376) (xy 421.280336 -384.865372) (xy 421.28015 -384.858498) (xy 421.276537 -384.845236)
			(xy 421.273224 -384.83921) (xy 421.256865 -384.810857) (xy 421.231061 -384.750699) (xy 421.213569 -384.687621)
			(xy 421.204707 -384.622765) (xy 421.204136 -384.590036) (xy 420.034863 -384.590036) (xy 420.040272 -384.60332)
			(xy 420.058507 -384.669647) (xy 420.064184 -384.703574) (xy 420.065962 -384.715766) (xy 420.079678 -384.73507)
			(xy 420.451534 -384.933952) (xy 421.325294 -385.400296) (xy 421.334144 -385.404491) (xy 421.3536 -385.406577)
			(xy 421.36314 -385.40436) (xy 421.378126 -385.400042) (xy 421.384222 -385.396232) (xy 421.411823 -385.379671)
			(xy 421.469977 -385.352071) (xy 421.530825 -385.331068) (xy 421.593622 -385.316922) (xy 421.657599 -385.309804)
			(xy 421.689784 -385.309364) (xy 421.724326 -385.30986) (xy 421.792922 -385.318057) (xy 421.860061 -385.334338)
			(xy 421.924792 -385.358471) (xy 421.986202 -385.390116) (xy 422.043423 -385.428826) (xy 422.095644 -385.474053)
			(xy 422.142129 -385.525158) (xy 422.182221 -385.581419) (xy 422.196953 -385.608376) (xy 454.303373 -385.608376)
			(xy 454.303373 -385.479236) (xy 454.311323 -385.350341) (xy 454.327193 -385.222181) (xy 454.350922 -385.09524)
			(xy 454.382421 -384.970001) (xy 454.42157 -384.846938) (xy 454.468221 -384.726519) (xy 454.522196 -384.6092)
			(xy 454.583291 -384.495426) (xy 454.651274 -384.385629) (xy 454.725888 -384.280226) (xy 454.806849 -384.179616)
			(xy 454.893849 -384.084181) (xy 454.98656 -383.994282) (xy 455.08463 -383.910261) (xy 455.187685 -383.832437)
			(xy 455.295336 -383.761105) (xy 455.407175 -383.696535) (xy 455.522776 -383.638973) (xy 455.641701 -383.588636)
			(xy 455.7635 -383.545716) (xy 455.88771 -383.510375) (xy 456.013859 -383.482748) (xy 456.141471 -383.462939)
			(xy 456.27006 -383.451023) (xy 456.399138 -383.447047) (xy 456.528216 -383.451023) (xy 456.656805 -383.462939)
			(xy 456.784417 -383.482748) (xy 456.910566 -383.510375) (xy 457.034776 -383.545716) (xy 457.156575 -383.588636)
			(xy 457.2755 -383.638973) (xy 457.391101 -383.696535) (xy 457.50294 -383.761105) (xy 457.610591 -383.832437)
			(xy 457.713646 -383.910261) (xy 457.811716 -383.994282) (xy 457.904427 -384.084181) (xy 457.991427 -384.179616)
			(xy 458.072388 -384.280226) (xy 458.147002 -384.385629) (xy 458.214985 -384.495426) (xy 458.27608 -384.6092)
			(xy 458.330055 -384.726519) (xy 458.376706 -384.846938) (xy 458.415855 -384.970001) (xy 458.447354 -385.09524)
			(xy 458.471083 -385.222181) (xy 458.486953 -385.350341) (xy 458.494903 -385.479236) (xy 458.4954 -385.543806)
			(xy 458.494903 -385.608376) (xy 458.486953 -385.737271) (xy 458.471083 -385.865431) (xy 458.447354 -385.992372)
			(xy 458.415855 -386.117611) (xy 458.376706 -386.240674) (xy 458.330055 -386.361093) (xy 458.27608 -386.478412)
			(xy 458.214985 -386.592186) (xy 458.147002 -386.701983) (xy 458.072388 -386.807386) (xy 457.991427 -386.907996)
			(xy 457.904427 -387.003431) (xy 457.811716 -387.09333) (xy 457.713646 -387.177351) (xy 457.610591 -387.255175)
			(xy 457.50294 -387.326507) (xy 457.391101 -387.391077) (xy 457.2755 -387.448639) (xy 457.156575 -387.498976)
			(xy 457.034776 -387.541896) (xy 456.910566 -387.577237) (xy 456.784417 -387.604864) (xy 456.656805 -387.624673)
			(xy 456.528216 -387.636589) (xy 456.399138 -387.640566) (xy 456.27006 -387.636589) (xy 456.141471 -387.624673)
			(xy 456.013859 -387.604864) (xy 455.88771 -387.577237) (xy 455.7635 -387.541896) (xy 455.641701 -387.498976)
			(xy 455.522776 -387.448639) (xy 455.407175 -387.391077) (xy 455.295336 -387.326507) (xy 455.187685 -387.255175)
			(xy 455.08463 -387.177351) (xy 454.98656 -387.09333) (xy 454.893849 -387.003431) (xy 454.806849 -386.907996)
			(xy 454.725888 -386.807386) (xy 454.651274 -386.701983) (xy 454.583291 -386.592186) (xy 454.522196 -386.478412)
			(xy 454.468221 -386.361093) (xy 454.42157 -386.240674) (xy 454.382421 -386.117611) (xy 454.350922 -385.992372)
			(xy 454.327193 -385.865431) (xy 454.311323 -385.737271) (xy 454.303373 -385.608376) (xy 422.196953 -385.608376)
			(xy 422.215351 -385.642041) (xy 422.241053 -385.706166) (xy 422.258963 -385.772888) (xy 422.268828 -385.841264)
			(xy 422.270174 -385.875784) (xy 422.270682 -385.889754) (xy 422.284906 -385.912868) (xy 434.995066 -392.700256)
			(xy 435.038057 -392.723897) (xy 435.119629 -392.778425) (xy 435.195446 -392.840705) (xy 435.230524 -392.875008)
			(xy 436.72125 -394.365988) (xy 436.751661 -394.397092) (xy 436.807558 -394.463751) (xy 436.857438 -394.535026)
			(xy 436.90092 -394.610375) (xy 436.937675 -394.689224) (xy 436.967422 -394.770974) (xy 436.989937 -394.855005)
			(xy 437.005047 -394.940678) (xy 437.012637 -395.027341) (xy 437.013096 -395.070838) (xy 437.013096 -395.903196)
			(xy 437.013533 -395.912891) (xy 437.020724 -395.9309) (xy 437.027066 -395.938248) (xy 437.052974 -395.965426)
			(xy 437.082946 -395.996668) (xy 437.100726 -396.004542) (xy 437.110632 -396.00505) (xy 437.141578 -396.006874)
			(xy 437.20267 -396.017405) (xy 437.261925 -396.035624) (xy 437.31838 -396.061235) (xy 437.371117 -396.093821)
			(xy 437.41928 -396.132852) (xy 437.462084 -396.177695) (xy 437.498834 -396.22762) (xy 437.528933 -396.281815)
			(xy 437.551891 -396.3394) (xy 437.567336 -396.399438) (xy 437.575015 -396.460953) (xy 437.574804 -396.522945)
			(xy 437.566707 -396.584406) (xy 437.550855 -396.644338) (xy 437.527506 -396.701765) (xy 437.497039 -396.755755)
			(xy 437.459951 -396.805429) (xy 437.416843 -396.84998) (xy 437.368416 -396.888683) (xy 437.315459 -396.92091)
			(xy 437.258831 -396.946136) (xy 437.199453 -396.963952) (xy 437.138292 -396.974067) (xy 437.10733 -396.975584)
			(xy 437.078374 -396.988792) (xy 437.076342 -396.990824) (xy 437.06034 -397.007588) (xy 437.02732 -397.041878)
			(xy 437.020847 -397.049233) (xy 437.013549 -397.067395) (xy 437.013096 -397.077184) (xy 437.013096 -397.203168)
			(xy 437.013528 -397.212865) (xy 437.020712 -397.230881) (xy 437.027066 -397.23822) (xy 437.052974 -397.265398)
			(xy 437.082946 -397.29664) (xy 437.100726 -397.304514) (xy 437.110632 -397.305022) (xy 437.14151 -397.306833)
			(xy 437.202472 -397.31731) (xy 437.261609 -397.335442) (xy 437.317967 -397.360935) (xy 437.370632 -397.393376)
			(xy 437.418752 -397.432242) (xy 437.461548 -397.476902) (xy 437.498328 -397.526634) (xy 437.528496 -397.580633)
			(xy 437.532265 -397.59001) (xy 438.803804 -397.59001) (xy 438.807795 -397.527843) (xy 438.819704 -397.466696)
			(xy 438.839333 -397.407575) (xy 438.866362 -397.351449) (xy 438.900346 -397.29924) (xy 438.940728 -397.251805)
			(xy 438.986844 -397.209924) (xy 439.037936 -397.174284) (xy 439.093167 -397.14547) (xy 439.151629 -397.123956)
			(xy 439.212363 -397.110094) (xy 439.27437 -397.104112) (xy 439.336633 -397.106108) (xy 439.39813 -397.116051)
			(xy 439.457851 -397.133775) (xy 439.514814 -397.158992) (xy 439.568085 -397.191285) (xy 439.61679 -397.230125)
			(xy 439.660127 -397.274875) (xy 439.697387 -397.324799) (xy 439.727956 -397.379078) (xy 439.751334 -397.436821)
			(xy 439.767135 -397.497079) (xy 439.775101 -397.558862) (xy 439.7756 -397.59001) (xy 439.775101 -397.621158)
			(xy 439.767135 -397.682941) (xy 439.751334 -397.743199) (xy 439.727956 -397.800942) (xy 439.697387 -397.855221)
			(xy 439.660127 -397.905145) (xy 439.61679 -397.949895) (xy 439.568085 -397.988735) (xy 439.514814 -398.021028)
			(xy 439.457851 -398.046245) (xy 439.39813 -398.063969) (xy 439.336633 -398.073912) (xy 439.27437 -398.075908)
			(xy 439.212363 -398.069926) (xy 439.151629 -398.056064) (xy 439.093167 -398.03455) (xy 439.037936 -398.005736)
			(xy 438.986844 -397.970096) (xy 438.940728 -397.928215) (xy 438.900346 -397.88078) (xy 438.866362 -397.828571)
			(xy 438.839333 -397.772445) (xy 438.819704 -397.713324) (xy 438.807795 -397.652177) (xy 438.803804 -397.59001)
			(xy 437.532265 -397.59001) (xy 437.551565 -397.638026) (xy 437.567161 -397.697882) (xy 437.575032 -397.759235)
			(xy 437.575452 -397.790162) (xy 437.574935 -397.82195) (xy 437.566644 -397.884983) (xy 437.550199 -397.946396)
			(xy 437.525881 -398.005137) (xy 437.494105 -398.060203) (xy 437.463553 -398.100042) (xy 459.541382 -398.100042)
			(xy 459.545364 -397.972056) (xy 459.557296 -397.844565) (xy 459.57713 -397.718062) (xy 459.604791 -397.593037)
			(xy 459.640171 -397.469974) (xy 459.683133 -397.349348) (xy 459.733511 -397.231627) (xy 459.791111 -397.117265)
			(xy 459.855709 -397.006706) (xy 459.927056 -396.900376) (xy 460.004875 -396.798688) (xy 460.088865 -396.702034)
			(xy 460.178702 -396.610789) (xy 460.274038 -396.525306) (xy 460.374503 -396.445915) (xy 460.479711 -396.372923)
			(xy 460.589252 -396.306614) (xy 460.702704 -396.247243) (xy 460.819628 -396.195039) (xy 460.939571 -396.150206)
			(xy 461.062069 -396.112917) (xy 461.186649 -396.083315) (xy 461.312827 -396.061516) (xy 461.440117 -396.047603)
			(xy 461.568026 -396.041631) (xy 461.696059 -396.043622) (xy 461.82372 -396.05357) (xy 461.950516 -396.071434)
			(xy 462.075955 -396.097147) (xy 462.199554 -396.130609) (xy 462.320833 -396.17169) (xy 462.439324 -396.220232)
			(xy 462.554568 -396.276046) (xy 462.666118 -396.338917) (xy 462.773545 -396.408601) (xy 462.876431 -396.484829)
			(xy 462.974379 -396.567306) (xy 463.06701 -396.655713) (xy 463.153966 -396.749708) (xy 463.23491 -396.848927)
			(xy 463.309529 -396.952986) (xy 463.377534 -397.061483) (xy 463.438662 -397.173998) (xy 463.492677 -397.290096)
			(xy 463.53937 -397.409327) (xy 463.57856 -397.531231) (xy 463.610096 -397.655335) (xy 463.633855 -397.781159)
			(xy 463.649745 -397.908218) (xy 463.657706 -398.036018) (xy 463.658204 -398.100042) (xy 463.657706 -398.164066)
			(xy 463.649745 -398.291866) (xy 463.633855 -398.418925) (xy 463.610096 -398.544749) (xy 463.57856 -398.668853)
			(xy 463.53937 -398.790757) (xy 463.492677 -398.909988) (xy 463.438662 -399.026086) (xy 463.377534 -399.138601)
			(xy 463.309529 -399.247098) (xy 463.23491 -399.351157) (xy 463.153966 -399.450376) (xy 463.06701 -399.544371)
			(xy 462.974379 -399.632778) (xy 462.876431 -399.715255) (xy 462.773545 -399.791483) (xy 462.666118 -399.861167)
			(xy 462.554568 -399.924038) (xy 462.439324 -399.979852) (xy 462.320833 -400.028394) (xy 462.199554 -400.069475)
			(xy 462.075955 -400.102937) (xy 461.950516 -400.12865) (xy 461.82372 -400.146514) (xy 461.696059 -400.156462)
			(xy 461.568026 -400.158453) (xy 461.440117 -400.152481) (xy 461.312827 -400.138568) (xy 461.186649 -400.116769)
			(xy 461.062069 -400.087167) (xy 460.939571 -400.049878) (xy 460.819628 -400.005045) (xy 460.702704 -399.952841)
			(xy 460.589252 -399.89347) (xy 460.479711 -399.827161) (xy 460.374503 -399.754169) (xy 460.274038 -399.674778)
			(xy 460.178702 -399.589295) (xy 460.088865 -399.49805) (xy 460.004875 -399.401396) (xy 459.927056 -399.299708)
			(xy 459.855709 -399.193378) (xy 459.791111 -399.082819) (xy 459.733511 -398.968457) (xy 459.683133 -398.850736)
			(xy 459.640171 -398.73011) (xy 459.604791 -398.607047) (xy 459.57713 -398.482022) (xy 459.557296 -398.355519)
			(xy 459.545364 -398.228028) (xy 459.541382 -398.100042) (xy 437.463553 -398.100042) (xy 437.455416 -398.110652)
			(xy 437.410474 -398.15562) (xy 437.360049 -398.19434) (xy 437.305003 -398.226149) (xy 437.246276 -398.250504)
			(xy 437.184874 -398.266986) (xy 437.121846 -398.275316) (xy 437.090058 -398.27581) (xy 437.089804 -398.27581)
			(xy 437.068092 -398.275534) (xy 437.024848 -398.27159) (xy 437.003444 -398.267936) (xy 436.999126 -398.267174)
			(xy 436.998872 -398.267174) (xy 436.989754 -398.265919) (xy 436.971663 -398.269226) (xy 436.955895 -398.278693)
			(xy 436.944471 -398.293106) (xy 436.941214 -398.301718) (xy 436.93969 -398.305528) (xy 436.926228 -398.337024)
			(xy 436.913782 -398.363694) (xy 436.911242 -398.36852) (xy 436.90794 -398.380712) (xy 436.906924 -398.384522)
			(xy 436.906416 -398.388332) (xy 436.902316 -398.417332) (xy 436.88638 -398.473689) (xy 436.862021 -398.526949)
			(xy 436.829811 -398.575864) (xy 436.790508 -398.619283) (xy 436.745033 -398.656189) (xy 436.694453 -398.685715)
			(xy 436.667402 -398.696942) (xy 436.66283 -398.69872) (xy 436.646574 -398.709134) (xy 436.64251 -398.713198)
			(xy 436.465351 -398.890236) (xy 438.803804 -398.890236) (xy 438.807795 -398.828069) (xy 438.819704 -398.766922)
			(xy 438.839333 -398.707801) (xy 438.866362 -398.651675) (xy 438.900346 -398.599466) (xy 438.940728 -398.552031)
			(xy 438.986844 -398.51015) (xy 439.037936 -398.47451) (xy 439.093167 -398.445696) (xy 439.151629 -398.424182)
			(xy 439.212363 -398.41032) (xy 439.27437 -398.404338) (xy 439.336633 -398.406334) (xy 439.39813 -398.416277)
			(xy 439.457851 -398.434001) (xy 439.514814 -398.459218) (xy 439.568085 -398.491511) (xy 439.61679 -398.530351)
			(xy 439.660127 -398.575101) (xy 439.697387 -398.625025) (xy 439.727956 -398.679304) (xy 439.751334 -398.737047)
			(xy 439.767135 -398.797305) (xy 439.775101 -398.859088) (xy 439.7756 -398.890236) (xy 439.775101 -398.921384)
			(xy 439.767135 -398.983167) (xy 439.751334 -399.043425) (xy 439.727956 -399.101168) (xy 439.697387 -399.155447)
			(xy 439.660127 -399.205371) (xy 439.61679 -399.250121) (xy 439.568085 -399.288961) (xy 439.514814 -399.321254)
			(xy 439.457851 -399.346471) (xy 439.39813 -399.364195) (xy 439.336633 -399.374138) (xy 439.27437 -399.376134)
			(xy 439.212363 -399.370152) (xy 439.151629 -399.35629) (xy 439.093167 -399.334776) (xy 439.037936 -399.305962)
			(xy 438.986844 -399.270322) (xy 438.940728 -399.228441) (xy 438.900346 -399.181006) (xy 438.866362 -399.128797)
			(xy 438.839333 -399.072671) (xy 438.819704 -399.01355) (xy 438.807795 -398.952403) (xy 438.803804 -398.890236)
			(xy 436.465351 -398.890236) (xy 436.26913 -399.086324) (xy 436.236862 -399.117902) (xy 436.167527 -399.175741)
			(xy 436.093248 -399.227076) (xy 436.014633 -399.271487) (xy 435.932325 -399.308611) (xy 435.846999 -399.338143)
			(xy 435.803294 -399.349468) (xy 435.798904 -399.350656) (xy 435.790596 -399.354354) (xy 435.786784 -399.356834)
			(xy 435.784752 -399.358358) (xy 435.76113 -399.376392) (xy 435.755796 -399.385282) (xy 435.755542 -399.38579)
			(xy 435.733433 -399.423466) (xy 435.683563 -399.495195) (xy 435.627611 -399.562288) (xy 435.566006 -399.624231)
			(xy 435.499219 -399.680548) (xy 435.427763 -399.730809) (xy 435.352185 -399.774628) (xy 435.273065 -399.811669)
			(xy 435.191008 -399.841649) (xy 435.106643 -399.864337) (xy 435.020618 -399.87956) (xy 434.933591 -399.887201)
			(xy 434.88991 -399.887694) (xy 434.889656 -399.887694) (xy 434.87594 -399.88744) (xy 434.828334 -399.886246)
			(xy 434.733664 -399.875887) (xy 434.640414 -399.856541) (xy 434.594762 -399.84299) (xy 434.569194 -399.834904)
			(xy 434.518876 -399.816351) (xy 434.494178 -399.805906) (xy 434.48478 -399.802858) (xy 434.478938 -399.801588)
			(xy 434.474231 -399.800655) (xy 434.464638 -399.800398) (xy 434.459888 -399.80108) (xy 434.454046 -399.802096)
			(xy 434.449982 -399.803366) (xy 434.428061 -399.810427) (xy 434.38298 -399.819854) (xy 434.360066 -399.822162)
			(xy 434.330602 -399.823432) (xy 434.325776 -399.823432) (xy 434.298619 -399.822809) (xy 434.244889 -399.814819)
			(xy 434.192835 -399.79929) (xy 434.14351 -399.776534) (xy 434.097911 -399.747013) (xy 434.056961 -399.711323)
			(xy 434.021486 -399.670186) (xy 433.992204 -399.624433) (xy 433.969708 -399.57499) (xy 433.954451 -399.522855)
			(xy 433.946744 -399.469084) (xy 433.9463 -399.441924) (xy 433.9463 -399.44167) (xy 433.947004 -399.409279)
			(xy 433.957978 -399.345432) (xy 433.968144 -399.31467) (xy 433.970938 -399.306542) (xy 433.970938 -399.283174)
			(xy 433.968906 -399.273522) (xy 433.967128 -399.26895) (xy 433.966874 -399.268442) (xy 433.949045 -399.223372)
			(xy 433.921191 -399.13053) (xy 433.902465 -399.035426) (xy 433.893044 -398.938955) (xy 433.892452 -398.89049)
			(xy 433.892452 -398.50822) (xy 433.892905 -398.465713) (xy 433.900169 -398.381009) (xy 433.914628 -398.297232)
			(xy 433.924964 -398.255998) (xy 433.925726 -398.253204) (xy 433.927504 -398.24025) (xy 433.926234 -398.23136)
			(xy 433.919884 -398.205706) (xy 433.916328 -398.196054) (xy 433.906676 -398.187418) (xy 433.903575 -398.184726)
			(xy 433.896683 -398.180261) (xy 433.89296 -398.178528) (xy 433.869338 -398.168114) (xy 433.86883 -398.168114)
			(xy 433.867306 -398.167352) (xy 433.85962 -398.164306) (xy 433.843169 -398.162755) (xy 433.835048 -398.164304)
			(xy 433.822094 -398.167352) (xy 433.81676 -398.170146) (xy 433.781205 -398.187754) (xy 433.707823 -398.217941)
			(xy 433.632275 -398.242202) (xy 433.593748 -398.25168) (xy 433.585112 -398.257776) (xy 433.568856 -398.270222)
			(xy 433.560474 -398.276572) (xy 433.555394 -398.285462) (xy 433.533299 -398.323155) (xy 433.483451 -398.394921)
			(xy 433.427516 -398.46205) (xy 433.365922 -398.524028) (xy 433.299142 -398.580379) (xy 433.227687 -398.630672)
			(xy 433.152106 -398.674519) (xy 433.072979 -398.711586) (xy 432.990912 -398.741588) (xy 432.906535 -398.764294)
			(xy 432.820495 -398.779531) (xy 432.733451 -398.787181) (xy 432.689762 -398.78762) (xy 432.649172 -398.7872)
			(xy 432.568262 -398.780582) (xy 432.488158 -398.767408) (xy 432.40939 -398.747766) (xy 432.332479 -398.721787)
			(xy 432.295046 -398.706086) (xy 432.294792 -398.706086) (xy 432.28533 -398.702486) (xy 432.265102 -398.702279)
			(xy 432.246364 -398.709904) (xy 432.238912 -398.716754) (xy 432.211734 -398.743932) (xy 431.869088 -399.086324)
			(xy 431.836819 -399.117901) (xy 431.767483 -399.175737) (xy 431.693203 -399.227069) (xy 431.614587 -399.271477)
			(xy 431.532279 -399.308597) (xy 431.446953 -399.338126) (xy 431.403252 -399.349468) (xy 431.398863 -399.350659)
			(xy 431.390559 -399.354363) (xy 431.386742 -399.356834) (xy 431.38471 -399.358358) (xy 431.361088 -399.376392)
			(xy 431.355754 -399.385282) (xy 431.3555 -399.38579) (xy 431.333583 -399.423137) (xy 431.284201 -399.49428)
			(xy 431.228839 -399.560875) (xy 431.167913 -399.62242) (xy 431.101881 -399.678453) (xy 431.031241 -399.728551)
			(xy 430.956524 -399.772337) (xy 430.878293 -399.809481) (xy 430.797136 -399.839705) (xy 430.713665 -399.86278)
			(xy 430.628509 -399.878532) (xy 430.542307 -399.886844) (xy 430.499012 -399.887694) (xy 430.479708 -399.88744)
			(xy 430.462224 -399.887149) (xy 430.427291 -399.885496) (xy 430.409858 -399.884138) (xy 430.360084 -399.879557)
			(xy 430.261733 -399.861681) (xy 430.165666 -399.834048) (xy 430.119028 -399.816066) (xy 430.09439 -399.805906)
			(xy 430.089818 -399.803874) (xy 430.078896 -399.801588) (xy 430.074189 -399.800659) (xy 430.064598 -399.80041)
			(xy 430.059846 -399.80108) (xy 430.054004 -399.802096) (xy 430.04994 -399.803366) (xy 430.028018 -399.810424)
			(xy 429.982937 -399.819847) (xy 429.960024 -399.822162) (xy 429.93056 -399.823432) (xy 429.925734 -399.823432)
			(xy 429.898579 -399.822806) (xy 429.844853 -399.814811) (xy 429.792804 -399.799278) (xy 429.743485 -399.776521)
			(xy 429.697891 -399.746999) (xy 429.656946 -399.711309) (xy 429.621475 -399.670172) (xy 429.592197 -399.624422)
			(xy 429.569704 -399.574981) (xy 429.55445 -399.52285) (xy 429.546743 -399.469082) (xy 429.546258 -399.441924)
			(xy 429.546258 -399.44167) (xy 429.546892 -399.409148) (xy 429.55787 -399.345039) (xy 429.568102 -399.314162)
			(xy 429.569372 -399.310606) (xy 429.572928 -399.29308) (xy 429.570896 -399.283428) (xy 429.568864 -399.273014)
			(xy 429.567086 -399.268442) (xy 429.549261 -399.223404) (xy 429.521409 -399.130626) (xy 429.502679 -399.035586)
			(xy 429.493248 -398.939178) (xy 429.492664 -398.890744) (xy 429.492664 -398.507458) (xy 429.493127 -398.465084)
			(xy 429.500334 -398.380643) (xy 429.514669 -398.297115) (xy 429.524922 -398.255998) (xy 429.525684 -398.253204)
			(xy 429.527462 -398.24025) (xy 429.525684 -398.227296) (xy 429.524668 -398.22374) (xy 429.523398 -398.218914)
			(xy 429.522128 -398.213326) (xy 429.521874 -398.212818) (xy 429.51908 -398.201642) (xy 429.50384 -398.183862)
			(xy 429.466756 -398.167352) (xy 429.458995 -398.164329) (xy 429.44241 -398.162915) (xy 429.434244 -398.164558)
			(xy 429.420274 -398.16786) (xy 429.41494 -398.170654) (xy 429.379888 -398.187672) (xy 429.379126 -398.187926)
			(xy 429.371252 -398.191482) (xy 429.370744 -398.19199) (xy 429.327908 -398.210508) (xy 429.239498 -398.240402)
			(xy 429.194214 -398.25168) (xy 429.185324 -398.257776) (xy 429.169068 -398.270222) (xy 429.160686 -398.276572)
			(xy 429.155606 -398.285462) (xy 429.133511 -398.323156) (xy 429.083664 -398.394922) (xy 429.027729 -398.462052)
			(xy 428.966135 -398.524031) (xy 428.899355 -398.580383) (xy 428.8279 -398.630676) (xy 428.752319 -398.674524)
			(xy 428.673192 -398.711592) (xy 428.591125 -398.741595) (xy 428.506748 -398.764302) (xy 428.420707 -398.77954)
			(xy 428.333664 -398.787191) (xy 428.289974 -398.78762) (xy 428.240474 -398.786987) (xy 428.141964 -398.777133)
			(xy 428.044914 -398.757573) (xy 427.950278 -398.7285) (xy 427.904402 -398.709896) (xy 427.880272 -398.699736)
			(xy 427.850046 -398.705578) (xy 427.811438 -398.744186) (xy 427.469046 -399.086324) (xy 427.436778 -399.117903)
			(xy 427.367443 -399.175743) (xy 427.293165 -399.227079) (xy 427.21455 -399.271491) (xy 427.132243 -399.308616)
			(xy 427.046917 -399.33815) (xy 427.00321 -399.349468) (xy 426.998823 -399.350662) (xy 426.990522 -399.354371)
			(xy 426.9867 -399.356834) (xy 426.984668 -399.358358) (xy 426.961046 -399.376392) (xy 426.955712 -399.385282)
			(xy 426.955458 -399.38579) (xy 426.933349 -399.423466) (xy 426.88348 -399.495196) (xy 426.827528 -399.56229)
			(xy 426.765923 -399.624234) (xy 426.699136 -399.680552) (xy 426.627681 -399.730814) (xy 426.552103 -399.774634)
			(xy 426.472982 -399.811677) (xy 426.390925 -399.841658) (xy 426.306561 -399.864347) (xy 426.220535 -399.879572)
			(xy 426.133507 -399.887214) (xy 426.089826 -399.887694) (xy 426.089572 -399.887694) (xy 426.075856 -399.88744)
			(xy 426.02825 -399.886247) (xy 425.933579 -399.875889) (xy 425.840329 -399.856545) (xy 425.794678 -399.84299)
			(xy 425.76911 -399.834905) (xy 425.718791 -399.816352) (xy 425.694094 -399.805906) (xy 425.684696 -399.802858)
			(xy 425.678854 -399.801588) (xy 425.674147 -399.800653) (xy 425.664554 -399.800393) (xy 425.659804 -399.80108)
			(xy 425.653962 -399.802096) (xy 425.649898 -399.803366) (xy 425.627977 -399.810428) (xy 425.582897 -399.819857)
			(xy 425.559982 -399.822162) (xy 425.530518 -399.823432) (xy 425.525692 -399.823432) (xy 425.498534 -399.82281)
			(xy 425.444802 -399.814822) (xy 425.392747 -399.799294) (xy 425.34342 -399.77654) (xy 425.297819 -399.747019)
			(xy 425.256866 -399.711329) (xy 425.22139 -399.670191) (xy 425.192107 -399.624438) (xy 425.169609 -399.574993)
			(xy 425.154352 -399.522858) (xy 425.146644 -399.469085) (xy 425.146216 -399.441924) (xy 425.146216 -399.44167)
			(xy 425.14692 -399.409279) (xy 425.157895 -399.345432) (xy 425.16806 -399.31467) (xy 425.170854 -399.306542)
			(xy 425.170854 -399.283174) (xy 425.168822 -399.273522) (xy 425.167044 -399.26895) (xy 425.16679 -399.268442)
			(xy 425.148961 -399.223372) (xy 425.121107 -399.13053) (xy 425.10238 -399.035426) (xy 425.092959 -398.938955)
			(xy 425.092368 -398.89049) (xy 425.092368 -398.50822) (xy 425.092821 -398.465713) (xy 425.100085 -398.381009)
			(xy 425.114545 -398.297232) (xy 425.12488 -398.255998) (xy 425.125642 -398.253204) (xy 425.12742 -398.24025)
			(xy 425.125642 -398.227296) (xy 425.124626 -398.22374) (xy 425.123356 -398.218914) (xy 425.122086 -398.213326)
			(xy 425.121832 -398.212818) (xy 425.119038 -398.201642) (xy 425.103798 -398.183862) (xy 425.066714 -398.167352)
			(xy 425.058954 -398.16432) (xy 425.042364 -398.162888) (xy 425.034202 -398.164558) (xy 425.020232 -398.16786)
			(xy 425.014898 -398.170654) (xy 424.979846 -398.187672) (xy 424.979084 -398.187926) (xy 424.97121 -398.191482)
			(xy 424.970702 -398.19199) (xy 424.927866 -398.210507) (xy 424.839454 -398.240397) (xy 424.794172 -398.25168)
			(xy 424.785282 -398.257776) (xy 424.769026 -398.270222) (xy 424.760644 -398.276572) (xy 424.755564 -398.285462)
			(xy 424.733468 -398.323155) (xy 424.683621 -398.394919) (xy 424.627685 -398.462046) (xy 424.56609 -398.524022)
			(xy 424.49931 -398.580371) (xy 424.427855 -398.630662) (xy 424.352274 -398.674507) (xy 424.273147 -398.711572)
			(xy 424.19108 -398.741571) (xy 424.106703 -398.764274) (xy 424.020664 -398.779509) (xy 423.933621 -398.787157)
			(xy 423.889932 -398.78762) (xy 423.840432 -398.786985) (xy 423.741924 -398.777127) (xy 423.644875 -398.757563)
			(xy 423.550241 -398.728486) (xy 423.50436 -398.709896) (xy 423.48023 -398.699736) (xy 423.450004 -398.705578)
			(xy 423.411396 -398.744186) (xy 423.069004 -399.086324) (xy 423.036735 -399.117901) (xy 422.9674 -399.175739)
			(xy 422.89312 -399.227072) (xy 422.814504 -399.271481) (xy 422.732197 -399.308603) (xy 422.64687 -399.338133)
			(xy 422.603168 -399.349468) (xy 422.598779 -399.350658) (xy 422.590473 -399.354359) (xy 422.586658 -399.356834)
			(xy 422.584626 -399.358358) (xy 422.561004 -399.376392) (xy 422.55567 -399.385282) (xy 422.555416 -399.38579)
			(xy 422.533499 -399.423137) (xy 422.484118 -399.494281) (xy 422.428756 -399.560877) (xy 422.36783 -399.622424)
			(xy 422.301798 -399.678457) (xy 422.231158 -399.728556) (xy 422.156441 -399.772343) (xy 422.07821 -399.809489)
			(xy 421.997054 -399.839714) (xy 421.913583 -399.86279) (xy 421.828425 -399.878544) (xy 421.742223 -399.886857)
			(xy 421.698928 -399.887694) (xy 421.679624 -399.88744) (xy 421.66214 -399.887149) (xy 421.627207 -399.885497)
			(xy 421.609774 -399.884138) (xy 421.559999 -399.879558) (xy 421.461648 -399.861684) (xy 421.365581 -399.834051)
			(xy 421.318944 -399.816066) (xy 421.294306 -399.805906) (xy 421.289734 -399.803874) (xy 421.278812 -399.801588)
			(xy 421.274105 -399.800657) (xy 421.264513 -399.800405) (xy 421.259762 -399.80108) (xy 421.25392 -399.802096)
			(xy 421.249856 -399.803366) (xy 421.227934 -399.810425) (xy 421.182854 -399.81985) (xy 421.15994 -399.822162)
			(xy 421.130476 -399.823432) (xy 421.12565 -399.823432) (xy 421.098494 -399.822807) (xy 421.044767 -399.814814)
			(xy 420.992716 -399.799283) (xy 420.943395 -399.776526) (xy 420.897799 -399.747004) (xy 420.856851 -399.711314)
			(xy 420.821379 -399.670178) (xy 420.7921 -399.624426) (xy 420.769605 -399.574984) (xy 420.75435 -399.522852)
			(xy 420.746643 -399.469083) (xy 420.746174 -399.441924) (xy 420.746174 -399.44167) (xy 420.746808 -399.409148)
			(xy 420.757787 -399.345039) (xy 420.768018 -399.314162) (xy 420.769288 -399.310606) (xy 420.772844 -399.29308)
			(xy 420.770812 -399.283428) (xy 420.76878 -399.273014) (xy 420.767002 -399.268442) (xy 420.749177 -399.223404)
			(xy 420.721324 -399.130626) (xy 420.702594 -399.035586) (xy 420.693163 -398.939178) (xy 420.69258 -398.890744)
			(xy 420.69258 -398.507458) (xy 420.693043 -398.465084) (xy 420.70025 -398.380643) (xy 420.714585 -398.297115)
			(xy 420.724838 -398.255998) (xy 420.7256 -398.253204) (xy 420.727378 -398.24025) (xy 420.7256 -398.227296)
			(xy 420.724584 -398.22374) (xy 420.723314 -398.218914) (xy 420.722044 -398.213326) (xy 420.72179 -398.212818)
			(xy 420.718996 -398.201642) (xy 420.703756 -398.183862) (xy 420.666672 -398.167352) (xy 420.658911 -398.164326)
			(xy 420.642325 -398.162908) (xy 420.63416 -398.164558) (xy 420.62019 -398.16786) (xy 420.614856 -398.170654)
			(xy 420.579804 -398.187672) (xy 420.579042 -398.187926) (xy 420.571168 -398.191482) (xy 420.57066 -398.19199)
			(xy 420.527825 -398.210509) (xy 420.439414 -398.240404) (xy 420.39413 -398.25168) (xy 420.38524 -398.257776)
			(xy 420.368984 -398.270222) (xy 420.360602 -398.276572) (xy 420.355522 -398.285462) (xy 420.333426 -398.323153)
			(xy 420.283577 -398.394915) (xy 420.227641 -398.46204) (xy 420.166046 -398.524014) (xy 420.099265 -398.58036)
			(xy 420.027809 -398.630647) (xy 419.952228 -398.67449) (xy 419.873101 -398.711551) (xy 419.791035 -398.741547)
			(xy 419.706659 -398.764247) (xy 419.62062 -398.779478) (xy 419.533578 -398.787122) (xy 419.48989 -398.78762)
			(xy 419.489636 -398.78762) (xy 419.44894 -398.787204) (xy 419.367818 -398.780573) (xy 419.287505 -398.767361)
			(xy 419.208534 -398.747655) (xy 419.13143 -398.721585) (xy 419.093904 -398.705832) (xy 419.084506 -398.702784)
			(xy 419.078918 -398.701514) (xy 419.074138 -398.70062) (xy 419.064415 -398.700488) (xy 419.059614 -398.70126)
			(xy 419.05301 -398.702276) (xy 419.0492 -398.703546) (xy 419.019769 -398.712799) (xy 418.958887 -398.722751)
			(xy 418.928042 -398.723358) (xy 418.927788 -398.723358) (xy 418.900537 -398.722894) (xy 418.84659 -398.715135)
			(xy 418.794297 -398.699778) (xy 418.744721 -398.677134) (xy 418.698873 -398.647665) (xy 418.657686 -398.61197)
			(xy 418.621998 -398.570777) (xy 418.592537 -398.524924) (xy 418.569901 -398.475345) (xy 418.554552 -398.423049)
			(xy 418.546802 -398.369101) (xy 418.54628 -398.34185) (xy 418.54628 -398.341342) (xy 418.546987 -398.308952)
			(xy 418.557967 -398.245107) (xy 418.568124 -398.214342) (xy 418.569648 -398.210278) (xy 418.572696 -398.193006)
			(xy 418.570918 -398.183608) (xy 418.568886 -398.173194) (xy 418.567108 -398.168622) (xy 418.549214 -398.123501)
			(xy 418.521255 -398.030543) (xy 418.502461 -397.935308) (xy 418.493012 -397.838698) (xy 418.492432 -397.790162)
			(xy 418.492432 -397.408146) (xy 418.492884 -397.365638) (xy 418.500146 -397.280934) (xy 418.514603 -397.197157)
			(xy 418.524944 -397.155924) (xy 418.525706 -397.15313) (xy 418.527484 -397.140176) (xy 418.525706 -397.127222)
			(xy 418.524944 -397.124428) (xy 418.514615 -397.083193) (xy 418.500169 -396.999415) (xy 418.492895 -396.914713)
			(xy 418.492432 -396.872206) (xy 418.492432 -396.489936) (xy 418.493017 -396.440886) (xy 418.502652 -396.343259)
			(xy 418.521832 -396.247052) (xy 418.550371 -396.153194) (xy 418.568632 -396.107666) (xy 418.569648 -396.10284)
			(xy 418.570664 -396.09776) (xy 418.571689 -396.092742) (xy 418.571937 -396.082505) (xy 418.571172 -396.07744)
			(xy 418.569648 -396.070074) (xy 418.568124 -396.06601) (xy 418.557968 -396.035245) (xy 418.546989 -395.9714)
			(xy 418.54628 -395.93901) (xy 418.54628 -395.938502) (xy 418.546762 -395.911308) (xy 418.554485 -395.857471)
			(xy 418.569776 -395.805277) (xy 418.592324 -395.755783) (xy 418.621672 -395.709993) (xy 418.657226 -395.668835)
			(xy 418.698264 -395.633143) (xy 418.743955 -395.603641) (xy 418.793373 -395.580926) (xy 418.845515 -395.56546)
			(xy 418.899326 -395.557555) (xy 418.926518 -395.556994) (xy 418.928296 -395.556994) (xy 418.93998 -395.557248)
			(xy 418.947346 -395.557502) (xy 418.954712 -395.55547) (xy 418.964206 -395.552396) (xy 418.980018 -395.540253)
			(xy 418.990042 -395.52302) (xy 418.99278 -395.503272) (xy 418.99078 -395.493494) (xy 418.987478 -395.48181)
			(xy 418.98443 -395.476222) (xy 418.966561 -395.443444) (xy 418.938451 -395.374282) (xy 418.919435 -395.302089)
			(xy 418.909826 -395.228054) (xy 418.909246 -395.190726) (xy 418.909246 -395.190218) (xy 418.91077 -395.148562)
			(xy 418.911532 -395.134846) (xy 418.899594 -395.110462) (xy 418.637466 -394.935964) (xy 418.627052 -394.934186)
			(xy 418.586358 -394.926696) (xy 418.50628 -394.905832) (xy 418.428209 -394.878396) (xy 418.352682 -394.84458)
			(xy 418.280222 -394.804614) (xy 418.245544 -394.78204) (xy 417.833048 -394.507466) (xy 417.799388 -394.484561)
			(xy 417.735529 -394.434044) (xy 417.676011 -394.378479) (xy 417.621229 -394.318239) (xy 417.596066 -394.286232)
			(xy 417.59072 -394.279843) (xy 417.576855 -394.270629) (xy 417.568888 -394.268198) (xy 417.529565 -394.257308)
			(xy 417.452687 -394.229945) (xy 417.378302 -394.196392) (xy 417.306907 -394.156875) (xy 417.272724 -394.134594)
			(xy 417.246816 -394.117322) (xy 417.237418 -394.112496) (xy 417.227152 -394.108884) (xy 417.205429 -394.109801)
			(xy 417.195508 -394.114274) (xy 417.104068 -394.161264) (xy 417.089336 -394.184378) (xy 417.088828 -394.198348)
			(xy 417.087393 -394.224929) (xy 417.07807 -394.277338) (xy 417.061551 -394.327941) (xy 417.038157 -394.375757)
			(xy 417.008342 -394.419856) (xy 416.972686 -394.459381) (xy 416.931881 -394.493565) (xy 416.88672 -394.521744)
			(xy 416.83808 -394.543371) (xy 416.786905 -394.558025) (xy 416.73419 -394.565422) (xy 416.707574 -394.565886)
			(xy 416.680325 -394.565398) (xy 416.626381 -394.557638) (xy 416.574091 -394.542281) (xy 416.524518 -394.519638)
			(xy 416.478673 -394.490171) (xy 416.437487 -394.454479) (xy 416.401801 -394.413289) (xy 416.372339 -394.36744)
			(xy 416.349702 -394.317864) (xy 416.334351 -394.265572) (xy 416.326599 -394.211627) (xy 416.326066 -394.184378)
			(xy 416.326617 -394.155258) (xy 416.335469 -394.097695) (xy 416.352965 -394.042145) (xy 416.378697 -393.989899)
			(xy 416.41207 -393.942169) (xy 416.452306 -393.900063) (xy 416.498473 -393.86456) (xy 416.549499 -393.836484)
			(xy 416.604198 -393.816486) (xy 416.632644 -393.810236) (xy 416.640264 -393.808712) (xy 416.653218 -393.801854)
			(xy 416.658806 -393.796266) (xy 416.663987 -393.790776) (xy 416.671085 -393.777461) (xy 416.672776 -393.770104)
			(xy 416.67938 -393.736068) (xy 416.680396 -393.726416) (xy 416.667442 -393.692634) (xy 416.641541 -393.662885)
			(xy 416.593987 -393.599947) (xy 416.572446 -393.566904) (xy 416.566604 -393.55776) (xy 413.725106 -391.666984)
			(xy 413.688132 -391.641779) (xy 413.618368 -391.58573) (xy 413.553902 -391.523662) (xy 413.524192 -391.4902)
			(xy 411.164024 -388.769352) (xy 411.136321 -388.736742) (xy 411.085961 -388.667558) (xy 411.06344 -388.631176)
			(xy 411.038294 -388.610094) (xy 411.02528 -388.604884) (xy 410.99998 -388.592809) (xy 410.987748 -388.585964)
			(xy 410.962881 -388.571362) (xy 410.917459 -388.535837) (xy 410.877902 -388.493879) (xy 410.845113 -388.446444)
			(xy 410.819838 -388.394613) (xy 410.802655 -388.339569) (xy 410.793954 -388.282564) (xy 410.793438 -388.253732)
			(xy 410.793438 -388.249668) (xy 410.793946 -388.241286) (xy 410.793946 -388.240524) (xy 410.795666 -388.209157)
			(xy 410.808094 -388.147585) (xy 410.830456 -388.088886) (xy 410.845762 -388.061454) (xy 410.851096 -388.052056)
			(xy 410.853636 -388.031736) (xy 409.716224 -384.14198) (xy 409.705006 -384.102077) (xy 409.688452 -384.020852)
			(xy 409.678712 -383.938532) (xy 409.676854 -383.897124) (xy 409.197556 -370.230908) (xy 409.196825 -370.221401)
			(xy 409.189248 -370.203919) (xy 409.182824 -370.196872) (xy 407.036016 -368.050064) (xy 407.029028 -368.043588)
			(xy 407.0116 -368.03592) (xy 406.992576 -368.035166) (xy 406.983438 -368.037872) (xy 406.9334 -368.055144)
			(xy 406.897586 -368.067336) (xy 406.891257 -368.069736) (xy 406.880055 -368.077327) (xy 406.875488 -368.082322)
			(xy 406.875234 -368.08283) (xy 406.870685 -368.088467) (xy 406.864623 -368.101617) (xy 406.863296 -368.108738)
			(xy 406.863296 -368.109754) (xy 406.85944 -368.137136) (xy 406.844852 -368.190473) (xy 406.822714 -368.241144)
			(xy 406.793492 -368.288088) (xy 406.757798 -368.330321) (xy 406.716379 -368.366956) (xy 406.670105 -368.397227)
			(xy 406.619944 -368.420499) (xy 406.566949 -368.436284) (xy 406.51223 -368.444252) (xy 406.484582 -368.44478)
			(xy 406.457331 -368.444315) (xy 406.403383 -368.436556) (xy 406.351089 -368.421198) (xy 406.301513 -368.398554)
			(xy 406.255664 -368.369085) (xy 406.214476 -368.333391) (xy 406.178787 -368.292199) (xy 406.149323 -368.246347)
			(xy 406.126686 -368.196768) (xy 406.111334 -368.144472) (xy 406.103581 -368.090523) (xy 406.103074 -368.063272)
			(xy 406.103568 -368.035614) (xy 406.111561 -367.980877) (xy 406.127374 -367.927868) (xy 406.150677 -367.877699)
			(xy 406.180982 -367.831421) (xy 406.217651 -367.790005) (xy 406.259917 -367.754318) (xy 406.306894 -367.72511)
			(xy 406.357597 -367.702992) (xy 406.410963 -367.688427) (xy 406.438354 -367.684558) (xy 406.452832 -367.68278)
			(xy 406.475438 -367.664746) (xy 406.49271 -367.614454) (xy 406.509982 -367.564416) (xy 406.5127 -367.555287)
			(xy 406.511901 -367.53627) (xy 406.504241 -367.518846) (xy 406.49779 -367.511838) (xy 405.766524 -366.780572)
			(xy 405.73807 -366.793866) (xy 405.678142 -366.812653) (xy 405.616062 -366.822152) (xy 405.58466 -366.822736)
			(xy 405.555106 -366.82223) (xy 405.4966 -366.813804) (xy 405.439892 -366.79713) (xy 405.386137 -366.772548)
			(xy 405.336431 -366.74056) (xy 405.29179 -366.701817) (xy 405.253122 -366.65711) (xy 405.221218 -366.607351)
			(xy 405.208486 -366.580674) (xy 405.19985 -366.579912) (xy 403.238462 -366.579912) (xy 403.227332 -366.580541)
			(xy 403.207188 -366.590032) (xy 403.1996 -366.5982) (xy 403.193361 -366.606446) (xy 403.187448 -366.62624)
			(xy 403.18817 -366.636554) (xy 403.275755 -367.407952) (xy 405.214326 -367.407952) (xy 405.218397 -367.35233)
			(xy 405.230523 -367.297893) (xy 405.250446 -367.245802) (xy 405.277742 -367.197167) (xy 405.311828 -367.153024)
			(xy 405.351977 -367.114315) (xy 405.397335 -367.081864) (xy 405.446935 -367.056363) (xy 405.499719 -367.038356)
			(xy 405.554562 -367.028226) (xy 405.610296 -367.026189) (xy 405.665733 -367.032289) (xy 405.71969 -367.046395)
			(xy 405.771019 -367.068207) (xy 405.818625 -367.097261) (xy 405.861493 -367.132936) (xy 405.89871 -367.174473)
			(xy 405.929483 -367.220986) (xy 405.953155 -367.271483) (xy 405.969223 -367.32489) (xy 405.977343 -367.380066)
			(xy 405.977852 -367.407952) (xy 405.977343 -367.435838) (xy 405.969223 -367.491014) (xy 405.953155 -367.544421)
			(xy 405.929483 -367.594918) (xy 405.89871 -367.641431) (xy 405.861493 -367.682968) (xy 405.818625 -367.718643)
			(xy 405.771019 -367.747697) (xy 405.71969 -367.769509) (xy 405.665733 -367.783615) (xy 405.610296 -367.789715)
			(xy 405.554562 -367.787678) (xy 405.499719 -367.777548) (xy 405.446935 -367.759541) (xy 405.397335 -367.73404)
			(xy 405.351977 -367.701589) (xy 405.311828 -367.66288) (xy 405.277742 -367.618737) (xy 405.250446 -367.570102)
			(xy 405.230523 -367.518011) (xy 405.218397 -367.463574) (xy 405.214326 -367.407952) (xy 403.275755 -367.407952)
			(xy 403.453346 -368.972084) (xy 403.456317 -369.000056) (xy 403.459493 -369.056223) (xy 403.459696 -369.084352)
			(xy 403.459696 -369.089432) (xy 403.459289 -369.174268) (xy 406.517854 -369.174268) (xy 406.521925 -369.118646)
			(xy 406.534051 -369.064209) (xy 406.553974 -369.012118) (xy 406.58127 -368.963483) (xy 406.615356 -368.91934)
			(xy 406.655505 -368.880631) (xy 406.700863 -368.84818) (xy 406.750463 -368.822679) (xy 406.803247 -368.804672)
			(xy 406.85809 -368.794542) (xy 406.913824 -368.792505) (xy 406.969261 -368.798605) (xy 407.023218 -368.812711)
			(xy 407.074547 -368.834523) (xy 407.122153 -368.863577) (xy 407.165021 -368.899252) (xy 407.202238 -368.940789)
			(xy 407.233011 -368.987302) (xy 407.256683 -369.037799) (xy 407.272751 -369.091206) (xy 407.280871 -369.146382)
			(xy 407.28138 -369.174268) (xy 407.280871 -369.202154) (xy 407.272751 -369.25733) (xy 407.256683 -369.310737)
			(xy 407.233011 -369.361234) (xy 407.202238 -369.407747) (xy 407.165021 -369.449284) (xy 407.122153 -369.484959)
			(xy 407.074547 -369.514013) (xy 407.023218 -369.535825) (xy 406.969261 -369.549931) (xy 406.913824 -369.556031)
			(xy 406.85809 -369.553994) (xy 406.803247 -369.543864) (xy 406.750463 -369.525857) (xy 406.700863 -369.500356)
			(xy 406.655505 -369.467905) (xy 406.615356 -369.429196) (xy 406.58127 -369.385053) (xy 406.553974 -369.336418)
			(xy 406.534051 -369.284327) (xy 406.521925 -369.22989) (xy 406.517854 -369.174268) (xy 403.459289 -369.174268)
			(xy 403.450437 -371.019578) (xy 404.149814 -371.019578) (xy 404.150207 -370.99322) (xy 404.157455 -370.941005)
			(xy 404.171825 -370.890286) (xy 404.193043 -370.842029) (xy 404.220703 -370.797153) (xy 404.25428 -370.756514)
			(xy 404.293133 -370.720885) (xy 404.336523 -370.690947) (xy 404.359872 -370.67871) (xy 404.372456 -370.671818)
			(xy 404.393539 -370.652384) (xy 404.408375 -370.627847) (xy 404.41579 -370.600149) (xy 404.415198 -370.571482)
			(xy 404.406645 -370.544113) (xy 404.390808 -370.52021) (xy 404.380192 -370.510562) (xy 404.359429 -370.492363)
			(xy 404.322896 -370.450966) (xy 404.292711 -370.404736) (xy 404.269504 -370.354639) (xy 404.253758 -370.30172)
			(xy 404.245804 -370.247084) (xy 404.245318 -370.219478) (xy 404.245804 -370.192227) (xy 404.25356 -370.138279)
			(xy 404.268915 -370.085984) (xy 404.291557 -370.036407) (xy 404.321023 -369.990557) (xy 404.356714 -369.949366)
			(xy 404.397905 -369.913675) (xy 404.443755 -369.884209) (xy 404.493332 -369.861567) (xy 404.545627 -369.846212)
			(xy 404.599575 -369.838456) (xy 404.654077 -369.838456) (xy 404.708025 -369.846212) (xy 404.76032 -369.861567)
			(xy 404.809897 -369.884209) (xy 404.855747 -369.913675) (xy 404.896938 -369.949366) (xy 404.932629 -369.990557)
			(xy 404.962095 -370.036407) (xy 404.984737 -370.085984) (xy 405.000092 -370.138279) (xy 405.007848 -370.192227)
			(xy 405.008334 -370.219478) (xy 405.007879 -370.245834) (xy 405.000637 -370.298045) (xy 404.986275 -370.348761)
			(xy 404.965066 -370.397017) (xy 404.937414 -370.441893) (xy 404.903846 -370.482533) (xy 404.865002 -370.518164)
			(xy 404.821621 -370.548106) (xy 404.798276 -370.560346) (xy 404.785647 -370.567166) (xy 404.764551 -370.58661)
			(xy 404.749709 -370.611162) (xy 404.742295 -370.638877) (xy 404.742897 -370.66756) (xy 404.751468 -370.69494)
			(xy 404.767328 -370.718847) (xy 404.777956 -370.728494) (xy 404.798687 -370.746728) (xy 404.835224 -370.788116)
			(xy 404.865415 -370.834338) (xy 404.888629 -370.884429) (xy 404.90438 -370.937342) (xy 404.91234 -370.991974)
			(xy 404.912627 -371.008148) (xy 405.37206 -371.008148) (xy 405.376131 -370.952526) (xy 405.388257 -370.898089)
			(xy 405.40818 -370.845998) (xy 405.435476 -370.797363) (xy 405.469562 -370.75322) (xy 405.509711 -370.714511)
			(xy 405.555069 -370.68206) (xy 405.604669 -370.656559) (xy 405.657453 -370.638552) (xy 405.712296 -370.628422)
			(xy 405.76803 -370.626385) (xy 405.823467 -370.632485) (xy 405.877424 -370.646591) (xy 405.928753 -370.668403)
			(xy 405.976359 -370.697457) (xy 406.019227 -370.733132) (xy 406.056444 -370.774669) (xy 406.087217 -370.821182)
			(xy 406.110889 -370.871679) (xy 406.126957 -370.925086) (xy 406.135077 -370.980262) (xy 406.135586 -371.008148)
			(xy 406.135077 -371.036034) (xy 406.126957 -371.09121) (xy 406.110889 -371.144617) (xy 406.087217 -371.195114)
			(xy 406.056444 -371.241627) (xy 406.019227 -371.283164) (xy 405.976359 -371.318839) (xy 405.928753 -371.347893)
			(xy 405.877424 -371.369705) (xy 405.823467 -371.383811) (xy 405.76803 -371.389911) (xy 405.712296 -371.387874)
			(xy 405.657453 -371.377744) (xy 405.604669 -371.359737) (xy 405.555069 -371.334236) (xy 405.509711 -371.301785)
			(xy 405.469562 -371.263076) (xy 405.435476 -371.218933) (xy 405.40818 -371.170298) (xy 405.388257 -371.118207)
			(xy 405.376131 -371.06377) (xy 405.37206 -371.008148) (xy 404.912627 -371.008148) (xy 404.91283 -371.019578)
			(xy 404.912344 -371.046829) (xy 404.904588 -371.100777) (xy 404.889233 -371.153072) (xy 404.866591 -371.202649)
			(xy 404.837125 -371.248499) (xy 404.801434 -371.28969) (xy 404.760243 -371.325381) (xy 404.714393 -371.354847)
			(xy 404.664816 -371.377489) (xy 404.612521 -371.392844) (xy 404.558573 -371.4006) (xy 404.504071 -371.4006)
			(xy 404.450123 -371.392844) (xy 404.397828 -371.377489) (xy 404.348251 -371.354847) (xy 404.302401 -371.325381)
			(xy 404.26121 -371.28969) (xy 404.225519 -371.248499) (xy 404.196053 -371.202649) (xy 404.173411 -371.153072)
			(xy 404.158056 -371.100777) (xy 404.1503 -371.046829) (xy 404.149814 -371.019578) (xy 403.450437 -371.019578)
			(xy 403.441523 -372.877842) (xy 407.397202 -372.877842) (xy 407.401273 -372.82222) (xy 407.413399 -372.767783)
			(xy 407.433322 -372.715692) (xy 407.460618 -372.667057) (xy 407.494704 -372.622914) (xy 407.534853 -372.584205)
			(xy 407.580211 -372.551754) (xy 407.629811 -372.526253) (xy 407.682595 -372.508246) (xy 407.737438 -372.498116)
			(xy 407.793172 -372.496079) (xy 407.848609 -372.502179) (xy 407.902566 -372.516285) (xy 407.953895 -372.538097)
			(xy 408.001501 -372.567151) (xy 408.044369 -372.602826) (xy 408.081586 -372.644363) (xy 408.112359 -372.690876)
			(xy 408.136031 -372.741373) (xy 408.152099 -372.79478) (xy 408.160219 -372.849956) (xy 408.160728 -372.877842)
			(xy 408.160219 -372.905728) (xy 408.152099 -372.960904) (xy 408.136031 -373.014311) (xy 408.112359 -373.064808)
			(xy 408.081586 -373.111321) (xy 408.044369 -373.152858) (xy 408.001501 -373.188533) (xy 407.953895 -373.217587)
			(xy 407.902566 -373.239399) (xy 407.848609 -373.253505) (xy 407.793172 -373.259605) (xy 407.737438 -373.257568)
			(xy 407.682595 -373.247438) (xy 407.629811 -373.229431) (xy 407.580211 -373.20393) (xy 407.534853 -373.171479)
			(xy 407.494704 -373.13277) (xy 407.460618 -373.088627) (xy 407.433322 -373.039992) (xy 407.413399 -372.987901)
			(xy 407.401273 -372.933464) (xy 407.397202 -372.877842) (xy 403.441523 -372.877842) (xy 403.435349 -374.16486)
			(xy 403.928832 -374.16486) (xy 403.932903 -374.109238) (xy 403.945029 -374.054801) (xy 403.964952 -374.00271)
			(xy 403.992248 -373.954075) (xy 404.026334 -373.909932) (xy 404.066483 -373.871223) (xy 404.111841 -373.838772)
			(xy 404.161441 -373.813271) (xy 404.214225 -373.795264) (xy 404.269068 -373.785134) (xy 404.324802 -373.783097)
			(xy 404.380239 -373.789197) (xy 404.434196 -373.803303) (xy 404.485525 -373.825115) (xy 404.533131 -373.854169)
			(xy 404.575999 -373.889844) (xy 404.613216 -373.931381) (xy 404.643989 -373.977894) (xy 404.667661 -374.028391)
			(xy 404.683729 -374.081798) (xy 404.691849 -374.136974) (xy 404.692358 -374.16486) (xy 404.691849 -374.192746)
			(xy 404.683729 -374.247922) (xy 404.667661 -374.301329) (xy 404.643989 -374.351826) (xy 404.613216 -374.398339)
			(xy 404.575999 -374.439876) (xy 404.533131 -374.475551) (xy 404.485525 -374.504605) (xy 404.434196 -374.526417)
			(xy 404.380239 -374.540523) (xy 404.324802 -374.546623) (xy 404.269068 -374.544586) (xy 404.214225 -374.534456)
			(xy 404.161441 -374.516449) (xy 404.111841 -374.490948) (xy 404.066483 -374.458497) (xy 404.026334 -374.419788)
			(xy 403.992248 -374.375645) (xy 403.964952 -374.32701) (xy 403.945029 -374.274919) (xy 403.932903 -374.220482)
			(xy 403.928832 -374.16486) (xy 403.435349 -374.16486) (xy 403.432769 -374.702653) (xy 405.266855 -374.702653)
			(xy 405.266855 -374.648147) (xy 405.274612 -374.594195) (xy 405.289969 -374.541897) (xy 405.312612 -374.492317)
			(xy 405.34208 -374.446463) (xy 405.377775 -374.40527) (xy 405.418968 -374.369577) (xy 405.464822 -374.340109)
			(xy 405.514403 -374.317467) (xy 405.566701 -374.302111) (xy 405.620653 -374.294355) (xy 405.647906 -374.293892)
			(xy 405.64816 -374.293892) (xy 405.676552 -374.294419) (xy 405.732706 -374.302865) (xy 405.78699 -374.319533)
			(xy 405.838208 -374.344055) (xy 405.885231 -374.375889) (xy 405.906478 -374.39473) (xy 405.913844 -374.401588)
			(xy 405.93264 -374.408446) (xy 406.014682 -374.405144) (xy 406.02457 -374.404284) (xy 406.042608 -374.396051)
			(xy 406.049734 -374.389142) (xy 406.049988 -374.388888) (xy 406.068094 -374.369853) (xy 406.108661 -374.336473)
			(xy 406.153427 -374.308978) (xy 406.201543 -374.287887) (xy 406.252098 -374.273602) (xy 406.304136 -374.266391)
			(xy 406.330404 -374.265952) (xy 406.357652 -374.266518) (xy 406.411594 -374.274275) (xy 406.463882 -374.289628)
			(xy 406.513454 -374.312267) (xy 406.559299 -374.341731) (xy 406.600484 -374.377418) (xy 406.636172 -374.418604)
			(xy 406.665634 -374.46445) (xy 406.688273 -374.514021) (xy 406.703626 -374.56631) (xy 406.711382 -374.620252)
			(xy 406.711382 -374.674748) (xy 406.703626 -374.72869) (xy 406.688273 -374.780979) (xy 406.665634 -374.83055)
			(xy 406.636172 -374.876396) (xy 406.600484 -374.917582) (xy 406.559299 -374.953269) (xy 406.513454 -374.982733)
			(xy 406.463882 -375.005372) (xy 406.411594 -375.020725) (xy 406.357652 -375.028482) (xy 406.330404 -375.028968)
			(xy 406.33015 -375.028968) (xy 406.301757 -375.028445) (xy 406.245603 -375.019999) (xy 406.191318 -375.003331)
			(xy 406.1401 -374.978809) (xy 406.093079 -374.946972) (xy 406.071832 -374.92813) (xy 406.064466 -374.921272)
			(xy 406.04567 -374.914414) (xy 405.963628 -374.917716) (xy 405.953738 -374.918564) (xy 405.935699 -374.926804)
			(xy 405.928576 -374.933718) (xy 405.928322 -374.933972) (xy 405.910204 -374.952995) (xy 405.86964 -374.986377)
			(xy 405.824877 -375.013875) (xy 405.776763 -375.034968) (xy 405.72621 -375.049256) (xy 405.674173 -375.056468)
			(xy 405.647906 -375.056908) (xy 405.620653 -375.056445) (xy 405.566701 -375.048689) (xy 405.514403 -375.033333)
			(xy 405.464822 -375.010691) (xy 405.418968 -374.981223) (xy 405.377775 -374.94553) (xy 405.34208 -374.904337)
			(xy 405.312612 -374.858483) (xy 405.289969 -374.808903) (xy 405.274612 -374.756605) (xy 405.266855 -374.702653)
			(xy 403.432769 -374.702653) (xy 403.416582 -378.076968) (xy 406.020014 -378.076968) (xy 406.024085 -378.021346)
			(xy 406.036211 -377.966909) (xy 406.056134 -377.914818) (xy 406.08343 -377.866183) (xy 406.117516 -377.82204)
			(xy 406.157665 -377.783331) (xy 406.203023 -377.75088) (xy 406.252623 -377.725379) (xy 406.305407 -377.707372)
			(xy 406.36025 -377.697242) (xy 406.415984 -377.695205) (xy 406.471421 -377.701305) (xy 406.525378 -377.715411)
			(xy 406.576707 -377.737223) (xy 406.624313 -377.766277) (xy 406.667181 -377.801952) (xy 406.704398 -377.843489)
			(xy 406.735171 -377.890002) (xy 406.758843 -377.940499) (xy 406.774911 -377.993906) (xy 406.783031 -378.049082)
			(xy 406.78354 -378.076968) (xy 406.783031 -378.104854) (xy 406.774911 -378.16003) (xy 406.758843 -378.213437)
			(xy 406.735171 -378.263934) (xy 406.704398 -378.310447) (xy 406.667181 -378.351984) (xy 406.624313 -378.387659)
			(xy 406.576707 -378.416713) (xy 406.525378 -378.438525) (xy 406.471421 -378.452631) (xy 406.415984 -378.458731)
			(xy 406.36025 -378.456694) (xy 406.305407 -378.446564) (xy 406.252623 -378.428557) (xy 406.203023 -378.403056)
			(xy 406.157665 -378.370605) (xy 406.117516 -378.331896) (xy 406.08343 -378.287753) (xy 406.056134 -378.239118)
			(xy 406.036211 -378.187027) (xy 406.024085 -378.13259) (xy 406.020014 -378.076968) (xy 403.416582 -378.076968)
			(xy 403.412307 -378.968) (xy 405.011634 -378.968) (xy 405.015705 -378.912378) (xy 405.027831 -378.857941)
			(xy 405.047754 -378.80585) (xy 405.07505 -378.757215) (xy 405.109136 -378.713072) (xy 405.149285 -378.674363)
			(xy 405.194643 -378.641912) (xy 405.244243 -378.616411) (xy 405.297027 -378.598404) (xy 405.35187 -378.588274)
			(xy 405.407604 -378.586237) (xy 405.463041 -378.592337) (xy 405.516998 -378.606443) (xy 405.568327 -378.628255)
			(xy 405.615933 -378.657309) (xy 405.658801 -378.692984) (xy 405.696018 -378.734521) (xy 405.726791 -378.781034)
			(xy 405.750463 -378.831531) (xy 405.766531 -378.884938) (xy 405.774651 -378.940114) (xy 405.77516 -378.968)
			(xy 405.774651 -378.995886) (xy 405.766531 -379.051062) (xy 405.750463 -379.104469) (xy 405.726791 -379.154966)
			(xy 405.696018 -379.201479) (xy 405.658801 -379.243016) (xy 405.615933 -379.278691) (xy 405.568327 -379.307745)
			(xy 405.516998 -379.329557) (xy 405.463041 -379.343663) (xy 405.407604 -379.349763) (xy 405.35187 -379.347726)
			(xy 405.297027 -379.337596) (xy 405.244243 -379.319589) (xy 405.194643 -379.294088) (xy 405.149285 -379.261637)
			(xy 405.109136 -379.222928) (xy 405.07505 -379.178785) (xy 405.047754 -379.13015) (xy 405.027831 -379.078059)
			(xy 405.015705 -379.023622) (xy 405.011634 -378.968) (xy 403.412307 -378.968) (xy 403.400147 -381.50292)
			(xy 403.816564 -381.50292) (xy 403.820635 -381.447298) (xy 403.832761 -381.392861) (xy 403.852684 -381.34077)
			(xy 403.87998 -381.292135) (xy 403.914066 -381.247992) (xy 403.954215 -381.209283) (xy 403.999573 -381.176832)
			(xy 404.049173 -381.151331) (xy 404.101957 -381.133324) (xy 404.1568 -381.123194) (xy 404.212534 -381.121157)
			(xy 404.267971 -381.127257) (xy 404.321928 -381.141363) (xy 404.373257 -381.163175) (xy 404.420863 -381.192229)
			(xy 404.463731 -381.227904) (xy 404.500948 -381.269441) (xy 404.531721 -381.315954) (xy 404.555393 -381.366451)
			(xy 404.571461 -381.419858) (xy 404.579581 -381.475034) (xy 404.58009 -381.50292) (xy 404.579581 -381.530806)
			(xy 404.571461 -381.585982) (xy 404.555393 -381.639389) (xy 404.531721 -381.689886) (xy 404.500948 -381.736399)
			(xy 404.463731 -381.777936) (xy 404.420863 -381.813611) (xy 404.373257 -381.842665) (xy 404.321928 -381.864477)
			(xy 404.267971 -381.878583) (xy 404.212534 -381.884683) (xy 404.1568 -381.882646) (xy 404.101957 -381.872516)
			(xy 404.049173 -381.854509) (xy 403.999573 -381.829008) (xy 403.954215 -381.796557) (xy 403.914066 -381.757848)
			(xy 403.87998 -381.713705) (xy 403.852684 -381.66507) (xy 403.832761 -381.612979) (xy 403.820635 -381.558542)
			(xy 403.816564 -381.50292) (xy 403.400147 -381.50292) (xy 403.395249 -382.524) (xy 408.176982 -382.524)
			(xy 408.181053 -382.468378) (xy 408.193179 -382.413941) (xy 408.213102 -382.36185) (xy 408.240398 -382.313215)
			(xy 408.274484 -382.269072) (xy 408.314633 -382.230363) (xy 408.359991 -382.197912) (xy 408.409591 -382.172411)
			(xy 408.462375 -382.154404) (xy 408.517218 -382.144274) (xy 408.572952 -382.142237) (xy 408.628389 -382.148337)
			(xy 408.682346 -382.162443) (xy 408.733675 -382.184255) (xy 408.781281 -382.213309) (xy 408.824149 -382.248984)
			(xy 408.861366 -382.290521) (xy 408.892139 -382.337034) (xy 408.915811 -382.387531) (xy 408.931879 -382.440938)
			(xy 408.939999 -382.496114) (xy 408.940508 -382.524) (xy 408.939999 -382.551886) (xy 408.931879 -382.607062)
			(xy 408.915811 -382.660469) (xy 408.892139 -382.710966) (xy 408.861366 -382.757479) (xy 408.824149 -382.799016)
			(xy 408.781281 -382.834691) (xy 408.733675 -382.863745) (xy 408.682346 -382.885557) (xy 408.628389 -382.899663)
			(xy 408.572952 -382.905763) (xy 408.517218 -382.903726) (xy 408.462375 -382.893596) (xy 408.409591 -382.875589)
			(xy 408.359991 -382.850088) (xy 408.314633 -382.817637) (xy 408.274484 -382.778928) (xy 408.240398 -382.734785)
			(xy 408.213102 -382.68615) (xy 408.193179 -382.634059) (xy 408.181053 -382.579622) (xy 408.176982 -382.524)
			(xy 403.395249 -382.524) (xy 403.387847 -384.06705) (xy 403.966932 -384.06705) (xy 403.971003 -384.011428)
			(xy 403.983129 -383.956991) (xy 404.003052 -383.9049) (xy 404.030348 -383.856265) (xy 404.064434 -383.812122)
			(xy 404.104583 -383.773413) (xy 404.149941 -383.740962) (xy 404.199541 -383.715461) (xy 404.252325 -383.697454)
			(xy 404.307168 -383.687324) (xy 404.362902 -383.685287) (xy 404.418339 -383.691387) (xy 404.472296 -383.705493)
			(xy 404.523625 -383.727305) (xy 404.571231 -383.756359) (xy 404.614099 -383.792034) (xy 404.651316 -383.833571)
			(xy 404.682089 -383.880084) (xy 404.705761 -383.930581) (xy 404.721829 -383.983988) (xy 404.729949 -384.039164)
			(xy 404.730458 -384.06705) (xy 404.729949 -384.094936) (xy 404.721829 -384.150112) (xy 404.705761 -384.203519)
			(xy 404.682089 -384.254016) (xy 404.651316 -384.300529) (xy 404.614099 -384.342066) (xy 404.571231 -384.377741)
			(xy 404.523625 -384.406795) (xy 404.472296 -384.428607) (xy 404.418339 -384.442713) (xy 404.362902 -384.448813)
			(xy 404.307168 -384.446776) (xy 404.252325 -384.436646) (xy 404.199541 -384.418639) (xy 404.149941 -384.393138)
			(xy 404.104583 -384.360687) (xy 404.064434 -384.321978) (xy 404.030348 -384.277835) (xy 404.003052 -384.2292)
			(xy 403.983129 -384.177109) (xy 403.971003 -384.122672) (xy 403.966932 -384.06705) (xy 403.387847 -384.06705)
			(xy 403.384892 -384.683) (xy 406.398982 -384.683) (xy 406.403053 -384.627378) (xy 406.415179 -384.572941)
			(xy 406.435102 -384.52085) (xy 406.462398 -384.472215) (xy 406.496484 -384.428072) (xy 406.536633 -384.389363)
			(xy 406.581991 -384.356912) (xy 406.631591 -384.331411) (xy 406.684375 -384.313404) (xy 406.739218 -384.303274)
			(xy 406.794952 -384.301237) (xy 406.850389 -384.307337) (xy 406.904346 -384.321443) (xy 406.955675 -384.343255)
			(xy 407.003281 -384.372309) (xy 407.046149 -384.407984) (xy 407.083366 -384.449521) (xy 407.114139 -384.496034)
			(xy 407.137811 -384.546531) (xy 407.153879 -384.599938) (xy 407.161999 -384.655114) (xy 407.162508 -384.683)
			(xy 407.161999 -384.710886) (xy 407.153879 -384.766062) (xy 407.14066 -384.81) (xy 408.176982 -384.81)
			(xy 408.181053 -384.754378) (xy 408.193179 -384.699941) (xy 408.213102 -384.64785) (xy 408.240398 -384.599215)
			(xy 408.274484 -384.555072) (xy 408.314633 -384.516363) (xy 408.359991 -384.483912) (xy 408.409591 -384.458411)
			(xy 408.462375 -384.440404) (xy 408.517218 -384.430274) (xy 408.572952 -384.428237) (xy 408.628389 -384.434337)
			(xy 408.682346 -384.448443) (xy 408.733675 -384.470255) (xy 408.781281 -384.499309) (xy 408.824149 -384.534984)
			(xy 408.861366 -384.576521) (xy 408.892139 -384.623034) (xy 408.915811 -384.673531) (xy 408.931879 -384.726938)
			(xy 408.939999 -384.782114) (xy 408.940508 -384.81) (xy 408.939999 -384.837886) (xy 408.931879 -384.893062)
			(xy 408.915811 -384.946469) (xy 408.892139 -384.996966) (xy 408.861366 -385.043479) (xy 408.824149 -385.085016)
			(xy 408.781281 -385.120691) (xy 408.733675 -385.149745) (xy 408.682346 -385.171557) (xy 408.628389 -385.185663)
			(xy 408.572952 -385.191763) (xy 408.517218 -385.189726) (xy 408.462375 -385.179596) (xy 408.409591 -385.161589)
			(xy 408.359991 -385.136088) (xy 408.314633 -385.103637) (xy 408.274484 -385.064928) (xy 408.240398 -385.020785)
			(xy 408.213102 -384.97215) (xy 408.193179 -384.920059) (xy 408.181053 -384.865622) (xy 408.176982 -384.81)
			(xy 407.14066 -384.81) (xy 407.137811 -384.819469) (xy 407.114139 -384.869966) (xy 407.083366 -384.916479)
			(xy 407.046149 -384.958016) (xy 407.003281 -384.993691) (xy 406.955675 -385.022745) (xy 406.904346 -385.044557)
			(xy 406.850389 -385.058663) (xy 406.794952 -385.064763) (xy 406.739218 -385.062726) (xy 406.684375 -385.052596)
			(xy 406.631591 -385.034589) (xy 406.581991 -385.009088) (xy 406.536633 -384.976637) (xy 406.496484 -384.937928)
			(xy 406.462398 -384.893785) (xy 406.435102 -384.84515) (xy 406.415179 -384.793059) (xy 406.403053 -384.738622)
			(xy 406.398982 -384.683) (xy 403.384892 -384.683) (xy 403.379409 -385.826) (xy 407.033982 -385.826)
			(xy 407.038053 -385.770378) (xy 407.050179 -385.715941) (xy 407.070102 -385.66385) (xy 407.097398 -385.615215)
			(xy 407.131484 -385.571072) (xy 407.171633 -385.532363) (xy 407.216991 -385.499912) (xy 407.266591 -385.474411)
			(xy 407.319375 -385.456404) (xy 407.374218 -385.446274) (xy 407.429952 -385.444237) (xy 407.485389 -385.450337)
			(xy 407.539346 -385.464443) (xy 407.590675 -385.486255) (xy 407.638281 -385.515309) (xy 407.681149 -385.550984)
			(xy 407.718366 -385.592521) (xy 407.749139 -385.639034) (xy 407.772811 -385.689531) (xy 407.788879 -385.742938)
			(xy 407.796999 -385.798114) (xy 407.797508 -385.826) (xy 407.796999 -385.853886) (xy 407.788879 -385.909062)
			(xy 407.772811 -385.962469) (xy 407.749139 -386.012966) (xy 407.718366 -386.059479) (xy 407.681149 -386.101016)
			(xy 407.638281 -386.136691) (xy 407.590675 -386.165745) (xy 407.539346 -386.187557) (xy 407.485389 -386.201663)
			(xy 407.429952 -386.207763) (xy 407.374218 -386.205726) (xy 407.319375 -386.195596) (xy 407.266591 -386.177589)
			(xy 407.216991 -386.152088) (xy 407.171633 -386.119637) (xy 407.131484 -386.080928) (xy 407.097398 -386.036785)
			(xy 407.070102 -385.98815) (xy 407.050179 -385.936059) (xy 407.038053 -385.881622) (xy 407.033982 -385.826)
			(xy 403.379409 -385.826) (xy 403.374076 -386.937758) (xy 403.667974 -386.937758) (xy 403.672045 -386.882136)
			(xy 403.684171 -386.827699) (xy 403.704094 -386.775608) (xy 403.73139 -386.726973) (xy 403.765476 -386.68283)
			(xy 403.805625 -386.644121) (xy 403.850983 -386.61167) (xy 403.900583 -386.586169) (xy 403.953367 -386.568162)
			(xy 404.00821 -386.558032) (xy 404.063944 -386.555995) (xy 404.119381 -386.562095) (xy 404.173338 -386.576201)
			(xy 404.224667 -386.598013) (xy 404.272273 -386.627067) (xy 404.315141 -386.662742) (xy 404.352358 -386.704279)
			(xy 404.383131 -386.750792) (xy 404.406803 -386.801289) (xy 404.422871 -386.854696) (xy 404.430991 -386.909872)
			(xy 404.431301 -386.926836) (xy 409.520642 -386.926836) (xy 409.524713 -386.871214) (xy 409.536839 -386.816777)
			(xy 409.556762 -386.764686) (xy 409.584058 -386.716051) (xy 409.618144 -386.671908) (xy 409.658293 -386.633199)
			(xy 409.703651 -386.600748) (xy 409.753251 -386.575247) (xy 409.806035 -386.55724) (xy 409.860878 -386.54711)
			(xy 409.916612 -386.545073) (xy 409.972049 -386.551173) (xy 410.026006 -386.565279) (xy 410.077335 -386.587091)
			(xy 410.124941 -386.616145) (xy 410.167809 -386.65182) (xy 410.205026 -386.693357) (xy 410.235799 -386.73987)
			(xy 410.259471 -386.790367) (xy 410.275539 -386.843774) (xy 410.283659 -386.89895) (xy 410.284168 -386.926836)
			(xy 410.283659 -386.954722) (xy 410.275539 -387.009898) (xy 410.259471 -387.063305) (xy 410.235799 -387.113802)
			(xy 410.205026 -387.160315) (xy 410.167809 -387.201852) (xy 410.124941 -387.237527) (xy 410.077335 -387.266581)
			(xy 410.026006 -387.288393) (xy 409.972049 -387.302499) (xy 409.916612 -387.308599) (xy 409.860878 -387.306562)
			(xy 409.806035 -387.296432) (xy 409.753251 -387.278425) (xy 409.703651 -387.252924) (xy 409.658293 -387.220473)
			(xy 409.618144 -387.181764) (xy 409.584058 -387.137621) (xy 409.556762 -387.088986) (xy 409.536839 -387.036895)
			(xy 409.524713 -386.982458) (xy 409.520642 -386.926836) (xy 404.431301 -386.926836) (xy 404.4315 -386.937758)
			(xy 404.430991 -386.965644) (xy 404.422871 -387.02082) (xy 404.406803 -387.074227) (xy 404.383131 -387.124724)
			(xy 404.352358 -387.171237) (xy 404.315141 -387.212774) (xy 404.272273 -387.248449) (xy 404.224667 -387.277503)
			(xy 404.173338 -387.299315) (xy 404.119381 -387.313421) (xy 404.063944 -387.319521) (xy 404.00821 -387.317484)
			(xy 403.953367 -387.307354) (xy 403.900583 -387.289347) (xy 403.850983 -387.263846) (xy 403.805625 -387.231395)
			(xy 403.765476 -387.192686) (xy 403.73139 -387.148543) (xy 403.704094 -387.099908) (xy 403.684171 -387.047817)
			(xy 403.672045 -386.99338) (xy 403.667974 -386.937758) (xy 403.374076 -386.937758) (xy 403.370034 -387.780276)
			(xy 403.369364 -387.823629) (xy 403.361433 -387.909976) (xy 403.355505 -387.942836) (xy 408.392374 -387.942836)
			(xy 408.396445 -387.887214) (xy 408.408571 -387.832777) (xy 408.428494 -387.780686) (xy 408.45579 -387.732051)
			(xy 408.489876 -387.687908) (xy 408.530025 -387.649199) (xy 408.575383 -387.616748) (xy 408.624983 -387.591247)
			(xy 408.677767 -387.57324) (xy 408.73261 -387.56311) (xy 408.788344 -387.561073) (xy 408.843781 -387.567173)
			(xy 408.897738 -387.581279) (xy 408.949067 -387.603091) (xy 408.996673 -387.632145) (xy 409.039541 -387.66782)
			(xy 409.076758 -387.709357) (xy 409.107531 -387.75587) (xy 409.131203 -387.806367) (xy 409.147271 -387.859774)
			(xy 409.155391 -387.91495) (xy 409.1559 -387.942836) (xy 409.155391 -387.970722) (xy 409.147271 -388.025898)
			(xy 409.131203 -388.079305) (xy 409.107531 -388.129802) (xy 409.076758 -388.176315) (xy 409.039541 -388.217852)
			(xy 408.996673 -388.253527) (xy 408.949067 -388.282581) (xy 408.897738 -388.304393) (xy 408.843781 -388.318499)
			(xy 408.788344 -388.324599) (xy 408.73261 -388.322562) (xy 408.677767 -388.312432) (xy 408.624983 -388.294425)
			(xy 408.575383 -388.268924) (xy 408.530025 -388.236473) (xy 408.489876 -388.197764) (xy 408.45579 -388.153621)
			(xy 408.428494 -388.104986) (xy 408.408571 -388.052895) (xy 408.396445 -387.998458) (xy 408.392374 -387.942836)
			(xy 403.355505 -387.942836) (xy 403.346038 -387.99531) (xy 403.323295 -388.078985) (xy 403.293375 -388.16037)
			(xy 403.256505 -388.238852) (xy 403.23516 -388.276592) (xy 402.865844 -388.912354) (xy 402.838835 -388.958836)
			(xy 409.520642 -388.958836) (xy 409.524713 -388.903214) (xy 409.536839 -388.848777) (xy 409.556762 -388.796686)
			(xy 409.584058 -388.748051) (xy 409.618144 -388.703908) (xy 409.658293 -388.665199) (xy 409.703651 -388.632748)
			(xy 409.753251 -388.607247) (xy 409.806035 -388.58924) (xy 409.860878 -388.57911) (xy 409.916612 -388.577073)
			(xy 409.972049 -388.583173) (xy 410.026006 -388.597279) (xy 410.077335 -388.619091) (xy 410.124941 -388.648145)
			(xy 410.167809 -388.68382) (xy 410.205026 -388.725357) (xy 410.235799 -388.77187) (xy 410.259471 -388.822367)
			(xy 410.275539 -388.875774) (xy 410.283659 -388.93095) (xy 410.284168 -388.958836) (xy 410.283659 -388.986722)
			(xy 410.275539 -389.041898) (xy 410.259471 -389.095305) (xy 410.235799 -389.145802) (xy 410.205026 -389.192315)
			(xy 410.167809 -389.233852) (xy 410.124941 -389.269527) (xy 410.077335 -389.298581) (xy 410.026006 -389.320393)
			(xy 409.972049 -389.334499) (xy 409.916612 -389.340599) (xy 409.860878 -389.338562) (xy 409.806035 -389.328432)
			(xy 409.753251 -389.310425) (xy 409.703651 -389.284924) (xy 409.658293 -389.252473) (xy 409.618144 -389.213764)
			(xy 409.584058 -389.169621) (xy 409.556762 -389.120986) (xy 409.536839 -389.068895) (xy 409.524713 -389.014458)
			(xy 409.520642 -388.958836) (xy 402.838835 -388.958836) (xy 402.248478 -389.974836) (xy 408.392374 -389.974836)
			(xy 408.396445 -389.919214) (xy 408.408571 -389.864777) (xy 408.428494 -389.812686) (xy 408.45579 -389.764051)
			(xy 408.489876 -389.719908) (xy 408.530025 -389.681199) (xy 408.575383 -389.648748) (xy 408.624983 -389.623247)
			(xy 408.677767 -389.60524) (xy 408.73261 -389.59511) (xy 408.788344 -389.593073) (xy 408.843781 -389.599173)
			(xy 408.897738 -389.613279) (xy 408.949067 -389.635091) (xy 408.996673 -389.664145) (xy 409.039541 -389.69982)
			(xy 409.076758 -389.741357) (xy 409.107531 -389.78787) (xy 409.131203 -389.838367) (xy 409.147271 -389.891774)
			(xy 409.155391 -389.94695) (xy 409.1559 -389.974836) (xy 409.155391 -390.002722) (xy 409.147271 -390.057898)
			(xy 409.131203 -390.111305) (xy 409.107531 -390.161802) (xy 409.076758 -390.208315) (xy 409.039541 -390.249852)
			(xy 408.996673 -390.285527) (xy 408.949067 -390.314581) (xy 408.897738 -390.336393) (xy 408.843781 -390.350499)
			(xy 408.788344 -390.356599) (xy 408.73261 -390.354562) (xy 408.677767 -390.344432) (xy 408.624983 -390.326425)
			(xy 408.575383 -390.300924) (xy 408.530025 -390.268473) (xy 408.489876 -390.229764) (xy 408.45579 -390.185621)
			(xy 408.428494 -390.136986) (xy 408.408571 -390.084895) (xy 408.396445 -390.030458) (xy 408.392374 -389.974836)
			(xy 402.248478 -389.974836) (xy 402.189442 -390.076436) (xy 401.658042 -390.990836) (xy 406.20391 -390.990836)
			(xy 406.207981 -390.935214) (xy 406.220107 -390.880777) (xy 406.24003 -390.828686) (xy 406.267326 -390.780051)
			(xy 406.301412 -390.735908) (xy 406.341561 -390.697199) (xy 406.386919 -390.664748) (xy 406.436519 -390.639247)
			(xy 406.489303 -390.62124) (xy 406.544146 -390.61111) (xy 406.59988 -390.609073) (xy 406.655317 -390.615173)
			(xy 406.709274 -390.629279) (xy 406.760603 -390.651091) (xy 406.808209 -390.680145) (xy 406.851077 -390.71582)
			(xy 406.888294 -390.757357) (xy 406.919067 -390.80387) (xy 406.942739 -390.854367) (xy 406.958807 -390.907774)
			(xy 406.966927 -390.96295) (xy 406.967436 -390.990836) (xy 406.966927 -391.018722) (xy 406.958807 -391.073898)
			(xy 406.942739 -391.127305) (xy 406.919067 -391.177802) (xy 406.888294 -391.224315) (xy 406.851077 -391.265852)
			(xy 406.808209 -391.301527) (xy 406.760603 -391.330581) (xy 406.709274 -391.352393) (xy 406.655317 -391.366499)
			(xy 406.59988 -391.372599) (xy 406.544146 -391.370562) (xy 406.489303 -391.360432) (xy 406.436519 -391.342425)
			(xy 406.386919 -391.316924) (xy 406.341561 -391.284473) (xy 406.301412 -391.245764) (xy 406.267326 -391.201621)
			(xy 406.24003 -391.152986) (xy 406.220107 -391.100895) (xy 406.207981 -391.046458) (xy 406.20391 -390.990836)
			(xy 401.658042 -390.990836) (xy 401.14347 -391.87628) (xy 401.120068 -391.915516) (xy 401.067125 -391.989975)
			(xy 401.044136 -392.016742) (xy 405.655778 -392.016742) (xy 405.659849 -391.96112) (xy 405.671975 -391.906683)
			(xy 405.691898 -391.854592) (xy 405.719194 -391.805957) (xy 405.75328 -391.761814) (xy 405.793429 -391.723105)
			(xy 405.838787 -391.690654) (xy 405.888387 -391.665153) (xy 405.941171 -391.647146) (xy 405.996014 -391.637016)
			(xy 406.051748 -391.634979) (xy 406.107185 -391.641079) (xy 406.161142 -391.655185) (xy 406.212471 -391.676997)
			(xy 406.260077 -391.706051) (xy 406.302945 -391.741726) (xy 406.340162 -391.783263) (xy 406.370935 -391.829776)
			(xy 406.394607 -391.880273) (xy 406.410675 -391.93368) (xy 406.418795 -391.988856) (xy 406.419304 -392.016742)
			(xy 406.418795 -392.044628) (xy 406.410675 -392.099804) (xy 406.394607 -392.153211) (xy 406.370935 -392.203708)
			(xy 406.340162 -392.250221) (xy 406.302945 -392.291758) (xy 406.260077 -392.327433) (xy 406.212471 -392.356487)
			(xy 406.161142 -392.378299) (xy 406.107185 -392.392405) (xy 406.051748 -392.398505) (xy 405.996014 -392.396468)
			(xy 405.941171 -392.386338) (xy 405.888387 -392.368331) (xy 405.838787 -392.34283) (xy 405.793429 -392.310379)
			(xy 405.75328 -392.27167) (xy 405.719194 -392.227527) (xy 405.691898 -392.178892) (xy 405.671975 -392.126801)
			(xy 405.659849 -392.072364) (xy 405.655778 -392.016742) (xy 401.044136 -392.016742) (xy 401.007598 -392.059284)
			(xy 400.941987 -392.122864) (xy 400.87084 -392.180182) (xy 400.794753 -392.230759) (xy 400.714363 -392.274171)
			(xy 400.672554 -392.292586) (xy 393.688062 -395.272514) (xy 393.677169 -395.277934) (xy 393.661635 -395.296617)
			(xy 393.658344 -395.308328) (xy 393.658344 -395.30909) (xy 393.65111 -395.341314) (xy 393.630308 -395.403999)
			(xy 393.602531 -395.46392) (xy 393.56814 -395.520305) (xy 393.527576 -395.572426) (xy 393.481363 -395.619611)
			(xy 393.430098 -395.661252) (xy 393.374442 -395.696811) (xy 393.315112 -395.725829) (xy 393.252875 -395.747932)
			(xy 393.188532 -395.762836) (xy 393.122915 -395.770347) (xy 393.089892 -395.770862) (xy 393.08659 -395.770862)
			(xy 393.076671 -395.77123) (xy 393.058237 -395.77854) (xy 393.050776 -395.785086) (xy 393.028932 -395.806168)
			(xy 393.021821 -395.813596) (xy 393.013715 -395.832473) (xy 393.013184 -395.842744) (xy 393.013184 -395.903196)
			(xy 393.013621 -395.912891) (xy 393.02081 -395.930902) (xy 393.027154 -395.938248) (xy 393.053062 -395.965426)
			(xy 393.083034 -395.996668) (xy 393.100814 -396.004542) (xy 393.11072 -396.00505) (xy 393.141667 -396.006874)
			(xy 393.20276 -396.017403) (xy 393.262016 -396.035621) (xy 393.318472 -396.061231) (xy 393.371211 -396.093817)
			(xy 393.419375 -396.132848) (xy 393.46218 -396.177691) (xy 393.498931 -396.227616) (xy 393.529031 -396.281812)
			(xy 393.55199 -396.339398) (xy 393.567435 -396.399436) (xy 393.575114 -396.460952) (xy 393.574904 -396.522945)
			(xy 393.566806 -396.584408) (xy 393.550954 -396.64434) (xy 393.527604 -396.701768) (xy 393.497137 -396.755758)
			(xy 393.460047 -396.805433) (xy 393.416937 -396.849984) (xy 393.36851 -396.888687) (xy 393.315551 -396.920913)
			(xy 393.258922 -396.946139) (xy 393.199543 -396.963954) (xy 393.13838 -396.974068) (xy 393.107418 -396.975584)
			(xy 393.078462 -396.988792) (xy 393.07643 -396.990824) (xy 393.060428 -397.007588) (xy 393.027408 -397.041878)
			(xy 393.020936 -397.049233) (xy 393.01364 -397.067396) (xy 393.013184 -397.077184) (xy 393.013184 -397.203168)
			(xy 393.013616 -397.212865) (xy 393.020798 -397.230883) (xy 393.027154 -397.23822) (xy 393.053062 -397.265398)
			(xy 393.083034 -397.29664) (xy 393.100814 -397.304514) (xy 393.11072 -397.305022) (xy 393.141662 -397.306846)
			(xy 393.202746 -397.317374) (xy 393.261993 -397.335589) (xy 393.318441 -397.361196) (xy 393.371172 -397.393777)
			(xy 393.419328 -397.432803) (xy 393.462127 -397.47764) (xy 393.498872 -397.527558) (xy 393.528967 -397.581746)
			(xy 393.532262 -397.59001) (xy 394.803892 -397.59001) (xy 394.807883 -397.527843) (xy 394.819792 -397.466696)
			(xy 394.839421 -397.407575) (xy 394.86645 -397.351449) (xy 394.900434 -397.29924) (xy 394.940816 -397.251805)
			(xy 394.986932 -397.209924) (xy 395.038024 -397.174284) (xy 395.093255 -397.14547) (xy 395.151717 -397.123956)
			(xy 395.212451 -397.110094) (xy 395.274458 -397.104112) (xy 395.336721 -397.106108) (xy 395.398218 -397.116051)
			(xy 395.457939 -397.133775) (xy 395.514902 -397.158992) (xy 395.568173 -397.191285) (xy 395.616878 -397.230125)
			(xy 395.660215 -397.274875) (xy 395.697475 -397.324799) (xy 395.728044 -397.379078) (xy 395.751422 -397.436821)
			(xy 395.767223 -397.497079) (xy 395.775189 -397.558862) (xy 395.775688 -397.59001) (xy 395.775189 -397.621158)
			(xy 395.767223 -397.682941) (xy 395.751422 -397.743199) (xy 395.728044 -397.800942) (xy 395.697475 -397.855221)
			(xy 395.660215 -397.905145) (xy 395.616878 -397.949895) (xy 395.568173 -397.988735) (xy 395.514902 -398.021028)
			(xy 395.457939 -398.046245) (xy 395.398218 -398.063969) (xy 395.336721 -398.073912) (xy 395.274458 -398.075908)
			(xy 395.212451 -398.069926) (xy 395.151717 -398.056064) (xy 395.093255 -398.03455) (xy 395.038024 -398.005736)
			(xy 394.986932 -397.970096) (xy 394.940816 -397.928215) (xy 394.900434 -397.88078) (xy 394.86645 -397.828571)
			(xy 394.839421 -397.772445) (xy 394.819792 -397.713324) (xy 394.807883 -397.652177) (xy 394.803892 -397.59001)
			(xy 393.532262 -397.59001) (xy 393.551923 -397.639323) (xy 393.567365 -397.699353) (xy 393.575043 -397.76086)
			(xy 393.574832 -397.822843) (xy 393.566735 -397.884297) (xy 393.550885 -397.94422) (xy 393.527538 -398.001639)
			(xy 393.497075 -398.055621) (xy 393.45999 -398.105288) (xy 393.416887 -398.149832) (xy 393.368466 -398.188529)
			(xy 393.315515 -398.220751) (xy 393.258894 -398.245972) (xy 393.199524 -398.263784) (xy 393.13837 -398.273896)
			(xy 393.107418 -398.275556) (xy 393.078462 -398.288764) (xy 393.07643 -398.290796) (xy 393.060428 -398.30756)
			(xy 393.027408 -398.34185) (xy 393.020932 -398.349204) (xy 393.013626 -398.367366) (xy 393.013184 -398.377156)
			(xy 393.013184 -398.890236) (xy 394.803892 -398.890236) (xy 394.807883 -398.828069) (xy 394.819792 -398.766922)
			(xy 394.839421 -398.707801) (xy 394.86645 -398.651675) (xy 394.900434 -398.599466) (xy 394.940816 -398.552031)
			(xy 394.986932 -398.51015) (xy 395.038024 -398.47451) (xy 395.093255 -398.445696) (xy 395.151717 -398.424182)
			(xy 395.212451 -398.41032) (xy 395.274458 -398.404338) (xy 395.336721 -398.406334) (xy 395.398218 -398.416277)
			(xy 395.457939 -398.434001) (xy 395.514902 -398.459218) (xy 395.568173 -398.491511) (xy 395.616878 -398.530351)
			(xy 395.660215 -398.575101) (xy 395.697475 -398.625025) (xy 395.728044 -398.679304) (xy 395.751422 -398.737047)
			(xy 395.767223 -398.797305) (xy 395.775189 -398.859088) (xy 395.775688 -398.890236) (xy 395.775189 -398.921384)
			(xy 395.767223 -398.983167) (xy 395.751422 -399.043425) (xy 395.728044 -399.101168) (xy 395.697475 -399.155447)
			(xy 395.660215 -399.205371) (xy 395.616878 -399.250121) (xy 395.568173 -399.288961) (xy 395.514902 -399.321254)
			(xy 395.457939 -399.346471) (xy 395.398218 -399.364195) (xy 395.336721 -399.374138) (xy 395.274458 -399.376134)
			(xy 395.212451 -399.370152) (xy 395.151717 -399.35629) (xy 395.093255 -399.334776) (xy 395.038024 -399.305962)
			(xy 394.986932 -399.270322) (xy 394.940816 -399.228441) (xy 394.900434 -399.181006) (xy 394.86645 -399.128797)
			(xy 394.839421 -399.072671) (xy 394.819792 -399.01355) (xy 394.807883 -398.952403) (xy 394.803892 -398.890236)
			(xy 393.013184 -398.890236) (xy 393.013184 -399.803112) (xy 393.013606 -399.812814) (xy 393.020774 -399.830845)
			(xy 393.027154 -399.838164) (xy 393.053062 -399.865342) (xy 393.083034 -399.896584) (xy 393.100814 -399.904458)
			(xy 393.11072 -399.904966) (xy 393.141666 -399.90679) (xy 393.202757 -399.917319) (xy 393.262011 -399.935536)
			(xy 393.318465 -399.961145) (xy 393.371202 -399.99373) (xy 393.419364 -400.03276) (xy 393.462168 -400.077602)
			(xy 393.498918 -400.127525) (xy 393.529017 -400.18172) (xy 393.551975 -400.239303) (xy 393.567419 -400.29934)
			(xy 393.575098 -400.360854) (xy 393.574888 -400.422845) (xy 393.56679 -400.484305) (xy 393.550938 -400.544236)
			(xy 393.527589 -400.601662) (xy 393.497123 -400.65565) (xy 393.460034 -400.705323) (xy 393.416926 -400.749872)
			(xy 393.3685 -400.788574) (xy 393.315543 -400.820799) (xy 393.258916 -400.846024) (xy 393.199539 -400.863838)
			(xy 393.138378 -400.873952) (xy 393.107418 -400.8755) (xy 393.078462 -400.888708) (xy 393.07643 -400.89074)
			(xy 393.060428 -400.907504) (xy 393.027408 -400.941794) (xy 393.020923 -400.949145) (xy 393.013597 -400.967307)
			(xy 393.013184 -400.9771) (xy 393.013184 -401.103084) (xy 393.013618 -401.11278) (xy 393.020805 -401.130793)
			(xy 393.027154 -401.138136) (xy 393.053062 -401.165314) (xy 393.083034 -401.196556) (xy 393.100814 -401.20443)
			(xy 393.11072 -401.204938) (xy 393.141661 -401.206762) (xy 393.202743 -401.21729) (xy 393.261988 -401.235505)
			(xy 393.318434 -401.26111) (xy 393.371163 -401.29369) (xy 393.419318 -401.332715) (xy 393.462115 -401.37755)
			(xy 393.498859 -401.427467) (xy 393.528953 -401.481653) (xy 393.532353 -401.49018) (xy 394.803892 -401.49018)
			(xy 394.807883 -401.428013) (xy 394.819792 -401.366866) (xy 394.839421 -401.307745) (xy 394.86645 -401.251619)
			(xy 394.900434 -401.19941) (xy 394.940816 -401.151975) (xy 394.986932 -401.110094) (xy 395.038024 -401.074454)
			(xy 395.093255 -401.04564) (xy 395.151717 -401.024126) (xy 395.212451 -401.010264) (xy 395.274458 -401.004282)
			(xy 395.336721 -401.006278) (xy 395.398218 -401.016221) (xy 395.457939 -401.033945) (xy 395.514902 -401.059162)
			(xy 395.568173 -401.091455) (xy 395.616878 -401.130295) (xy 395.660215 -401.175045) (xy 395.697475 -401.224969)
			(xy 395.728044 -401.279248) (xy 395.751422 -401.336991) (xy 395.767223 -401.397249) (xy 395.775189 -401.459032)
			(xy 395.775688 -401.49018) (xy 395.775189 -401.521328) (xy 395.767223 -401.583111) (xy 395.751422 -401.643369)
			(xy 395.728044 -401.701112) (xy 395.697475 -401.755391) (xy 395.660215 -401.805315) (xy 395.616878 -401.850065)
			(xy 395.568173 -401.888905) (xy 395.514902 -401.921198) (xy 395.457939 -401.946415) (xy 395.398218 -401.964139)
			(xy 395.336721 -401.974082) (xy 395.274458 -401.976078) (xy 395.212451 -401.970096) (xy 395.151717 -401.956234)
			(xy 395.093255 -401.93472) (xy 395.038024 -401.905906) (xy 394.986932 -401.870266) (xy 394.940816 -401.828385)
			(xy 394.900434 -401.78095) (xy 394.86645 -401.728741) (xy 394.839421 -401.672615) (xy 394.819792 -401.613494)
			(xy 394.807883 -401.552347) (xy 394.803892 -401.49018) (xy 393.532353 -401.49018) (xy 393.551908 -401.539228)
			(xy 393.567349 -401.599256) (xy 393.575027 -401.660761) (xy 393.574816 -401.722743) (xy 393.566719 -401.784194)
			(xy 393.550869 -401.844116) (xy 393.527523 -401.901533) (xy 393.497061 -401.955513) (xy 393.459978 -402.005178)
			(xy 393.416876 -402.049721) (xy 393.368457 -402.088417) (xy 393.315507 -402.120637) (xy 393.258888 -402.145858)
			(xy 393.19952 -402.163669) (xy 393.138368 -402.17378) (xy 393.107418 -402.175472) (xy 393.078462 -402.18868)
			(xy 393.07643 -402.190712) (xy 393.060428 -402.207476) (xy 393.027408 -402.241766) (xy 393.020934 -402.249121)
			(xy 393.013634 -402.267283) (xy 393.013184 -402.277072) (xy 393.013184 -402.790152) (xy 394.803892 -402.790152)
			(xy 394.807883 -402.727985) (xy 394.819792 -402.666838) (xy 394.839421 -402.607717) (xy 394.86645 -402.551591)
			(xy 394.900434 -402.499382) (xy 394.940816 -402.451947) (xy 394.986932 -402.410066) (xy 395.038024 -402.374426)
			(xy 395.093255 -402.345612) (xy 395.151717 -402.324098) (xy 395.212451 -402.310236) (xy 395.274458 -402.304254)
			(xy 395.336721 -402.30625) (xy 395.398218 -402.316193) (xy 395.457939 -402.333917) (xy 395.514902 -402.359134)
			(xy 395.568173 -402.391427) (xy 395.616878 -402.430267) (xy 395.660215 -402.475017) (xy 395.697475 -402.524941)
			(xy 395.728044 -402.57922) (xy 395.751422 -402.636963) (xy 395.767223 -402.697221) (xy 395.775189 -402.759004)
			(xy 395.775688 -402.790152) (xy 395.775189 -402.8213) (xy 395.767223 -402.883083) (xy 395.751422 -402.943341)
			(xy 395.728044 -403.001084) (xy 395.697475 -403.055363) (xy 395.660215 -403.105287) (xy 395.616878 -403.150037)
			(xy 395.568173 -403.188877) (xy 395.514902 -403.22117) (xy 395.457939 -403.246387) (xy 395.398218 -403.264111)
			(xy 395.336721 -403.274054) (xy 395.274458 -403.27605) (xy 395.212451 -403.270068) (xy 395.151717 -403.256206)
			(xy 395.093255 -403.234692) (xy 395.038024 -403.205878) (xy 394.986932 -403.170238) (xy 394.940816 -403.128357)
			(xy 394.900434 -403.080922) (xy 394.86645 -403.028713) (xy 394.839421 -402.972587) (xy 394.819792 -402.913466)
			(xy 394.807883 -402.852319) (xy 394.803892 -402.790152) (xy 393.013184 -402.790152) (xy 393.013184 -403.703028)
			(xy 393.013609 -403.712729) (xy 393.020781 -403.730756) (xy 393.027154 -403.73808) (xy 393.053062 -403.765258)
			(xy 393.083034 -403.7965) (xy 393.100814 -403.804374) (xy 393.11072 -403.804882) (xy 393.141665 -403.806706)
			(xy 393.202754 -403.817235) (xy 393.262006 -403.835452) (xy 393.318458 -403.86106) (xy 393.371194 -403.893643)
			(xy 393.419354 -403.932673) (xy 393.462156 -403.977513) (xy 393.498905 -404.027435) (xy 393.529003 -404.081627)
			(xy 393.55196 -404.139209) (xy 393.567404 -404.199244) (xy 393.575082 -404.260756) (xy 393.574872 -404.322745)
			(xy 393.566775 -404.384203) (xy 393.550923 -404.444131) (xy 393.527575 -404.501555) (xy 393.497109 -404.555542)
			(xy 393.460022 -404.605213) (xy 393.416915 -404.649761) (xy 393.36849 -404.688461) (xy 393.315535 -404.720685)
			(xy 393.258909 -404.745909) (xy 393.199535 -404.763723) (xy 393.138376 -404.773836) (xy 393.107418 -404.775416)
			(xy 393.078462 -404.788624) (xy 393.07643 -404.790656) (xy 393.060428 -404.80742) (xy 393.027408 -404.84171)
			(xy 393.020926 -404.849062) (xy 393.013605 -404.867224) (xy 393.013184 -404.877016) (xy 393.013184 -405.003)
			(xy 393.013621 -405.012695) (xy 393.020812 -405.030704) (xy 393.027154 -405.038052) (xy 393.053062 -405.06523)
			(xy 393.083034 -405.096472) (xy 393.100814 -405.104346) (xy 393.11072 -405.104854) (xy 393.141594 -405.10667)
			(xy 393.202545 -405.117156) (xy 393.261672 -405.135295) (xy 393.318018 -405.160794) (xy 393.370671 -405.193239)
			(xy 393.418779 -405.232105) (xy 393.461564 -405.276765) (xy 393.498333 -405.326494) (xy 393.528492 -405.380489)
			(xy 393.532352 -405.390096) (xy 394.803892 -405.390096) (xy 394.807883 -405.327929) (xy 394.819792 -405.266782)
			(xy 394.839421 -405.207661) (xy 394.86645 -405.151535) (xy 394.900434 -405.099326) (xy 394.940816 -405.051891)
			(xy 394.986932 -405.01001) (xy 395.038024 -404.97437) (xy 395.093255 -404.945556) (xy 395.151717 -404.924042)
			(xy 395.212451 -404.91018) (xy 395.274458 -404.904198) (xy 395.336721 -404.906194) (xy 395.398218 -404.916137)
			(xy 395.457939 -404.933861) (xy 395.514902 -404.959078) (xy 395.568173 -404.991371) (xy 395.616878 -405.030211)
			(xy 395.660215 -405.074961) (xy 395.697475 -405.124885) (xy 395.728044 -405.179164) (xy 395.751422 -405.236907)
			(xy 395.767223 -405.297165) (xy 395.775189 -405.358948) (xy 395.775688 -405.390096) (xy 395.775189 -405.421244)
			(xy 395.767223 -405.483027) (xy 395.751422 -405.543285) (xy 395.728044 -405.601028) (xy 395.697475 -405.655307)
			(xy 395.660215 -405.705231) (xy 395.616878 -405.749981) (xy 395.568173 -405.788821) (xy 395.514902 -405.821114)
			(xy 395.457939 -405.846331) (xy 395.398218 -405.864055) (xy 395.336721 -405.873998) (xy 395.274458 -405.875994)
			(xy 395.212451 -405.870012) (xy 395.151717 -405.85615) (xy 395.093255 -405.834636) (xy 395.038024 -405.805822)
			(xy 394.986932 -405.770182) (xy 394.940816 -405.728301) (xy 394.900434 -405.680866) (xy 394.86645 -405.628657)
			(xy 394.839421 -405.572531) (xy 394.819792 -405.51341) (xy 394.807883 -405.452263) (xy 394.803892 -405.390096)
			(xy 393.532352 -405.390096) (xy 393.551552 -405.437876) (xy 393.567141 -405.497726) (xy 393.575006 -405.559071)
			(xy 393.57554 -405.589994) (xy 393.575043 -405.621793) (xy 393.566742 -405.684846) (xy 393.550283 -405.746276)
			(xy 393.525946 -405.805032) (xy 393.494147 -405.860108) (xy 393.455432 -405.910563) (xy 393.410462 -405.955533)
			(xy 393.360007 -405.994248) (xy 393.30493 -406.026046) (xy 393.246174 -406.050383) (xy 393.184744 -406.066843)
			(xy 393.121691 -406.075143) (xy 393.089892 -406.075642) (xy 393.067082 -406.075358) (xy 393.021667 -406.071033)
			(xy 392.999214 -406.067006) (xy 392.98758 -406.065414) (xy 392.964984 -406.071707) (xy 392.947489 -406.087332)
			(xy 392.942572 -406.097994) (xy 392.936404 -406.113231) (xy 392.923193 -406.143336) (xy 392.916156 -406.158192)
			(xy 392.915648 -406.158954) (xy 392.911838 -406.167844) (xy 392.907012 -406.1841) (xy 392.906504 -406.188418)
			(xy 392.902419 -406.217451) (xy 392.886493 -406.273874) (xy 392.862121 -406.327196) (xy 392.829876 -406.376161)
			(xy 392.790518 -406.419614) (xy 392.744975 -406.456534) (xy 392.694318 -406.486049) (xy 392.667236 -406.497282)
			(xy 392.66241 -406.49906) (xy 392.646154 -406.509474) (xy 392.64209 -406.513538) (xy 392.46544 -406.690068)
			(xy 394.803892 -406.690068) (xy 394.807883 -406.627901) (xy 394.819792 -406.566754) (xy 394.839421 -406.507633)
			(xy 394.86645 -406.451507) (xy 394.900434 -406.399298) (xy 394.940816 -406.351863) (xy 394.986932 -406.309982)
			(xy 395.038024 -406.274342) (xy 395.093255 -406.245528) (xy 395.151717 -406.224014) (xy 395.212451 -406.210152)
			(xy 395.274458 -406.20417) (xy 395.336721 -406.206166) (xy 395.398218 -406.216109) (xy 395.457939 -406.233833)
			(xy 395.514902 -406.25905) (xy 395.568173 -406.291343) (xy 395.616878 -406.330183) (xy 395.660215 -406.374933)
			(xy 395.697475 -406.424857) (xy 395.728044 -406.479136) (xy 395.751422 -406.536879) (xy 395.767223 -406.597137)
			(xy 395.775189 -406.65892) (xy 395.775688 -406.690068) (xy 395.775189 -406.721216) (xy 395.767223 -406.782999)
			(xy 395.751422 -406.843257) (xy 395.728044 -406.901) (xy 395.697475 -406.955279) (xy 395.660215 -407.005203)
			(xy 395.616878 -407.049953) (xy 395.568173 -407.088793) (xy 395.514902 -407.121086) (xy 395.457939 -407.146303)
			(xy 395.398218 -407.164027) (xy 395.336721 -407.17397) (xy 395.274458 -407.175966) (xy 395.212451 -407.169984)
			(xy 395.151717 -407.156122) (xy 395.093255 -407.134608) (xy 395.038024 -407.105794) (xy 394.986932 -407.070154)
			(xy 394.940816 -407.028273) (xy 394.900434 -406.980838) (xy 394.86645 -406.928629) (xy 394.839421 -406.872503)
			(xy 394.819792 -406.813382) (xy 394.807883 -406.752235) (xy 394.803892 -406.690068) (xy 392.46544 -406.690068)
			(xy 392.269218 -406.886156) (xy 392.236949 -406.917733) (xy 392.167613 -406.975569) (xy 392.093333 -407.026902)
			(xy 392.014717 -407.071311) (xy 391.93241 -407.108432) (xy 391.847084 -407.137962) (xy 391.803382 -407.1493)
			(xy 391.798993 -407.15049) (xy 391.790687 -407.154191) (xy 391.786872 -407.156666) (xy 391.78484 -407.15819)
			(xy 391.761218 -407.176224) (xy 391.755884 -407.185114) (xy 391.75563 -407.185622) (xy 391.73352 -407.223296)
			(xy 391.683649 -407.295023) (xy 391.627696 -407.362113) (xy 391.566089 -407.424053) (xy 391.499302 -407.480368)
			(xy 391.427846 -407.530626) (xy 391.352268 -407.574443) (xy 391.273148 -407.611482) (xy 391.191092 -407.641459)
			(xy 391.106729 -407.664146) (xy 391.020704 -407.679367) (xy 390.933678 -407.687007) (xy 390.889998 -407.687526)
			(xy 390.882378 -407.687526) (xy 390.863328 -407.687018) (xy 390.813539 -407.685085) (xy 390.714691 -407.672499)
			(xy 390.617594 -407.65011) (xy 390.570212 -407.634694) (xy 390.549926 -407.6277) (xy 390.509907 -407.6122)
			(xy 390.490202 -407.603706) (xy 390.48132 -407.600195) (xy 390.462253 -407.599398) (xy 390.453118 -407.602182)
			(xy 390.422763 -407.612093) (xy 390.35982 -407.622818) (xy 390.327896 -407.623518) (xy 390.300645 -407.623032)
			(xy 390.246697 -407.615275) (xy 390.194402 -407.59992) (xy 390.144825 -407.577278) (xy 390.098974 -407.547812)
			(xy 390.057783 -407.512121) (xy 390.022091 -407.470931) (xy 389.992624 -407.425081) (xy 389.969982 -407.375504)
			(xy 389.954626 -407.323209) (xy 389.946868 -407.269261) (xy 389.946388 -407.24201) (xy 389.946388 -407.241756)
			(xy 389.947023 -407.209234) (xy 389.958004 -407.145126) (xy 389.968232 -407.114248) (xy 389.969502 -407.110692)
			(xy 389.973058 -407.093166) (xy 389.971026 -407.083514) (xy 389.968994 -407.0731) (xy 389.967216 -407.068528)
			(xy 389.949322 -407.023407) (xy 389.921361 -406.93045) (xy 389.902567 -406.835215) (xy 389.893117 -406.738604)
			(xy 389.89254 -406.690068) (xy 389.89254 -406.308052) (xy 389.892992 -406.265544) (xy 389.900253 -406.18084)
			(xy 389.91471 -406.097063) (xy 389.925052 -406.05583) (xy 389.925814 -406.053036) (xy 389.927592 -406.040082)
			(xy 389.926322 -406.031192) (xy 389.919972 -406.005538) (xy 389.916416 -405.995886) (xy 389.906764 -405.98725)
			(xy 389.903663 -405.984557) (xy 389.896772 -405.980091) (xy 389.893048 -405.97836) (xy 389.869426 -405.967946)
			(xy 389.868918 -405.967946) (xy 389.867394 -405.967184) (xy 389.859708 -405.964139) (xy 389.843258 -405.962591)
			(xy 389.835136 -405.964136) (xy 389.822182 -405.967184) (xy 389.816848 -405.969978) (xy 389.781293 -405.987585)
			(xy 389.707911 -406.01777) (xy 389.632362 -406.04203) (xy 389.593836 -406.051512) (xy 389.5852 -406.057608)
			(xy 389.568944 -406.070054) (xy 389.560562 -406.076404) (xy 389.555482 -406.085294) (xy 389.533386 -406.122986)
			(xy 389.483537 -406.194749) (xy 389.427601 -406.261876) (xy 389.366006 -406.323851) (xy 389.299225 -406.380199)
			(xy 389.22777 -406.430489) (xy 389.15219 -406.474335) (xy 389.073063 -406.511399) (xy 388.990996 -406.541399)
			(xy 388.90662 -406.564103) (xy 388.820581 -406.579338) (xy 388.733539 -406.586987) (xy 388.68985 -406.587452)
			(xy 388.64926 -406.587031) (xy 388.568351 -406.580412) (xy 388.488247 -406.567236) (xy 388.40948 -406.547593)
			(xy 388.33257 -406.521611) (xy 388.295134 -406.505918) (xy 388.285637 -406.502246) (xy 388.265296 -406.501975)
			(xy 388.24646 -406.509659) (xy 388.239 -406.516586) (xy 388.211568 -406.544018) (xy 387.869176 -406.886156)
			(xy 387.836908 -406.917735) (xy 387.767573 -406.975575) (xy 387.693295 -407.026912) (xy 387.614681 -407.071325)
			(xy 387.532374 -407.108451) (xy 387.447048 -407.137986) (xy 387.40334 -407.1493) (xy 387.398952 -407.150493)
			(xy 387.39065 -407.1542) (xy 387.38683 -407.156666) (xy 387.384798 -407.15819) (xy 387.361176 -407.176224)
			(xy 387.355842 -407.185114) (xy 387.355588 -407.185622) (xy 387.333479 -407.223298) (xy 387.283609 -407.295028)
			(xy 387.227656 -407.362121) (xy 387.166051 -407.424065) (xy 387.099265 -407.480384) (xy 387.027809 -407.530646)
			(xy 386.952231 -407.574467) (xy 386.873111 -407.61151) (xy 386.791054 -407.641492) (xy 386.70669 -407.664184)
			(xy 386.620665 -407.67941) (xy 386.533637 -407.687055) (xy 386.489956 -407.687526) (xy 386.489956 -407.687272)
			(xy 386.448841 -407.686852) (xy 386.366889 -407.68008) (xy 386.285774 -407.666578) (xy 386.206048 -407.646437)
			(xy 386.128253 -407.619795) (xy 386.090414 -407.603706) (xy 386.081532 -407.600193) (xy 386.062463 -407.599392)
			(xy 386.05333 -407.602182) (xy 386.023098 -407.61206) (xy 385.960412 -407.622783) (xy 385.928616 -407.623518)
			(xy 385.927854 -407.623518) (xy 385.900605 -407.623029) (xy 385.846661 -407.615267) (xy 385.794372 -407.599908)
			(xy 385.744799 -407.577265) (xy 385.698954 -407.547797) (xy 385.657769 -407.512106) (xy 385.622081 -407.470917)
			(xy 385.592618 -407.425069) (xy 385.569979 -407.375495) (xy 385.554625 -407.323203) (xy 385.546868 -407.269259)
			(xy 385.546346 -407.24201) (xy 385.546346 -407.241248) (xy 385.547001 -407.208791) (xy 385.55799 -407.144814)
			(xy 385.56819 -407.113994) (xy 385.56946 -407.110438) (xy 385.573016 -407.092912) (xy 385.570984 -407.08326)
			(xy 385.568952 -407.072846) (xy 385.567174 -407.068274) (xy 385.549352 -407.023235) (xy 385.521507 -406.930457)
			(xy 385.502784 -406.835417) (xy 385.49336 -406.739009) (xy 385.492752 -406.690576) (xy 385.492752 -406.30729)
			(xy 385.493217 -406.264916) (xy 385.500431 -406.180476) (xy 385.514771 -406.096951) (xy 385.52501 -406.05583)
			(xy 385.525772 -406.053036) (xy 385.52755 -406.040082) (xy 385.525772 -406.027128) (xy 385.524756 -406.023572)
			(xy 385.523486 -406.018746) (xy 385.522216 -406.013158) (xy 385.521962 -406.01265) (xy 385.519168 -406.001474)
			(xy 385.503928 -405.983694) (xy 385.466844 -405.967184) (xy 385.459083 -405.96415) (xy 385.442493 -405.96271)
			(xy 385.434332 -405.96439) (xy 385.420362 -405.967692) (xy 385.415028 -405.970486) (xy 385.379976 -405.987504)
			(xy 385.379214 -405.987758) (xy 385.37134 -405.991314) (xy 385.370832 -405.991822) (xy 385.327997 -406.010341)
			(xy 385.239586 -406.040236) (xy 385.194302 -406.051512) (xy 385.185412 -406.057608) (xy 385.169156 -406.070054)
			(xy 385.160774 -406.076404) (xy 385.155694 -406.085294) (xy 385.133598 -406.122986) (xy 385.083749 -406.19475)
			(xy 385.027813 -406.261877) (xy 384.966219 -406.323853) (xy 384.899438 -406.380203) (xy 384.827983 -406.430493)
			(xy 384.752403 -406.474339) (xy 384.673276 -406.511405) (xy 384.591209 -406.541405) (xy 384.506833 -406.564111)
			(xy 384.420793 -406.579347) (xy 384.333751 -406.586997) (xy 384.290062 -406.587452) (xy 384.249498 -406.587021)
			(xy 384.168641 -406.580387) (xy 384.08859 -406.567206) (xy 384.009874 -406.547566) (xy 383.933014 -406.521597)
			(xy 383.8956 -406.505918) (xy 383.895092 -406.505664) (xy 383.893822 -406.505156) (xy 383.884483 -406.501925)
			(xy 383.86474 -406.502078) (xy 383.84652 -406.509681) (xy 383.839212 -406.516332) (xy 383.818384 -406.53716)
			(xy 383.469134 -406.886156) (xy 383.436865 -406.917733) (xy 383.36753 -406.975571) (xy 383.29325 -407.026905)
			(xy 383.214635 -407.071315) (xy 383.132327 -407.108438) (xy 383.047002 -407.137969) (xy 383.003298 -407.1493)
			(xy 382.998908 -407.150489) (xy 382.990601 -407.154188) (xy 382.986788 -407.156666) (xy 382.984756 -407.15819)
			(xy 382.961134 -407.176224) (xy 382.9558 -407.185114) (xy 382.955546 -407.185622) (xy 382.933436 -407.223297)
			(xy 382.883565 -407.295024) (xy 382.827612 -407.362116) (xy 382.766006 -407.424057) (xy 382.69922 -407.480372)
			(xy 382.627763 -407.530632) (xy 382.552186 -407.574449) (xy 382.473066 -407.61149) (xy 382.391009 -407.641468)
			(xy 382.306646 -407.664156) (xy 382.220621 -407.679379) (xy 382.133595 -407.68702) (xy 382.089914 -407.687526)
			(xy 382.082294 -407.687526) (xy 382.063244 -407.687018) (xy 382.013455 -407.685085) (xy 381.914607 -407.672501)
			(xy 381.817509 -407.650114) (xy 381.770128 -407.634694) (xy 381.749842 -407.6277) (xy 381.709823 -407.612201)
			(xy 381.690118 -407.603706) (xy 381.681236 -407.600211) (xy 381.662179 -407.599444) (xy 381.653034 -407.602182)
			(xy 381.62268 -407.612094) (xy 381.559736 -407.622822) (xy 381.527812 -407.623518) (xy 381.500558 -407.623056)
			(xy 381.446605 -407.6153) (xy 381.394306 -407.599946) (xy 381.344723 -407.577304) (xy 381.298868 -407.547836)
			(xy 381.257673 -407.512143) (xy 381.221977 -407.47095) (xy 381.192507 -407.425096) (xy 381.169862 -407.375515)
			(xy 381.154504 -407.323216) (xy 381.146746 -407.269264) (xy 381.146304 -407.24201) (xy 381.146304 -407.241756)
			(xy 381.146938 -407.209234) (xy 381.157918 -407.145125) (xy 381.168148 -407.114248) (xy 381.169418 -407.110692)
			(xy 381.172974 -407.093166) (xy 381.170942 -407.083514) (xy 381.16891 -407.0731) (xy 381.167132 -407.068528)
			(xy 381.149239 -407.023407) (xy 381.121281 -406.930449) (xy 381.102488 -406.835214) (xy 381.093039 -406.738604)
			(xy 381.092456 -406.690068) (xy 381.092456 -406.308052) (xy 381.092908 -406.265544) (xy 381.100169 -406.18084)
			(xy 381.114626 -406.097063) (xy 381.124968 -406.05583) (xy 381.12573 -406.053036) (xy 381.127508 -406.040082)
			(xy 381.12573 -406.027128) (xy 381.124714 -406.023572) (xy 381.123444 -406.018746) (xy 381.122174 -406.013158)
			(xy 381.12192 -406.01265) (xy 381.119126 -406.001474) (xy 381.103886 -405.983694) (xy 381.066802 -405.967184)
			(xy 381.059041 -405.964157) (xy 381.042454 -405.96273) (xy 381.03429 -405.96439) (xy 381.02032 -405.967692)
			(xy 381.014986 -405.970486) (xy 380.979934 -405.987504) (xy 380.979172 -405.987758) (xy 380.971298 -405.991314)
			(xy 380.97079 -405.991822) (xy 380.927955 -406.010343) (xy 380.839546 -406.040243) (xy 380.79426 -406.051512)
			(xy 380.78537 -406.057608) (xy 380.769114 -406.070054) (xy 380.760732 -406.076404) (xy 380.755652 -406.085294)
			(xy 380.733555 -406.122985) (xy 380.683706 -406.194747) (xy 380.627769 -406.261871) (xy 380.566174 -406.323845)
			(xy 380.499393 -406.380191) (xy 380.427938 -406.430479) (xy 380.352357 -406.474322) (xy 380.27323 -406.511384)
			(xy 380.191164 -406.541381) (xy 380.106788 -406.564083) (xy 380.02075 -406.579316) (xy 379.933708 -406.586963)
			(xy 379.89002 -406.587452) (xy 379.849455 -406.587023) (xy 379.768597 -406.580394) (xy 379.688544 -406.567217)
			(xy 379.609827 -406.547581) (xy 379.532964 -406.521616) (xy 379.495558 -406.505918) (xy 379.49505 -406.505664)
			(xy 379.49378 -406.505156) (xy 379.484443 -406.501934) (xy 379.464709 -406.5021) (xy 379.446502 -406.509711)
			(xy 379.43917 -406.516332) (xy 379.418342 -406.53716) (xy 379.069092 -406.886156) (xy 379.036823 -406.917732)
			(xy 378.967486 -406.975567) (xy 378.893205 -407.026898) (xy 378.814589 -407.071305) (xy 378.732281 -407.108424)
			(xy 378.646955 -407.137952) (xy 378.603256 -407.1493) (xy 378.598868 -407.150492) (xy 378.590564 -407.154196)
			(xy 378.586746 -407.156666) (xy 378.584714 -407.15819) (xy 378.561092 -407.176224) (xy 378.555758 -407.185114)
			(xy 378.555504 -407.185622) (xy 378.533395 -407.223298) (xy 378.483525 -407.295029) (xy 378.427573 -407.362124)
			(xy 378.365968 -407.424068) (xy 378.299182 -407.480388) (xy 378.227726 -407.530651) (xy 378.152149 -407.574473)
			(xy 378.073028 -407.611518) (xy 377.990972 -407.641501) (xy 377.906607 -407.664194) (xy 377.820581 -407.679422)
			(xy 377.733554 -407.687068) (xy 377.689872 -407.687526) (xy 377.689872 -407.687272) (xy 377.648756 -407.686853)
			(xy 377.566805 -407.680082) (xy 377.48569 -407.666581) (xy 377.405963 -407.646441) (xy 377.328167 -407.6198)
			(xy 377.29033 -407.603706) (xy 377.281448 -407.600209) (xy 377.26239 -407.599438) (xy 377.253246 -407.602182)
			(xy 377.223014 -407.612061) (xy 377.160328 -407.622787) (xy 377.128532 -407.623518) (xy 377.12777 -407.623518)
			(xy 377.10052 -407.62303) (xy 377.046575 -407.61527) (xy 376.994283 -407.599913) (xy 376.944709 -407.57727)
			(xy 376.898862 -407.547803) (xy 376.857674 -407.512112) (xy 376.821985 -407.470922) (xy 376.79252 -407.425073)
			(xy 376.76988 -407.375498) (xy 376.754525 -407.323206) (xy 376.746768 -407.26926) (xy 376.746262 -407.24201)
			(xy 376.746262 -407.241248) (xy 376.746917 -407.208791) (xy 376.757907 -407.144814) (xy 376.768106 -407.113994)
			(xy 376.769376 -407.110438) (xy 376.772932 -407.092912) (xy 376.7709 -407.08326) (xy 376.768868 -407.072846)
			(xy 376.76709 -407.068274) (xy 376.749268 -407.023235) (xy 376.721422 -406.930457) (xy 376.702699 -406.835417)
			(xy 376.693274 -406.739009) (xy 376.692668 -406.690576) (xy 376.692668 -406.30729) (xy 376.693133 -406.264916)
			(xy 376.700347 -406.180476) (xy 376.714687 -406.096951) (xy 376.724926 -406.05583) (xy 376.725688 -406.053036)
			(xy 376.727466 -406.040082) (xy 376.725688 -406.027128) (xy 376.724672 -406.023572) (xy 376.723402 -406.018746)
			(xy 376.722132 -406.013158) (xy 376.721878 -406.01265) (xy 376.719084 -406.001474) (xy 376.703844 -405.983694)
			(xy 376.66676 -405.967184) (xy 376.658999 -405.964163) (xy 376.642414 -405.96275) (xy 376.634248 -405.96439)
			(xy 376.620278 -405.967692) (xy 376.614944 -405.970486) (xy 376.579892 -405.987504) (xy 376.57913 -405.987758)
			(xy 376.571256 -405.991314) (xy 376.570748 -405.991822) (xy 376.527913 -406.010342) (xy 376.439503 -406.040238)
			(xy 376.394218 -406.051512) (xy 376.385328 -406.057608) (xy 376.369072 -406.070054) (xy 376.36069 -406.076404)
			(xy 376.35561 -406.085294) (xy 376.333514 -406.122987) (xy 376.283666 -406.194751) (xy 376.22773 -406.26188)
			(xy 376.166136 -406.323857) (xy 376.099355 -406.380207) (xy 376.0279 -406.430499) (xy 375.95232 -406.474346)
			(xy 375.873193 -406.511413) (xy 375.791126 -406.541415) (xy 375.70675 -406.564121) (xy 375.62071 -406.579359)
			(xy 375.533667 -406.58701) (xy 375.489978 -406.587452) (xy 375.48947 -406.587452) (xy 375.448829 -406.587051)
			(xy 375.367815 -406.580457) (xy 375.287606 -406.567292) (xy 375.208735 -406.547643) (xy 375.131725 -406.521639)
			(xy 375.094246 -406.505918) (xy 375.084848 -406.50287) (xy 375.079006 -406.5016) (xy 375.074299 -406.500669)
			(xy 375.064707 -406.500419) (xy 375.059956 -406.501092) (xy 375.054114 -406.502108) (xy 375.05005 -406.503378)
			(xy 375.028128 -406.510437) (xy 374.983048 -406.51986) (xy 374.960134 -406.522174) (xy 374.93067 -406.523444)
			(xy 374.925844 -406.523444) (xy 374.898688 -406.522819) (xy 374.844961 -406.514825) (xy 374.79291 -406.499293)
			(xy 374.743588 -406.476536) (xy 374.697993 -406.447015) (xy 374.657045 -406.411325) (xy 374.621572 -406.370189)
			(xy 374.592292 -406.324437) (xy 374.569797 -406.274996) (xy 374.554541 -406.222864) (xy 374.546832 -406.169095)
			(xy 374.546368 -406.141936) (xy 374.546368 -406.141682) (xy 374.547001 -406.10916) (xy 374.557977 -406.04505)
			(xy 374.568212 -406.014174) (xy 374.569482 -406.010618) (xy 374.573038 -405.993092) (xy 374.571006 -405.98344)
			(xy 374.568974 -405.973026) (xy 374.567196 -405.968454) (xy 374.549301 -405.923334) (xy 374.521339 -405.830376)
			(xy 374.502542 -405.735141) (xy 374.49309 -405.63853) (xy 374.49252 -405.589994) (xy 374.49252 -405.207978)
			(xy 374.492971 -405.16547) (xy 374.50023 -405.080765) (xy 374.514684 -404.996987) (xy 374.525032 -404.955756)
			(xy 374.525794 -404.952962) (xy 374.527572 -404.940008) (xy 374.525794 -404.927054) (xy 374.525032 -404.92426)
			(xy 374.514702 -404.883025) (xy 374.500254 -404.799247) (xy 374.492976 -404.714545) (xy 374.49252 -404.672038)
			(xy 374.49252 -404.290022) (xy 374.493104 -404.241385) (xy 374.502576 -404.144573) (xy 374.521432 -404.049143)
			(xy 374.549492 -403.956004) (xy 374.56745 -403.9108) (xy 374.569482 -403.906228) (xy 374.571006 -403.897338)
			(xy 374.57181 -403.892742) (xy 374.571933 -403.883413) (xy 374.57126 -403.878796) (xy 374.569736 -403.87016)
			(xy 374.568212 -403.866096) (xy 374.558055 -403.835331) (xy 374.547076 -403.771487) (xy 374.546368 -403.739096)
			(xy 374.546368 -403.738588) (xy 374.546837 -403.711166) (xy 374.554677 -403.656887) (xy 374.570208 -403.604289)
			(xy 374.59311 -403.554457) (xy 374.622911 -403.508417) (xy 374.658997 -403.467119) (xy 374.700624 -403.431413)
			(xy 374.746935 -403.402036) (xy 374.796976 -403.379592) (xy 374.849714 -403.364544) (xy 374.876822 -403.360382)
			(xy 374.88876 -403.358858) (xy 374.908826 -403.345396) (xy 374.95988 -403.253956) (xy 374.96115 -403.230334)
			(xy 374.956578 -403.219412) (xy 374.941664 -403.183076) (xy 374.920647 -403.107397) (xy 374.910014 -403.029576)
			(xy 374.909334 -402.990304) (xy 374.909334 -402.977604) (xy 374.909588 -402.971508) (xy 374.909588 -402.971254)
			(xy 374.91125 -402.936163) (xy 374.922006 -402.866738) (xy 374.941058 -402.799117) (xy 374.968126 -402.734288)
			(xy 375.002817 -402.673198) (xy 375.044623 -402.616737) (xy 375.092934 -402.565732) (xy 375.147045 -402.520926)
			(xy 375.206165 -402.482974) (xy 375.269431 -402.45243) (xy 375.302526 -402.440648) (xy 375.31802 -402.435314)
			(xy 375.336816 -402.409152) (xy 375.336816 -402.35378) (xy 375.336325 -402.343774) (xy 375.328662 -402.325286)
			(xy 375.314511 -402.311135) (xy 375.296022 -402.303474) (xy 375.286016 -402.30298) (xy 375.131838 -402.30298)
			(xy 375.12166 -402.302561) (xy 375.102849 -402.294783) (xy 375.088448 -402.280398) (xy 375.08065 -402.261595)
			(xy 375.080276 -402.251418) (xy 375.080276 -401.968462) (xy 375.080211 -401.964453) (xy 375.078942 -401.956537)
			(xy 375.077736 -401.952714) (xy 375.073164 -401.939252) (xy 375.070624 -401.934934) (xy 375.054882 -401.906962)
			(xy 375.030091 -401.847757) (xy 375.013321 -401.7858) (xy 375.004863 -401.722174) (xy 375.004865 -401.657988)
			(xy 375.013328 -401.594362) (xy 375.030104 -401.532407) (xy 375.054899 -401.473204) (xy 375.070624 -401.445222)
			(xy 375.073164 -401.440904) (xy 375.077736 -401.427442) (xy 375.0789 -401.423608) (xy 375.080182 -401.415699)
			(xy 375.080276 -401.411694) (xy 375.080276 -400.66849) (xy 375.080205 -400.664482) (xy 375.078925 -400.65657)
			(xy 375.077736 -400.652742) (xy 375.073164 -400.63928) (xy 375.070624 -400.634962) (xy 375.05488 -400.60699)
			(xy 375.030086 -400.547784) (xy 375.013312 -400.485827) (xy 375.00485 -400.422199) (xy 375.00485 -400.358011)
			(xy 375.01331 -400.294383) (xy 375.030082 -400.232425) (xy 375.054876 -400.173219) (xy 375.070624 -400.14525)
			(xy 375.073164 -400.140932) (xy 375.077736 -400.12747) (xy 375.078895 -400.123635) (xy 375.080166 -400.115727)
			(xy 375.080276 -400.111722) (xy 375.080276 -399.828766) (xy 375.080708 -399.818602) (xy 375.088501 -399.799825)
			(xy 375.102886 -399.78546) (xy 375.121673 -399.777694) (xy 375.131838 -399.777204) (xy 375.286016 -399.777204)
			(xy 375.296022 -399.776713) (xy 375.314509 -399.769051) (xy 375.328658 -399.754899) (xy 375.336315 -399.73641)
			(xy 375.336816 -399.726404) (xy 375.336816 -399.671032) (xy 375.31802 -399.64487) (xy 375.302526 -399.639536)
			(xy 375.270186 -399.627967) (xy 375.20825 -399.59827) (xy 375.150252 -399.561471) (xy 375.097001 -399.518085)
			(xy 375.049242 -399.468719) (xy 375.007643 -399.414061) (xy 374.972784 -399.354877) (xy 374.945153 -399.291993)
			(xy 374.925135 -399.226287) (xy 374.913011 -399.158678) (xy 374.90895 -399.090111) (xy 374.913008 -399.021544)
			(xy 374.92513 -398.953934) (xy 374.945145 -398.888228) (xy 374.972774 -398.825342) (xy 375.007631 -398.766157)
			(xy 375.049228 -398.711498) (xy 375.096985 -398.66213) (xy 375.150234 -398.618742) (xy 375.208231 -398.581941)
			(xy 375.270165 -398.552241) (xy 375.302526 -398.540732) (xy 375.31802 -398.535398) (xy 375.336816 -398.509236)
			(xy 375.336816 -398.453864) (xy 375.336322 -398.44386) (xy 375.328657 -398.425378) (xy 375.314506 -398.411232)
			(xy 375.29602 -398.403574) (xy 375.286016 -398.403064) (xy 375.131838 -398.403064) (xy 375.121661 -398.402645)
			(xy 375.102853 -398.394867) (xy 375.088456 -398.38048) (xy 375.080663 -398.361678) (xy 375.080276 -398.351502)
			(xy 375.080276 -398.068546) (xy 375.08021 -398.064537) (xy 375.078938 -398.056622) (xy 375.077736 -398.052798)
			(xy 375.073164 -398.039336) (xy 375.070624 -398.035018) (xy 375.054883 -398.007046) (xy 375.030095 -397.947841)
			(xy 375.013326 -397.885885) (xy 375.00487 -397.82226) (xy 375.004874 -397.758075) (xy 375.013339 -397.69445)
			(xy 375.030116 -397.632497) (xy 375.054913 -397.573295) (xy 375.070624 -397.545306) (xy 375.073164 -397.540988)
			(xy 375.077736 -397.527526) (xy 375.078899 -397.523692) (xy 375.080178 -397.515783) (xy 375.080276 -397.511778)
			(xy 375.080276 -396.768574) (xy 375.080204 -396.764567) (xy 375.078921 -396.756655) (xy 375.077736 -396.752826)
			(xy 375.073164 -396.739364) (xy 375.070624 -396.735046) (xy 375.054881 -396.707074) (xy 375.030089 -396.647869)
			(xy 375.013317 -396.585912) (xy 375.004858 -396.522285) (xy 375.004859 -396.458098) (xy 375.01332 -396.394471)
			(xy 375.030095 -396.332515) (xy 375.054889 -396.27331) (xy 375.070624 -396.245334) (xy 375.073164 -396.241016)
			(xy 375.077736 -396.227554) (xy 375.078893 -396.223719) (xy 375.080162 -396.21581) (xy 375.080276 -396.211806)
			(xy 375.080276 -395.92885) (xy 375.080694 -395.918675) (xy 375.088471 -395.899869) (xy 375.102859 -395.885478)
			(xy 375.121663 -395.877696) (xy 375.131838 -395.877288) (xy 375.297446 -395.877288) (xy 375.306459 -395.876921)
			(xy 375.323364 -395.870661) (xy 375.330466 -395.865096) (xy 375.337578 -395.859) (xy 375.346468 -395.843252)
			(xy 375.347738 -395.833854) (xy 375.355214 -395.787992) (xy 375.377605 -395.697803) (xy 375.392442 -395.653768)
			(xy 375.855992 -394.325602) (xy 375.963942 -394.016484) (xy 375.980066 -393.972) (xy 376.01958 -393.886019)
			(xy 376.067054 -393.804164) (xy 376.122062 -393.727169) (xy 376.184109 -393.655725) (xy 376.25264 -393.590475)
			(xy 376.327038 -393.532002) (xy 376.366532 -393.505944) (xy 382.635252 -389.480044) (xy 382.668486 -389.459213)
			(xy 382.737655 -389.422215) (xy 382.773428 -389.40613) (xy 390.300464 -386.10159) (xy 390.310283 -386.096646)
			(xy 390.324846 -386.080204) (xy 390.331302 -386.059211) (xy 390.330436 -386.04825) (xy 390.32942 -386.041392)
			(xy 390.328658 -386.038344) (xy 390.319633 -386.001926) (xy 390.309949 -385.927523) (xy 390.309354 -385.890008)
			(xy 390.309354 -385.889754) (xy 390.309923 -385.852537) (xy 390.319439 -385.778715) (xy 390.338322 -385.706717)
			(xy 390.366262 -385.637726) (xy 390.38403 -385.60502) (xy 390.384284 -385.604766) (xy 390.387332 -385.599178)
			(xy 390.390634 -385.587494) (xy 390.392895 -385.577682) (xy 390.390377 -385.55772) (xy 390.380379 -385.54026)
			(xy 390.364438 -385.527984) (xy 390.35482 -385.52501) (xy 390.347454 -385.522978) (xy 390.339834 -385.523232)
			(xy 390.327896 -385.523486) (xy 390.300644 -385.523022) (xy 390.246695 -385.515265) (xy 390.194398 -385.499908)
			(xy 390.14482 -385.477265) (xy 390.098969 -385.447797) (xy 390.057779 -385.412103) (xy 390.022088 -385.37091)
			(xy 389.992622 -385.325057) (xy 389.969983 -385.275477) (xy 389.95463 -385.22318) (xy 389.946876 -385.16923)
			(xy 389.946388 -385.141978) (xy 389.946388 -385.141724) (xy 389.947025 -385.109203) (xy 389.958012 -385.045096)
			(xy 389.968232 -385.014216) (xy 389.969502 -385.01066) (xy 389.973058 -384.993134) (xy 389.971026 -384.983482)
			(xy 389.968994 -384.973068) (xy 389.967216 -384.968496) (xy 389.949323 -384.923375) (xy 389.921366 -384.830417)
			(xy 389.902575 -384.735182) (xy 389.893128 -384.638572) (xy 389.89254 -384.590036) (xy 389.89254 -384.20802)
			(xy 389.892993 -384.165513) (xy 389.900257 -384.080809) (xy 389.914716 -383.997032) (xy 389.925052 -383.955798)
			(xy 389.925814 -383.953004) (xy 389.927592 -383.94005) (xy 389.926068 -383.929128) (xy 389.92556 -383.926842)
			(xy 389.924798 -383.924556) (xy 389.922004 -383.913126) (xy 389.90143 -383.888488) (xy 389.900922 -383.88798)
			(xy 389.897366 -383.883662) (xy 389.888476 -383.876804) (xy 389.867902 -383.867406) (xy 389.860164 -383.8643)
			(xy 389.843573 -383.86275) (xy 389.83539 -383.864358) (xy 389.822436 -383.867152) (xy 389.816848 -383.8702)
			(xy 389.782743 -383.8871) (xy 389.712434 -383.916276) (xy 389.64011 -383.94002) (xy 389.603234 -383.949448)
			(xy 389.599678 -383.950464) (xy 389.586724 -383.956814) (xy 389.584692 -383.958338) (xy 389.56107 -383.976372)
			(xy 389.555736 -383.985262) (xy 389.555482 -383.98577) (xy 389.533374 -384.023447) (xy 389.483506 -384.09518)
			(xy 389.427555 -384.162277) (xy 389.365951 -384.224223) (xy 389.299165 -384.280544) (xy 389.227709 -384.330809)
			(xy 389.152131 -384.374632) (xy 389.07301 -384.411677) (xy 388.990953 -384.44166) (xy 388.906587 -384.464352)
			(xy 388.820561 -384.479579) (xy 388.733532 -384.487224) (xy 388.68985 -384.487674) (xy 388.649234 -384.487265)
			(xy 388.568272 -384.480661) (xy 388.488115 -384.467493) (xy 388.409294 -384.447849) (xy 388.332333 -384.421858)
			(xy 388.29488 -384.40614) (xy 388.294626 -384.40614) (xy 388.285166 -384.402556) (xy 388.264952 -384.402372)
			(xy 388.246234 -384.410004) (xy 388.238746 -384.416808) (xy 388.211314 -384.44424) (xy 387.869176 -384.786124)
			(xy 387.836908 -384.817704) (xy 387.767575 -384.875545) (xy 387.693297 -384.926884) (xy 387.614683 -384.971298)
			(xy 387.532376 -385.008426) (xy 387.44705 -385.037962) (xy 387.40334 -385.049268) (xy 387.398952 -385.05046)
			(xy 387.390649 -385.054165) (xy 387.38683 -385.056634) (xy 387.384798 -385.058158) (xy 387.361176 -385.076192)
			(xy 387.355842 -385.085082) (xy 387.355588 -385.08559) (xy 387.33348 -385.123267) (xy 387.283611 -385.194999)
			(xy 387.227659 -385.262094) (xy 387.166055 -385.32404) (xy 387.099269 -385.380361) (xy 387.027813 -385.430625)
			(xy 386.952235 -385.474447) (xy 386.873115 -385.511491) (xy 386.791057 -385.541475) (xy 386.706692 -385.564167)
			(xy 386.620666 -385.579394) (xy 386.533638 -385.587039) (xy 386.489956 -385.587494) (xy 386.489956 -385.58724)
			(xy 386.448841 -385.58682) (xy 386.366889 -385.580049) (xy 386.285774 -385.566547) (xy 386.206047 -385.546408)
			(xy 386.128252 -385.519767) (xy 386.090414 -385.503674) (xy 386.081532 -385.500163) (xy 386.062464 -385.499362)
			(xy 386.05333 -385.50215) (xy 386.023098 -385.512029) (xy 385.960412 -385.522752) (xy 385.928616 -385.523486)
			(xy 385.927854 -385.523486) (xy 385.900606 -385.522997) (xy 385.846664 -385.515235) (xy 385.794376 -385.499875)
			(xy 385.744806 -385.477231) (xy 385.698963 -385.447763) (xy 385.65778 -385.412072) (xy 385.622096 -385.370882)
			(xy 385.592636 -385.325034) (xy 385.570001 -385.27546) (xy 385.554651 -385.223169) (xy 385.546899 -385.169227)
			(xy 385.546346 -385.141978) (xy 385.546346 -385.141216) (xy 385.546996 -385.108758) (xy 385.557974 -385.044777)
			(xy 385.56819 -385.013962) (xy 385.56946 -385.010406) (xy 385.573016 -384.99288) (xy 385.570984 -384.983228)
			(xy 385.568952 -384.972814) (xy 385.567174 -384.968242) (xy 385.549349 -384.923204) (xy 385.521497 -384.830426)
			(xy 385.502768 -384.735386) (xy 385.493337 -384.638978) (xy 385.492752 -384.590544) (xy 385.492752 -384.207258)
			(xy 385.493215 -384.164884) (xy 385.500422 -384.080443) (xy 385.514757 -383.996915) (xy 385.52501 -383.955798)
			(xy 385.525772 -383.953004) (xy 385.52755 -383.94005) (xy 385.526026 -383.929128) (xy 385.525518 -383.926842)
			(xy 385.524756 -383.924556) (xy 385.521962 -383.913126) (xy 385.501388 -383.888742) (xy 385.501388 -383.888234)
			(xy 385.497578 -383.883916) (xy 385.488688 -383.877058) (xy 385.467606 -383.86766) (xy 385.45982 -383.864486)
			(xy 385.443101 -383.862793) (xy 385.43484 -383.864358) (xy 385.420362 -383.867914) (xy 385.415028 -383.870708)
			(xy 385.379976 -383.887726) (xy 385.379214 -383.88798) (xy 385.37134 -383.891536) (xy 385.370832 -383.892044)
			(xy 385.330166 -383.909634) (xy 385.246349 -383.938382) (xy 385.203446 -383.949448) (xy 385.201414 -383.949956)
			(xy 385.197572 -383.951157) (xy 385.190299 -383.954603) (xy 385.186936 -383.956814) (xy 385.184904 -383.958338)
			(xy 385.161282 -383.976372) (xy 385.155948 -383.985262) (xy 385.155694 -383.98577) (xy 385.133685 -384.023258)
			(xy 385.084086 -384.094658) (xy 385.028461 -384.161471) (xy 384.967232 -384.223189) (xy 384.900865 -384.279344)
			(xy 384.829863 -384.329511) (xy 384.754764 -384.373309) (xy 384.676138 -384.410404) (xy 384.594583 -384.440517)
			(xy 384.510716 -384.463418) (xy 384.425175 -384.478933) (xy 384.338607 -384.486945) (xy 384.295142 -384.487674)
			(xy 384.276092 -384.48742) (xy 384.227044 -384.486146) (xy 384.129541 -384.475146) (xy 384.033588 -384.45463)
			(xy 383.940112 -384.424795) (xy 383.894838 -384.405886) (xy 383.880614 -384.39979) (xy 383.84988 -384.405632)
			(xy 383.811272 -384.44424) (xy 383.469134 -384.786124) (xy 383.436866 -384.817702) (xy 383.367531 -384.875541)
			(xy 383.293252 -384.926877) (xy 383.214637 -384.971288) (xy 383.13233 -385.008412) (xy 383.047004 -385.037945)
			(xy 383.003298 -385.049268) (xy 382.998908 -385.050456) (xy 382.990599 -385.054153) (xy 382.986788 -385.056634)
			(xy 382.984756 -385.058158) (xy 382.961134 -385.076192) (xy 382.9558 -385.085082) (xy 382.955546 -385.08559)
			(xy 382.933437 -385.123266) (xy 382.883567 -385.194995) (xy 382.827615 -385.262089) (xy 382.76601 -385.324031)
			(xy 382.699224 -385.380349) (xy 382.627768 -385.43061) (xy 382.55219 -385.474429) (xy 382.473069 -385.511471)
			(xy 382.391012 -385.541451) (xy 382.306648 -385.564139) (xy 382.220622 -385.579363) (xy 382.133595 -385.587004)
			(xy 382.089914 -385.587494) (xy 382.082294 -385.587494) (xy 382.063244 -385.586986) (xy 382.013455 -385.585053)
			(xy 381.914607 -385.572469) (xy 381.817509 -385.55008) (xy 381.770128 -385.534662) (xy 381.749842 -385.527668)
			(xy 381.709823 -385.512168) (xy 381.690118 -385.503674) (xy 381.681236 -385.500181) (xy 381.66218 -385.499415)
			(xy 381.653034 -385.50215) (xy 381.622679 -385.512061) (xy 381.559736 -385.522786) (xy 381.527812 -385.523486)
			(xy 381.500559 -385.523023) (xy 381.446608 -385.515268) (xy 381.39431 -385.499913) (xy 381.34473 -385.47727)
			(xy 381.298877 -385.447802) (xy 381.257684 -385.412108) (xy 381.221992 -385.370915) (xy 381.192525 -385.325061)
			(xy 381.169884 -385.275481) (xy 381.15453 -385.223182) (xy 381.146776 -385.169231) (xy 381.146304 -385.141978)
			(xy 381.146304 -385.141724) (xy 381.146941 -385.109203) (xy 381.157926 -385.045095) (xy 381.168148 -385.014216)
			(xy 381.169418 -385.01066) (xy 381.172974 -384.993134) (xy 381.170942 -384.983482) (xy 381.16891 -384.973068)
			(xy 381.167132 -384.968496) (xy 381.14924 -384.923375) (xy 381.121285 -384.830417) (xy 381.102495 -384.735182)
			(xy 381.093049 -384.638571) (xy 381.092456 -384.590036) (xy 381.092456 -384.20802) (xy 381.092909 -384.165513)
			(xy 381.100173 -384.080809) (xy 381.114633 -383.997032) (xy 381.124968 -383.955798) (xy 381.12573 -383.953004)
			(xy 381.127508 -383.94005) (xy 381.125984 -383.929128) (xy 381.125476 -383.926842) (xy 381.124714 -383.924556)
			(xy 381.12192 -383.913126) (xy 381.101346 -383.888742) (xy 381.101346 -383.888234) (xy 381.097536 -383.883916)
			(xy 381.088646 -383.877058) (xy 381.067564 -383.86766) (xy 381.059777 -383.864493) (xy 381.043062 -383.862813)
			(xy 381.034798 -383.864358) (xy 381.02032 -383.867914) (xy 381.014986 -383.870708) (xy 380.979934 -383.887726)
			(xy 380.979172 -383.88798) (xy 380.971298 -383.891536) (xy 380.97079 -383.892044) (xy 380.930123 -383.909633)
			(xy 380.846306 -383.938377) (xy 380.803404 -383.949448) (xy 380.801372 -383.949956) (xy 380.797528 -383.951153)
			(xy 380.790251 -383.954592) (xy 380.786894 -383.956814) (xy 380.784862 -383.958338) (xy 380.76124 -383.976372)
			(xy 380.755906 -383.985262) (xy 380.755652 -383.98577) (xy 380.733644 -384.02326) (xy 380.684046 -384.094663)
			(xy 380.628422 -384.161479) (xy 380.567194 -384.2232) (xy 380.500827 -384.27936) (xy 380.429825 -384.329531)
			(xy 380.354727 -384.373332) (xy 380.276101 -384.410433) (xy 380.194545 -384.44055) (xy 380.110678 -384.463455)
			(xy 380.025135 -384.478975) (xy 379.938567 -384.486993) (xy 379.8951 -384.487674) (xy 379.87605 -384.48742)
			(xy 379.827003 -384.486144) (xy 379.729501 -384.47514) (xy 379.633549 -384.45462) (xy 379.540075 -384.424782)
			(xy 379.494796 -384.405886) (xy 379.480572 -384.39979) (xy 379.449838 -384.405632) (xy 379.41123 -384.44424)
			(xy 379.069092 -384.786124) (xy 379.036823 -384.817701) (xy 378.967487 -384.875537) (xy 378.893207 -384.92687)
			(xy 378.814591 -384.971278) (xy 378.732283 -385.008399) (xy 378.646957 -385.037928) (xy 378.603256 -385.049268)
			(xy 378.598867 -385.050459) (xy 378.590563 -385.054162) (xy 378.586746 -385.056634) (xy 378.584714 -385.058158)
			(xy 378.561092 -385.076192) (xy 378.555758 -385.085082) (xy 378.555504 -385.08559) (xy 378.533396 -385.123267)
			(xy 378.483527 -385.195) (xy 378.427576 -385.262097) (xy 378.365972 -385.324043) (xy 378.299186 -385.380365)
			(xy 378.22773 -385.43063) (xy 378.152153 -385.474453) (xy 378.073032 -385.511499) (xy 377.990975 -385.541484)
			(xy 377.906609 -385.564177) (xy 377.820583 -385.579406) (xy 377.733554 -385.587052) (xy 377.689872 -385.587494)
			(xy 377.689872 -385.58724) (xy 377.648756 -385.586821) (xy 377.566804 -385.580051) (xy 377.485689 -385.56655)
			(xy 377.405962 -385.546412) (xy 377.328165 -385.519772) (xy 377.29033 -385.503674) (xy 377.281448 -385.500179)
			(xy 377.26239 -385.499408) (xy 377.253246 -385.50215) (xy 377.223015 -385.51203) (xy 377.160328 -385.522756)
			(xy 377.128532 -385.523486) (xy 377.12777 -385.523486) (xy 377.100521 -385.522998) (xy 377.046578 -385.515238)
			(xy 376.994288 -385.49988) (xy 376.944716 -385.477237) (xy 376.898871 -385.447769) (xy 376.857686 -385.412077)
			(xy 376.822 -385.370888) (xy 376.792539 -385.325039) (xy 376.769902 -385.275464) (xy 376.754551 -385.223172)
			(xy 376.746799 -385.169227) (xy 376.746262 -385.141978) (xy 376.746262 -385.141216) (xy 376.746912 -385.108758)
			(xy 376.75789 -385.044777) (xy 376.768106 -385.013962) (xy 376.769376 -385.010406) (xy 376.772932 -384.99288)
			(xy 376.7709 -384.983228) (xy 376.768868 -384.972814) (xy 376.76709 -384.968242) (xy 376.749265 -384.923204)
			(xy 376.721412 -384.830426) (xy 376.702683 -384.735386) (xy 376.693252 -384.638978) (xy 376.692668 -384.590544)
			(xy 376.692668 -384.207258) (xy 376.693131 -384.164884) (xy 376.700338 -384.080443) (xy 376.714673 -383.996915)
			(xy 376.724926 -383.955798) (xy 376.725688 -383.953004) (xy 376.727466 -383.94005) (xy 376.725942 -383.929128)
			(xy 376.725434 -383.926842) (xy 376.724672 -383.924556) (xy 376.721878 -383.913126) (xy 376.701304 -383.888742)
			(xy 376.701304 -383.888234) (xy 376.697494 -383.883916) (xy 376.688604 -383.877058) (xy 376.667522 -383.86766)
			(xy 376.659736 -383.864484) (xy 376.643016 -383.862786) (xy 376.634756 -383.864358) (xy 376.620278 -383.867914)
			(xy 376.614944 -383.870708) (xy 376.579892 -383.887726) (xy 376.57913 -383.88798) (xy 376.571256 -383.891536)
			(xy 376.570748 -383.892044) (xy 376.530082 -383.909635) (xy 376.446266 -383.938384) (xy 376.403362 -383.949448)
			(xy 376.40133 -383.949956) (xy 376.397488 -383.951156) (xy 376.390213 -383.9546) (xy 376.386852 -383.956814)
			(xy 376.38482 -383.958338) (xy 376.361198 -383.976372) (xy 376.355864 -383.985262) (xy 376.35561 -383.98577)
			(xy 376.333502 -384.023448) (xy 376.283635 -384.095182) (xy 376.227684 -384.162281) (xy 376.16608 -384.224229)
			(xy 376.099295 -384.280552) (xy 376.027839 -384.330819) (xy 375.952262 -384.374643) (xy 375.873141 -384.411691)
			(xy 375.791083 -384.441676) (xy 375.706717 -384.464371) (xy 375.62069 -384.4796) (xy 375.53366 -384.487247)
			(xy 375.489978 -384.487674) (xy 375.489724 -384.487674) (xy 375.476008 -384.48742) (xy 375.428402 -384.486224)
			(xy 375.333733 -384.475862) (xy 375.240484 -384.456513) (xy 375.19483 -384.44297) (xy 375.169263 -384.434883)
			(xy 375.118945 -384.416328) (xy 375.094246 -384.405886) (xy 375.084848 -384.402838) (xy 375.079006 -384.401568)
			(xy 375.074299 -384.400638) (xy 375.064707 -384.400387) (xy 375.059956 -384.40106) (xy 375.054114 -384.402076)
			(xy 375.05005 -384.403346) (xy 375.028128 -384.410405) (xy 374.983048 -384.419829) (xy 374.960134 -384.422142)
			(xy 374.93067 -384.423412) (xy 374.925844 -384.423412) (xy 374.898689 -384.422787) (xy 374.844963 -384.414793)
			(xy 374.792914 -384.399261) (xy 374.743595 -384.376503) (xy 374.698002 -384.346981) (xy 374.657056 -384.311291)
			(xy 374.621587 -384.270154) (xy 374.59231 -384.224403) (xy 374.569818 -384.174962) (xy 374.554566 -384.12283)
			(xy 374.546862 -384.069062) (xy 374.546368 -384.041904) (xy 374.546368 -384.04165) (xy 374.547074 -384.009259)
			(xy 374.558053 -383.945414) (xy 374.568212 -383.91465) (xy 374.571006 -383.906522) (xy 374.571006 -383.883154)
			(xy 374.568974 -383.873502) (xy 374.567196 -383.86893) (xy 374.566942 -383.868422) (xy 374.549115 -383.823351)
			(xy 374.521263 -383.730509) (xy 374.50254 -383.635405) (xy 374.493121 -383.538935) (xy 374.49252 -383.49047)
			(xy 374.49252 -383.1082) (xy 374.49297 -383.065692) (xy 374.500227 -382.980987) (xy 374.514679 -382.897208)
			(xy 374.525032 -382.855978) (xy 374.525794 -382.853184) (xy 374.527572 -382.84023) (xy 374.525794 -382.827276)
			(xy 374.525032 -382.824482) (xy 374.514705 -382.783246) (xy 374.500263 -382.699469) (xy 374.492993 -382.614766)
			(xy 374.49252 -382.57226) (xy 374.49252 -382.18999) (xy 374.493106 -382.141353) (xy 374.502581 -382.044542)
			(xy 374.521439 -381.949114) (xy 374.549502 -381.855976) (xy 374.56745 -381.810768) (xy 374.569482 -381.806196)
			(xy 374.571006 -381.797306) (xy 374.571816 -381.79271) (xy 374.571952 -381.783379) (xy 374.57126 -381.778764)
			(xy 374.569736 -381.770128) (xy 374.568212 -381.766064) (xy 374.558049 -381.7353) (xy 374.547059 -381.671455)
			(xy 374.546368 -381.639064) (xy 374.546368 -381.638556) (xy 374.546839 -381.611136) (xy 374.554682 -381.55686)
			(xy 374.570216 -381.504265) (xy 374.59312 -381.454437) (xy 374.622923 -381.408402) (xy 374.659009 -381.367107)
			(xy 374.700636 -381.331405) (xy 374.746945 -381.30203) (xy 374.796983 -381.279589) (xy 374.849719 -381.264542)
			(xy 374.876822 -381.26035) (xy 374.88876 -381.258826) (xy 374.908826 -381.245364) (xy 374.95988 -381.153924)
			(xy 374.96115 -381.130302) (xy 374.956578 -381.11938) (xy 374.941666 -381.083044) (xy 374.920653 -381.007364)
			(xy 374.910024 -380.929543) (xy 374.909334 -380.890272) (xy 374.909334 -380.877572) (xy 374.909588 -380.871476)
			(xy 374.909588 -380.871222) (xy 374.911252 -380.836132) (xy 374.922011 -380.76671) (xy 374.941065 -380.699092)
			(xy 374.968136 -380.634266) (xy 375.002828 -380.573178) (xy 375.044635 -380.516721) (xy 375.092947 -380.465719)
			(xy 375.147057 -380.420916) (xy 375.206176 -380.382967) (xy 375.269441 -380.352425) (xy 375.302526 -380.340616)
			(xy 375.31802 -380.335282) (xy 375.336816 -380.30912) (xy 375.336816 -380.253748) (xy 375.336405 -380.243719)
			(xy 375.328744 -380.225183) (xy 375.314571 -380.210992) (xy 375.296044 -380.203308) (xy 375.286016 -380.202948)
			(xy 375.131838 -380.202948) (xy 375.121662 -380.202529) (xy 375.102857 -380.19475) (xy 375.088464 -380.180363)
			(xy 375.080676 -380.161561) (xy 375.080276 -380.151386) (xy 375.080276 -379.86843) (xy 375.080208 -379.864422)
			(xy 375.078934 -379.856507) (xy 375.077736 -379.852682) (xy 375.073164 -379.83922) (xy 375.070624 -379.834902)
			(xy 375.054878 -379.80693) (xy 375.030078 -379.747724) (xy 375.013299 -379.685765) (xy 375.004833 -379.622135)
			(xy 375.004827 -379.557944) (xy 375.013283 -379.494313) (xy 375.030052 -379.432352) (xy 375.054842 -379.373141)
			(xy 375.070624 -379.34519) (xy 375.073164 -379.340872) (xy 375.077736 -379.32741) (xy 375.078898 -379.323576)
			(xy 375.080175 -379.315667) (xy 375.080276 -379.311662) (xy 375.080276 -378.568458) (xy 375.080211 -378.564449)
			(xy 375.078941 -378.556534) (xy 375.077736 -378.55271) (xy 375.073164 -378.539248) (xy 375.070624 -378.53493)
			(xy 375.054882 -378.506958) (xy 375.030092 -378.447753) (xy 375.013322 -378.385797) (xy 375.004865 -378.32217)
			(xy 375.004868 -378.257985) (xy 375.013331 -378.194359) (xy 375.030107 -378.132405) (xy 375.054902 -378.073202)
			(xy 375.070624 -378.045218) (xy 375.073164 -378.0409) (xy 375.077736 -378.027438) (xy 375.0789 -378.023604)
			(xy 375.080181 -378.015695) (xy 375.080276 -378.01169) (xy 375.080276 -377.728734) (xy 375.080697 -377.718561)
			(xy 375.088477 -377.699761) (xy 375.102864 -377.685375) (xy 375.121665 -377.677596) (xy 375.131838 -377.677172)
			(xy 375.286016 -377.677172) (xy 375.296033 -377.676749) (xy 375.31454 -377.669075) (xy 375.3287 -377.654903)
			(xy 375.336358 -377.636389) (xy 375.336816 -377.626372) (xy 375.336816 -377.571) (xy 375.31802 -377.544838)
			(xy 375.302526 -377.539504) (xy 375.270187 -377.527935) (xy 375.208256 -377.498238) (xy 375.150261 -377.46144)
			(xy 375.097014 -377.418056) (xy 375.049259 -377.368691) (xy 375.007662 -377.314036) (xy 374.972806 -377.254854)
			(xy 374.945177 -377.191972) (xy 374.925162 -377.12627) (xy 374.91304 -377.058664) (xy 374.90898 -376.990101)
			(xy 374.91304 -376.921537) (xy 374.925162 -376.853931) (xy 374.945177 -376.788229) (xy 374.972806 -376.725347)
			(xy 375.007662 -376.666165) (xy 375.049258 -376.61151) (xy 375.097013 -376.562145) (xy 375.15026 -376.51876)
			(xy 375.208255 -376.481962) (xy 375.270186 -376.452265) (xy 375.302526 -376.4407) (xy 375.31802 -376.435366)
			(xy 375.336816 -376.409204) (xy 375.336816 -376.353832) (xy 375.336402 -376.343805) (xy 375.328738 -376.325275)
			(xy 375.314566 -376.311089) (xy 375.296042 -376.303407) (xy 375.286016 -376.303032) (xy 375.131838 -376.303032)
			(xy 375.121664 -376.302612) (xy 375.102861 -376.294833) (xy 375.088472 -376.280446) (xy 375.080689 -376.261644)
			(xy 375.080276 -376.25147) (xy 375.080276 -375.968514) (xy 375.080207 -375.964506) (xy 375.078931 -375.956593)
			(xy 375.077736 -375.952766) (xy 375.073164 -375.939304) (xy 375.070624 -375.934986) (xy 375.054879 -375.907014)
			(xy 375.030081 -375.847808) (xy 375.013304 -375.78585) (xy 375.00484 -375.722221) (xy 375.004836 -375.658031)
			(xy 375.013294 -375.594401) (xy 375.030064 -375.532441) (xy 375.054856 -375.473232) (xy 375.070624 -375.445274)
			(xy 375.073164 -375.440956) (xy 375.077736 -375.427494) (xy 375.078896 -375.42366) (xy 375.080171 -375.415751)
			(xy 375.080276 -375.411746) (xy 375.080276 -374.668542) (xy 375.080209 -374.664534) (xy 375.078937 -374.656619)
			(xy 375.077736 -374.652794) (xy 375.073164 -374.639332) (xy 375.070624 -374.635014) (xy 375.054883 -374.607042)
			(xy 375.030095 -374.547837) (xy 375.013327 -374.485881) (xy 375.004872 -374.422256) (xy 375.004877 -374.358071)
			(xy 375.013342 -374.294447) (xy 375.030119 -374.232494) (xy 375.054916 -374.173293) (xy 375.070624 -374.145302)
			(xy 375.073164 -374.140984) (xy 375.077736 -374.127522) (xy 375.078898 -374.123688) (xy 375.080177 -374.115779)
			(xy 375.080276 -374.111774) (xy 375.080276 -373.828818) (xy 375.080699 -373.818647) (xy 375.088483 -373.799853)
			(xy 375.102869 -373.785471) (xy 375.121667 -373.777695) (xy 375.131838 -373.777256) (xy 375.286016 -373.777256)
			(xy 375.296032 -373.776833) (xy 375.314536 -373.769159) (xy 375.328692 -373.754985) (xy 375.336345 -373.736472)
			(xy 375.336816 -373.726456) (xy 375.336816 -373.671084) (xy 375.31802 -373.644922) (xy 375.302526 -373.639588)
			(xy 375.270188 -373.628019) (xy 375.208259 -373.598322) (xy 375.150266 -373.561525) (xy 375.097021 -373.518141)
			(xy 375.049267 -373.468777) (xy 375.007672 -373.414123) (xy 374.972817 -373.354943) (xy 374.94519 -373.292062)
			(xy 374.925175 -373.226361) (xy 374.913054 -373.158757) (xy 374.908995 -373.090195) (xy 374.913055 -373.021634)
			(xy 374.925178 -372.95403) (xy 374.945193 -372.888329) (xy 374.972821 -372.825449) (xy 375.007677 -372.766269)
			(xy 375.049273 -372.711616) (xy 375.097027 -372.662253) (xy 375.150273 -372.61887) (xy 375.208266 -372.582073)
			(xy 375.270197 -372.552377) (xy 375.302526 -372.540784) (xy 375.31802 -372.53545) (xy 375.336816 -372.509288)
			(xy 375.336816 -372.453916) (xy 375.336331 -372.443905) (xy 375.328675 -372.425405) (xy 375.314522 -372.411243)
			(xy 375.296027 -372.403575) (xy 375.286016 -372.403116) (xy 375.131838 -372.403116) (xy 375.121665 -372.402696)
			(xy 375.102865 -372.394916) (xy 375.088479 -372.380528) (xy 375.080702 -372.361727) (xy 375.080276 -372.351554)
			(xy 375.080276 -372.068598) (xy 375.080206 -372.06459) (xy 375.078927 -372.056678) (xy 375.077736 -372.05285)
			(xy 375.073164 -372.039388) (xy 375.070624 -372.03507) (xy 375.05488 -372.007098) (xy 375.030084 -371.947892)
			(xy 375.013309 -371.885935) (xy 375.004847 -371.822306) (xy 375.004845 -371.758118) (xy 375.013304 -371.694489)
			(xy 375.030076 -371.632531) (xy 375.054869 -371.573324) (xy 375.070624 -371.545358) (xy 375.073164 -371.54104)
			(xy 375.077736 -371.527578) (xy 375.078895 -371.523743) (xy 375.080167 -371.515835) (xy 375.080276 -371.51183)
			(xy 375.080276 -370.768372) (xy 375.080204 -370.764365) (xy 375.078921 -370.756453) (xy 375.077736 -370.752624)
			(xy 375.073164 -370.739162) (xy 375.070624 -370.734844) (xy 375.054881 -370.706872) (xy 375.030089 -370.647667)
			(xy 375.013317 -370.58571) (xy 375.004858 -370.522083) (xy 375.00486 -370.457896) (xy 375.013322 -370.39427)
			(xy 375.030096 -370.332314) (xy 375.054891 -370.273109) (xy 375.070624 -370.245132) (xy 375.073164 -370.240814)
			(xy 375.077736 -370.227352) (xy 375.078893 -370.223517) (xy 375.080162 -370.215608) (xy 375.080276 -370.211604)
			(xy 375.080276 -369.928902) (xy 375.080702 -369.918733) (xy 375.088488 -369.899944) (xy 375.102874 -369.885568)
			(xy 375.121669 -369.877795) (xy 375.131838 -369.87734) (xy 375.286016 -369.87734) (xy 375.296024 -369.87685)
			(xy 375.314518 -369.869189) (xy 375.328675 -369.855038) (xy 375.336345 -369.836548) (xy 375.336816 -369.82654)
			(xy 375.336816 -369.770914) (xy 375.31802 -369.744752) (xy 375.302526 -369.739418) (xy 375.271638 -369.728416)
			(xy 375.21235 -369.700405) (xy 375.156597 -369.665891) (xy 375.105089 -369.625312) (xy 375.058484 -369.579186)
			(xy 375.017375 -369.5281) (xy 374.982287 -369.472706) (xy 374.953665 -369.413711) (xy 374.931877 -369.351865)
			(xy 374.917198 -369.287957) (xy 374.909816 -369.222802) (xy 374.909334 -369.190016) (xy 374.909814 -369.156405)
			(xy 374.917573 -369.089632) (xy 374.93299 -369.024201) (xy 374.955858 -368.960988) (xy 374.985872 -368.900837)
			(xy 375.02263 -368.844555) (xy 375.06564 -368.792892) (xy 375.089674 -368.769392) (xy 375.09704 -368.76228)
			(xy 375.106438 -368.740944) (xy 375.110361 -368.730817) (xy 375.110219 -368.709118) (xy 375.106184 -368.699034)
			(xy 374.243346 -366.845342) (xy 374.133364 -366.609376) (xy 374.128949 -366.600786) (xy 374.114961 -366.587492)
			(xy 374.097039 -366.580336) (xy 374.08739 -366.579912) (xy 355.621082 -366.579912) (xy 355.611014 -366.580339)
			(xy 355.592415 -366.588059) (xy 355.585014 -366.594898) (xy 353.989386 -368.190526) (xy 353.982534 -368.197922)
			(xy 353.974796 -368.216521) (xy 353.9744 -368.226594) (xy 353.9744 -379.088396) (xy 362.932978 -379.088396)
			(xy 362.937049 -379.032774) (xy 362.949175 -378.978337) (xy 362.969098 -378.926246) (xy 362.996394 -378.877611)
			(xy 363.03048 -378.833468) (xy 363.070629 -378.794759) (xy 363.115987 -378.762308) (xy 363.165587 -378.736807)
			(xy 363.218371 -378.7188) (xy 363.273214 -378.70867) (xy 363.328948 -378.706633) (xy 363.384385 -378.712733)
			(xy 363.438342 -378.726839) (xy 363.489671 -378.748651) (xy 363.537277 -378.777705) (xy 363.580145 -378.81338)
			(xy 363.617362 -378.854917) (xy 363.648135 -378.90143) (xy 363.671807 -378.951927) (xy 363.687875 -379.005334)
			(xy 363.695995 -379.06051) (xy 363.696504 -379.088396) (xy 363.695995 -379.116282) (xy 363.687875 -379.171458)
			(xy 363.671807 -379.224865) (xy 363.648135 -379.275362) (xy 363.617362 -379.321875) (xy 363.580145 -379.363412)
			(xy 363.537277 -379.399087) (xy 363.489671 -379.428141) (xy 363.438342 -379.449953) (xy 363.384385 -379.464059)
			(xy 363.328948 -379.470159) (xy 363.273214 -379.468122) (xy 363.218371 -379.457992) (xy 363.165587 -379.439985)
			(xy 363.115987 -379.414484) (xy 363.070629 -379.382033) (xy 363.03048 -379.343324) (xy 362.996394 -379.299181)
			(xy 362.969098 -379.250546) (xy 362.949175 -379.198455) (xy 362.937049 -379.144018) (xy 362.932978 -379.088396)
			(xy 353.9744 -379.088396) (xy 353.9744 -379.655324) (xy 360.52074 -379.655324) (xy 360.524811 -379.599702)
			(xy 360.536937 -379.545265) (xy 360.55686 -379.493174) (xy 360.584156 -379.444539) (xy 360.618242 -379.400396)
			(xy 360.658391 -379.361687) (xy 360.703749 -379.329236) (xy 360.753349 -379.303735) (xy 360.806133 -379.285728)
			(xy 360.860976 -379.275598) (xy 360.91671 -379.273561) (xy 360.972147 -379.279661) (xy 361.026104 -379.293767)
			(xy 361.077433 -379.315579) (xy 361.125039 -379.344633) (xy 361.167907 -379.380308) (xy 361.205124 -379.421845)
			(xy 361.235897 -379.468358) (xy 361.259569 -379.518855) (xy 361.275637 -379.572262) (xy 361.283757 -379.627438)
			(xy 361.284266 -379.655324) (xy 361.283757 -379.68321) (xy 361.275637 -379.738386) (xy 361.259569 -379.791793)
			(xy 361.235897 -379.84229) (xy 361.205124 -379.888803) (xy 361.167907 -379.93034) (xy 361.125039 -379.966015)
			(xy 361.077433 -379.995069) (xy 361.026104 -380.016881) (xy 360.972147 -380.030987) (xy 360.91671 -380.037087)
			(xy 360.860976 -380.03505) (xy 360.806133 -380.02492) (xy 360.753349 -380.006913) (xy 360.703749 -379.981412)
			(xy 360.658391 -379.948961) (xy 360.618242 -379.910252) (xy 360.584156 -379.866109) (xy 360.55686 -379.817474)
			(xy 360.536937 -379.765383) (xy 360.524811 -379.710946) (xy 360.52074 -379.655324) (xy 353.9744 -379.655324)
			(xy 353.9744 -381.714502) (xy 360.796838 -381.714502) (xy 360.800909 -381.65888) (xy 360.813035 -381.604443)
			(xy 360.832958 -381.552352) (xy 360.860254 -381.503717) (xy 360.89434 -381.459574) (xy 360.934489 -381.420865)
			(xy 360.979847 -381.388414) (xy 361.029447 -381.362913) (xy 361.082231 -381.344906) (xy 361.137074 -381.334776)
			(xy 361.192808 -381.332739) (xy 361.248245 -381.338839) (xy 361.302202 -381.352945) (xy 361.353531 -381.374757)
			(xy 361.401137 -381.403811) (xy 361.444005 -381.439486) (xy 361.481222 -381.481023) (xy 361.511995 -381.527536)
			(xy 361.535667 -381.578033) (xy 361.551735 -381.63144) (xy 361.559855 -381.686616) (xy 361.560364 -381.714502)
			(xy 361.559855 -381.742388) (xy 361.551735 -381.797564) (xy 361.535667 -381.850971) (xy 361.511995 -381.901468)
			(xy 361.481222 -381.947981) (xy 361.444005 -381.989518) (xy 361.401137 -382.025193) (xy 361.353531 -382.054247)
			(xy 361.302202 -382.076059) (xy 361.248245 -382.090165) (xy 361.192808 -382.096265) (xy 361.137074 -382.094228)
			(xy 361.082231 -382.084098) (xy 361.029447 -382.066091) (xy 360.979847 -382.04059) (xy 360.934489 -382.008139)
			(xy 360.89434 -381.96943) (xy 360.860254 -381.925287) (xy 360.832958 -381.876652) (xy 360.813035 -381.824561)
			(xy 360.800909 -381.770124) (xy 360.796838 -381.714502) (xy 353.9744 -381.714502) (xy 353.9744 -386.172456)
			(xy 361.296202 -386.172456) (xy 361.300273 -386.116834) (xy 361.312399 -386.062397) (xy 361.332322 -386.010306)
			(xy 361.359618 -385.961671) (xy 361.393704 -385.917528) (xy 361.433853 -385.878819) (xy 361.479211 -385.846368)
			(xy 361.528811 -385.820867) (xy 361.581595 -385.80286) (xy 361.636438 -385.79273) (xy 361.692172 -385.790693)
			(xy 361.747609 -385.796793) (xy 361.801566 -385.810899) (xy 361.852895 -385.832711) (xy 361.900501 -385.861765)
			(xy 361.943369 -385.89744) (xy 361.980586 -385.938977) (xy 362.011359 -385.98549) (xy 362.035031 -386.035987)
			(xy 362.051099 -386.089394) (xy 362.059219 -386.14457) (xy 362.059728 -386.172456) (xy 362.059219 -386.200342)
			(xy 362.051099 -386.255518) (xy 362.035031 -386.308925) (xy 362.011359 -386.359422) (xy 361.980586 -386.405935)
			(xy 361.943369 -386.447472) (xy 361.900501 -386.483147) (xy 361.852895 -386.512201) (xy 361.801566 -386.534013)
			(xy 361.747609 -386.548119) (xy 361.692172 -386.554219) (xy 361.636438 -386.552182) (xy 361.581595 -386.542052)
			(xy 361.528811 -386.524045) (xy 361.479211 -386.498544) (xy 361.433853 -386.466093) (xy 361.393704 -386.427384)
			(xy 361.359618 -386.383241) (xy 361.332322 -386.334606) (xy 361.312399 -386.282515) (xy 361.300273 -386.228078)
			(xy 361.296202 -386.172456) (xy 353.9744 -386.172456) (xy 353.9744 -387.9723) (xy 362.73308 -387.9723)
			(xy 362.737151 -387.916678) (xy 362.749277 -387.862241) (xy 362.7692 -387.81015) (xy 362.796496 -387.761515)
			(xy 362.830582 -387.717372) (xy 362.870731 -387.678663) (xy 362.916089 -387.646212) (xy 362.965689 -387.620711)
			(xy 363.018473 -387.602704) (xy 363.073316 -387.592574) (xy 363.12905 -387.590537) (xy 363.184487 -387.596637)
			(xy 363.238444 -387.610743) (xy 363.289773 -387.632555) (xy 363.337379 -387.661609) (xy 363.380247 -387.697284)
			(xy 363.417464 -387.738821) (xy 363.448237 -387.785334) (xy 363.471909 -387.835831) (xy 363.487977 -387.889238)
			(xy 363.490893 -387.909054) (xy 366.166144 -387.909054) (xy 366.170215 -387.853432) (xy 366.182341 -387.798995)
			(xy 366.202264 -387.746904) (xy 366.22956 -387.698269) (xy 366.263646 -387.654126) (xy 366.303795 -387.615417)
			(xy 366.349153 -387.582966) (xy 366.398753 -387.557465) (xy 366.451537 -387.539458) (xy 366.50638 -387.529328)
			(xy 366.562114 -387.527291) (xy 366.617551 -387.533391) (xy 366.671508 -387.547497) (xy 366.722837 -387.569309)
			(xy 366.770443 -387.598363) (xy 366.813311 -387.634038) (xy 366.850528 -387.675575) (xy 366.881301 -387.722088)
			(xy 366.904973 -387.772585) (xy 366.921041 -387.825992) (xy 366.929161 -387.881168) (xy 366.92967 -387.909054)
			(xy 366.929161 -387.93694) (xy 366.921041 -387.992116) (xy 366.904973 -388.045523) (xy 366.881301 -388.09602)
			(xy 366.850528 -388.142533) (xy 366.813311 -388.18407) (xy 366.770443 -388.219745) (xy 366.722837 -388.248799)
			(xy 366.671508 -388.270611) (xy 366.617551 -388.284717) (xy 366.562114 -388.290817) (xy 366.50638 -388.28878)
			(xy 366.451537 -388.27865) (xy 366.398753 -388.260643) (xy 366.349153 -388.235142) (xy 366.303795 -388.202691)
			(xy 366.263646 -388.163982) (xy 366.22956 -388.119839) (xy 366.202264 -388.071204) (xy 366.182341 -388.019113)
			(xy 366.170215 -387.964676) (xy 366.166144 -387.909054) (xy 363.490893 -387.909054) (xy 363.496097 -387.944414)
			(xy 363.496606 -387.9723) (xy 363.496097 -388.000186) (xy 363.487977 -388.055362) (xy 363.471909 -388.108769)
			(xy 363.448237 -388.159266) (xy 363.417464 -388.205779) (xy 363.380247 -388.247316) (xy 363.337379 -388.282991)
			(xy 363.289773 -388.312045) (xy 363.238444 -388.333857) (xy 363.184487 -388.347963) (xy 363.12905 -388.354063)
			(xy 363.073316 -388.352026) (xy 363.018473 -388.341896) (xy 362.965689 -388.323889) (xy 362.916089 -388.298388)
			(xy 362.870731 -388.265937) (xy 362.830582 -388.227228) (xy 362.796496 -388.183085) (xy 362.7692 -388.13445)
			(xy 362.749277 -388.082359) (xy 362.737151 -388.027922) (xy 362.73308 -387.9723) (xy 353.9744 -387.9723)
			(xy 353.9744 -388.842504) (xy 366.936272 -388.842504) (xy 366.940343 -388.786882) (xy 366.952469 -388.732445)
			(xy 366.972392 -388.680354) (xy 366.999688 -388.631719) (xy 367.033774 -388.587576) (xy 367.073923 -388.548867)
			(xy 367.119281 -388.516416) (xy 367.168881 -388.490915) (xy 367.221665 -388.472908) (xy 367.276508 -388.462778)
			(xy 367.332242 -388.460741) (xy 367.387679 -388.466841) (xy 367.441636 -388.480947) (xy 367.492965 -388.502759)
			(xy 367.540571 -388.531813) (xy 367.583439 -388.567488) (xy 367.620656 -388.609025) (xy 367.651429 -388.655538)
			(xy 367.675101 -388.706035) (xy 367.691169 -388.759442) (xy 367.699289 -388.814618) (xy 367.699798 -388.842504)
			(xy 367.699289 -388.87039) (xy 367.691169 -388.925566) (xy 367.675101 -388.978973) (xy 367.651429 -389.02947)
			(xy 367.620656 -389.075983) (xy 367.583439 -389.11752) (xy 367.540571 -389.153195) (xy 367.492965 -389.182249)
			(xy 367.441636 -389.204061) (xy 367.387679 -389.218167) (xy 367.332242 -389.224267) (xy 367.276508 -389.22223)
			(xy 367.221665 -389.2121) (xy 367.168881 -389.194093) (xy 367.119281 -389.168592) (xy 367.073923 -389.136141)
			(xy 367.033774 -389.097432) (xy 366.999688 -389.053289) (xy 366.972392 -389.004654) (xy 366.952469 -388.952563)
			(xy 366.940343 -388.898126) (xy 366.936272 -388.842504) (xy 353.9744 -388.842504) (xy 353.9744 -390.28878)
			(xy 357.386126 -390.28878) (xy 357.390197 -390.233158) (xy 357.402323 -390.178721) (xy 357.422246 -390.12663)
			(xy 357.449542 -390.077995) (xy 357.483628 -390.033852) (xy 357.523777 -389.995143) (xy 357.569135 -389.962692)
			(xy 357.618735 -389.937191) (xy 357.671519 -389.919184) (xy 357.726362 -389.909054) (xy 357.782096 -389.907017)
			(xy 357.837533 -389.913117) (xy 357.89149 -389.927223) (xy 357.942819 -389.949035) (xy 357.990425 -389.978089)
			(xy 358.033293 -390.013764) (xy 358.07051 -390.055301) (xy 358.101283 -390.101814) (xy 358.124955 -390.152311)
			(xy 358.141023 -390.205718) (xy 358.149143 -390.260894) (xy 358.149652 -390.28878) (xy 358.149143 -390.316666)
			(xy 358.141023 -390.371842) (xy 358.124955 -390.425249) (xy 358.101283 -390.475746) (xy 358.07051 -390.522259)
			(xy 358.033293 -390.563796) (xy 357.990425 -390.599471) (xy 357.942819 -390.628525) (xy 357.89149 -390.650337)
			(xy 357.837533 -390.664443) (xy 357.782096 -390.670543) (xy 357.726362 -390.668506) (xy 357.671519 -390.658376)
			(xy 357.618735 -390.640369) (xy 357.569135 -390.614868) (xy 357.523777 -390.582417) (xy 357.483628 -390.543708)
			(xy 357.449542 -390.499565) (xy 357.422246 -390.45093) (xy 357.402323 -390.398839) (xy 357.390197 -390.344402)
			(xy 357.386126 -390.28878) (xy 353.9744 -390.28878) (xy 353.9744 -391.26541) (xy 365.668812 -391.26541)
			(xy 365.672883 -391.209788) (xy 365.685009 -391.155351) (xy 365.704932 -391.10326) (xy 365.732228 -391.054625)
			(xy 365.766314 -391.010482) (xy 365.806463 -390.971773) (xy 365.851821 -390.939322) (xy 365.901421 -390.913821)
			(xy 365.954205 -390.895814) (xy 366.009048 -390.885684) (xy 366.064782 -390.883647) (xy 366.120219 -390.889747)
			(xy 366.174176 -390.903853) (xy 366.225505 -390.925665) (xy 366.273111 -390.954719) (xy 366.315979 -390.990394)
			(xy 366.353196 -391.031931) (xy 366.383969 -391.078444) (xy 366.407641 -391.128941) (xy 366.423709 -391.182348)
			(xy 366.431829 -391.237524) (xy 366.432338 -391.26541) (xy 366.431829 -391.293296) (xy 366.423709 -391.348472)
			(xy 366.407641 -391.401879) (xy 366.383969 -391.452376) (xy 366.353196 -391.498889) (xy 366.315979 -391.540426)
			(xy 366.273111 -391.576101) (xy 366.225505 -391.605155) (xy 366.174176 -391.626967) (xy 366.120219 -391.641073)
			(xy 366.064782 -391.647173) (xy 366.009048 -391.645136) (xy 365.954205 -391.635006) (xy 365.901421 -391.616999)
			(xy 365.851821 -391.591498) (xy 365.806463 -391.559047) (xy 365.766314 -391.520338) (xy 365.732228 -391.476195)
			(xy 365.704932 -391.42756) (xy 365.685009 -391.375469) (xy 365.672883 -391.321032) (xy 365.668812 -391.26541)
			(xy 353.9744 -391.26541) (xy 353.9744 -392.684254) (xy 363.702852 -392.684254) (xy 363.706923 -392.628632)
			(xy 363.719049 -392.574195) (xy 363.738972 -392.522104) (xy 363.766268 -392.473469) (xy 363.800354 -392.429326)
			(xy 363.840503 -392.390617) (xy 363.885861 -392.358166) (xy 363.935461 -392.332665) (xy 363.988245 -392.314658)
			(xy 364.043088 -392.304528) (xy 364.098822 -392.302491) (xy 364.154259 -392.308591) (xy 364.208216 -392.322697)
			(xy 364.259545 -392.344509) (xy 364.307151 -392.373563) (xy 364.350019 -392.409238) (xy 364.387236 -392.450775)
			(xy 364.418009 -392.497288) (xy 364.441681 -392.547785) (xy 364.457749 -392.601192) (xy 364.465869 -392.656368)
			(xy 364.466378 -392.684254) (xy 364.465869 -392.71214) (xy 364.457749 -392.767316) (xy 364.441681 -392.820723)
			(xy 364.418009 -392.87122) (xy 364.387236 -392.917733) (xy 364.350019 -392.95927) (xy 364.307151 -392.994945)
			(xy 364.259545 -393.023999) (xy 364.208216 -393.045811) (xy 364.154259 -393.059917) (xy 364.098822 -393.066017)
			(xy 364.043088 -393.06398) (xy 363.988245 -393.05385) (xy 363.935461 -393.035843) (xy 363.885861 -393.010342)
			(xy 363.840503 -392.977891) (xy 363.800354 -392.939182) (xy 363.766268 -392.895039) (xy 363.738972 -392.846404)
			(xy 363.719049 -392.794313) (xy 363.706923 -392.739876) (xy 363.702852 -392.684254) (xy 353.9744 -392.684254)
			(xy 353.9744 -393.459716) (xy 357.18572 -393.459716) (xy 357.189791 -393.404094) (xy 357.201917 -393.349657)
			(xy 357.22184 -393.297566) (xy 357.249136 -393.248931) (xy 357.283222 -393.204788) (xy 357.323371 -393.166079)
			(xy 357.368729 -393.133628) (xy 357.418329 -393.108127) (xy 357.471113 -393.09012) (xy 357.525956 -393.07999)
			(xy 357.58169 -393.077953) (xy 357.637127 -393.084053) (xy 357.691084 -393.098159) (xy 357.742413 -393.119971)
			(xy 357.790019 -393.149025) (xy 357.832887 -393.1847) (xy 357.870104 -393.226237) (xy 357.900877 -393.27275)
			(xy 357.924549 -393.323247) (xy 357.940617 -393.376654) (xy 357.948737 -393.43183) (xy 357.949246 -393.459716)
			(xy 357.948737 -393.487602) (xy 357.940617 -393.542778) (xy 357.924549 -393.596185) (xy 357.900877 -393.646682)
			(xy 357.870104 -393.693195) (xy 357.832887 -393.734732) (xy 357.790019 -393.770407) (xy 357.742413 -393.799461)
			(xy 357.691084 -393.821273) (xy 357.637127 -393.835379) (xy 357.58169 -393.841479) (xy 357.525956 -393.839442)
			(xy 357.471113 -393.829312) (xy 357.418329 -393.811305) (xy 357.368729 -393.785804) (xy 357.323371 -393.753353)
			(xy 357.283222 -393.714644) (xy 357.249136 -393.670501) (xy 357.22184 -393.621866) (xy 357.201917 -393.569775)
			(xy 357.189791 -393.515338) (xy 357.18572 -393.459716) (xy 353.9744 -393.459716) (xy 353.9744 -396.063724)
			(xy 357.261158 -396.063724) (xy 357.265229 -396.008102) (xy 357.277355 -395.953665) (xy 357.297278 -395.901574)
			(xy 357.324574 -395.852939) (xy 357.35866 -395.808796) (xy 357.398809 -395.770087) (xy 357.444167 -395.737636)
			(xy 357.493767 -395.712135) (xy 357.546551 -395.694128) (xy 357.601394 -395.683998) (xy 357.657128 -395.681961)
			(xy 357.712565 -395.688061) (xy 357.766522 -395.702167) (xy 357.817851 -395.723979) (xy 357.865457 -395.753033)
			(xy 357.908325 -395.788708) (xy 357.945542 -395.830245) (xy 357.976315 -395.876758) (xy 357.999987 -395.927255)
			(xy 358.016055 -395.980662) (xy 358.024175 -396.035838) (xy 358.024684 -396.063724) (xy 358.024175 -396.09161)
			(xy 358.016055 -396.146786) (xy 357.999987 -396.200193) (xy 357.976315 -396.25069) (xy 357.945542 -396.297203)
			(xy 357.908325 -396.33874) (xy 357.865457 -396.374415) (xy 357.817851 -396.403469) (xy 357.766522 -396.425281)
			(xy 357.712565 -396.439387) (xy 357.657128 -396.445487) (xy 357.601394 -396.44345) (xy 357.546551 -396.43332)
			(xy 357.493767 -396.415313) (xy 357.444167 -396.389812) (xy 357.398809 -396.357361) (xy 357.35866 -396.318652)
			(xy 357.324574 -396.274509) (xy 357.297278 -396.225874) (xy 357.277355 -396.173783) (xy 357.265229 -396.119346)
			(xy 357.261158 -396.063724) (xy 353.9744 -396.063724) (xy 353.9744 -397.025622) (xy 365.416844 -397.025622)
			(xy 365.420915 -396.97) (xy 365.433041 -396.915563) (xy 365.452964 -396.863472) (xy 365.48026 -396.814837)
			(xy 365.514346 -396.770694) (xy 365.554495 -396.731985) (xy 365.599853 -396.699534) (xy 365.649453 -396.674033)
			(xy 365.702237 -396.656026) (xy 365.75708 -396.645896) (xy 365.812814 -396.643859) (xy 365.868251 -396.649959)
			(xy 365.922208 -396.664065) (xy 365.973537 -396.685877) (xy 366.021143 -396.714931) (xy 366.064011 -396.750606)
			(xy 366.101048 -396.791942) (xy 366.335308 -396.791942) (xy 366.339379 -396.73632) (xy 366.351505 -396.681883)
			(xy 366.371428 -396.629792) (xy 366.398724 -396.581157) (xy 366.43281 -396.537014) (xy 366.472959 -396.498305)
			(xy 366.518317 -396.465854) (xy 366.567917 -396.440353) (xy 366.620701 -396.422346) (xy 366.675544 -396.412216)
			(xy 366.731278 -396.410179) (xy 366.786715 -396.416279) (xy 366.840672 -396.430385) (xy 366.892001 -396.452197)
			(xy 366.939607 -396.481251) (xy 366.982475 -396.516926) (xy 367.019692 -396.558463) (xy 367.050465 -396.604976)
			(xy 367.074137 -396.655473) (xy 367.090205 -396.70888) (xy 367.098325 -396.764056) (xy 367.098834 -396.791942)
			(xy 367.098325 -396.819828) (xy 367.090205 -396.875004) (xy 367.074137 -396.928411) (xy 367.050465 -396.978908)
			(xy 367.019692 -397.025421) (xy 366.982475 -397.066958) (xy 366.939607 -397.102633) (xy 366.892001 -397.131687)
			(xy 366.840672 -397.153499) (xy 366.786715 -397.167605) (xy 366.731278 -397.173705) (xy 366.675544 -397.171668)
			(xy 366.620701 -397.161538) (xy 366.567917 -397.143531) (xy 366.518317 -397.11803) (xy 366.472959 -397.085579)
			(xy 366.43281 -397.04687) (xy 366.398724 -397.002727) (xy 366.371428 -396.954092) (xy 366.351505 -396.902001)
			(xy 366.339379 -396.847564) (xy 366.335308 -396.791942) (xy 366.101048 -396.791942) (xy 366.101228 -396.792143)
			(xy 366.132001 -396.838656) (xy 366.155673 -396.889153) (xy 366.171741 -396.94256) (xy 366.179861 -396.997736)
			(xy 366.18037 -397.025622) (xy 366.179861 -397.053508) (xy 366.171741 -397.108684) (xy 366.155673 -397.162091)
			(xy 366.132001 -397.212588) (xy 366.101228 -397.259101) (xy 366.064011 -397.300638) (xy 366.021143 -397.336313)
			(xy 365.973537 -397.365367) (xy 365.922208 -397.387179) (xy 365.868251 -397.401285) (xy 365.812814 -397.407385)
			(xy 365.75708 -397.405348) (xy 365.702237 -397.395218) (xy 365.649453 -397.377211) (xy 365.599853 -397.35171)
			(xy 365.554495 -397.319259) (xy 365.514346 -397.28055) (xy 365.48026 -397.236407) (xy 365.452964 -397.187772)
			(xy 365.433041 -397.135681) (xy 365.420915 -397.081244) (xy 365.416844 -397.025622) (xy 353.9744 -397.025622)
			(xy 353.9744 -398.444466) (xy 363.577884 -398.444466) (xy 363.581955 -398.388844) (xy 363.594081 -398.334407)
			(xy 363.614004 -398.282316) (xy 363.6413 -398.233681) (xy 363.675386 -398.189538) (xy 363.715535 -398.150829)
			(xy 363.760893 -398.118378) (xy 363.810493 -398.092877) (xy 363.863277 -398.07487) (xy 363.91812 -398.06474)
			(xy 363.973854 -398.062703) (xy 364.029291 -398.068803) (xy 364.083248 -398.082909) (xy 364.134577 -398.104721)
			(xy 364.182183 -398.133775) (xy 364.225051 -398.16945) (xy 364.262268 -398.210987) (xy 364.293041 -398.2575)
			(xy 364.316713 -398.307997) (xy 364.332781 -398.361404) (xy 364.340901 -398.41658) (xy 364.34141 -398.444466)
			(xy 364.340901 -398.472352) (xy 364.332781 -398.527528) (xy 364.316713 -398.580935) (xy 364.293041 -398.631432)
			(xy 364.262268 -398.677945) (xy 364.225051 -398.719482) (xy 364.182183 -398.755157) (xy 364.134577 -398.784211)
			(xy 364.083248 -398.806023) (xy 364.029291 -398.820129) (xy 363.973854 -398.826229) (xy 363.91812 -398.824192)
			(xy 363.863277 -398.814062) (xy 363.810493 -398.796055) (xy 363.760893 -398.770554) (xy 363.715535 -398.738103)
			(xy 363.675386 -398.699394) (xy 363.6413 -398.655251) (xy 363.614004 -398.606616) (xy 363.594081 -398.554525)
			(xy 363.581955 -398.500088) (xy 363.577884 -398.444466) (xy 353.9744 -398.444466) (xy 353.9744 -399.219928)
			(xy 357.060752 -399.219928) (xy 357.064823 -399.164306) (xy 357.076949 -399.109869) (xy 357.096872 -399.057778)
			(xy 357.124168 -399.009143) (xy 357.158254 -398.965) (xy 357.198403 -398.926291) (xy 357.243761 -398.89384)
			(xy 357.293361 -398.868339) (xy 357.346145 -398.850332) (xy 357.400988 -398.840202) (xy 357.456722 -398.838165)
			(xy 357.512159 -398.844265) (xy 357.566116 -398.858371) (xy 357.617445 -398.880183) (xy 357.665051 -398.909237)
			(xy 357.707919 -398.944912) (xy 357.745136 -398.986449) (xy 357.775909 -399.032962) (xy 357.799581 -399.083459)
			(xy 357.815649 -399.136866) (xy 357.823769 -399.192042) (xy 357.824278 -399.219928) (xy 357.823769 -399.247814)
			(xy 357.815649 -399.30299) (xy 357.799581 -399.356397) (xy 357.775909 -399.406894) (xy 357.745136 -399.453407)
			(xy 357.707919 -399.494944) (xy 357.665051 -399.530619) (xy 357.617445 -399.559673) (xy 357.566116 -399.581485)
			(xy 357.512159 -399.595591) (xy 357.456722 -399.601691) (xy 357.400988 -399.599654) (xy 357.346145 -399.589524)
			(xy 357.293361 -399.571517) (xy 357.243761 -399.546016) (xy 357.198403 -399.513565) (xy 357.158254 -399.474856)
			(xy 357.124168 -399.430713) (xy 357.096872 -399.382078) (xy 357.076949 -399.329987) (xy 357.064823 -399.27555)
			(xy 357.060752 -399.219928) (xy 353.9744 -399.219928) (xy 353.9744 -401.400518) (xy 353.973973 -401.410587)
			(xy 353.966254 -401.429186) (xy 353.959414 -401.436586) (xy 351.728532 -403.667468) (xy 351.7265 -403.706584)
			(xy 351.738946 -403.721824) (xy 351.759695 -403.747822) (xy 351.79575 -403.80372) (xy 351.825178 -403.863375)
			(xy 351.847593 -403.926003) (xy 351.862701 -403.990783) (xy 351.870303 -404.056865) (xy 351.870772 -404.090124)
			(xy 351.870241 -404.125214) (xy 351.861779 -404.194882) (xy 351.844982 -404.263023) (xy 351.820094 -404.328642)
			(xy 351.787479 -404.390783) (xy 351.747612 -404.44854) (xy 351.701074 -404.501071) (xy 351.648543 -404.547609)
			(xy 351.590787 -404.587477) (xy 351.528646 -404.620093) (xy 351.463027 -404.644981) (xy 351.394886 -404.661778)
			(xy 351.325218 -404.670241) (xy 351.290128 -404.670768) (xy 351.256868 -404.670309) (xy 351.190785 -404.662707)
			(xy 351.126004 -404.647599) (xy 351.063375 -404.625184) (xy 351.003719 -404.595756) (xy 350.947819 -404.5597)
			(xy 350.921828 -404.538942) (xy 350.906588 -404.526496) (xy 350.867472 -404.528528) (xy 350.005904 -405.390096)
			(xy 350.80398 -405.390096) (xy 350.807971 -405.327929) (xy 350.81988 -405.266782) (xy 350.839509 -405.207661)
			(xy 350.866538 -405.151535) (xy 350.900522 -405.099326) (xy 350.940904 -405.051891) (xy 350.98702 -405.01001)
			(xy 351.038112 -404.97437) (xy 351.093343 -404.945556) (xy 351.151805 -404.924042) (xy 351.212539 -404.91018)
			(xy 351.274546 -404.904198) (xy 351.336809 -404.906194) (xy 351.398306 -404.916137) (xy 351.458027 -404.933861)
			(xy 351.51499 -404.959078) (xy 351.568261 -404.991371) (xy 351.616966 -405.030211) (xy 351.660303 -405.074961)
			(xy 351.697563 -405.124885) (xy 351.728132 -405.179164) (xy 351.75151 -405.236907) (xy 351.767311 -405.297165)
			(xy 351.775277 -405.358948) (xy 351.775776 -405.390096) (xy 351.775277 -405.421244) (xy 351.767311 -405.483027)
			(xy 351.75151 -405.543285) (xy 351.728132 -405.601028) (xy 351.697563 -405.655307) (xy 351.660303 -405.705231)
			(xy 351.616966 -405.749981) (xy 351.568261 -405.788821) (xy 351.51499 -405.821114) (xy 351.458027 -405.846331)
			(xy 351.398306 -405.864055) (xy 351.336809 -405.873998) (xy 351.274546 -405.875994) (xy 351.212539 -405.870012)
			(xy 351.151805 -405.85615) (xy 351.093343 -405.834636) (xy 351.038112 -405.805822) (xy 350.98702 -405.770182)
			(xy 350.940904 -405.728301) (xy 350.900522 -405.680866) (xy 350.866538 -405.628657) (xy 350.839509 -405.572531)
			(xy 350.81988 -405.51341) (xy 350.807971 -405.452263) (xy 350.80398 -405.390096) (xy 350.005904 -405.390096)
			(xy 348.705932 -406.690068) (xy 350.80398 -406.690068) (xy 350.807971 -406.627901) (xy 350.81988 -406.566754)
			(xy 350.839509 -406.507633) (xy 350.866538 -406.451507) (xy 350.900522 -406.399298) (xy 350.940904 -406.351863)
			(xy 350.98702 -406.309982) (xy 351.038112 -406.274342) (xy 351.093343 -406.245528) (xy 351.151805 -406.224014)
			(xy 351.212539 -406.210152) (xy 351.274546 -406.20417) (xy 351.336809 -406.206166) (xy 351.398306 -406.216109)
			(xy 351.458027 -406.233833) (xy 351.51499 -406.25905) (xy 351.568261 -406.291343) (xy 351.616966 -406.330183)
			(xy 351.660303 -406.374933) (xy 351.697563 -406.424857) (xy 351.728132 -406.479136) (xy 351.75151 -406.536879)
			(xy 351.767311 -406.597137) (xy 351.775277 -406.65892) (xy 351.775776 -406.690068) (xy 351.775277 -406.721216)
			(xy 351.767311 -406.782999) (xy 351.75151 -406.843257) (xy 351.728132 -406.901) (xy 351.697563 -406.955279)
			(xy 351.660303 -407.005203) (xy 351.616966 -407.049953) (xy 351.568261 -407.088793) (xy 351.51499 -407.121086)
			(xy 351.458027 -407.146303) (xy 351.398306 -407.164027) (xy 351.336809 -407.17397) (xy 351.274546 -407.175966)
			(xy 351.212539 -407.169984) (xy 351.151805 -407.156122) (xy 351.093343 -407.134608) (xy 351.038112 -407.105794)
			(xy 350.98702 -407.070154) (xy 350.940904 -407.028273) (xy 350.900522 -406.980838) (xy 350.866538 -406.928629)
			(xy 350.839509 -406.872503) (xy 350.81988 -406.813382) (xy 350.807971 -406.752235) (xy 350.80398 -406.690068)
			(xy 348.705932 -406.690068) (xy 348.401386 -406.994614) (xy 348.393991 -407.001468) (xy 348.375392 -407.00921)
			(xy 348.365318 -407.0096) (xy 348.134686 -407.0096) (xy 348.127418 -407.009835) (xy 348.113485 -407.013977)
			(xy 348.107254 -407.017728) (xy 348.107 -407.017728) (xy 348.071915 -407.039993) (xy 347.998686 -407.07928)
			(xy 347.92244 -407.112332) (xy 347.843705 -407.138918) (xy 347.80347 -407.1493) (xy 347.801692 -407.149808)
			(xy 347.79778 -407.150979) (xy 347.79038 -407.154434) (xy 347.78696 -407.156666) (xy 347.784928 -407.15819)
			(xy 347.761306 -407.176224) (xy 347.755972 -407.185114) (xy 347.755718 -407.185622) (xy 347.733609 -407.223298)
			(xy 347.683739 -407.29503) (xy 347.627788 -407.362126) (xy 347.566183 -407.424071) (xy 347.499397 -407.480392)
			(xy 347.427941 -407.530656) (xy 347.352364 -407.574479) (xy 347.273244 -407.611525) (xy 347.191187 -407.641509)
			(xy 347.106822 -407.664203) (xy 347.020796 -407.679432) (xy 346.933768 -407.68708) (xy 346.890086 -407.687526)
			(xy 346.882466 -407.687526) (xy 346.863416 -407.687018) (xy 346.813627 -407.685084) (xy 346.71478 -407.672497)
			(xy 346.617683 -407.650107) (xy 346.5703 -407.634694) (xy 346.550013 -407.627702) (xy 346.509993 -407.612205)
			(xy 346.49029 -407.603706) (xy 346.481408 -407.600198) (xy 346.462342 -407.599405) (xy 346.453206 -407.602182)
			(xy 346.422851 -407.612092) (xy 346.359908 -407.622815) (xy 346.327984 -407.623518) (xy 346.300733 -407.623031)
			(xy 346.246787 -407.615273) (xy 346.194493 -407.599916) (xy 346.144917 -407.577274) (xy 346.099068 -407.547808)
			(xy 346.057879 -407.512117) (xy 346.022188 -407.470927) (xy 345.992723 -407.425077) (xy 345.970081 -407.375501)
			(xy 345.954726 -407.323207) (xy 345.946968 -407.269261) (xy 345.946476 -407.24201) (xy 345.946476 -407.241756)
			(xy 345.947111 -407.209234) (xy 345.958092 -407.145126) (xy 345.96832 -407.114248) (xy 345.96959 -407.110692)
			(xy 345.973146 -407.093166) (xy 345.971114 -407.083514) (xy 345.969082 -407.0731) (xy 345.96705 -407.068528)
			(xy 345.962478 -407.056844) (xy 345.959684 -407.049732) (xy 345.950286 -407.038048) (xy 345.922092 -407.01849)
			(xy 345.915639 -407.014385) (xy 345.901034 -407.009866) (xy 345.89339 -407.0096) (xy 345.280742 -407.0096)
			(xy 345.253564 -407.030174) (xy 345.248992 -407.046684) (xy 345.239288 -407.079552) (xy 345.213201 -407.142925)
			(xy 345.179833 -407.202786) (xy 345.139648 -407.258301) (xy 345.093205 -407.308698) (xy 345.041151 -407.353275)
			(xy 344.98421 -407.391413) (xy 344.923174 -407.42258) (xy 344.858893 -407.446343) (xy 344.792261 -407.462371)
			(xy 344.724204 -407.470441) (xy 344.655672 -407.470441) (xy 344.587615 -407.462371) (xy 344.520983 -407.446343)
			(xy 344.456702 -407.42258) (xy 344.395666 -407.391413) (xy 344.338725 -407.353275) (xy 344.286671 -407.308698)
			(xy 344.240228 -407.258301) (xy 344.200043 -407.202786) (xy 344.166675 -407.142925) (xy 344.140588 -407.079552)
			(xy 344.130884 -407.046684) (xy 344.127412 -407.036207) (xy 344.113147 -407.019396) (xy 344.09314 -407.01013)
			(xy 344.082116 -407.0096) (xy 343.734644 -407.0096) (xy 343.727373 -407.009826) (xy 343.713431 -407.013955)
			(xy 343.707212 -407.017728) (xy 343.706958 -407.017728) (xy 343.671873 -407.039992) (xy 343.598643 -407.079276)
			(xy 343.522395 -407.112324) (xy 343.44366 -407.138907) (xy 343.403428 -407.1493) (xy 343.40165 -407.149808)
			(xy 343.397736 -407.150975) (xy 343.390331 -407.154423) (xy 343.386918 -407.156666) (xy 343.384886 -407.15819)
			(xy 343.361264 -407.176224) (xy 343.35593 -407.185114) (xy 343.355676 -407.185622) (xy 343.333567 -407.223297)
			(xy 343.283696 -407.295027) (xy 343.227744 -407.36212) (xy 343.166138 -407.424063) (xy 343.099352 -407.480381)
			(xy 343.027896 -407.530642) (xy 342.952318 -407.574462) (xy 342.873198 -407.611504) (xy 342.791142 -407.641486)
			(xy 342.706777 -407.664176) (xy 342.620752 -407.679401) (xy 342.533725 -407.687045) (xy 342.490044 -407.687526)
			(xy 342.482424 -407.687526) (xy 342.463374 -407.687018) (xy 342.413586 -407.685082) (xy 342.314739 -407.672491)
			(xy 342.217644 -407.650097) (xy 342.170258 -407.634694) (xy 342.149971 -407.627701) (xy 342.109952 -407.612202)
			(xy 342.090248 -407.603706) (xy 342.081366 -407.600206) (xy 342.062306 -407.599428) (xy 342.053164 -407.602182)
			(xy 342.02281 -407.612097) (xy 341.959867 -407.622829) (xy 341.927942 -407.623518) (xy 341.900687 -407.623058)
			(xy 341.846731 -407.615306) (xy 341.794427 -407.599954) (xy 341.744841 -407.577314) (xy 341.698982 -407.547847)
			(xy 341.657783 -407.512153) (xy 341.622084 -407.47096) (xy 341.592611 -407.425105) (xy 341.569965 -407.375521)
			(xy 341.554605 -407.32322) (xy 341.546846 -407.269265) (xy 341.546434 -407.24201) (xy 341.546434 -407.241756)
			(xy 341.547069 -407.209234) (xy 341.558049 -407.145125) (xy 341.568278 -407.114248) (xy 341.569548 -407.110692)
			(xy 341.573104 -407.093166) (xy 341.571072 -407.083514) (xy 341.56904 -407.0731) (xy 341.567008 -407.068528)
			(xy 341.562436 -407.056844) (xy 341.559642 -407.049732) (xy 341.550244 -407.038048) (xy 341.52205 -407.01849)
			(xy 341.515599 -407.014377) (xy 341.500994 -407.009842) (xy 341.493348 -407.0096) (xy 340.880954 -407.0096)
			(xy 340.853776 -407.030174) (xy 340.849204 -407.046684) (xy 340.8395 -407.079552) (xy 340.813413 -407.142925)
			(xy 340.780045 -407.202786) (xy 340.73986 -407.258301) (xy 340.693417 -407.308698) (xy 340.641363 -407.353275)
			(xy 340.584422 -407.391413) (xy 340.523386 -407.42258) (xy 340.459105 -407.446343) (xy 340.392473 -407.462371)
			(xy 340.324416 -407.470441) (xy 340.255884 -407.470441) (xy 340.187827 -407.462371) (xy 340.121195 -407.446343)
			(xy 340.056914 -407.42258) (xy 339.995878 -407.391413) (xy 339.938937 -407.353275) (xy 339.886883 -407.308698)
			(xy 339.84044 -407.258301) (xy 339.800255 -407.202786) (xy 339.766887 -407.142925) (xy 339.7408 -407.079552)
			(xy 339.731096 -407.046684) (xy 339.727625 -407.036205) (xy 339.71336 -407.019391) (xy 339.693353 -407.010121)
			(xy 339.682328 -407.0096) (xy 339.334602 -407.0096) (xy 339.327333 -407.009832) (xy 339.313398 -407.013971)
			(xy 339.30717 -407.017728) (xy 339.306916 -407.017728) (xy 339.271831 -407.039994) (xy 339.198603 -407.079282)
			(xy 339.122357 -407.112334) (xy 339.043622 -407.138922) (xy 339.003386 -407.1493) (xy 339.001608 -407.149808)
			(xy 338.997695 -407.150978) (xy 338.990294 -407.154431) (xy 338.986876 -407.156666) (xy 338.984844 -407.15819)
			(xy 338.961222 -407.176224) (xy 338.955888 -407.185114) (xy 338.955634 -407.185622) (xy 338.933524 -407.223296)
			(xy 338.883653 -407.295023) (xy 338.8277 -407.362114) (xy 338.766094 -407.424054) (xy 338.699307 -407.480369)
			(xy 338.627851 -407.530628) (xy 338.552273 -407.574444) (xy 338.473153 -407.611484) (xy 338.391096 -407.641462)
			(xy 338.306733 -407.664148) (xy 338.220708 -407.67937) (xy 338.133682 -407.687011) (xy 338.090002 -407.687526)
			(xy 338.082382 -407.687526) (xy 338.063332 -407.687018) (xy 338.013543 -407.685085) (xy 337.914695 -407.672499)
			(xy 337.817597 -407.650111) (xy 337.770216 -407.634694) (xy 337.74993 -407.6277) (xy 337.709911 -407.6122)
			(xy 337.690206 -407.603706) (xy 337.681324 -407.600195) (xy 337.662256 -407.599396) (xy 337.653122 -407.602182)
			(xy 337.622767 -407.612093) (xy 337.559824 -407.622819) (xy 337.5279 -407.623518) (xy 337.500648 -407.623032)
			(xy 337.4467 -407.615276) (xy 337.394405 -407.599921) (xy 337.344827 -407.57728) (xy 337.298976 -407.547814)
			(xy 337.257785 -407.512122) (xy 337.222092 -407.470932) (xy 337.192625 -407.425082) (xy 337.169983 -407.375504)
			(xy 337.154626 -407.32321) (xy 337.146868 -407.269261) (xy 337.146392 -407.24201) (xy 337.146392 -407.241756)
			(xy 337.147027 -407.209234) (xy 337.158009 -407.145126) (xy 337.168236 -407.114248) (xy 337.169506 -407.110692)
			(xy 337.173062 -407.093166) (xy 337.17103 -407.083514) (xy 337.168998 -407.0731) (xy 337.166966 -407.068528)
			(xy 337.162394 -407.056844) (xy 337.1596 -407.049732) (xy 337.150202 -407.038048) (xy 337.122008 -407.01849)
			(xy 337.115555 -407.014383) (xy 337.100951 -407.00986) (xy 337.093306 -407.0096) (xy 336.480912 -407.0096)
			(xy 336.453734 -407.030174) (xy 336.449162 -407.046684) (xy 336.439458 -407.079552) (xy 336.413371 -407.142925)
			(xy 336.380003 -407.202786) (xy 336.339818 -407.258301) (xy 336.293375 -407.308698) (xy 336.241321 -407.353275)
			(xy 336.18438 -407.391413) (xy 336.123344 -407.42258) (xy 336.059063 -407.446343) (xy 335.992431 -407.462371)
			(xy 335.924374 -407.470441) (xy 335.855842 -407.470441) (xy 335.787785 -407.462371) (xy 335.721153 -407.446343)
			(xy 335.656872 -407.42258) (xy 335.595836 -407.391413) (xy 335.538895 -407.353275) (xy 335.486841 -407.308698)
			(xy 335.440398 -407.258301) (xy 335.400213 -407.202786) (xy 335.366845 -407.142925) (xy 335.340758 -407.079552)
			(xy 335.331054 -407.046684) (xy 335.327581 -407.03621) (xy 335.313313 -407.019407) (xy 335.293308 -407.010153)
			(xy 335.282286 -407.0096) (xy 334.93456 -407.0096) (xy 334.927288 -407.009824) (xy 334.913344 -407.013949)
			(xy 334.907128 -407.017728) (xy 334.906874 -407.017728) (xy 334.871789 -407.039992) (xy 334.798559 -407.079277)
			(xy 334.722312 -407.112327) (xy 334.643578 -407.138912) (xy 334.603344 -407.1493) (xy 334.601566 -407.149808)
			(xy 334.597651 -407.150974) (xy 334.590245 -407.154419) (xy 334.586834 -407.156666) (xy 334.584802 -407.15819)
			(xy 334.56118 -407.176224) (xy 334.555846 -407.185114) (xy 334.555592 -407.185622) (xy 334.533483 -407.223298)
			(xy 334.483613 -407.295028) (xy 334.427661 -407.362122) (xy 334.366055 -407.424066) (xy 334.299269 -407.480385)
			(xy 334.227813 -407.530647) (xy 334.152236 -407.574468) (xy 334.073115 -407.611512) (xy 333.991059 -407.641495)
			(xy 333.906694 -407.664186) (xy 333.820669 -407.679413) (xy 333.733641 -407.687058) (xy 333.68996 -407.687526)
			(xy 333.68234 -407.687526) (xy 333.66329 -407.687018) (xy 333.613501 -407.685083) (xy 333.514655 -407.672493)
			(xy 333.417558 -407.650101) (xy 333.370174 -407.634694) (xy 333.349887 -407.627701) (xy 333.309868 -407.612203)
			(xy 333.290164 -407.603706) (xy 333.281282 -407.600203) (xy 333.26222 -407.599419) (xy 333.25308 -407.602182)
			(xy 333.222725 -407.61209) (xy 333.159782 -407.622808) (xy 333.127858 -407.623518) (xy 333.100608 -407.623029)
			(xy 333.046665 -407.615268) (xy 332.994374 -407.599909) (xy 332.944802 -407.577266) (xy 332.898956 -407.547799)
			(xy 332.85777 -407.512107) (xy 332.822082 -407.470918) (xy 332.792619 -407.42507) (xy 332.769979 -407.375496)
			(xy 332.754625 -407.323204) (xy 332.746868 -407.26926) (xy 332.74635 -407.24201) (xy 332.74635 -407.241756)
			(xy 332.746985 -407.209234) (xy 332.757965 -407.145126) (xy 332.768194 -407.114248) (xy 332.769464 -407.110692)
			(xy 332.77302 -407.093166) (xy 332.770988 -407.083514) (xy 332.768956 -407.0731) (xy 332.766924 -407.068528)
			(xy 332.762352 -407.056844) (xy 332.759558 -407.049732) (xy 332.75016 -407.038048) (xy 332.721966 -407.01849)
			(xy 332.715515 -407.014375) (xy 332.700911 -407.009835) (xy 332.693264 -407.0096) (xy 332.08087 -407.0096)
			(xy 332.053692 -407.030174) (xy 332.04912 -407.046684) (xy 332.039416 -407.079552) (xy 332.013329 -407.142925)
			(xy 331.979961 -407.202786) (xy 331.939776 -407.258301) (xy 331.893333 -407.308698) (xy 331.841279 -407.353275)
			(xy 331.784338 -407.391413) (xy 331.723302 -407.42258) (xy 331.659021 -407.446343) (xy 331.592389 -407.462371)
			(xy 331.524332 -407.470441) (xy 331.4558 -407.470441) (xy 331.387743 -407.462371) (xy 331.321111 -407.446343)
			(xy 331.25683 -407.42258) (xy 331.195794 -407.391413) (xy 331.138853 -407.353275) (xy 331.086799 -407.308698)
			(xy 331.040356 -407.258301) (xy 331.000171 -407.202786) (xy 330.966803 -407.142925) (xy 330.940716 -407.079552)
			(xy 330.931012 -407.046684) (xy 330.927542 -407.036203) (xy 330.913278 -407.019385) (xy 330.89327 -407.010108)
			(xy 330.882244 -407.0096) (xy 326.673718 -407.0096) (xy 326.663654 -407.010038) (xy 326.645072 -407.017774)
			(xy 326.63765 -407.024586) (xy 326.540622 -407.121614) (xy 326.533256 -407.128726) (xy 326.525636 -407.147522)
			(xy 326.525636 -409.522889) (xy 331.004998 -409.522889) (xy 331.005002 -409.457449) (xy 331.013791 -409.392603)
			(xy 331.031204 -409.329523) (xy 331.056927 -409.269351) (xy 331.073252 -409.24099) (xy 331.076566 -409.234965)
			(xy 331.080173 -409.221702) (xy 331.080364 -409.214828) (xy 331.080364 -408.465528) (xy 331.080166 -408.458655)
			(xy 331.076562 -408.445392) (xy 331.073252 -408.439366) (xy 331.056923 -408.411009) (xy 331.031205 -408.350837)
			(xy 331.013797 -408.287757) (xy 331.005014 -408.222912) (xy 331.005015 -408.157474) (xy 331.0138 -408.092629)
			(xy 331.031209 -408.02955) (xy 331.056929 -407.969379) (xy 331.073252 -407.941018) (xy 331.076556 -407.934988)
			(xy 331.080169 -407.921729) (xy 331.080364 -407.914856) (xy 331.080364 -407.628852) (xy 331.080782 -407.618699)
			(xy 331.088586 -407.599953) (xy 331.102983 -407.585633) (xy 331.121771 -407.577928) (xy 331.131926 -407.577544)
			(xy 331.848206 -407.577544) (xy 331.858334 -407.578022) (xy 331.877056 -407.585752) (xy 331.891412 -407.600041)
			(xy 331.89923 -407.618727) (xy 331.899768 -407.628852) (xy 331.899768 -407.914856) (xy 331.899981 -407.921728)
			(xy 331.903575 -407.93499) (xy 331.90688 -407.941018) (xy 331.923195 -407.969383) (xy 331.948912 -408.029554)
			(xy 331.96632 -408.092632) (xy 331.975104 -408.157475) (xy 331.975105 -408.222911) (xy 331.966323 -408.287755)
			(xy 331.948917 -408.350833) (xy 331.923201 -408.411005) (xy 331.90688 -408.439366) (xy 331.903576 -408.445396)
			(xy 331.899964 -408.458656) (xy 331.899768 -408.465528) (xy 331.899768 -409.214828) (xy 331.899953 -409.221702)
			(xy 331.903567 -409.234964) (xy 331.90688 -409.24099) (xy 331.923171 -409.269368) (xy 331.948891 -409.329536)
			(xy 331.966301 -409.392611) (xy 331.975088 -409.457452) (xy 331.975093 -409.522886) (xy 331.966314 -409.587729)
			(xy 331.948911 -409.650806) (xy 331.923199 -409.710977) (xy 331.90688 -409.739338) (xy 331.90355 -409.745355)
			(xy 331.899954 -409.758625) (xy 331.899768 -409.7655) (xy 331.899768 -410.051504) (xy 331.899381 -410.061662)
			(xy 331.891578 -410.080421) (xy 331.87717 -410.094745) (xy 331.858367 -410.102439) (xy 331.848206 -410.102812)
			(xy 331.131926 -410.102812) (xy 331.121807 -410.102254) (xy 331.103097 -410.094544) (xy 331.088741 -410.08028)
			(xy 331.080912 -410.061619) (xy 331.080364 -410.051504) (xy 331.080364 -409.7655) (xy 331.080176 -409.758626)
			(xy 331.076566 -409.745363) (xy 331.073252 -409.739338) (xy 331.056899 -409.710994) (xy 331.031183 -409.650819)
			(xy 331.013778 -409.587736) (xy 331.004998 -409.522889) (xy 326.525636 -409.522889) (xy 326.525636 -410.589984)
			(xy 333.204312 -410.589984) (xy 333.204891 -410.557255) (xy 333.213743 -410.492397) (xy 333.231229 -410.429317)
			(xy 333.257033 -410.369158) (xy 333.2734 -410.34081) (xy 333.276711 -410.334784) (xy 333.280319 -410.321521)
			(xy 333.280512 -410.314648) (xy 333.280512 -409.565348) (xy 333.2803 -409.558476) (xy 333.276705 -409.545214)
			(xy 333.2734 -409.539186) (xy 333.257029 -409.51084) (xy 333.231228 -409.450679) (xy 333.21374 -409.387599)
			(xy 333.204882 -409.322741) (xy 333.204312 -409.290012) (xy 333.204859 -409.257282) (xy 333.21372 -409.192423)
			(xy 333.231216 -409.129343) (xy 333.257029 -409.069185) (xy 333.2734 -409.040838) (xy 333.276701 -409.034807)
			(xy 333.280315 -409.021548) (xy 333.280512 -409.014676) (xy 333.280512 -408.728672) (xy 333.280962 -408.71856)
			(xy 333.288711 -408.699879) (xy 333.303019 -408.685585) (xy 333.321708 -408.677853) (xy 333.33182 -408.677364)
			(xy 334.0481 -408.677364) (xy 334.058204 -408.677884) (xy 334.076876 -408.685615) (xy 334.091169 -408.699901)
			(xy 334.09891 -408.718568) (xy 334.099408 -408.728672) (xy 334.099408 -409.014676) (xy 334.099608 -409.021549)
			(xy 334.103211 -409.034811) (xy 334.10652 -409.040838) (xy 334.122903 -409.069178) (xy 334.1487 -409.129341)
			(xy 334.166185 -409.192423) (xy 334.17504 -409.257282) (xy 334.175608 -409.290012) (xy 334.175024 -409.322741)
			(xy 334.166173 -409.387598) (xy 334.148688 -409.450679) (xy 334.131753 -409.490164) (xy 335.40446 -409.490164)
			(xy 335.405037 -409.457435) (xy 335.41389 -409.392577) (xy 335.431377 -409.329497) (xy 335.457181 -409.269338)
			(xy 335.473548 -409.24099) (xy 335.476862 -409.234965) (xy 335.480469 -409.221702) (xy 335.48066 -409.214828)
			(xy 335.48066 -408.465528) (xy 335.480462 -408.458655) (xy 335.476859 -408.445392) (xy 335.473548 -408.439366)
			(xy 335.457173 -408.411022) (xy 335.431373 -408.350861) (xy 335.413885 -408.28778) (xy 335.405028 -408.222921)
			(xy 335.40446 -408.190192) (xy 335.40505 -408.157463) (xy 335.4139 -408.092606) (xy 335.431383 -408.029526)
			(xy 335.457183 -407.969367) (xy 335.473548 -407.941018) (xy 335.476852 -407.934988) (xy 335.480465 -407.921729)
			(xy 335.48066 -407.914856) (xy 335.48066 -407.628852) (xy 335.481145 -407.618745) (xy 335.488891 -407.600074)
			(xy 335.503187 -407.585782) (xy 335.521861 -407.578042) (xy 335.531968 -407.577544) (xy 336.248248 -407.577544)
			(xy 336.258353 -407.578045) (xy 336.277021 -407.585788) (xy 336.291312 -407.600079) (xy 336.299055 -407.618747)
			(xy 336.299556 -407.628852) (xy 336.299556 -407.914856) (xy 336.299758 -407.921729) (xy 336.303358 -407.934992)
			(xy 336.306668 -407.941018) (xy 336.323038 -407.969365) (xy 336.348839 -408.029525) (xy 336.366328 -408.092605)
			(xy 336.375187 -408.157463) (xy 336.375756 -408.190192) (xy 336.375202 -408.222922) (xy 336.366341 -408.28778)
			(xy 336.348847 -408.35086) (xy 336.323038 -408.411018) (xy 336.306668 -408.439366) (xy 336.303363 -408.445395)
			(xy 336.299752 -408.458656) (xy 336.299556 -408.465528) (xy 336.299556 -409.214828) (xy 336.29973 -409.221703)
			(xy 336.30335 -409.234966) (xy 336.306668 -409.24099) (xy 336.323027 -409.269343) (xy 336.348831 -409.329501)
			(xy 336.366323 -409.392579) (xy 336.375185 -409.457435) (xy 336.375756 -409.490164) (xy 336.375189 -409.522893)
			(xy 336.366332 -409.587751) (xy 336.348842 -409.650831) (xy 336.323036 -409.71099) (xy 336.306668 -409.739338)
			(xy 336.303338 -409.745355) (xy 336.299742 -409.758625) (xy 336.299556 -409.7655) (xy 336.299556 -410.051504)
			(xy 336.299019 -410.061606) (xy 336.291291 -410.080274) (xy 336.277011 -410.094566) (xy 336.25835 -410.102311)
			(xy 336.248248 -410.102812) (xy 335.531968 -410.102812) (xy 335.521859 -410.102341) (xy 335.503182 -410.094595)
			(xy 335.488889 -410.080294) (xy 335.481153 -410.061614) (xy 335.48066 -410.051504) (xy 335.48066 -409.7655)
			(xy 335.480473 -409.758626) (xy 335.476862 -409.745363) (xy 335.473548 -409.739338) (xy 335.457202 -409.710978)
			(xy 335.431394 -409.650823) (xy 335.413899 -409.587746) (xy 335.405033 -409.522892) (xy 335.40446 -409.490164)
			(xy 334.131753 -409.490164) (xy 334.122886 -409.510837) (xy 334.10652 -409.539186) (xy 334.103212 -409.545214)
			(xy 334.099602 -409.558475) (xy 334.099408 -409.565348) (xy 334.099408 -410.314648) (xy 334.099619 -410.32152)
			(xy 334.103214 -410.334783) (xy 334.10652 -410.34081) (xy 334.122891 -410.369156) (xy 334.148691 -410.429317)
			(xy 334.166179 -410.492397) (xy 334.175038 -410.557255) (xy 334.175608 -410.589984) (xy 334.175057 -410.622705)
			(xy 337.604954 -410.622705) (xy 337.604956 -410.557268) (xy 337.613741 -410.492423) (xy 337.631149 -410.429344)
			(xy 337.656866 -410.369172) (xy 337.673188 -410.34081) (xy 337.676498 -410.334783) (xy 337.680107 -410.321521)
			(xy 337.6803 -410.314648) (xy 337.6803 -409.565348) (xy 337.68009 -409.558476) (xy 337.676494 -409.545213)
			(xy 337.673188 -409.539186) (xy 337.656878 -409.510819) (xy 337.631162 -409.450648) (xy 337.613754 -409.387571)
			(xy 337.60497 -409.322728) (xy 337.604969 -409.257293) (xy 337.61375 -409.192449) (xy 337.631155 -409.129371)
			(xy 337.656868 -409.0692) (xy 337.673188 -409.040838) (xy 337.676488 -409.034806) (xy 337.680103 -409.021548)
			(xy 337.6803 -409.014676) (xy 337.6803 -408.728672) (xy 337.680699 -408.718516) (xy 337.688503 -408.699763)
			(xy 337.702907 -408.685441) (xy 337.721704 -408.677742) (xy 337.731862 -408.677364) (xy 338.448142 -408.677364)
			(xy 338.458274 -408.677793) (xy 338.477001 -408.685539) (xy 338.491357 -408.699843) (xy 338.49917 -408.718542)
			(xy 338.499704 -408.728672) (xy 338.499704 -409.014676) (xy 338.499905 -409.021549) (xy 338.503507 -409.034811)
			(xy 338.506816 -409.040838) (xy 338.52315 -409.069193) (xy 338.548869 -409.129365) (xy 338.566277 -409.192445)
			(xy 338.575061 -409.257291) (xy 338.575059 -409.322729) (xy 338.566273 -409.387575) (xy 338.548862 -409.450654)
			(xy 338.52314 -409.510825) (xy 338.516196 -409.522889) (xy 339.805084 -409.522889) (xy 339.805089 -409.45745)
			(xy 339.813877 -409.392603) (xy 339.831289 -409.329523) (xy 339.857011 -409.269351) (xy 339.873336 -409.24099)
			(xy 339.876649 -409.234965) (xy 339.880257 -409.221702) (xy 339.880448 -409.214828) (xy 339.880448 -408.465528)
			(xy 339.880252 -408.458655) (xy 339.876647 -408.445392) (xy 339.873336 -408.439366) (xy 339.857007 -408.411008)
			(xy 339.83129 -408.350836) (xy 339.813883 -408.287757) (xy 339.8051 -408.222912) (xy 339.805101 -408.157475)
			(xy 339.813886 -408.09263) (xy 339.831295 -408.029551) (xy 339.857013 -407.969379) (xy 339.873336 -407.941018)
			(xy 339.876639 -407.934988) (xy 339.880253 -407.921728) (xy 339.880448 -407.914856) (xy 339.880448 -407.628852)
			(xy 339.880881 -407.618701) (xy 339.888683 -407.599958) (xy 339.903075 -407.585638) (xy 339.921857 -407.577931)
			(xy 339.93201 -407.577544) (xy 340.64829 -407.577544) (xy 340.658417 -407.578035) (xy 340.677138 -407.58576)
			(xy 340.691495 -407.600045) (xy 340.699314 -407.618728) (xy 340.699852 -407.628852) (xy 340.699852 -407.914856)
			(xy 340.700054 -407.921729) (xy 340.703655 -407.934992) (xy 340.706964 -407.941018) (xy 340.723279 -407.969383)
			(xy 340.748997 -408.029553) (xy 340.766406 -408.092631) (xy 340.775191 -408.157475) (xy 340.775191 -408.222911)
			(xy 340.766409 -408.287755) (xy 340.749002 -408.350834) (xy 340.723286 -408.411005) (xy 340.706964 -408.439366)
			(xy 340.703666 -408.445399) (xy 340.700049 -408.458656) (xy 340.699852 -408.465528) (xy 340.699852 -409.214828)
			(xy 340.700027 -409.221703) (xy 340.703646 -409.234966) (xy 340.706964 -409.24099) (xy 340.723256 -409.269368)
			(xy 340.748976 -409.329535) (xy 340.766387 -409.392611) (xy 340.775175 -409.457452) (xy 340.775179 -409.522886)
			(xy 340.7664 -409.587729) (xy 340.748996 -409.650806) (xy 340.723284 -409.710977) (xy 340.706964 -409.739338)
			(xy 340.703641 -409.745359) (xy 340.70004 -409.758625) (xy 340.699852 -409.7655) (xy 340.699852 -410.051504)
			(xy 340.699383 -410.061652) (xy 340.691595 -410.080394) (xy 340.677214 -410.094716) (xy 340.65844 -410.102424)
			(xy 340.64829 -410.102812) (xy 339.93201 -410.102812) (xy 339.92189 -410.102267) (xy 339.903179 -410.094552)
			(xy 339.888824 -410.080284) (xy 339.880996 -410.061621) (xy 339.880448 -410.051504) (xy 339.880448 -409.7655)
			(xy 339.880263 -409.758626) (xy 339.876651 -409.745363) (xy 339.873336 -409.739338) (xy 339.856983 -409.710994)
			(xy 339.831269 -409.650818) (xy 339.813864 -409.587736) (xy 339.805084 -409.522889) (xy 338.516196 -409.522889)
			(xy 338.506816 -409.539186) (xy 338.503507 -409.545214) (xy 338.499898 -409.558475) (xy 338.499704 -409.565348)
			(xy 338.499704 -410.314648) (xy 338.499915 -410.32152) (xy 338.50351 -410.334783) (xy 338.506816 -410.34081)
			(xy 338.523126 -410.369178) (xy 338.548847 -410.429347) (xy 338.566259 -410.492425) (xy 338.575045 -410.557268)
			(xy 338.575045 -410.589984) (xy 342.004396 -410.589984) (xy 342.004978 -410.557255) (xy 342.013829 -410.492397)
			(xy 342.031315 -410.429317) (xy 342.057118 -410.369159) (xy 342.073484 -410.34081) (xy 342.076794 -410.334783)
			(xy 342.080403 -410.321521) (xy 342.080596 -410.314648) (xy 342.080596 -409.565348) (xy 342.080386 -409.558476)
			(xy 342.07679 -409.545213) (xy 342.073484 -409.539186) (xy 342.057111 -409.510841) (xy 342.031312 -409.45068)
			(xy 342.013824 -409.387599) (xy 342.004966 -409.322741) (xy 342.004396 -409.290012) (xy 342.004945 -409.257282)
			(xy 342.013806 -409.192423) (xy 342.031301 -409.129343) (xy 342.057113 -409.069185) (xy 342.073484 -409.040838)
			(xy 342.076784 -409.034806) (xy 342.080399 -409.021548) (xy 342.080596 -409.014676) (xy 342.080596 -408.728672)
			(xy 342.081062 -408.718562) (xy 342.088808 -408.699884) (xy 342.103111 -408.68559) (xy 342.121794 -408.677856)
			(xy 342.131904 -408.677364) (xy 342.848184 -408.677364) (xy 342.858287 -408.677897) (xy 342.876958 -408.685623)
			(xy 342.891252 -408.699905) (xy 342.898994 -408.718569) (xy 342.899492 -408.728672) (xy 342.899492 -409.014676)
			(xy 342.899694 -409.021548) (xy 342.903295 -409.034811) (xy 342.906604 -409.040838) (xy 342.922985 -409.069179)
			(xy 342.948783 -409.129341) (xy 342.966268 -409.192423) (xy 342.975124 -409.257282) (xy 342.975692 -409.290012)
			(xy 342.97511 -409.322741) (xy 342.966259 -409.387599) (xy 342.948774 -409.450679) (xy 342.92297 -409.510837)
			(xy 342.916012 -409.522889) (xy 344.204874 -409.522889) (xy 344.204878 -409.45745) (xy 344.213666 -409.392603)
			(xy 344.231078 -409.329523) (xy 344.2568 -409.269351) (xy 344.273124 -409.24099) (xy 344.276444 -409.234968)
			(xy 344.280046 -409.221702) (xy 344.280236 -409.214828) (xy 344.280236 -408.465528) (xy 344.280029 -408.458656)
			(xy 344.276431 -408.445393) (xy 344.273124 -408.439366) (xy 344.256795 -408.411008) (xy 344.231079 -408.350836)
			(xy 344.213672 -408.287757) (xy 344.20489 -408.222912) (xy 344.204891 -408.157475) (xy 344.213675 -408.09263)
			(xy 344.231084 -408.029551) (xy 344.256802 -407.969379) (xy 344.273124 -407.941018) (xy 344.276434 -407.934991)
			(xy 344.280042 -407.921729) (xy 344.280236 -407.914856) (xy 344.280236 -407.628852) (xy 344.280583 -407.61869)
			(xy 344.288401 -407.59993) (xy 344.302821 -407.585607) (xy 344.321634 -407.577916) (xy 344.331798 -407.577544)
			(xy 345.048078 -407.577544) (xy 345.058204 -407.578045) (xy 345.076925 -407.585766) (xy 345.091283 -407.600048)
			(xy 345.099102 -407.618729) (xy 345.09964 -407.628852) (xy 345.09964 -407.914856) (xy 345.099844 -407.921728)
			(xy 345.103443 -407.934991) (xy 345.106752 -407.941018) (xy 345.123068 -407.969383) (xy 345.148786 -408.029553)
			(xy 345.166196 -408.092631) (xy 345.17498 -408.157475) (xy 345.17498 -408.190192) (xy 348.603832 -408.190192)
			(xy 348.607823 -408.128025) (xy 348.619732 -408.066878) (xy 348.639361 -408.007757) (xy 348.66639 -407.951631)
			(xy 348.700374 -407.899422) (xy 348.740756 -407.851987) (xy 348.786872 -407.810106) (xy 348.837964 -407.774466)
			(xy 348.893195 -407.745652) (xy 348.951657 -407.724138) (xy 349.012391 -407.710276) (xy 349.074398 -407.704294)
			(xy 349.136661 -407.70629) (xy 349.198158 -407.716233) (xy 349.257879 -407.733957) (xy 349.314842 -407.759174)
			(xy 349.368113 -407.791467) (xy 349.416818 -407.830307) (xy 349.460155 -407.875057) (xy 349.497415 -407.924981)
			(xy 349.527984 -407.97926) (xy 349.551362 -408.037003) (xy 349.567163 -408.097261) (xy 349.575129 -408.159044)
			(xy 349.575628 -408.190192) (xy 349.575129 -408.22134) (xy 349.567163 -408.283123) (xy 349.551362 -408.343381)
			(xy 349.527984 -408.401124) (xy 349.497415 -408.455403) (xy 349.460155 -408.505327) (xy 349.416818 -408.550077)
			(xy 349.368113 -408.588917) (xy 349.314842 -408.62121) (xy 349.257879 -408.646427) (xy 349.198158 -408.664151)
			(xy 349.136661 -408.674094) (xy 349.074398 -408.67609) (xy 349.012391 -408.670108) (xy 348.951657 -408.656246)
			(xy 348.893195 -408.634732) (xy 348.837964 -408.605918) (xy 348.786872 -408.570278) (xy 348.740756 -408.528397)
			(xy 348.700374 -408.480962) (xy 348.66639 -408.428753) (xy 348.639361 -408.372627) (xy 348.619732 -408.313506)
			(xy 348.607823 -408.252359) (xy 348.603832 -408.190192) (xy 345.17498 -408.190192) (xy 345.174981 -408.222911)
			(xy 345.166198 -408.287755) (xy 345.148791 -408.350834) (xy 345.123074 -408.411005) (xy 345.106752 -408.439366)
			(xy 345.103453 -408.445399) (xy 345.099837 -408.458656) (xy 345.09964 -408.465528) (xy 345.09964 -409.214828)
			(xy 345.099816 -409.221702) (xy 345.103435 -409.234965) (xy 345.106752 -409.24099) (xy 345.123044 -409.269368)
			(xy 345.148765 -409.329535) (xy 345.166177 -409.39261) (xy 345.174964 -409.457452) (xy 345.174968 -409.522886)
			(xy 345.166189 -409.587729) (xy 345.148785 -409.650806) (xy 345.123072 -409.710977) (xy 345.106752 -409.739338)
			(xy 345.103428 -409.745358) (xy 345.099828 -409.758625) (xy 345.09964 -409.7655) (xy 345.09964 -410.051504)
			(xy 345.099182 -410.061653) (xy 345.091393 -410.080398) (xy 345.077008 -410.09472) (xy 345.058229 -410.102427)
			(xy 345.048078 -410.102812) (xy 344.331798 -410.102812) (xy 344.321678 -410.102277) (xy 344.302966 -410.094558)
			(xy 344.288612 -410.080287) (xy 344.280784 -410.061621) (xy 344.280236 -410.051504) (xy 344.280236 -409.7655)
			(xy 344.28004 -409.758627) (xy 344.276434 -409.745365) (xy 344.273124 -409.739338) (xy 344.256772 -409.710993)
			(xy 344.231058 -409.650818) (xy 344.213654 -409.587736) (xy 344.204874 -409.522889) (xy 342.916012 -409.522889)
			(xy 342.906604 -409.539186) (xy 342.903295 -409.545213) (xy 342.899685 -409.558475) (xy 342.899492 -409.565348)
			(xy 342.899492 -410.314648) (xy 342.899705 -410.32152) (xy 342.903299 -410.334782) (xy 342.906604 -410.34081)
			(xy 342.922974 -410.369157) (xy 342.948775 -410.429317) (xy 342.966263 -410.492397) (xy 342.975122 -410.557255)
			(xy 342.975692 -410.589984) (xy 342.975142 -410.622705) (xy 346.405027 -410.622705) (xy 346.405029 -410.557267)
			(xy 346.413815 -410.492421) (xy 346.431226 -410.429342) (xy 346.456948 -410.369171) (xy 346.473272 -410.34081)
			(xy 346.476581 -410.334783) (xy 346.480191 -410.321521) (xy 346.480384 -410.314648) (xy 346.480384 -409.565348)
			(xy 346.480176 -409.558476) (xy 346.476579 -409.545213) (xy 346.473272 -409.539186) (xy 346.456959 -409.510819)
			(xy 346.431239 -409.45065) (xy 346.413828 -409.387572) (xy 346.405043 -409.322728) (xy 346.405041 -409.257292)
			(xy 346.413824 -409.192448) (xy 346.431232 -409.12937) (xy 346.45695 -409.069199) (xy 346.473272 -409.040838)
			(xy 346.476571 -409.034806) (xy 346.480187 -409.021548) (xy 346.480384 -409.014676) (xy 346.480384 -408.728672)
			(xy 346.480798 -408.718518) (xy 346.4886 -408.699768) (xy 346.502999 -408.685446) (xy 346.52179 -408.677745)
			(xy 346.531946 -408.677364) (xy 347.248226 -408.677364) (xy 347.258357 -408.677806) (xy 347.277084 -408.685547)
			(xy 347.29144 -408.699847) (xy 347.299254 -408.718543) (xy 347.299788 -408.728672) (xy 347.299788 -409.014676)
			(xy 347.29999 -409.021548) (xy 347.303592 -409.034811) (xy 347.3069 -409.040838) (xy 347.323231 -409.069194)
			(xy 347.348946 -409.129367) (xy 347.366351 -409.192447) (xy 347.375133 -409.257292) (xy 347.375132 -409.322729)
			(xy 347.366347 -409.387574) (xy 347.348939 -409.450653) (xy 347.332052 -409.490164) (xy 348.603832 -409.490164)
			(xy 348.607823 -409.427997) (xy 348.619732 -409.36685) (xy 348.639361 -409.307729) (xy 348.66639 -409.251603)
			(xy 348.700374 -409.199394) (xy 348.740756 -409.151959) (xy 348.786872 -409.110078) (xy 348.837964 -409.074438)
			(xy 348.893195 -409.045624) (xy 348.951657 -409.02411) (xy 349.012391 -409.010248) (xy 349.074398 -409.004266)
			(xy 349.136661 -409.006262) (xy 349.198158 -409.016205) (xy 349.257879 -409.033929) (xy 349.314842 -409.059146)
			(xy 349.368113 -409.091439) (xy 349.416818 -409.130279) (xy 349.460155 -409.175029) (xy 349.497415 -409.224953)
			(xy 349.527984 -409.279232) (xy 349.532348 -409.290012) (xy 350.80398 -409.290012) (xy 350.807971 -409.227845)
			(xy 350.81988 -409.166698) (xy 350.839509 -409.107577) (xy 350.866538 -409.051451) (xy 350.900522 -408.999242)
			(xy 350.940904 -408.951807) (xy 350.98702 -408.909926) (xy 351.038112 -408.874286) (xy 351.093343 -408.845472)
			(xy 351.151805 -408.823958) (xy 351.212539 -408.810096) (xy 351.274546 -408.804114) (xy 351.336809 -408.80611)
			(xy 351.398306 -408.816053) (xy 351.458027 -408.833777) (xy 351.51499 -408.858994) (xy 351.568261 -408.891287)
			(xy 351.616966 -408.930127) (xy 351.660303 -408.974877) (xy 351.697563 -409.024801) (xy 351.728132 -409.07908)
			(xy 351.75151 -409.136823) (xy 351.767311 -409.197081) (xy 351.775277 -409.258864) (xy 351.775776 -409.290012)
			(xy 351.775277 -409.32116) (xy 351.767311 -409.382943) (xy 351.75151 -409.443201) (xy 351.728132 -409.500944)
			(xy 351.715773 -409.522889) (xy 375.004909 -409.522889) (xy 375.004913 -409.457449) (xy 375.013701 -409.392603)
			(xy 375.031115 -409.329523) (xy 375.056839 -409.269351) (xy 375.073164 -409.24099) (xy 375.076479 -409.234966)
			(xy 375.080085 -409.221702) (xy 375.080276 -409.214828) (xy 375.080276 -408.465528) (xy 375.080076 -408.458655)
			(xy 375.076474 -408.445392) (xy 375.073164 -408.439366) (xy 375.056834 -408.411009) (xy 375.031116 -408.350837)
			(xy 375.013708 -408.287757) (xy 375.004924 -408.222912) (xy 375.004925 -408.157474) (xy 375.01371 -408.092629)
			(xy 375.03112 -408.02955) (xy 375.05684 -407.969379) (xy 375.073164 -407.941018) (xy 375.076469 -407.934989)
			(xy 375.080081 -407.921729) (xy 375.080276 -407.914856) (xy 375.080276 -407.628852) (xy 375.080682 -407.618698)
			(xy 375.088489 -407.599949) (xy 375.10289 -407.585628) (xy 375.121682 -407.577926) (xy 375.131838 -407.577544)
			(xy 375.848118 -407.577544) (xy 375.858246 -407.578012) (xy 375.876969 -407.585746) (xy 375.891325 -407.600038)
			(xy 375.899143 -407.618726) (xy 375.89968 -407.628852) (xy 375.89968 -407.914856) (xy 375.899891 -407.921728)
			(xy 375.903486 -407.934991) (xy 375.906792 -407.941018) (xy 375.923106 -407.969383) (xy 375.948823 -408.029554)
			(xy 375.966231 -408.092632) (xy 375.975015 -408.157475) (xy 375.975016 -408.222911) (xy 375.966234 -408.287755)
			(xy 375.948828 -408.350833) (xy 375.923113 -408.411004) (xy 375.906792 -408.439366) (xy 375.903489 -408.445396)
			(xy 375.899876 -408.458656) (xy 375.89968 -408.465528) (xy 375.89968 -409.214828) (xy 375.899864 -409.221702)
			(xy 375.903478 -409.234964) (xy 375.906792 -409.24099) (xy 375.923083 -409.269368) (xy 375.948802 -409.329536)
			(xy 375.966212 -409.392611) (xy 375.974999 -409.457452) (xy 375.975003 -409.522886) (xy 375.966224 -409.587728)
			(xy 375.948822 -409.650806) (xy 375.923111 -409.710976) (xy 375.906792 -409.739338) (xy 375.903463 -409.745356)
			(xy 375.899867 -409.758625) (xy 375.89968 -409.7655) (xy 375.89968 -410.051504) (xy 375.899281 -410.061661)
			(xy 375.891481 -410.080417) (xy 375.877077 -410.094741) (xy 375.858277 -410.102437) (xy 375.848118 -410.102812)
			(xy 375.131838 -410.102812) (xy 375.12172 -410.102244) (xy 375.10301 -410.094538) (xy 375.088654 -410.080277)
			(xy 375.080824 -410.061618) (xy 375.080276 -410.051504) (xy 375.080276 -409.7655) (xy 375.080087 -409.758627)
			(xy 375.076477 -409.745364) (xy 375.073164 -409.739338) (xy 375.05681 -409.710994) (xy 375.031094 -409.650819)
			(xy 375.013689 -409.587737) (xy 375.004909 -409.522889) (xy 351.715773 -409.522889) (xy 351.697563 -409.555223)
			(xy 351.660303 -409.605147) (xy 351.616966 -409.649897) (xy 351.568261 -409.688737) (xy 351.51499 -409.72103)
			(xy 351.458027 -409.746247) (xy 351.398306 -409.763971) (xy 351.336809 -409.773914) (xy 351.274546 -409.77591)
			(xy 351.212539 -409.769928) (xy 351.151805 -409.756066) (xy 351.093343 -409.734552) (xy 351.038112 -409.705738)
			(xy 350.98702 -409.670098) (xy 350.940904 -409.628217) (xy 350.900522 -409.580782) (xy 350.866538 -409.528573)
			(xy 350.839509 -409.472447) (xy 350.81988 -409.413326) (xy 350.807971 -409.352179) (xy 350.80398 -409.290012)
			(xy 349.532348 -409.290012) (xy 349.551362 -409.336975) (xy 349.567163 -409.397233) (xy 349.575129 -409.459016)
			(xy 349.575628 -409.490164) (xy 349.575129 -409.521312) (xy 349.567163 -409.583095) (xy 349.551362 -409.643353)
			(xy 349.527984 -409.701096) (xy 349.497415 -409.755375) (xy 349.460155 -409.805299) (xy 349.416818 -409.850049)
			(xy 349.368113 -409.888889) (xy 349.314842 -409.921182) (xy 349.257879 -409.946399) (xy 349.198158 -409.964123)
			(xy 349.136661 -409.974066) (xy 349.074398 -409.976062) (xy 349.012391 -409.97008) (xy 348.951657 -409.956218)
			(xy 348.893195 -409.934704) (xy 348.837964 -409.90589) (xy 348.786872 -409.87025) (xy 348.740756 -409.828369)
			(xy 348.700374 -409.780934) (xy 348.66639 -409.728725) (xy 348.639361 -409.672599) (xy 348.619732 -409.613478)
			(xy 348.607823 -409.552331) (xy 348.603832 -409.490164) (xy 347.332052 -409.490164) (xy 347.323222 -409.510824)
			(xy 347.3069 -409.539186) (xy 347.30359 -409.545213) (xy 347.299981 -409.558475) (xy 347.299788 -409.565348)
			(xy 347.299788 -410.314648) (xy 347.300002 -410.32152) (xy 347.303595 -410.334782) (xy 347.3069 -410.34081)
			(xy 347.323207 -410.369179) (xy 347.348924 -410.429349) (xy 347.366332 -410.492426) (xy 347.375117 -410.557269)
			(xy 347.375118 -410.589984) (xy 350.80398 -410.589984) (xy 350.807971 -410.527817) (xy 350.81988 -410.46667)
			(xy 350.839509 -410.407549) (xy 350.866538 -410.351423) (xy 350.900522 -410.299214) (xy 350.940904 -410.251779)
			(xy 350.98702 -410.209898) (xy 351.038112 -410.174258) (xy 351.093343 -410.145444) (xy 351.151805 -410.12393)
			(xy 351.212539 -410.110068) (xy 351.274546 -410.104086) (xy 351.336809 -410.106082) (xy 351.398306 -410.116025)
			(xy 351.458027 -410.133749) (xy 351.51499 -410.158966) (xy 351.568261 -410.191259) (xy 351.616966 -410.230099)
			(xy 351.660303 -410.274849) (xy 351.697563 -410.324773) (xy 351.728132 -410.379052) (xy 351.75151 -410.436795)
			(xy 351.767311 -410.497053) (xy 351.775277 -410.558836) (xy 351.775776 -410.589984) (xy 377.204224 -410.589984)
			(xy 377.204802 -410.557255) (xy 377.213653 -410.492397) (xy 377.23114 -410.429317) (xy 377.256945 -410.369158)
			(xy 377.273312 -410.34081) (xy 377.276624 -410.334784) (xy 377.280231 -410.321521) (xy 377.280424 -410.314648)
			(xy 377.280424 -409.565348) (xy 377.280211 -409.558476) (xy 377.276617 -409.545214) (xy 377.273312 -409.539186)
			(xy 377.256942 -409.510839) (xy 377.231141 -409.450679) (xy 377.213653 -409.387599) (xy 377.204794 -409.322741)
			(xy 377.204224 -409.290012) (xy 377.20477 -409.257282) (xy 377.213631 -409.192423) (xy 377.231127 -409.129342)
			(xy 377.256941 -409.069185) (xy 377.273312 -409.040838) (xy 377.276614 -409.034807) (xy 377.280227 -409.021548)
			(xy 377.280424 -409.014676) (xy 377.280424 -408.728672) (xy 377.280794 -408.718545) (xy 377.288555 -408.699836)
			(xy 377.302886 -408.685522) (xy 377.321604 -408.677782) (xy 377.331732 -408.677364) (xy 378.048012 -408.677364)
			(xy 378.058117 -408.677875) (xy 378.076789 -408.685609) (xy 378.091082 -408.699898) (xy 378.098822 -408.718567)
			(xy 378.09932 -408.728672) (xy 378.09932 -409.014676) (xy 378.099519 -409.021549) (xy 378.103122 -409.034812)
			(xy 378.106432 -409.040838) (xy 378.122806 -409.069183) (xy 378.148607 -409.129343) (xy 378.166095 -409.192424)
			(xy 378.174952 -409.257283) (xy 378.17552 -409.290012) (xy 378.174934 -409.322741) (xy 378.166084 -409.387598)
			(xy 378.148599 -409.450678) (xy 378.131664 -409.490164) (xy 379.404372 -409.490164) (xy 379.404948 -409.457435)
			(xy 379.413801 -409.392577) (xy 379.431289 -409.329497) (xy 379.457093 -409.269339) (xy 379.47346 -409.24099)
			(xy 379.476775 -409.234965) (xy 379.480381 -409.221702) (xy 379.480572 -409.214828) (xy 379.480572 -408.465528)
			(xy 379.480373 -408.458655) (xy 379.47677 -408.445392) (xy 379.47346 -408.439366) (xy 379.457087 -408.411021)
			(xy 379.431285 -408.35086) (xy 379.413798 -408.287779) (xy 379.40494 -408.222921) (xy 379.404372 -408.190192)
			(xy 379.404961 -408.157463) (xy 379.41381 -408.092606) (xy 379.431294 -408.029526) (xy 379.457095 -407.969367)
			(xy 379.47346 -407.941018) (xy 379.476765 -407.934989) (xy 379.480377 -407.921729) (xy 379.480572 -407.914856)
			(xy 379.480572 -407.628852) (xy 379.481045 -407.618744) (xy 379.488793 -407.60007) (xy 379.503093 -407.585778)
			(xy 379.521771 -407.57804) (xy 379.53188 -407.577544) (xy 380.24816 -407.577544) (xy 380.258259 -407.578117)
			(xy 380.276926 -407.585831) (xy 380.29122 -407.6001) (xy 380.298966 -407.618754) (xy 380.299468 -407.628852)
			(xy 380.299468 -407.914856) (xy 380.299681 -407.921728) (xy 380.303275 -407.93499) (xy 380.30658 -407.941018)
			(xy 380.322951 -407.969364) (xy 380.348752 -408.029525) (xy 380.36624 -408.092605) (xy 380.375099 -408.157463)
			(xy 380.375668 -408.190192) (xy 380.375112 -408.222922) (xy 380.366252 -408.28778) (xy 380.348758 -408.35086)
			(xy 380.322949 -408.411018) (xy 380.30658 -408.439366) (xy 380.303276 -408.445396) (xy 380.299664 -408.458656)
			(xy 380.299468 -408.465528) (xy 380.299468 -409.214828) (xy 380.299653 -409.221702) (xy 380.303267 -409.234964)
			(xy 380.30658 -409.24099) (xy 380.32294 -409.269343) (xy 380.348743 -409.329501) (xy 380.366235 -409.392579)
			(xy 380.375097 -409.457435) (xy 380.375668 -409.490164) (xy 380.375099 -409.522893) (xy 380.366243 -409.587751)
			(xy 380.348753 -409.650831) (xy 380.322948 -409.71099) (xy 380.30658 -409.739338) (xy 380.30325 -409.745355)
			(xy 380.299654 -409.758625) (xy 380.299468 -409.7655) (xy 380.299468 -410.051504) (xy 380.299086 -410.061631)
			(xy 380.291331 -410.08034) (xy 380.277003 -410.094656) (xy 380.258287 -410.102395) (xy 380.24816 -410.102812)
			(xy 379.53188 -410.102812) (xy 379.521771 -410.102332) (xy 379.503095 -410.09459) (xy 379.488801 -410.080292)
			(xy 379.481065 -410.061613) (xy 379.480572 -410.051504) (xy 379.480572 -409.7655) (xy 379.480383 -409.758626)
			(xy 379.476773 -409.745364) (xy 379.47346 -409.739338) (xy 379.457115 -409.710977) (xy 379.431307 -409.650822)
			(xy 379.413811 -409.587746) (xy 379.404945 -409.522892) (xy 379.404372 -409.490164) (xy 378.131664 -409.490164)
			(xy 378.122798 -409.510837) (xy 378.106432 -409.539186) (xy 378.103125 -409.545214) (xy 378.099514 -409.558475)
			(xy 378.09932 -409.565348) (xy 378.09932 -410.314648) (xy 378.099529 -410.32152) (xy 378.103126 -410.334783)
			(xy 378.106432 -410.34081) (xy 378.122795 -410.369161) (xy 378.148599 -410.429319) (xy 378.16609 -410.492398)
			(xy 378.17495 -410.557255) (xy 378.17552 -410.589984) (xy 378.174967 -410.622705) (xy 381.604865 -410.622705)
			(xy 381.604867 -410.557268) (xy 381.613651 -410.492423) (xy 381.63106 -410.429343) (xy 381.656778 -410.369172)
			(xy 381.6731 -410.34081) (xy 381.676411 -410.334784) (xy 381.680019 -410.321521) (xy 381.680212 -410.314648)
			(xy 381.680212 -409.565348) (xy 381.68 -409.558476) (xy 381.676405 -409.545214) (xy 381.6731 -409.539186)
			(xy 381.656789 -409.510819) (xy 381.631073 -409.450649) (xy 381.613665 -409.387571) (xy 381.604881 -409.322728)
			(xy 381.604879 -409.257293) (xy 381.613661 -409.192449) (xy 381.631066 -409.129371) (xy 381.65678 -409.0692)
			(xy 381.6731 -409.040838) (xy 381.676401 -409.034807) (xy 381.680015 -409.021548) (xy 381.680212 -409.014676)
			(xy 381.680212 -408.728672) (xy 381.680599 -408.718515) (xy 381.688406 -408.699759) (xy 381.702813 -408.685436)
			(xy 381.721614 -408.67774) (xy 381.731774 -408.677364) (xy 382.448054 -408.677364) (xy 382.458181 -408.677865)
			(xy 382.476905 -408.685582) (xy 382.491264 -408.699865) (xy 382.499081 -408.718548) (xy 382.499616 -408.728672)
			(xy 382.499616 -409.014676) (xy 382.499815 -409.021549) (xy 382.503418 -409.034812) (xy 382.506728 -409.040838)
			(xy 382.523061 -409.069193) (xy 382.54878 -409.129365) (xy 382.566188 -409.192445) (xy 382.574971 -409.257291)
			(xy 382.57497 -409.322729) (xy 382.566184 -409.387575) (xy 382.548773 -409.450654) (xy 382.523052 -409.510825)
			(xy 382.516108 -409.522889) (xy 383.804995 -409.522889) (xy 383.804999 -409.457449) (xy 383.813787 -409.392603)
			(xy 383.8312 -409.329523) (xy 383.856923 -409.269351) (xy 383.873248 -409.24099) (xy 383.876562 -409.234965)
			(xy 383.880169 -409.221702) (xy 383.88036 -409.214828) (xy 383.88036 -408.465528) (xy 383.880162 -408.458655)
			(xy 383.876559 -408.445392) (xy 383.873248 -408.439366) (xy 383.856919 -408.411009) (xy 383.831201 -408.350837)
			(xy 383.813794 -408.287757) (xy 383.805011 -408.222912) (xy 383.805012 -408.157474) (xy 383.813796 -408.092629)
			(xy 383.831206 -408.02955) (xy 383.856925 -407.969379) (xy 383.873248 -407.941018) (xy 383.876552 -407.934988)
			(xy 383.880165 -407.921729) (xy 383.88036 -407.914856) (xy 383.88036 -407.628852) (xy 383.880782 -407.6187)
			(xy 383.888586 -407.599954) (xy 383.902981 -407.585634) (xy 383.921768 -407.577929) (xy 383.931922 -407.577544)
			(xy 384.648202 -407.577544) (xy 384.658329 -407.578025) (xy 384.677051 -407.585754) (xy 384.691408 -407.600042)
			(xy 384.699226 -407.618727) (xy 384.699764 -407.628852) (xy 384.699764 -407.914856) (xy 384.699977 -407.921728)
			(xy 384.703571 -407.93499) (xy 384.706876 -407.941018) (xy 384.723191 -407.969383) (xy 384.748908 -408.029554)
			(xy 384.766317 -408.092631) (xy 384.775101 -408.157475) (xy 384.775102 -408.222911) (xy 384.76632 -408.287755)
			(xy 384.748913 -408.350833) (xy 384.723197 -408.411005) (xy 384.706876 -408.439366) (xy 384.703572 -408.445396)
			(xy 384.69996 -408.458656) (xy 384.699764 -408.465528) (xy 384.699764 -409.214828) (xy 384.69995 -409.221702)
			(xy 384.703563 -409.234964) (xy 384.706876 -409.24099) (xy 384.723167 -409.269368) (xy 384.748887 -409.329536)
			(xy 384.766298 -409.392611) (xy 384.775085 -409.457452) (xy 384.775089 -409.522886) (xy 384.76631 -409.587729)
			(xy 384.748907 -409.650806) (xy 384.723195 -409.710977) (xy 384.706876 -409.739338) (xy 384.703546 -409.745355)
			(xy 384.69995 -409.758625) (xy 384.699764 -409.7655) (xy 384.699764 -410.051504) (xy 384.699381 -410.061663)
			(xy 384.691577 -410.080422) (xy 384.677168 -410.094747) (xy 384.658363 -410.10244) (xy 384.648202 -410.102812)
			(xy 383.931922 -410.102812) (xy 383.921803 -410.102257) (xy 383.903092 -410.094546) (xy 383.888737 -410.080281)
			(xy 383.880908 -410.06162) (xy 383.88036 -410.051504) (xy 383.88036 -409.7655) (xy 383.880173 -409.758626)
			(xy 383.876562 -409.745363) (xy 383.873248 -409.739338) (xy 383.856895 -409.710994) (xy 383.83118 -409.650819)
			(xy 383.813775 -409.587736) (xy 383.804995 -409.522889) (xy 382.516108 -409.522889) (xy 382.506728 -409.539186)
			(xy 382.50342 -409.545214) (xy 382.49981 -409.558475) (xy 382.499616 -409.565348) (xy 382.499616 -410.314648)
			(xy 382.499826 -410.32152) (xy 382.503422 -410.334783) (xy 382.506728 -410.34081) (xy 382.523038 -410.369178)
			(xy 382.548758 -410.429348) (xy 382.566169 -410.492425) (xy 382.574955 -410.557268) (xy 382.574956 -410.589984)
			(xy 386.004308 -410.589984) (xy 386.004888 -410.557255) (xy 386.013739 -410.492397) (xy 386.031225 -410.429317)
			(xy 386.057029 -410.369158) (xy 386.073396 -410.34081) (xy 386.076707 -410.334783) (xy 386.080315 -410.321521)
			(xy 386.080508 -410.314648) (xy 386.080508 -409.565348) (xy 386.080296 -409.558476) (xy 386.076701 -409.545214)
			(xy 386.073396 -409.539186) (xy 386.057024 -409.51084) (xy 386.031224 -409.450679) (xy 386.013736 -409.387599)
			(xy 386.004878 -409.322741) (xy 386.004308 -409.290012) (xy 386.004856 -409.257282) (xy 386.013717 -409.192423)
			(xy 386.031212 -409.129343) (xy 386.057025 -409.069185) (xy 386.073396 -409.040838) (xy 386.076697 -409.034807)
			(xy 386.080311 -409.021548) (xy 386.080508 -409.014676) (xy 386.080508 -408.728672) (xy 386.080962 -408.71856)
			(xy 386.088711 -408.69988) (xy 386.103017 -408.685586) (xy 386.121704 -408.677854) (xy 386.131816 -408.677364)
			(xy 386.848096 -408.677364) (xy 386.8582 -408.677888) (xy 386.876871 -408.685617) (xy 386.891165 -408.699902)
			(xy 386.898906 -408.718568) (xy 386.899404 -408.728672) (xy 386.899404 -409.014676) (xy 386.899605 -409.021549)
			(xy 386.903207 -409.034811) (xy 386.906516 -409.040838) (xy 386.922898 -409.069178) (xy 386.948696 -409.129341)
			(xy 386.966181 -409.192423) (xy 386.975036 -409.257282) (xy 386.975604 -409.290012) (xy 386.975021 -409.322741)
			(xy 386.96617 -409.387598) (xy 386.948685 -409.450679) (xy 386.922882 -409.510837) (xy 386.915924 -409.522889)
			(xy 388.204784 -409.522889) (xy 388.204789 -409.45745) (xy 388.213577 -409.392603) (xy 388.230989 -409.329523)
			(xy 388.256711 -409.269351) (xy 388.273036 -409.24099) (xy 388.276349 -409.234965) (xy 388.279957 -409.221702)
			(xy 388.280148 -409.214828) (xy 388.280148 -408.465528) (xy 388.279952 -408.458655) (xy 388.276347 -408.445392)
			(xy 388.273036 -408.439366) (xy 388.256707 -408.411008) (xy 388.23099 -408.350836) (xy 388.213583 -408.287757)
			(xy 388.2048 -408.222912) (xy 388.204801 -408.157475) (xy 388.213586 -408.09263) (xy 388.230995 -408.029551)
			(xy 388.256713 -407.969379) (xy 388.273036 -407.941018) (xy 388.276339 -407.934988) (xy 388.279953 -407.921728)
			(xy 388.280148 -407.914856) (xy 388.280148 -407.628852) (xy 388.280581 -407.618701) (xy 388.288383 -407.599958)
			(xy 388.302775 -407.585638) (xy 388.321557 -407.577931) (xy 388.33171 -407.577544) (xy 389.04799 -407.577544)
			(xy 389.058117 -407.578035) (xy 389.076838 -407.58576) (xy 389.091195 -407.600045) (xy 389.099014 -407.618728)
			(xy 389.099552 -407.628852) (xy 389.099552 -407.914856) (xy 389.099754 -407.921729) (xy 389.103355 -407.934992)
			(xy 389.106664 -407.941018) (xy 389.122979 -407.969383) (xy 389.148697 -408.029553) (xy 389.166106 -408.092631)
			(xy 389.174891 -408.157475) (xy 389.174891 -408.190192) (xy 392.603744 -408.190192) (xy 392.607735 -408.128025)
			(xy 392.619644 -408.066878) (xy 392.639273 -408.007757) (xy 392.666302 -407.951631) (xy 392.700286 -407.899422)
			(xy 392.740668 -407.851987) (xy 392.786784 -407.810106) (xy 392.837876 -407.774466) (xy 392.893107 -407.745652)
			(xy 392.951569 -407.724138) (xy 393.012303 -407.710276) (xy 393.07431 -407.704294) (xy 393.136573 -407.70629)
			(xy 393.19807 -407.716233) (xy 393.257791 -407.733957) (xy 393.314754 -407.759174) (xy 393.368025 -407.791467)
			(xy 393.41673 -407.830307) (xy 393.460067 -407.875057) (xy 393.497327 -407.924981) (xy 393.527896 -407.97926)
			(xy 393.551274 -408.037003) (xy 393.567075 -408.097261) (xy 393.575041 -408.159044) (xy 393.57554 -408.190192)
			(xy 393.575041 -408.22134) (xy 393.567075 -408.283123) (xy 393.551274 -408.343381) (xy 393.527896 -408.401124)
			(xy 393.497327 -408.455403) (xy 393.460067 -408.505327) (xy 393.41673 -408.550077) (xy 393.368025 -408.588917)
			(xy 393.314754 -408.62121) (xy 393.257791 -408.646427) (xy 393.19807 -408.664151) (xy 393.136573 -408.674094)
			(xy 393.07431 -408.67609) (xy 393.012303 -408.670108) (xy 392.951569 -408.656246) (xy 392.893107 -408.634732)
			(xy 392.837876 -408.605918) (xy 392.786784 -408.570278) (xy 392.740668 -408.528397) (xy 392.700286 -408.480962)
			(xy 392.666302 -408.428753) (xy 392.639273 -408.372627) (xy 392.619644 -408.313506) (xy 392.607735 -408.252359)
			(xy 392.603744 -408.190192) (xy 389.174891 -408.190192) (xy 389.174891 -408.222911) (xy 389.166109 -408.287755)
			(xy 389.148702 -408.350834) (xy 389.122986 -408.411005) (xy 389.106664 -408.439366) (xy 389.103366 -408.445399)
			(xy 389.099749 -408.458656) (xy 389.099552 -408.465528) (xy 389.099552 -409.214828) (xy 389.099727 -409.221703)
			(xy 389.103346 -409.234966) (xy 389.106664 -409.24099) (xy 389.122956 -409.269368) (xy 389.148676 -409.329535)
			(xy 389.166087 -409.392611) (xy 389.174875 -409.457452) (xy 389.174879 -409.522886) (xy 389.1661 -409.587729)
			(xy 389.148696 -409.650806) (xy 389.122984 -409.710977) (xy 389.106664 -409.739338) (xy 389.103341 -409.745359)
			(xy 389.09974 -409.758625) (xy 389.099552 -409.7655) (xy 389.099552 -410.051504) (xy 389.099083 -410.061652)
			(xy 389.091295 -410.080394) (xy 389.076914 -410.094716) (xy 389.05814 -410.102424) (xy 389.04799 -410.102812)
			(xy 388.33171 -410.102812) (xy 388.32159 -410.102267) (xy 388.302879 -410.094552) (xy 388.288524 -410.080284)
			(xy 388.280696 -410.061621) (xy 388.280148 -410.051504) (xy 388.280148 -409.7655) (xy 388.279963 -409.758626)
			(xy 388.276351 -409.745363) (xy 388.273036 -409.739338) (xy 388.256683 -409.710994) (xy 388.230969 -409.650818)
			(xy 388.213564 -409.587736) (xy 388.204784 -409.522889) (xy 386.915924 -409.522889) (xy 386.906516 -409.539186)
			(xy 386.903207 -409.545214) (xy 386.899598 -409.558475) (xy 386.899404 -409.565348) (xy 386.899404 -410.314648)
			(xy 386.899615 -410.32152) (xy 386.90321 -410.334783) (xy 386.906516 -410.34081) (xy 386.922887 -410.369156)
			(xy 386.948687 -410.429317) (xy 386.966175 -410.492397) (xy 386.975034 -410.557255) (xy 386.975604 -410.589984)
			(xy 386.975053 -410.622705) (xy 390.404937 -410.622705) (xy 390.404939 -410.557267) (xy 390.413725 -410.492421)
			(xy 390.431137 -410.429342) (xy 390.456859 -410.369171) (xy 390.473184 -410.34081) (xy 390.476494 -410.334783)
			(xy 390.480103 -410.321521) (xy 390.480296 -410.314648) (xy 390.480296 -409.565348) (xy 390.480086 -409.558476)
			(xy 390.47649 -409.545213) (xy 390.473184 -409.539186) (xy 390.456871 -409.51082) (xy 390.43115 -409.45065)
			(xy 390.413739 -409.387572) (xy 390.404953 -409.322729) (xy 390.404952 -409.257292) (xy 390.413735 -409.192448)
			(xy 390.431143 -409.129369) (xy 390.456861 -409.069199) (xy 390.473184 -409.040838) (xy 390.476484 -409.034806)
			(xy 390.480099 -409.021548) (xy 390.480296 -409.014676) (xy 390.480296 -408.728672) (xy 390.480699 -408.718517)
			(xy 390.488503 -408.699764) (xy 390.502905 -408.685442) (xy 390.5217 -408.677743) (xy 390.531858 -408.677364)
			(xy 391.248138 -408.677364) (xy 391.25827 -408.677796) (xy 391.276997 -408.685541) (xy 391.291352 -408.699844)
			(xy 391.299166 -408.718542) (xy 391.2997 -408.728672) (xy 391.2997 -409.014676) (xy 391.299901 -409.021549)
			(xy 391.303503 -409.034811) (xy 391.306812 -409.040838) (xy 391.323143 -409.069194) (xy 391.348857 -409.129367)
			(xy 391.366262 -409.192447) (xy 391.375043 -409.257292) (xy 391.375042 -409.322729) (xy 391.366258 -409.387573)
			(xy 391.34885 -409.450652) (xy 391.331963 -409.490164) (xy 392.603744 -409.490164) (xy 392.607735 -409.427997)
			(xy 392.619644 -409.36685) (xy 392.639273 -409.307729) (xy 392.666302 -409.251603) (xy 392.700286 -409.199394)
			(xy 392.740668 -409.151959) (xy 392.786784 -409.110078) (xy 392.837876 -409.074438) (xy 392.893107 -409.045624)
			(xy 392.951569 -409.02411) (xy 393.012303 -409.010248) (xy 393.07431 -409.004266) (xy 393.136573 -409.006262)
			(xy 393.19807 -409.016205) (xy 393.257791 -409.033929) (xy 393.314754 -409.059146) (xy 393.368025 -409.091439)
			(xy 393.41673 -409.130279) (xy 393.460067 -409.175029) (xy 393.497327 -409.224953) (xy 393.527896 -409.279232)
			(xy 393.53226 -409.290012) (xy 394.803892 -409.290012) (xy 394.807883 -409.227845) (xy 394.819792 -409.166698)
			(xy 394.839421 -409.107577) (xy 394.86645 -409.051451) (xy 394.900434 -408.999242) (xy 394.940816 -408.951807)
			(xy 394.986932 -408.909926) (xy 395.038024 -408.874286) (xy 395.093255 -408.845472) (xy 395.151717 -408.823958)
			(xy 395.212451 -408.810096) (xy 395.274458 -408.804114) (xy 395.336721 -408.80611) (xy 395.398218 -408.816053)
			(xy 395.457939 -408.833777) (xy 395.514902 -408.858994) (xy 395.568173 -408.891287) (xy 395.616878 -408.930127)
			(xy 395.660215 -408.974877) (xy 395.697475 -409.024801) (xy 395.728044 -409.07908) (xy 395.751422 -409.136823)
			(xy 395.767223 -409.197081) (xy 395.775189 -409.258864) (xy 395.775688 -409.290012) (xy 395.775189 -409.32116)
			(xy 395.767223 -409.382943) (xy 395.751422 -409.443201) (xy 395.728044 -409.500944) (xy 395.697475 -409.555223)
			(xy 395.660215 -409.605147) (xy 395.616878 -409.649897) (xy 395.568173 -409.688737) (xy 395.514902 -409.72103)
			(xy 395.457939 -409.746247) (xy 395.398218 -409.763971) (xy 395.336721 -409.773914) (xy 395.274458 -409.77591)
			(xy 395.212451 -409.769928) (xy 395.151717 -409.756066) (xy 395.093255 -409.734552) (xy 395.038024 -409.705738)
			(xy 394.986932 -409.670098) (xy 394.940816 -409.628217) (xy 394.900434 -409.580782) (xy 394.86645 -409.528573)
			(xy 394.839421 -409.472447) (xy 394.819792 -409.413326) (xy 394.807883 -409.352179) (xy 394.803892 -409.290012)
			(xy 393.53226 -409.290012) (xy 393.551274 -409.336975) (xy 393.567075 -409.397233) (xy 393.575041 -409.459016)
			(xy 393.57554 -409.490164) (xy 393.575041 -409.521312) (xy 393.567075 -409.583095) (xy 393.551274 -409.643353)
			(xy 393.527896 -409.701096) (xy 393.497327 -409.755375) (xy 393.460067 -409.805299) (xy 393.41673 -409.850049)
			(xy 393.368025 -409.888889) (xy 393.314754 -409.921182) (xy 393.257791 -409.946399) (xy 393.19807 -409.964123)
			(xy 393.136573 -409.974066) (xy 393.07431 -409.976062) (xy 393.012303 -409.97008) (xy 392.951569 -409.956218)
			(xy 392.893107 -409.934704) (xy 392.837876 -409.90589) (xy 392.786784 -409.87025) (xy 392.740668 -409.828369)
			(xy 392.700286 -409.780934) (xy 392.666302 -409.728725) (xy 392.639273 -409.672599) (xy 392.619644 -409.613478)
			(xy 392.607735 -409.552331) (xy 392.603744 -409.490164) (xy 391.331963 -409.490164) (xy 391.323133 -409.510824)
			(xy 391.306812 -409.539186) (xy 391.303503 -409.545214) (xy 391.299894 -409.558475) (xy 391.2997 -409.565348)
			(xy 391.2997 -410.314648) (xy 391.299912 -410.32152) (xy 391.303507 -410.334782) (xy 391.306812 -410.34081)
			(xy 391.323119 -410.369179) (xy 391.348835 -410.429349) (xy 391.366243 -410.492426) (xy 391.375027 -410.557269)
			(xy 391.375028 -410.589984) (xy 394.803892 -410.589984) (xy 394.807883 -410.527817) (xy 394.819792 -410.46667)
			(xy 394.839421 -410.407549) (xy 394.86645 -410.351423) (xy 394.900434 -410.299214) (xy 394.940816 -410.251779)
			(xy 394.986932 -410.209898) (xy 395.038024 -410.174258) (xy 395.093255 -410.145444) (xy 395.151717 -410.12393)
			(xy 395.212451 -410.110068) (xy 395.274458 -410.104086) (xy 395.336721 -410.106082) (xy 395.398218 -410.116025)
			(xy 395.457939 -410.133749) (xy 395.514902 -410.158966) (xy 395.568173 -410.191259) (xy 395.616878 -410.230099)
			(xy 395.660215 -410.274849) (xy 395.697475 -410.324773) (xy 395.728044 -410.379052) (xy 395.751422 -410.436795)
			(xy 395.767223 -410.497053) (xy 395.775189 -410.558836) (xy 395.775688 -410.589984) (xy 395.775189 -410.621132)
			(xy 395.767223 -410.682915) (xy 395.751422 -410.743173) (xy 395.728044 -410.800916) (xy 395.697475 -410.855195)
			(xy 395.660215 -410.905119) (xy 395.616878 -410.949869) (xy 395.568173 -410.988709) (xy 395.514902 -411.021002)
			(xy 395.457939 -411.046219) (xy 395.398218 -411.063943) (xy 395.336721 -411.073886) (xy 395.274458 -411.075882)
			(xy 395.212451 -411.0699) (xy 395.151717 -411.056038) (xy 395.093255 -411.034524) (xy 395.038024 -411.00571)
			(xy 394.986932 -410.97007) (xy 394.940816 -410.928189) (xy 394.900434 -410.880754) (xy 394.86645 -410.828545)
			(xy 394.839421 -410.772419) (xy 394.819792 -410.713298) (xy 394.807883 -410.652151) (xy 394.803892 -410.589984)
			(xy 391.375028 -410.589984) (xy 391.375029 -410.622704) (xy 391.366249 -410.687547) (xy 391.348844 -410.750625)
			(xy 391.323132 -410.810796) (xy 391.306812 -410.839158) (xy 391.303513 -410.84519) (xy 391.299897 -410.858448)
			(xy 391.2997 -410.86532) (xy 391.2997 -411.151324) (xy 391.299298 -411.16148) (xy 391.291495 -411.180233)
			(xy 391.277092 -411.194555) (xy 391.258296 -411.202254) (xy 391.248138 -411.202632) (xy 390.531858 -411.202632)
			(xy 390.521725 -411.202207) (xy 390.502998 -411.19446) (xy 390.488642 -411.180155) (xy 390.480829 -411.161455)
			(xy 390.480296 -411.151324) (xy 390.480296 -410.86532) (xy 390.480097 -410.858447) (xy 390.476493 -410.845185)
			(xy 390.473184 -410.839158) (xy 390.456847 -410.810805) (xy 390.431128 -410.750632) (xy 390.41372 -410.687552)
			(xy 390.404937 -410.622705) (xy 386.975053 -410.622705) (xy 386.975053 -410.622714) (xy 386.966193 -410.687573)
			(xy 386.948698 -410.750653) (xy 386.922887 -410.810811) (xy 386.906516 -410.839158) (xy 386.903217 -410.845191)
			(xy 386.899601 -410.858448) (xy 386.899404 -410.86532) (xy 386.899404 -411.151324) (xy 386.898935 -411.161434)
			(xy 386.89119 -411.180112) (xy 386.876888 -411.194406) (xy 386.858206 -411.20214) (xy 386.848096 -411.202632)
			(xy 386.131816 -411.202632) (xy 386.121712 -411.202103) (xy 386.10304 -411.194376) (xy 386.088746 -411.180093)
			(xy 386.081005 -411.161427) (xy 386.080508 -411.151324) (xy 386.080508 -410.86532) (xy 386.080308 -410.858447)
			(xy 386.076705 -410.845185) (xy 386.073396 -410.839158) (xy 386.057013 -410.810818) (xy 386.031216 -410.750655)
			(xy 386.013731 -410.687573) (xy 386.004876 -410.622714) (xy 386.004308 -410.589984) (xy 382.574956 -410.589984)
			(xy 382.574957 -410.622704) (xy 382.566175 -410.687548) (xy 382.548767 -410.750627) (xy 382.52305 -410.810797)
			(xy 382.506728 -410.839158) (xy 382.50343 -410.845191) (xy 382.499813 -410.858448) (xy 382.499616 -410.86532)
			(xy 382.499616 -411.151324) (xy 382.499198 -411.161478) (xy 382.491398 -411.180228) (xy 382.477 -411.19455)
			(xy 382.45821 -411.202251) (xy 382.448054 -411.202632) (xy 381.731774 -411.202632) (xy 381.721642 -411.202194)
			(xy 381.702915 -411.194453) (xy 381.688559 -411.180151) (xy 381.680745 -411.161454) (xy 381.680212 -411.151324)
			(xy 381.680212 -410.86532) (xy 381.680011 -410.858447) (xy 381.676409 -410.845185) (xy 381.6731 -410.839158)
			(xy 381.656765 -410.810804) (xy 381.631051 -410.750631) (xy 381.613646 -410.68755) (xy 381.604865 -410.622705)
			(xy 378.174967 -410.622705) (xy 378.174967 -410.622714) (xy 378.166107 -410.687573) (xy 378.148613 -410.750653)
			(xy 378.122802 -410.81081) (xy 378.106432 -410.839158) (xy 378.103135 -410.845191) (xy 378.099518 -410.858448)
			(xy 378.09932 -410.86532) (xy 378.09932 -411.151324) (xy 378.098835 -411.161432) (xy 378.091093 -411.180107)
			(xy 378.076797 -411.1944) (xy 378.05812 -411.202138) (xy 378.048012 -411.202632) (xy 377.331732 -411.202632)
			(xy 377.321615 -411.202159) (xy 377.302919 -411.194427) (xy 377.288604 -411.180128) (xy 377.280852 -411.16144)
			(xy 377.280424 -411.151324) (xy 377.280424 -410.86532) (xy 377.280221 -410.858448) (xy 377.27662 -410.845185)
			(xy 377.273312 -410.839158) (xy 377.256931 -410.810817) (xy 377.231132 -410.750655) (xy 377.213647 -410.687573)
			(xy 377.204792 -410.622714) (xy 377.204224 -410.589984) (xy 351.775776 -410.589984) (xy 351.775277 -410.621132)
			(xy 351.767311 -410.682915) (xy 351.75151 -410.743173) (xy 351.728132 -410.800916) (xy 351.697563 -410.855195)
			(xy 351.660303 -410.905119) (xy 351.616966 -410.949869) (xy 351.568261 -410.988709) (xy 351.51499 -411.021002)
			(xy 351.458027 -411.046219) (xy 351.398306 -411.063943) (xy 351.336809 -411.073886) (xy 351.274546 -411.075882)
			(xy 351.212539 -411.0699) (xy 351.151805 -411.056038) (xy 351.093343 -411.034524) (xy 351.038112 -411.00571)
			(xy 350.98702 -410.97007) (xy 350.940904 -410.928189) (xy 350.900522 -410.880754) (xy 350.866538 -410.828545)
			(xy 350.839509 -410.772419) (xy 350.81988 -410.713298) (xy 350.807971 -410.652151) (xy 350.80398 -410.589984)
			(xy 347.375118 -410.589984) (xy 347.375119 -410.622704) (xy 347.366338 -410.687547) (xy 347.348933 -410.750625)
			(xy 347.32322 -410.810796) (xy 347.3069 -410.839158) (xy 347.3036 -410.84519) (xy 347.299985 -410.858448)
			(xy 347.299788 -410.86532) (xy 347.299788 -411.151324) (xy 347.299398 -411.161481) (xy 347.291592 -411.180236)
			(xy 347.277186 -411.194559) (xy 347.258386 -411.202256) (xy 347.248226 -411.202632) (xy 346.531946 -411.202632)
			(xy 346.521819 -411.202135) (xy 346.503093 -411.194417) (xy 346.488735 -411.180133) (xy 346.480919 -411.161449)
			(xy 346.480384 -411.151324) (xy 346.480384 -410.86532) (xy 346.480186 -410.858447) (xy 346.476582 -410.845184)
			(xy 346.473272 -410.839158) (xy 346.456935 -410.810805) (xy 346.431217 -410.750632) (xy 346.413809 -410.687552)
			(xy 346.405027 -410.622705) (xy 342.975142 -410.622705) (xy 342.975142 -410.622714) (xy 342.966282 -410.687573)
			(xy 342.948787 -410.750653) (xy 342.922975 -410.81081) (xy 342.906604 -410.839158) (xy 342.903304 -410.84519)
			(xy 342.899689 -410.858448) (xy 342.899492 -410.86532) (xy 342.899492 -411.151324) (xy 342.899034 -411.161435)
			(xy 342.891287 -411.180116) (xy 342.876982 -411.19441) (xy 342.858296 -411.202142) (xy 342.848184 -411.202632)
			(xy 342.131904 -411.202632) (xy 342.121799 -411.202112) (xy 342.103128 -411.194382) (xy 342.088834 -411.180096)
			(xy 342.081093 -411.161428) (xy 342.080596 -411.151324) (xy 342.080596 -410.86532) (xy 342.080397 -410.858447)
			(xy 342.076793 -410.845185) (xy 342.073484 -410.839158) (xy 342.0571 -410.810819) (xy 342.031303 -410.750656)
			(xy 342.013819 -410.687573) (xy 342.004964 -410.622714) (xy 342.004396 -410.589984) (xy 338.575045 -410.589984)
			(xy 338.575046 -410.622704) (xy 338.566264 -410.687549) (xy 338.548856 -410.750627) (xy 338.523139 -410.810797)
			(xy 338.506816 -410.839158) (xy 338.503517 -410.845191) (xy 338.499901 -410.858448) (xy 338.499704 -410.86532)
			(xy 338.499704 -411.151324) (xy 338.499298 -411.161479) (xy 338.491495 -411.180231) (xy 338.477094 -411.194554)
			(xy 338.458299 -411.202253) (xy 338.448142 -411.202632) (xy 337.731862 -411.202632) (xy 337.721729 -411.202204)
			(xy 337.703002 -411.194458) (xy 337.688646 -411.180154) (xy 337.680833 -411.161455) (xy 337.6803 -411.151324)
			(xy 337.6803 -410.86532) (xy 337.6801 -410.858447) (xy 337.676497 -410.845185) (xy 337.673188 -410.839158)
			(xy 337.656854 -410.810804) (xy 337.63114 -410.75063) (xy 337.613735 -410.68755) (xy 337.604954 -410.622705)
			(xy 334.175057 -410.622705) (xy 334.175057 -410.622714) (xy 334.166196 -410.687573) (xy 334.148702 -410.750653)
			(xy 334.122891 -410.810811) (xy 334.10652 -410.839158) (xy 334.103222 -410.845191) (xy 334.099605 -410.858448)
			(xy 334.099408 -410.86532) (xy 334.099408 -411.151324) (xy 334.098935 -411.161433) (xy 334.091191 -411.180111)
			(xy 334.07689 -411.194404) (xy 334.05821 -411.20214) (xy 334.0481 -411.202632) (xy 333.33182 -411.202632)
			(xy 333.321716 -411.202099) (xy 333.303045 -411.194374) (xy 333.28875 -411.180092) (xy 333.281009 -411.161427)
			(xy 333.280512 -411.151324) (xy 333.280512 -410.86532) (xy 333.280311 -410.858447) (xy 333.276709 -410.845185)
			(xy 333.2734 -410.839158) (xy 333.257018 -410.810818) (xy 333.23122 -410.750655) (xy 333.213735 -410.687573)
			(xy 333.20488 -410.622714) (xy 333.204312 -410.589984) (xy 326.525636 -410.589984) (xy 326.525636 -412.090108)
			(xy 331.003918 -412.090108) (xy 331.007909 -412.027941) (xy 331.019818 -411.966794) (xy 331.039447 -411.907673)
			(xy 331.066476 -411.851547) (xy 331.10046 -411.799338) (xy 331.140842 -411.751903) (xy 331.186958 -411.710022)
			(xy 331.23805 -411.674382) (xy 331.293281 -411.645568) (xy 331.351743 -411.624054) (xy 331.412477 -411.610192)
			(xy 331.474484 -411.60421) (xy 331.536747 -411.606206) (xy 331.598244 -411.616149) (xy 331.657965 -411.633873)
			(xy 331.714928 -411.65909) (xy 331.768199 -411.691383) (xy 331.816904 -411.730223) (xy 331.860241 -411.774973)
			(xy 331.897501 -411.824897) (xy 331.92807 -411.879176) (xy 331.951448 -411.936919) (xy 331.967249 -411.997177)
			(xy 331.975215 -412.05896) (xy 331.975714 -412.090108) (xy 335.40396 -412.090108) (xy 335.407951 -412.027941)
			(xy 335.41986 -411.966794) (xy 335.439489 -411.907673) (xy 335.466518 -411.851547) (xy 335.500502 -411.799338)
			(xy 335.540884 -411.751903) (xy 335.587 -411.710022) (xy 335.638092 -411.674382) (xy 335.693323 -411.645568)
			(xy 335.751785 -411.624054) (xy 335.812519 -411.610192) (xy 335.874526 -411.60421) (xy 335.936789 -411.606206)
			(xy 335.998286 -411.616149) (xy 336.058007 -411.633873) (xy 336.11497 -411.65909) (xy 336.168241 -411.691383)
			(xy 336.216946 -411.730223) (xy 336.260283 -411.774973) (xy 336.297543 -411.824897) (xy 336.328112 -411.879176)
			(xy 336.35149 -411.936919) (xy 336.367291 -411.997177) (xy 336.375257 -412.05896) (xy 336.375756 -412.090108)
			(xy 339.804002 -412.090108) (xy 339.807993 -412.027941) (xy 339.819902 -411.966794) (xy 339.839531 -411.907673)
			(xy 339.86656 -411.851547) (xy 339.900544 -411.799338) (xy 339.940926 -411.751903) (xy 339.987042 -411.710022)
			(xy 340.038134 -411.674382) (xy 340.093365 -411.645568) (xy 340.151827 -411.624054) (xy 340.212561 -411.610192)
			(xy 340.274568 -411.60421) (xy 340.336831 -411.606206) (xy 340.398328 -411.616149) (xy 340.458049 -411.633873)
			(xy 340.515012 -411.65909) (xy 340.568283 -411.691383) (xy 340.616988 -411.730223) (xy 340.660325 -411.774973)
			(xy 340.697585 -411.824897) (xy 340.728154 -411.879176) (xy 340.751532 -411.936919) (xy 340.767333 -411.997177)
			(xy 340.775299 -412.05896) (xy 340.775798 -412.090108) (xy 344.20379 -412.090108) (xy 344.207781 -412.027941)
			(xy 344.21969 -411.966794) (xy 344.239319 -411.907673) (xy 344.266348 -411.851547) (xy 344.300332 -411.799338)
			(xy 344.340714 -411.751903) (xy 344.38683 -411.710022) (xy 344.437922 -411.674382) (xy 344.493153 -411.645568)
			(xy 344.551615 -411.624054) (xy 344.612349 -411.610192) (xy 344.674356 -411.60421) (xy 344.736619 -411.606206)
			(xy 344.798116 -411.616149) (xy 344.857837 -411.633873) (xy 344.9148 -411.65909) (xy 344.968071 -411.691383)
			(xy 345.016776 -411.730223) (xy 345.060113 -411.774973) (xy 345.097373 -411.824897) (xy 345.127942 -411.879176)
			(xy 345.15132 -411.936919) (xy 345.167121 -411.997177) (xy 345.175087 -412.05896) (xy 345.175586 -412.090108)
			(xy 348.603832 -412.090108) (xy 348.607823 -412.027941) (xy 348.619732 -411.966794) (xy 348.639361 -411.907673)
			(xy 348.66639 -411.851547) (xy 348.700374 -411.799338) (xy 348.740756 -411.751903) (xy 348.786872 -411.710022)
			(xy 348.837964 -411.674382) (xy 348.893195 -411.645568) (xy 348.951657 -411.624054) (xy 349.012391 -411.610192)
			(xy 349.074398 -411.60421) (xy 349.136661 -411.606206) (xy 349.198158 -411.616149) (xy 349.257879 -411.633873)
			(xy 349.314842 -411.65909) (xy 349.368113 -411.691383) (xy 349.416818 -411.730223) (xy 349.460155 -411.774973)
			(xy 349.497415 -411.824897) (xy 349.527984 -411.879176) (xy 349.551362 -411.936919) (xy 349.567163 -411.997177)
			(xy 349.575129 -412.05896) (xy 349.575628 -412.090108) (xy 375.00383 -412.090108) (xy 375.007821 -412.027941)
			(xy 375.01973 -411.966794) (xy 375.039359 -411.907673) (xy 375.066388 -411.851547) (xy 375.100372 -411.799338)
			(xy 375.140754 -411.751903) (xy 375.18687 -411.710022) (xy 375.237962 -411.674382) (xy 375.293193 -411.645568)
			(xy 375.351655 -411.624054) (xy 375.412389 -411.610192) (xy 375.474396 -411.60421) (xy 375.536659 -411.606206)
			(xy 375.598156 -411.616149) (xy 375.657877 -411.633873) (xy 375.71484 -411.65909) (xy 375.768111 -411.691383)
			(xy 375.816816 -411.730223) (xy 375.860153 -411.774973) (xy 375.897413 -411.824897) (xy 375.927982 -411.879176)
			(xy 375.95136 -411.936919) (xy 375.967161 -411.997177) (xy 375.975127 -412.05896) (xy 375.975626 -412.090108)
			(xy 379.403872 -412.090108) (xy 379.407863 -412.027941) (xy 379.419772 -411.966794) (xy 379.439401 -411.907673)
			(xy 379.46643 -411.851547) (xy 379.500414 -411.799338) (xy 379.540796 -411.751903) (xy 379.586912 -411.710022)
			(xy 379.638004 -411.674382) (xy 379.693235 -411.645568) (xy 379.751697 -411.624054) (xy 379.812431 -411.610192)
			(xy 379.874438 -411.60421) (xy 379.936701 -411.606206) (xy 379.998198 -411.616149) (xy 380.057919 -411.633873)
			(xy 380.114882 -411.65909) (xy 380.168153 -411.691383) (xy 380.216858 -411.730223) (xy 380.260195 -411.774973)
			(xy 380.297455 -411.824897) (xy 380.328024 -411.879176) (xy 380.351402 -411.936919) (xy 380.367203 -411.997177)
			(xy 380.375169 -412.05896) (xy 380.375668 -412.090108) (xy 383.803914 -412.090108) (xy 383.807905 -412.027941)
			(xy 383.819814 -411.966794) (xy 383.839443 -411.907673) (xy 383.866472 -411.851547) (xy 383.900456 -411.799338)
			(xy 383.940838 -411.751903) (xy 383.986954 -411.710022) (xy 384.038046 -411.674382) (xy 384.093277 -411.645568)
			(xy 384.151739 -411.624054) (xy 384.212473 -411.610192) (xy 384.27448 -411.60421) (xy 384.336743 -411.606206)
			(xy 384.39824 -411.616149) (xy 384.457961 -411.633873) (xy 384.514924 -411.65909) (xy 384.568195 -411.691383)
			(xy 384.6169 -411.730223) (xy 384.660237 -411.774973) (xy 384.697497 -411.824897) (xy 384.728066 -411.879176)
			(xy 384.751444 -411.936919) (xy 384.767245 -411.997177) (xy 384.775211 -412.05896) (xy 384.77571 -412.090108)
			(xy 388.203702 -412.090108) (xy 388.207693 -412.027941) (xy 388.219602 -411.966794) (xy 388.239231 -411.907673)
			(xy 388.26626 -411.851547) (xy 388.300244 -411.799338) (xy 388.340626 -411.751903) (xy 388.386742 -411.710022)
			(xy 388.437834 -411.674382) (xy 388.493065 -411.645568) (xy 388.551527 -411.624054) (xy 388.612261 -411.610192)
			(xy 388.674268 -411.60421) (xy 388.736531 -411.606206) (xy 388.798028 -411.616149) (xy 388.857749 -411.633873)
			(xy 388.914712 -411.65909) (xy 388.967983 -411.691383) (xy 389.016688 -411.730223) (xy 389.060025 -411.774973)
			(xy 389.097285 -411.824897) (xy 389.127854 -411.879176) (xy 389.151232 -411.936919) (xy 389.167033 -411.997177)
			(xy 389.174999 -412.05896) (xy 389.175498 -412.090108) (xy 392.603744 -412.090108) (xy 392.607735 -412.027941)
			(xy 392.619644 -411.966794) (xy 392.639273 -411.907673) (xy 392.666302 -411.851547) (xy 392.700286 -411.799338)
			(xy 392.740668 -411.751903) (xy 392.786784 -411.710022) (xy 392.837876 -411.674382) (xy 392.893107 -411.645568)
			(xy 392.951569 -411.624054) (xy 393.012303 -411.610192) (xy 393.07431 -411.60421) (xy 393.136573 -411.606206)
			(xy 393.19807 -411.616149) (xy 393.257791 -411.633873) (xy 393.314754 -411.65909) (xy 393.368025 -411.691383)
			(xy 393.41673 -411.730223) (xy 393.460067 -411.774973) (xy 393.497327 -411.824897) (xy 393.527896 -411.879176)
			(xy 393.551274 -411.936919) (xy 393.567075 -411.997177) (xy 393.575041 -412.05896) (xy 393.57554 -412.090108)
			(xy 393.575041 -412.121256) (xy 393.567075 -412.183039) (xy 393.551274 -412.243297) (xy 393.527896 -412.30104)
			(xy 393.497327 -412.355319) (xy 393.460067 -412.405243) (xy 393.41673 -412.449993) (xy 393.368025 -412.488833)
			(xy 393.314754 -412.521126) (xy 393.257791 -412.546343) (xy 393.19807 -412.564067) (xy 393.136573 -412.57401)
			(xy 393.07431 -412.576006) (xy 393.012303 -412.570024) (xy 392.951569 -412.556162) (xy 392.893107 -412.534648)
			(xy 392.837876 -412.505834) (xy 392.786784 -412.470194) (xy 392.740668 -412.428313) (xy 392.700286 -412.380878)
			(xy 392.666302 -412.328669) (xy 392.639273 -412.272543) (xy 392.619644 -412.213422) (xy 392.607735 -412.152275)
			(xy 392.603744 -412.090108) (xy 389.175498 -412.090108) (xy 389.174999 -412.121256) (xy 389.167033 -412.183039)
			(xy 389.151232 -412.243297) (xy 389.127854 -412.30104) (xy 389.097285 -412.355319) (xy 389.060025 -412.405243)
			(xy 389.016688 -412.449993) (xy 388.967983 -412.488833) (xy 388.914712 -412.521126) (xy 388.857749 -412.546343)
			(xy 388.798028 -412.564067) (xy 388.736531 -412.57401) (xy 388.674268 -412.576006) (xy 388.612261 -412.570024)
			(xy 388.551527 -412.556162) (xy 388.493065 -412.534648) (xy 388.437834 -412.505834) (xy 388.386742 -412.470194)
			(xy 388.340626 -412.428313) (xy 388.300244 -412.380878) (xy 388.26626 -412.328669) (xy 388.239231 -412.272543)
			(xy 388.219602 -412.213422) (xy 388.207693 -412.152275) (xy 388.203702 -412.090108) (xy 384.77571 -412.090108)
			(xy 384.775211 -412.121256) (xy 384.767245 -412.183039) (xy 384.751444 -412.243297) (xy 384.728066 -412.30104)
			(xy 384.697497 -412.355319) (xy 384.660237 -412.405243) (xy 384.6169 -412.449993) (xy 384.568195 -412.488833)
			(xy 384.514924 -412.521126) (xy 384.457961 -412.546343) (xy 384.39824 -412.564067) (xy 384.336743 -412.57401)
			(xy 384.27448 -412.576006) (xy 384.212473 -412.570024) (xy 384.151739 -412.556162) (xy 384.093277 -412.534648)
			(xy 384.038046 -412.505834) (xy 383.986954 -412.470194) (xy 383.940838 -412.428313) (xy 383.900456 -412.380878)
			(xy 383.866472 -412.328669) (xy 383.839443 -412.272543) (xy 383.819814 -412.213422) (xy 383.807905 -412.152275)
			(xy 383.803914 -412.090108) (xy 380.375668 -412.090108) (xy 380.375169 -412.121256) (xy 380.367203 -412.183039)
			(xy 380.351402 -412.243297) (xy 380.328024 -412.30104) (xy 380.297455 -412.355319) (xy 380.260195 -412.405243)
			(xy 380.216858 -412.449993) (xy 380.168153 -412.488833) (xy 380.114882 -412.521126) (xy 380.057919 -412.546343)
			(xy 379.998198 -412.564067) (xy 379.936701 -412.57401) (xy 379.874438 -412.576006) (xy 379.812431 -412.570024)
			(xy 379.751697 -412.556162) (xy 379.693235 -412.534648) (xy 379.638004 -412.505834) (xy 379.586912 -412.470194)
			(xy 379.540796 -412.428313) (xy 379.500414 -412.380878) (xy 379.46643 -412.328669) (xy 379.439401 -412.272543)
			(xy 379.419772 -412.213422) (xy 379.407863 -412.152275) (xy 379.403872 -412.090108) (xy 375.975626 -412.090108)
			(xy 375.975127 -412.121256) (xy 375.967161 -412.183039) (xy 375.95136 -412.243297) (xy 375.927982 -412.30104)
			(xy 375.897413 -412.355319) (xy 375.860153 -412.405243) (xy 375.816816 -412.449993) (xy 375.768111 -412.488833)
			(xy 375.71484 -412.521126) (xy 375.657877 -412.546343) (xy 375.598156 -412.564067) (xy 375.536659 -412.57401)
			(xy 375.474396 -412.576006) (xy 375.412389 -412.570024) (xy 375.351655 -412.556162) (xy 375.293193 -412.534648)
			(xy 375.237962 -412.505834) (xy 375.18687 -412.470194) (xy 375.140754 -412.428313) (xy 375.100372 -412.380878)
			(xy 375.066388 -412.328669) (xy 375.039359 -412.272543) (xy 375.01973 -412.213422) (xy 375.007821 -412.152275)
			(xy 375.00383 -412.090108) (xy 349.575628 -412.090108) (xy 349.575129 -412.121256) (xy 349.567163 -412.183039)
			(xy 349.551362 -412.243297) (xy 349.527984 -412.30104) (xy 349.497415 -412.355319) (xy 349.460155 -412.405243)
			(xy 349.416818 -412.449993) (xy 349.368113 -412.488833) (xy 349.314842 -412.521126) (xy 349.257879 -412.546343)
			(xy 349.198158 -412.564067) (xy 349.136661 -412.57401) (xy 349.074398 -412.576006) (xy 349.012391 -412.570024)
			(xy 348.951657 -412.556162) (xy 348.893195 -412.534648) (xy 348.837964 -412.505834) (xy 348.786872 -412.470194)
			(xy 348.740756 -412.428313) (xy 348.700374 -412.380878) (xy 348.66639 -412.328669) (xy 348.639361 -412.272543)
			(xy 348.619732 -412.213422) (xy 348.607823 -412.152275) (xy 348.603832 -412.090108) (xy 345.175586 -412.090108)
			(xy 345.175087 -412.121256) (xy 345.167121 -412.183039) (xy 345.15132 -412.243297) (xy 345.127942 -412.30104)
			(xy 345.097373 -412.355319) (xy 345.060113 -412.405243) (xy 345.016776 -412.449993) (xy 344.968071 -412.488833)
			(xy 344.9148 -412.521126) (xy 344.857837 -412.546343) (xy 344.798116 -412.564067) (xy 344.736619 -412.57401)
			(xy 344.674356 -412.576006) (xy 344.612349 -412.570024) (xy 344.551615 -412.556162) (xy 344.493153 -412.534648)
			(xy 344.437922 -412.505834) (xy 344.38683 -412.470194) (xy 344.340714 -412.428313) (xy 344.300332 -412.380878)
			(xy 344.266348 -412.328669) (xy 344.239319 -412.272543) (xy 344.21969 -412.213422) (xy 344.207781 -412.152275)
			(xy 344.20379 -412.090108) (xy 340.775798 -412.090108) (xy 340.775299 -412.121256) (xy 340.767333 -412.183039)
			(xy 340.751532 -412.243297) (xy 340.728154 -412.30104) (xy 340.697585 -412.355319) (xy 340.660325 -412.405243)
			(xy 340.616988 -412.449993) (xy 340.568283 -412.488833) (xy 340.515012 -412.521126) (xy 340.458049 -412.546343)
			(xy 340.398328 -412.564067) (xy 340.336831 -412.57401) (xy 340.274568 -412.576006) (xy 340.212561 -412.570024)
			(xy 340.151827 -412.556162) (xy 340.093365 -412.534648) (xy 340.038134 -412.505834) (xy 339.987042 -412.470194)
			(xy 339.940926 -412.428313) (xy 339.900544 -412.380878) (xy 339.86656 -412.328669) (xy 339.839531 -412.272543)
			(xy 339.819902 -412.213422) (xy 339.807993 -412.152275) (xy 339.804002 -412.090108) (xy 336.375756 -412.090108)
			(xy 336.375257 -412.121256) (xy 336.367291 -412.183039) (xy 336.35149 -412.243297) (xy 336.328112 -412.30104)
			(xy 336.297543 -412.355319) (xy 336.260283 -412.405243) (xy 336.216946 -412.449993) (xy 336.168241 -412.488833)
			(xy 336.11497 -412.521126) (xy 336.058007 -412.546343) (xy 335.998286 -412.564067) (xy 335.936789 -412.57401)
			(xy 335.874526 -412.576006) (xy 335.812519 -412.570024) (xy 335.751785 -412.556162) (xy 335.693323 -412.534648)
			(xy 335.638092 -412.505834) (xy 335.587 -412.470194) (xy 335.540884 -412.428313) (xy 335.500502 -412.380878)
			(xy 335.466518 -412.328669) (xy 335.439489 -412.272543) (xy 335.41986 -412.213422) (xy 335.407951 -412.152275)
			(xy 335.40396 -412.090108) (xy 331.975714 -412.090108) (xy 331.975215 -412.121256) (xy 331.967249 -412.183039)
			(xy 331.951448 -412.243297) (xy 331.92807 -412.30104) (xy 331.897501 -412.355319) (xy 331.860241 -412.405243)
			(xy 331.816904 -412.449993) (xy 331.768199 -412.488833) (xy 331.714928 -412.521126) (xy 331.657965 -412.546343)
			(xy 331.598244 -412.564067) (xy 331.536747 -412.57401) (xy 331.474484 -412.576006) (xy 331.412477 -412.570024)
			(xy 331.351743 -412.556162) (xy 331.293281 -412.534648) (xy 331.23805 -412.505834) (xy 331.186958 -412.470194)
			(xy 331.140842 -412.428313) (xy 331.10046 -412.380878) (xy 331.066476 -412.328669) (xy 331.039447 -412.272543)
			(xy 331.019818 -412.213422) (xy 331.007909 -412.152275) (xy 331.003918 -412.090108) (xy 326.525636 -412.090108)
			(xy 326.525636 -417.126674) (xy 326.526052 -417.136696) (xy 326.533718 -417.155216) (xy 326.547893 -417.169387)
			(xy 326.566414 -417.17705) (xy 326.576436 -417.177474) (xy 400.72564 -417.177474) (xy 400.73564 -417.176979)
			(xy 400.754114 -417.169311) (xy 400.768248 -417.155159) (xy 400.775892 -417.136675) (xy 400.77644 -417.126674)
			(xy 400.77644 -393.895834) (xy 400.776876 -393.88577) (xy 400.784612 -393.867187) (xy 400.791426 -393.859766)
			(xy 401.21713 -393.434062) (xy 401.224527 -393.427214) (xy 401.243126 -393.41948) (xy 401.253198 -393.419076)
			(xy 414.167828 -393.419076) (xy 414.177896 -393.419504) (xy 414.196496 -393.427222) (xy 414.203896 -393.434062)
			(xy 414.900618 -394.130784) (xy 414.90746 -394.138183) (xy 414.915177 -394.156782) (xy 414.915604 -394.166852)
			(xy 414.915604 -401.7228) (xy 419.004827 -401.7228) (xy 419.004829 -401.657362) (xy 419.013616 -401.592516)
			(xy 419.031029 -401.529436) (xy 419.056751 -401.469265) (xy 419.073076 -401.440904) (xy 419.076388 -401.434878)
			(xy 419.079996 -401.421615) (xy 419.080188 -401.414742) (xy 419.080188 -400.665442) (xy 419.079981 -400.65857)
			(xy 419.076383 -400.645307) (xy 419.073076 -400.63928) (xy 419.056758 -400.610916) (xy 419.031038 -400.550746)
			(xy 419.013628 -400.487668) (xy 419.004843 -400.422824) (xy 419.004842 -400.357387) (xy 419.013626 -400.292542)
			(xy 419.031034 -400.229464) (xy 419.056753 -400.169293) (xy 419.073076 -400.140932) (xy 419.076378 -400.134901)
			(xy 419.079992 -400.121642) (xy 419.080188 -400.11477) (xy 419.080188 -399.828766) (xy 419.080537 -399.818586)
			(xy 419.088343 -399.799781) (xy 419.102752 -399.785395) (xy 419.121569 -399.777621) (xy 419.13175 -399.777204)
			(xy 419.84803 -399.777204) (xy 419.858186 -399.777708) (xy 419.876949 -399.785486) (xy 419.891312 -399.799848)
			(xy 419.899091 -399.818611) (xy 419.899592 -399.828766) (xy 419.899592 -400.11477) (xy 419.899796 -400.121642)
			(xy 419.903396 -400.134905) (xy 419.906704 -400.140932) (xy 419.92303 -400.169291) (xy 419.948745 -400.229463)
			(xy 419.966151 -400.292542) (xy 419.974933 -400.357387) (xy 419.974932 -400.422823) (xy 419.966149 -400.487668)
			(xy 419.948741 -400.550747) (xy 419.923025 -400.610918) (xy 419.906704 -400.63928) (xy 419.903397 -400.645308)
			(xy 419.899786 -400.658569) (xy 419.899592 -400.665442) (xy 419.899592 -401.414742) (xy 419.899807 -401.421614)
			(xy 419.9034 -401.434876) (xy 419.906704 -401.440904) (xy 419.923006 -401.469276) (xy 419.948723 -401.529445)
			(xy 419.966132 -401.592522) (xy 419.974917 -401.657364) (xy 419.97492 -401.722798) (xy 419.96614 -401.787641)
			(xy 419.948736 -401.850719) (xy 419.923023 -401.91089) (xy 419.906704 -401.939252) (xy 419.903371 -401.945268)
			(xy 419.899777 -401.958538) (xy 419.899592 -401.965414) (xy 419.899592 -402.251418) (xy 419.899082 -402.261573)
			(xy 419.891308 -402.280337) (xy 419.876947 -402.294701) (xy 419.858185 -402.30248) (xy 419.84803 -402.30298)
			(xy 419.13175 -402.30298) (xy 419.121584 -402.302496) (xy 419.102794 -402.29473) (xy 419.088408 -402.280363)
			(xy 419.080618 -402.261584) (xy 419.080188 -402.251418) (xy 419.080188 -401.965414) (xy 419.079992 -401.958541)
			(xy 419.076387 -401.945278) (xy 419.073076 -401.939252) (xy 419.056734 -401.910901) (xy 419.031016 -401.850728)
			(xy 419.013609 -401.787647) (xy 419.004827 -401.7228) (xy 414.915604 -401.7228) (xy 414.915604 -402.790152)
			(xy 421.204136 -402.790152) (xy 421.204711 -402.757423) (xy 421.213566 -402.692565) (xy 421.231053 -402.629485)
			(xy 421.256857 -402.569327) (xy 421.273224 -402.540978) (xy 421.276548 -402.534958) (xy 421.280147 -402.521691)
			(xy 421.280336 -402.514816) (xy 421.280336 -401.765516) (xy 421.280133 -401.758644) (xy 421.276532 -401.745381)
			(xy 421.273224 -401.739354) (xy 421.256842 -401.711014) (xy 421.231044 -401.650851) (xy 421.213559 -401.587769)
			(xy 421.204703 -401.52291) (xy 421.204136 -401.49018) (xy 421.204724 -401.457451) (xy 421.213574 -401.392594)
			(xy 421.231058 -401.329514) (xy 421.256859 -401.269355) (xy 421.273224 -401.241006) (xy 421.276538 -401.234981)
			(xy 421.280144 -401.221718) (xy 421.280336 -401.214844) (xy 421.280336 -400.92884) (xy 421.28075 -400.918716)
			(xy 421.288491 -400.900006) (xy 421.302809 -400.885689) (xy 421.32152 -400.877949) (xy 421.331644 -400.877532)
			(xy 422.047924 -400.877532) (xy 422.058052 -400.877897) (xy 422.076762 -400.885659) (xy 422.091077 -400.899991)
			(xy 422.098816 -400.918711) (xy 422.099232 -400.92884) (xy 422.099232 -401.214844) (xy 422.099441 -401.221716)
			(xy 422.103037 -401.234979) (xy 422.106344 -401.241006) (xy 422.122707 -401.269357) (xy 422.14851 -401.329515)
			(xy 422.166001 -401.392594) (xy 422.174862 -401.457451) (xy 422.175432 -401.49018) (xy 422.174876 -401.52291)
			(xy 422.166016 -401.587768) (xy 422.148523 -401.650848) (xy 422.131693 -401.690078) (xy 423.404284 -401.690078)
			(xy 423.404865 -401.657349) (xy 423.413716 -401.592491) (xy 423.431202 -401.529411) (xy 423.457006 -401.469253)
			(xy 423.473372 -401.440904) (xy 423.476683 -401.434878) (xy 423.480292 -401.421615) (xy 423.480484 -401.414742)
			(xy 423.480484 -400.665442) (xy 423.480278 -400.65857) (xy 423.476679 -400.645307) (xy 423.473372 -400.63928)
			(xy 423.456996 -400.610937) (xy 423.431197 -400.550775) (xy 423.413711 -400.487694) (xy 423.404853 -400.422835)
			(xy 423.404284 -400.390106) (xy 423.404832 -400.357376) (xy 423.413693 -400.292517) (xy 423.431189 -400.229437)
			(xy 423.457001 -400.169279) (xy 423.473372 -400.140932) (xy 423.476673 -400.134901) (xy 423.480288 -400.121642)
			(xy 423.480484 -400.11477) (xy 423.480484 -399.828766) (xy 423.4809 -399.818632) (xy 423.488647 -399.799901)
			(xy 423.502955 -399.785545) (xy 423.521659 -399.777735) (xy 423.531792 -399.777204) (xy 424.248072 -399.777204)
			(xy 424.258225 -399.777644) (xy 424.276977 -399.785431) (xy 424.291302 -399.799823) (xy 424.299002 -399.818611)
			(xy 424.29938 -399.828766) (xy 424.29938 -400.11477) (xy 424.299586 -400.121642) (xy 424.303185 -400.134905)
			(xy 424.306492 -400.140932) (xy 424.32287 -400.169275) (xy 424.348669 -400.229437) (xy 424.366155 -400.292518)
			(xy 424.375012 -400.357376) (xy 424.37558 -400.390106) (xy 424.374997 -400.422835) (xy 424.366147 -400.487693)
			(xy 424.348662 -400.550773) (xy 424.322859 -400.610931) (xy 424.306492 -400.63928) (xy 424.303184 -400.645308)
			(xy 424.299574 -400.658569) (xy 424.29938 -400.665442) (xy 424.29938 -401.414742) (xy 424.299597 -401.421613)
			(xy 424.303189 -401.434876) (xy 424.306492 -401.440904) (xy 424.322858 -401.469253) (xy 424.34866 -401.529412)
			(xy 424.36615 -401.592492) (xy 424.37501 -401.657349) (xy 424.37558 -401.690078) (xy 424.375029 -401.722808)
			(xy 424.366169 -401.787667) (xy 424.348675 -401.850747) (xy 424.322863 -401.910905) (xy 424.306492 -401.939252)
			(xy 424.303158 -401.945267) (xy 424.299565 -401.958538) (xy 424.29938 -401.965414) (xy 424.29938 -402.251418)
			(xy 424.298889 -402.261543) (xy 424.291159 -402.280261) (xy 424.276874 -402.294616) (xy 424.258195 -402.302438)
			(xy 424.248072 -402.30298) (xy 423.531792 -402.30298) (xy 423.521635 -402.302584) (xy 423.502879 -402.294782)
			(xy 423.488555 -402.280378) (xy 423.480859 -402.261577) (xy 423.480484 -402.251418) (xy 423.480484 -401.965414)
			(xy 423.480289 -401.958541) (xy 423.476683 -401.945278) (xy 423.473372 -401.939252) (xy 423.456985 -401.910915)
			(xy 423.431189 -401.850751) (xy 423.413705 -401.787668) (xy 423.404851 -401.722808) (xy 423.404284 -401.690078)
			(xy 422.131693 -401.690078) (xy 422.122714 -401.711006) (xy 422.106344 -401.739354) (xy 422.103049 -401.745388)
			(xy 422.09943 -401.758645) (xy 422.099232 -401.765516) (xy 422.099232 -402.514816) (xy 422.099414 -402.52169)
			(xy 422.103029 -402.534953) (xy 422.106344 -402.540978) (xy 422.122695 -402.569335) (xy 422.148502 -402.629491)
			(xy 422.165996 -402.692568) (xy 422.17486 -402.757424) (xy 422.175432 -402.790152) (xy 422.174863 -402.822879)
			(xy 425.604757 -402.822879) (xy 425.604762 -402.757439) (xy 425.613551 -402.692592) (xy 425.630965 -402.629512)
			(xy 425.656687 -402.56934) (xy 425.673012 -402.540978) (xy 425.676335 -402.534958) (xy 425.679935 -402.521691)
			(xy 425.680124 -402.514816) (xy 425.680124 -401.765516) (xy 425.679923 -401.758643) (xy 425.676321 -401.745381)
			(xy 425.673012 -401.739354) (xy 425.656674 -401.711002) (xy 425.630959 -401.650828) (xy 425.613554 -401.587748)
			(xy 425.604773 -401.522902) (xy 425.604775 -401.457464) (xy 425.613561 -401.392619) (xy 425.63097 -401.329539)
			(xy 425.656689 -401.269368) (xy 425.673012 -401.241006) (xy 425.676325 -401.234981) (xy 425.679932 -401.221717)
			(xy 425.680124 -401.214844) (xy 425.680124 -400.92884) (xy 425.680555 -400.918686) (xy 425.688342 -400.899929)
			(xy 425.702736 -400.885604) (xy 425.72153 -400.877907) (xy 425.731686 -400.877532) (xy 426.447966 -400.877532)
			(xy 426.45809 -400.878054) (xy 426.476808 -400.88577) (xy 426.491165 -400.900045) (xy 426.498987 -400.918719)
			(xy 426.499528 -400.92884) (xy 426.499528 -401.214844) (xy 426.499738 -401.221716) (xy 426.503334 -401.234979)
			(xy 426.50664 -401.241006) (xy 426.522946 -401.269376) (xy 426.548666 -401.329545) (xy 426.566077 -401.392622)
			(xy 426.574863 -401.457465) (xy 426.574865 -401.522901) (xy 426.566084 -401.587744) (xy 426.548678 -401.650822)
			(xy 426.522962 -401.710993) (xy 426.516167 -401.7228) (xy 427.804913 -401.7228) (xy 427.804916 -401.657362)
			(xy 427.813702 -401.592516) (xy 427.831114 -401.529436) (xy 427.856836 -401.469265) (xy 427.87316 -401.440904)
			(xy 427.87647 -401.434877) (xy 427.880079 -401.421615) (xy 427.880272 -401.414742) (xy 427.880272 -400.665442)
			(xy 427.880067 -400.65857) (xy 427.876468 -400.645307) (xy 427.87316 -400.63928) (xy 427.856842 -400.610916)
			(xy 427.831123 -400.550746) (xy 427.813714 -400.487668) (xy 427.804929 -400.422823) (xy 427.804928 -400.357387)
			(xy 427.813712 -400.292542) (xy 427.83112 -400.229464) (xy 427.856838 -400.169293) (xy 427.87316 -400.140932)
			(xy 427.87646 -400.1349) (xy 427.880075 -400.121642) (xy 427.880272 -400.11477) (xy 427.880272 -399.828766)
			(xy 427.880706 -399.818602) (xy 427.888498 -399.799825) (xy 427.902883 -399.78546) (xy 427.921669 -399.777693)
			(xy 427.931834 -399.777204) (xy 428.648114 -399.777204) (xy 428.658268 -399.777721) (xy 428.677031 -399.785494)
			(xy 428.691395 -399.799852) (xy 428.699175 -399.818612) (xy 428.699676 -399.828766) (xy 428.699676 -400.11477)
			(xy 428.699882 -400.121642) (xy 428.703481 -400.134905) (xy 428.706788 -400.140932) (xy 428.723114 -400.169291)
			(xy 428.74883 -400.229463) (xy 428.766237 -400.292542) (xy 428.775019 -400.357387) (xy 428.775018 -400.422824)
			(xy 428.766235 -400.487668) (xy 428.748827 -400.550747) (xy 428.72311 -400.610918) (xy 428.706788 -400.63928)
			(xy 428.70348 -400.645308) (xy 428.69987 -400.658569) (xy 428.699676 -400.665442) (xy 428.699676 -401.414742)
			(xy 428.699893 -401.421613) (xy 428.703484 -401.434876) (xy 428.706788 -401.440904) (xy 428.723091 -401.469276)
			(xy 428.748809 -401.529445) (xy 428.766218 -401.592521) (xy 428.775003 -401.657364) (xy 428.775006 -401.722799)
			(xy 428.766225 -401.787642) (xy 428.748821 -401.850719) (xy 428.723108 -401.91089) (xy 428.706788 -401.939252)
			(xy 428.703454 -401.945267) (xy 428.699861 -401.958538) (xy 428.699676 -401.965414) (xy 428.699676 -402.251418)
			(xy 428.699182 -402.261575) (xy 428.691404 -402.280342) (xy 428.677039 -402.294706) (xy 428.658271 -402.302483)
			(xy 428.648114 -402.30298) (xy 427.931834 -402.30298) (xy 427.921667 -402.302509) (xy 427.902876 -402.294738)
			(xy 427.888491 -402.280367) (xy 427.880702 -402.261585) (xy 427.880272 -402.251418) (xy 427.880272 -401.965414)
			(xy 427.880078 -401.958541) (xy 427.876471 -401.945278) (xy 427.87316 -401.939252) (xy 427.856818 -401.910901)
			(xy 427.831102 -401.850728) (xy 427.813695 -401.787647) (xy 427.804913 -401.7228) (xy 426.516167 -401.7228)
			(xy 426.50664 -401.739354) (xy 426.503345 -401.745388) (xy 426.499726 -401.758645) (xy 426.499528 -401.765516)
			(xy 426.499528 -402.514816) (xy 426.499711 -402.52169) (xy 426.503325 -402.534953) (xy 426.50664 -402.540978)
			(xy 426.522922 -402.569361) (xy 426.548645 -402.629527) (xy 426.566058 -402.692601) (xy 426.574847 -402.757442)
			(xy 426.57485 -402.790152) (xy 430.00422 -402.790152) (xy 430.004784 -402.757422) (xy 430.01364 -402.692564)
			(xy 430.031131 -402.629484) (xy 430.056939 -402.569326) (xy 430.073308 -402.540978) (xy 430.076631 -402.534958)
			(xy 430.080231 -402.521691) (xy 430.08042 -402.514816) (xy 430.08042 -401.765516) (xy 430.08022 -401.758643)
			(xy 430.076617 -401.745381) (xy 430.073308 -401.739354) (xy 430.056925 -401.711014) (xy 430.031127 -401.650851)
			(xy 430.013642 -401.587769) (xy 430.004787 -401.52291) (xy 430.00422 -401.49018) (xy 430.004796 -401.457451)
			(xy 430.013649 -401.392593) (xy 430.031136 -401.329513) (xy 430.056941 -401.269354) (xy 430.073308 -401.241006)
			(xy 430.076621 -401.234981) (xy 430.080228 -401.221717) (xy 430.08042 -401.214844) (xy 430.08042 -400.92884)
			(xy 430.080849 -400.918718) (xy 430.088588 -400.900011) (xy 430.102901 -400.885695) (xy 430.121606 -400.877952)
			(xy 430.131728 -400.877532) (xy 430.848008 -400.877532) (xy 430.858135 -400.87791) (xy 430.876845 -400.885667)
			(xy 430.89116 -400.899996) (xy 430.898899 -400.918713) (xy 430.899316 -400.92884) (xy 430.899316 -401.214844)
			(xy 430.899527 -401.221716) (xy 430.903122 -401.234979) (xy 430.906428 -401.241006) (xy 430.922799 -401.269352)
			(xy 430.948599 -401.329513) (xy 430.966087 -401.392593) (xy 430.974946 -401.457451) (xy 430.975516 -401.49018)
			(xy 430.974962 -401.52291) (xy 430.966102 -401.587769) (xy 430.948609 -401.650849) (xy 430.922798 -401.711006)
			(xy 430.915987 -401.7228) (xy 432.204703 -401.7228) (xy 432.204705 -401.657362) (xy 432.213492 -401.592516)
			(xy 432.230903 -401.529437) (xy 432.256624 -401.469265) (xy 432.272948 -401.440904) (xy 432.276257 -401.434877)
			(xy 432.279867 -401.421615) (xy 432.28006 -401.414742) (xy 432.28006 -400.665442) (xy 432.279857 -400.65857)
			(xy 432.276257 -400.645307) (xy 432.272948 -400.63928) (xy 432.256631 -400.610916) (xy 432.230912 -400.550746)
			(xy 432.213503 -400.487667) (xy 432.204719 -400.422823) (xy 432.204718 -400.357387) (xy 432.213501 -400.292543)
			(xy 432.230909 -400.229464) (xy 432.256626 -400.169293) (xy 432.272948 -400.140932) (xy 432.276247 -400.1349)
			(xy 432.279863 -400.121642) (xy 432.28006 -400.11477) (xy 432.28006 -399.828766) (xy 432.280506 -399.818603)
			(xy 432.288296 -399.799829) (xy 432.302676 -399.785464) (xy 432.321459 -399.777695) (xy 432.331622 -399.777204)
			(xy 433.047902 -399.777204) (xy 433.058056 -399.777731) (xy 433.076818 -399.7855) (xy 433.091182 -399.799855)
			(xy 433.098963 -399.818613) (xy 433.099464 -399.828766) (xy 433.099464 -400.11477) (xy 433.099672 -400.121642)
			(xy 433.10327 -400.134905) (xy 433.106576 -400.140932) (xy 433.122903 -400.169291) (xy 433.148619 -400.229463)
			(xy 433.166026 -400.292542) (xy 433.174809 -400.357387) (xy 433.174808 -400.390106) (xy 436.603656 -400.390106)
			(xy 436.607647 -400.327939) (xy 436.619556 -400.266792) (xy 436.639185 -400.207671) (xy 436.666214 -400.151545)
			(xy 436.700198 -400.099336) (xy 436.74058 -400.051901) (xy 436.786696 -400.01002) (xy 436.837788 -399.97438)
			(xy 436.893019 -399.945566) (xy 436.951481 -399.924052) (xy 437.012215 -399.91019) (xy 437.074222 -399.904208)
			(xy 437.136485 -399.906204) (xy 437.197982 -399.916147) (xy 437.257703 -399.933871) (xy 437.314666 -399.959088)
			(xy 437.367937 -399.991381) (xy 437.416642 -400.030221) (xy 437.459979 -400.074971) (xy 437.497239 -400.124895)
			(xy 437.527808 -400.179174) (xy 437.551186 -400.236917) (xy 437.566987 -400.297175) (xy 437.574953 -400.358958)
			(xy 437.575452 -400.390106) (xy 437.574953 -400.421254) (xy 437.566987 -400.483037) (xy 437.551186 -400.543295)
			(xy 437.527808 -400.601038) (xy 437.497239 -400.655317) (xy 437.459979 -400.705241) (xy 437.416642 -400.749991)
			(xy 437.369142 -400.78787) (xy 446.249042 -400.78787) (xy 446.253113 -400.732248) (xy 446.265239 -400.677811)
			(xy 446.285162 -400.62572) (xy 446.312458 -400.577085) (xy 446.346544 -400.532942) (xy 446.386693 -400.494233)
			(xy 446.432051 -400.461782) (xy 446.481651 -400.436281) (xy 446.534435 -400.418274) (xy 446.589278 -400.408144)
			(xy 446.645012 -400.406107) (xy 446.700449 -400.412207) (xy 446.754406 -400.426313) (xy 446.805735 -400.448125)
			(xy 446.853341 -400.477179) (xy 446.896209 -400.512854) (xy 446.933426 -400.554391) (xy 446.964199 -400.600904)
			(xy 446.987871 -400.651401) (xy 447.003939 -400.704808) (xy 447.012059 -400.759984) (xy 447.012568 -400.78787)
			(xy 447.012059 -400.815756) (xy 447.003939 -400.870932) (xy 446.987871 -400.924339) (xy 446.964199 -400.974836)
			(xy 446.933426 -401.021349) (xy 446.896209 -401.062886) (xy 446.853341 -401.098561) (xy 446.805735 -401.127615)
			(xy 446.754406 -401.149427) (xy 446.700449 -401.163533) (xy 446.645012 -401.169633) (xy 446.589278 -401.167596)
			(xy 446.534435 -401.157466) (xy 446.481651 -401.139459) (xy 446.432051 -401.113958) (xy 446.386693 -401.081507)
			(xy 446.346544 -401.042798) (xy 446.312458 -400.998655) (xy 446.285162 -400.95002) (xy 446.265239 -400.897929)
			(xy 446.253113 -400.843492) (xy 446.249042 -400.78787) (xy 437.369142 -400.78787) (xy 437.367937 -400.788831)
			(xy 437.314666 -400.821124) (xy 437.257703 -400.846341) (xy 437.197982 -400.864065) (xy 437.136485 -400.874008)
			(xy 437.074222 -400.876004) (xy 437.012215 -400.870022) (xy 436.951481 -400.85616) (xy 436.893019 -400.834646)
			(xy 436.837788 -400.805832) (xy 436.786696 -400.770192) (xy 436.74058 -400.728311) (xy 436.700198 -400.680876)
			(xy 436.666214 -400.628667) (xy 436.639185 -400.572541) (xy 436.619556 -400.51342) (xy 436.607647 -400.452273)
			(xy 436.603656 -400.390106) (xy 433.174808 -400.390106) (xy 433.174808 -400.422824) (xy 433.166024 -400.487668)
			(xy 433.148616 -400.550747) (xy 433.122898 -400.610919) (xy 433.106576 -400.63928) (xy 433.103267 -400.645307)
			(xy 433.099658 -400.658569) (xy 433.099464 -400.665442) (xy 433.099464 -401.414742) (xy 433.099682 -401.421613)
			(xy 433.103273 -401.434876) (xy 433.106576 -401.440904) (xy 433.122879 -401.469276) (xy 433.148598 -401.529445)
			(xy 433.166007 -401.592521) (xy 433.174793 -401.657364) (xy 433.174795 -401.722799) (xy 433.166015 -401.787642)
			(xy 433.14861 -401.85072) (xy 433.122896 -401.910891) (xy 433.106576 -401.939252) (xy 433.103241 -401.945267)
			(xy 433.099649 -401.958538) (xy 433.099464 -401.965414) (xy 433.099464 -402.251418) (xy 433.098982 -402.261577)
			(xy 433.091202 -402.280346) (xy 433.076833 -402.294711) (xy 433.058061 -402.302485) (xy 433.047902 -402.30298)
			(xy 432.331622 -402.30298) (xy 432.321454 -402.302518) (xy 432.302663 -402.294744) (xy 432.288278 -402.28037)
			(xy 432.28049 -402.261586) (xy 432.28006 -402.251418) (xy 432.28006 -401.965414) (xy 432.279868 -401.958541)
			(xy 432.27626 -401.945278) (xy 432.272948 -401.939252) (xy 432.256607 -401.910901) (xy 432.230891 -401.850728)
			(xy 432.213484 -401.787647) (xy 432.204703 -401.7228) (xy 430.915987 -401.7228) (xy 430.906428 -401.739354)
			(xy 430.903132 -401.745388) (xy 430.899514 -401.758644) (xy 430.899316 -401.765516) (xy 430.899316 -402.514816)
			(xy 430.8995 -402.52169) (xy 430.903113 -402.534953) (xy 430.906428 -402.540978) (xy 430.922787 -402.569331)
			(xy 430.94859 -402.629489) (xy 430.966081 -402.692567) (xy 430.974944 -402.757423) (xy 430.975516 -402.790152)
			(xy 430.974949 -402.822879) (xy 434.404843 -402.822879) (xy 434.404849 -402.757439) (xy 434.413637 -402.692592)
			(xy 434.43105 -402.629512) (xy 434.456772 -402.56934) (xy 434.473096 -402.540978) (xy 434.476418 -402.534957)
			(xy 434.480019 -402.52169) (xy 434.480208 -402.514816) (xy 434.480208 -401.765516) (xy 434.480009 -401.758643)
			(xy 434.476406 -401.74538) (xy 434.473096 -401.739354) (xy 434.456758 -401.711002) (xy 434.431044 -401.650828)
			(xy 434.41364 -401.587747) (xy 434.404859 -401.522902) (xy 434.404861 -401.457464) (xy 434.413647 -401.392619)
			(xy 434.431056 -401.32954) (xy 434.456774 -401.269368) (xy 434.473096 -401.241006) (xy 434.476408 -401.23498)
			(xy 434.480016 -401.221717) (xy 434.480208 -401.214844) (xy 434.480208 -400.92884) (xy 434.480655 -400.918688)
			(xy 434.488438 -400.899934) (xy 434.502828 -400.885609) (xy 434.521616 -400.87791) (xy 434.53177 -400.877532)
			(xy 435.24805 -400.877532) (xy 435.258173 -400.878067) (xy 435.276891 -400.885777) (xy 435.291249 -400.900049)
			(xy 435.299071 -400.918721) (xy 435.299612 -400.92884) (xy 435.299612 -401.214844) (xy 435.299824 -401.221716)
			(xy 435.303418 -401.234979) (xy 435.306724 -401.241006) (xy 435.32303 -401.269376) (xy 435.348752 -401.329545)
			(xy 435.366163 -401.392622) (xy 435.374949 -401.457465) (xy 435.374952 -401.522901) (xy 435.36617 -401.587745)
			(xy 435.348763 -401.650823) (xy 435.331985 -401.690078) (xy 436.603656 -401.690078) (xy 436.607647 -401.627911)
			(xy 436.619556 -401.566764) (xy 436.639185 -401.507643) (xy 436.666214 -401.451517) (xy 436.700198 -401.399308)
			(xy 436.74058 -401.351873) (xy 436.786696 -401.309992) (xy 436.837788 -401.274352) (xy 436.893019 -401.245538)
			(xy 436.951481 -401.224024) (xy 437.012215 -401.210162) (xy 437.074222 -401.20418) (xy 437.136485 -401.206176)
			(xy 437.197982 -401.216119) (xy 437.257703 -401.233843) (xy 437.314666 -401.25906) (xy 437.367937 -401.291353)
			(xy 437.416642 -401.330193) (xy 437.459979 -401.374943) (xy 437.497239 -401.424867) (xy 437.527808 -401.479146)
			(xy 437.532275 -401.49018) (xy 438.803804 -401.49018) (xy 438.807795 -401.428013) (xy 438.819704 -401.366866)
			(xy 438.839333 -401.307745) (xy 438.866362 -401.251619) (xy 438.900346 -401.19941) (xy 438.940728 -401.151975)
			(xy 438.986844 -401.110094) (xy 439.037936 -401.074454) (xy 439.093167 -401.04564) (xy 439.151629 -401.024126)
			(xy 439.212363 -401.010264) (xy 439.27437 -401.004282) (xy 439.336633 -401.006278) (xy 439.39813 -401.016221)
			(xy 439.457851 -401.033945) (xy 439.514814 -401.059162) (xy 439.568085 -401.091455) (xy 439.61679 -401.130295)
			(xy 439.660127 -401.175045) (xy 439.697387 -401.224969) (xy 439.727956 -401.279248) (xy 439.751334 -401.336991)
			(xy 439.760066 -401.370292) (xy 448.261484 -401.370292) (xy 448.265555 -401.31467) (xy 448.277681 -401.260233)
			(xy 448.297604 -401.208142) (xy 448.3249 -401.159507) (xy 448.358986 -401.115364) (xy 448.399135 -401.076655)
			(xy 448.444493 -401.044204) (xy 448.494093 -401.018703) (xy 448.546877 -401.000696) (xy 448.60172 -400.990566)
			(xy 448.657454 -400.988529) (xy 448.712891 -400.994629) (xy 448.766848 -401.008735) (xy 448.818177 -401.030547)
			(xy 448.865783 -401.059601) (xy 448.908651 -401.095276) (xy 448.945868 -401.136813) (xy 448.976641 -401.183326)
			(xy 449.000313 -401.233823) (xy 449.016381 -401.28723) (xy 449.024501 -401.342406) (xy 449.02501 -401.370292)
			(xy 449.024501 -401.398178) (xy 449.016381 -401.453354) (xy 449.000313 -401.506761) (xy 448.976641 -401.557258)
			(xy 448.945868 -401.603771) (xy 448.908651 -401.645308) (xy 448.865783 -401.680983) (xy 448.818177 -401.710037)
			(xy 448.766848 -401.731849) (xy 448.712891 -401.745955) (xy 448.657454 -401.752055) (xy 448.60172 -401.750018)
			(xy 448.546877 -401.739888) (xy 448.494093 -401.721881) (xy 448.444493 -401.69638) (xy 448.399135 -401.663929)
			(xy 448.358986 -401.62522) (xy 448.3249 -401.581077) (xy 448.297604 -401.532442) (xy 448.277681 -401.480351)
			(xy 448.265555 -401.425914) (xy 448.261484 -401.370292) (xy 439.760066 -401.370292) (xy 439.767135 -401.397249)
			(xy 439.775101 -401.459032) (xy 439.7756 -401.49018) (xy 439.775101 -401.521328) (xy 439.767135 -401.583111)
			(xy 439.751334 -401.643369) (xy 439.727956 -401.701112) (xy 439.697387 -401.755391) (xy 439.660127 -401.805315)
			(xy 439.61679 -401.850065) (xy 439.568085 -401.888905) (xy 439.514814 -401.921198) (xy 439.457851 -401.946415)
			(xy 439.39813 -401.964139) (xy 439.336633 -401.974082) (xy 439.27437 -401.976078) (xy 439.212363 -401.970096)
			(xy 439.151629 -401.956234) (xy 439.093167 -401.93472) (xy 439.037936 -401.905906) (xy 438.986844 -401.870266)
			(xy 438.940728 -401.828385) (xy 438.900346 -401.78095) (xy 438.866362 -401.728741) (xy 438.839333 -401.672615)
			(xy 438.819704 -401.613494) (xy 438.807795 -401.552347) (xy 438.803804 -401.49018) (xy 437.532275 -401.49018)
			(xy 437.551186 -401.536889) (xy 437.566987 -401.597147) (xy 437.574953 -401.65893) (xy 437.575452 -401.690078)
			(xy 437.574953 -401.721226) (xy 437.566987 -401.783009) (xy 437.551186 -401.843267) (xy 437.527808 -401.90101)
			(xy 437.497239 -401.955289) (xy 437.459979 -402.005213) (xy 437.416642 -402.049963) (xy 437.367937 -402.088803)
			(xy 437.314666 -402.121096) (xy 437.257703 -402.146313) (xy 437.197982 -402.164037) (xy 437.136485 -402.17398)
			(xy 437.074222 -402.175976) (xy 437.012215 -402.169994) (xy 436.951481 -402.156132) (xy 436.893019 -402.134618)
			(xy 436.837788 -402.105804) (xy 436.786696 -402.070164) (xy 436.74058 -402.028283) (xy 436.700198 -401.980848)
			(xy 436.666214 -401.928639) (xy 436.639185 -401.872513) (xy 436.619556 -401.813392) (xy 436.607647 -401.752245)
			(xy 436.603656 -401.690078) (xy 435.331985 -401.690078) (xy 435.323046 -401.710993) (xy 435.306724 -401.739354)
			(xy 435.303427 -401.745388) (xy 435.29981 -401.758644) (xy 435.299612 -401.765516) (xy 435.299612 -402.514816)
			(xy 435.299796 -402.52169) (xy 435.303409 -402.534953) (xy 435.306724 -402.540978) (xy 435.323007 -402.569361)
			(xy 435.34873 -402.629527) (xy 435.366144 -402.692601) (xy 435.374933 -402.757442) (xy 435.374936 -402.790152)
			(xy 438.803804 -402.790152) (xy 438.807795 -402.727985) (xy 438.819704 -402.666838) (xy 438.839333 -402.607717)
			(xy 438.866362 -402.551591) (xy 438.900346 -402.499382) (xy 438.940728 -402.451947) (xy 438.986844 -402.410066)
			(xy 439.037936 -402.374426) (xy 439.093167 -402.345612) (xy 439.151629 -402.324098) (xy 439.212363 -402.310236)
			(xy 439.27437 -402.304254) (xy 439.336633 -402.30625) (xy 439.39813 -402.316193) (xy 439.457851 -402.333917)
			(xy 439.514814 -402.359134) (xy 439.568085 -402.391427) (xy 439.61679 -402.430267) (xy 439.660127 -402.475017)
			(xy 439.697387 -402.524941) (xy 439.727956 -402.57922) (xy 439.751334 -402.636963) (xy 439.767135 -402.697221)
			(xy 439.775101 -402.759004) (xy 439.7756 -402.790152) (xy 439.775101 -402.8213) (xy 439.767135 -402.883083)
			(xy 439.751334 -402.943341) (xy 439.727956 -403.001084) (xy 439.697387 -403.055363) (xy 439.660127 -403.105287)
			(xy 439.61679 -403.150037) (xy 439.568085 -403.188877) (xy 439.514814 -403.22117) (xy 439.457851 -403.246387)
			(xy 439.39813 -403.264111) (xy 439.336633 -403.274054) (xy 439.27437 -403.27605) (xy 439.212363 -403.270068)
			(xy 439.151629 -403.256206) (xy 439.093167 -403.234692) (xy 439.037936 -403.205878) (xy 438.986844 -403.170238)
			(xy 438.940728 -403.128357) (xy 438.900346 -403.080922) (xy 438.866362 -403.028713) (xy 438.839333 -402.972587)
			(xy 438.819704 -402.913466) (xy 438.807795 -402.852319) (xy 438.803804 -402.790152) (xy 435.374936 -402.790152)
			(xy 435.374939 -402.822876) (xy 435.366161 -402.887718) (xy 435.348757 -402.950795) (xy 435.323044 -403.010965)
			(xy 435.306724 -403.039326) (xy 435.303402 -403.045347) (xy 435.2998 -403.058613) (xy 435.299612 -403.065488)
			(xy 435.299612 -403.351492) (xy 435.299172 -403.361644) (xy 435.291381 -403.380394) (xy 435.27699 -403.394717)
			(xy 435.258204 -403.402419) (xy 435.24805 -403.4028) (xy 434.53177 -403.4028) (xy 434.521646 -403.402299)
			(xy 434.502932 -403.394569) (xy 434.488578 -403.380288) (xy 434.480753 -403.361613) (xy 434.480208 -403.351492)
			(xy 434.480208 -403.065488) (xy 434.48002 -403.058615) (xy 434.476409 -403.045352) (xy 434.473096 -403.039326)
			(xy 434.456734 -403.010987) (xy 434.431023 -402.95081) (xy 434.413621 -402.887727) (xy 434.404843 -402.822879)
			(xy 430.974949 -402.822879) (xy 430.974949 -402.822881) (xy 430.966093 -402.88774) (xy 430.948603 -402.95082)
			(xy 430.922796 -403.010978) (xy 430.906428 -403.039326) (xy 430.903106 -403.045347) (xy 430.899504 -403.058614)
			(xy 430.899316 -403.065488) (xy 430.899316 -403.351492) (xy 430.898809 -403.361598) (xy 430.891077 -403.380273)
			(xy 430.876787 -403.394568) (xy 430.858114 -403.402306) (xy 430.848008 -403.4028) (xy 430.131728 -403.4028)
			(xy 430.121607 -403.402361) (xy 430.102904 -403.394622) (xy 430.088589 -403.380313) (xy 430.080843 -403.361613)
			(xy 430.08042 -403.351492) (xy 430.08042 -403.065488) (xy 430.08023 -403.058615) (xy 430.07662 -403.045352)
			(xy 430.073308 -403.039326) (xy 430.056954 -403.010971) (xy 430.031149 -402.950813) (xy 430.013656 -402.887736)
			(xy 430.004792 -402.82288) (xy 430.00422 -402.790152) (xy 426.57485 -402.790152) (xy 426.574853 -402.822876)
			(xy 426.566075 -402.887718) (xy 426.548672 -402.950795) (xy 426.52296 -403.010965) (xy 426.50664 -403.039326)
			(xy 426.503319 -403.045348) (xy 426.499717 -403.058614) (xy 426.499528 -403.065488) (xy 426.499528 -403.351492)
			(xy 426.499072 -403.361642) (xy 426.491285 -403.380389) (xy 426.476899 -403.394712) (xy 426.458118 -403.402417)
			(xy 426.447966 -403.4028) (xy 425.731686 -403.4028) (xy 425.721563 -403.402286) (xy 425.70285 -403.394561)
			(xy 425.688495 -403.380284) (xy 425.68067 -403.361612) (xy 425.680124 -403.351492) (xy 425.680124 -403.065488)
			(xy 425.679934 -403.058615) (xy 425.676324 -403.045352) (xy 425.673012 -403.039326) (xy 425.65665 -403.010987)
			(xy 425.630938 -402.95081) (xy 425.613535 -402.887727) (xy 425.604757 -402.822879) (xy 422.174863 -402.822879)
			(xy 422.174863 -402.822881) (xy 422.166008 -402.887739) (xy 422.148518 -402.95082) (xy 422.122712 -403.010978)
			(xy 422.106344 -403.039326) (xy 422.103024 -403.045348) (xy 422.099421 -403.058614) (xy 422.099232 -403.065488)
			(xy 422.099232 -403.351492) (xy 422.098709 -403.361596) (xy 422.09098 -403.380268) (xy 422.076695 -403.394562)
			(xy 422.058028 -403.402303) (xy 422.047924 -403.4028) (xy 421.331644 -403.4028) (xy 421.321524 -403.402348)
			(xy 421.302822 -403.394614) (xy 421.288506 -403.380308) (xy 421.280759 -403.361611) (xy 421.280336 -403.351492)
			(xy 421.280336 -403.065488) (xy 421.280144 -403.058615) (xy 421.276535 -403.045352) (xy 421.273224 -403.039326)
			(xy 421.256871 -403.01097) (xy 421.231066 -402.950813) (xy 421.213572 -402.887736) (xy 421.204708 -402.82288)
			(xy 421.204136 -402.790152) (xy 414.915604 -402.790152) (xy 414.915604 -405.622714) (xy 419.004836 -405.622714)
			(xy 419.004837 -405.557276) (xy 419.013622 -405.492431) (xy 419.031032 -405.429352) (xy 419.056752 -405.369181)
			(xy 419.073076 -405.34082) (xy 419.076382 -405.334791) (xy 419.079994 -405.321531) (xy 419.080188 -405.314658)
			(xy 419.080188 -404.565358) (xy 419.079975 -404.558486) (xy 419.076381 -404.545223) (xy 419.073076 -404.539196)
			(xy 419.056771 -404.510825) (xy 419.03105 -404.450656) (xy 419.013638 -404.38758) (xy 419.004852 -404.322737)
			(xy 419.004849 -404.257301) (xy 419.013631 -404.192457) (xy 419.031037 -404.129379) (xy 419.056754 -404.069209)
			(xy 419.073076 -404.040848) (xy 419.076408 -404.034832) (xy 419.080003 -404.021562) (xy 419.080188 -404.014686)
			(xy 419.080188 -403.728682) (xy 419.08055 -403.718503) (xy 419.088351 -403.699698) (xy 419.102756 -403.685313)
			(xy 419.12157 -403.677537) (xy 419.13175 -403.67712) (xy 419.84803 -403.67712) (xy 419.858187 -403.677608)
			(xy 419.876954 -403.685389) (xy 419.891317 -403.699756) (xy 419.899094 -403.718524) (xy 419.899592 -403.728682)
			(xy 419.899592 -404.014686) (xy 419.89979 -404.021559) (xy 419.903394 -404.034822) (xy 419.906704 -404.040848)
			(xy 419.923044 -404.069199) (xy 419.948757 -404.129373) (xy 419.966162 -404.192454) (xy 419.974942 -404.2573)
			(xy 419.974939 -404.322738) (xy 419.966154 -404.387583) (xy 419.948745 -404.450662) (xy 419.923026 -404.510834)
			(xy 419.906704 -404.539196) (xy 419.903391 -404.545221) (xy 419.899784 -404.558485) (xy 419.899592 -404.565358)
			(xy 419.899592 -405.314658) (xy 419.899801 -405.32153) (xy 419.903398 -405.334793) (xy 419.906704 -405.34082)
			(xy 419.92302 -405.369185) (xy 419.948736 -405.429355) (xy 419.966143 -405.492433) (xy 419.974926 -405.557277)
			(xy 419.974927 -405.622713) (xy 419.966145 -405.687557) (xy 419.948739 -405.750635) (xy 419.923024 -405.810806)
			(xy 419.906704 -405.839168) (xy 419.903401 -405.845198) (xy 419.899788 -405.858458) (xy 419.899592 -405.86533)
			(xy 419.899592 -406.151334) (xy 419.899095 -406.16149) (xy 419.891315 -406.180254) (xy 419.876951 -406.194617)
			(xy 419.858186 -406.202396) (xy 419.84803 -406.202896) (xy 419.13175 -406.202896) (xy 419.121586 -406.202396)
			(xy 419.102799 -406.194634) (xy 419.088413 -406.180272) (xy 419.08062 -406.161497) (xy 419.080188 -406.151334)
			(xy 419.080188 -405.86533) (xy 419.079986 -405.858458) (xy 419.076385 -405.845195) (xy 419.073076 -405.839168)
			(xy 419.056748 -405.81081) (xy 419.031028 -405.750638) (xy 419.01362 -405.687559) (xy 419.004836 -405.622714)
			(xy 414.915604 -405.622714) (xy 414.915604 -406.690068) (xy 421.204136 -406.690068) (xy 421.204718 -406.657339)
			(xy 421.213571 -406.592482) (xy 421.231056 -406.529402) (xy 421.256858 -406.469243) (xy 421.273224 -406.440894)
			(xy 421.276543 -406.434871) (xy 421.280145 -406.421606) (xy 421.280336 -406.414732) (xy 421.280336 -405.665432)
			(xy 421.280127 -405.65856) (xy 421.27653 -405.645297) (xy 421.273224 -405.63927) (xy 421.256849 -405.610926)
			(xy 421.231049 -405.550765) (xy 421.213562 -405.487684) (xy 421.204705 -405.422825) (xy 421.204136 -405.390096)
			(xy 421.204686 -405.357366) (xy 421.213548 -405.292507) (xy 421.231043 -405.229428) (xy 421.256854 -405.16927)
			(xy 421.273224 -405.140922) (xy 421.276533 -405.134894) (xy 421.280142 -405.121633) (xy 421.280336 -405.11476)
			(xy 421.280336 -404.828756) (xy 421.28075 -404.81864) (xy 421.288509 -404.799954) (xy 421.302828 -404.785659)
			(xy 421.321527 -404.777933) (xy 421.331644 -404.777448) (xy 422.047924 -404.777448) (xy 422.058028 -404.777964)
			(xy 422.076697 -404.7857) (xy 422.090989 -404.799986) (xy 422.098732 -404.818652) (xy 422.099232 -404.828756)
			(xy 422.099232 -405.11476) (xy 422.099435 -405.121632) (xy 422.103035 -405.134895) (xy 422.106344 -405.140922)
			(xy 422.122713 -405.169269) (xy 422.148515 -405.229429) (xy 422.166004 -405.292509) (xy 422.174863 -405.357367)
			(xy 422.175432 -405.390096) (xy 422.174883 -405.422826) (xy 422.166021 -405.487685) (xy 422.148526 -405.550765)
			(xy 422.131694 -405.589994) (xy 423.404284 -405.589994) (xy 423.404872 -405.557265) (xy 423.413721 -405.492408)
			(xy 423.431205 -405.429328) (xy 423.457007 -405.369169) (xy 423.473372 -405.34082) (xy 423.476678 -405.334791)
			(xy 423.48029 -405.321531) (xy 423.480484 -405.314658) (xy 423.480484 -404.565358) (xy 423.480272 -404.558486)
			(xy 423.476678 -404.545223) (xy 423.473372 -404.539196) (xy 423.457002 -404.510849) (xy 423.431202 -404.450689)
			(xy 423.413714 -404.387608) (xy 423.404854 -404.322751) (xy 423.404284 -404.290022) (xy 423.404839 -404.257292)
			(xy 423.413698 -404.192434) (xy 423.431192 -404.129353) (xy 423.457002 -404.069196) (xy 423.473372 -404.040848)
			(xy 423.476703 -404.034831) (xy 423.480299 -404.021561) (xy 423.480484 -404.014686) (xy 423.480484 -403.728682)
			(xy 423.480913 -403.718549) (xy 423.488655 -403.699819) (xy 423.502959 -403.685461) (xy 423.521661 -403.677651)
			(xy 423.531792 -403.67712) (xy 424.248072 -403.67712) (xy 424.258227 -403.677545) (xy 424.276983 -403.685335)
			(xy 424.291308 -403.699731) (xy 424.299005 -403.718525) (xy 424.29938 -403.728682) (xy 424.29938 -404.014686)
			(xy 424.29958 -404.021559) (xy 424.303183 -404.034821) (xy 424.306492 -404.040848) (xy 424.322876 -404.069187)
			(xy 424.348674 -404.12935) (xy 424.366158 -404.192433) (xy 424.375013 -404.257292) (xy 424.37558 -404.290022)
			(xy 424.375004 -404.322751) (xy 424.366152 -404.387609) (xy 424.348665 -404.450689) (xy 424.322859 -404.510848)
			(xy 424.306492 -404.539196) (xy 424.303178 -404.545221) (xy 424.299572 -404.558484) (xy 424.29938 -404.565358)
			(xy 424.29938 -405.314658) (xy 424.29959 -405.32153) (xy 424.303186 -405.334793) (xy 424.306492 -405.34082)
			(xy 424.322865 -405.369165) (xy 424.348665 -405.429326) (xy 424.366153 -405.492407) (xy 424.375011 -405.557265)
			(xy 424.37558 -405.589994) (xy 424.375037 -405.622724) (xy 424.366174 -405.687583) (xy 424.348678 -405.750664)
			(xy 424.322864 -405.810821) (xy 424.306492 -405.839168) (xy 424.303188 -405.845198) (xy 424.299576 -405.858458)
			(xy 424.29938 -405.86533) (xy 424.29938 -406.151334) (xy 424.298902 -406.16146) (xy 424.291167 -406.180179)
			(xy 424.276878 -406.194533) (xy 424.258196 -406.202355) (xy 424.248072 -406.202896) (xy 423.531792 -406.202896)
			(xy 423.521637 -406.202485) (xy 423.502884 -406.194686) (xy 423.48856 -406.180286) (xy 423.480862 -406.161491)
			(xy 423.480484 -406.151334) (xy 423.480484 -405.86533) (xy 423.480282 -405.858457) (xy 423.476681 -405.845195)
			(xy 423.473372 -405.839168) (xy 423.456991 -405.810827) (xy 423.431194 -405.750664) (xy 423.413708 -405.687582)
			(xy 423.404852 -405.622724) (xy 423.404284 -405.589994) (xy 422.131694 -405.589994) (xy 422.122715 -405.610922)
			(xy 422.106344 -405.63927) (xy 422.103043 -405.645302) (xy 422.099428 -405.65856) (xy 422.099232 -405.665432)
			(xy 422.099232 -406.414732) (xy 422.099408 -406.421606) (xy 422.103027 -406.434869) (xy 422.106344 -406.440894)
			(xy 422.122702 -406.469248) (xy 422.148507 -406.529405) (xy 422.165999 -406.592483) (xy 422.174861 -406.657339)
			(xy 422.175432 -406.690068) (xy 422.17487 -406.722792) (xy 425.604766 -406.722792) (xy 425.60477 -406.657353)
			(xy 425.613557 -406.592507) (xy 425.630968 -406.529428) (xy 425.656688 -406.469256) (xy 425.673012 -406.440894)
			(xy 425.67633 -406.434871) (xy 425.679933 -406.421606) (xy 425.680124 -406.414732) (xy 425.680124 -405.665432)
			(xy 425.679917 -405.65856) (xy 425.676319 -405.645297) (xy 425.673012 -405.63927) (xy 425.656687 -405.61091)
			(xy 425.630971 -405.550738) (xy 425.613565 -405.487659) (xy 425.604782 -405.422815) (xy 425.604782 -405.357378)
			(xy 425.613566 -405.292534) (xy 425.630974 -405.229455) (xy 425.65669 -405.169284) (xy 425.673012 -405.140922)
			(xy 425.67632 -405.134894) (xy 425.67993 -405.121633) (xy 425.680124 -405.11476) (xy 425.680124 -404.828756)
			(xy 425.680486 -404.818596) (xy 425.688301 -404.799838) (xy 425.702716 -404.785515) (xy 425.721523 -404.777822)
			(xy 425.731686 -404.777448) (xy 426.447966 -404.777448) (xy 426.458091 -404.777955) (xy 426.476813 -404.785673)
			(xy 426.491171 -404.799953) (xy 426.49899 -404.818633) (xy 426.499528 -404.828756) (xy 426.499528 -405.11476)
			(xy 426.499732 -405.121632) (xy 426.503332 -405.134895) (xy 426.50664 -405.140922) (xy 426.522959 -405.169285)
			(xy 426.548679 -405.229455) (xy 426.566088 -405.292534) (xy 426.574872 -405.357378) (xy 426.574873 -405.422815)
			(xy 426.566089 -405.487659) (xy 426.548681 -405.550738) (xy 426.522963 -405.610909) (xy 426.516169 -405.622714)
			(xy 427.804922 -405.622714) (xy 427.804923 -405.557276) (xy 427.813708 -405.492431) (xy 427.831117 -405.429352)
			(xy 427.856837 -405.369181) (xy 427.87316 -405.34082) (xy 427.876464 -405.33479) (xy 427.880077 -405.321531)
			(xy 427.880272 -405.314658) (xy 427.880272 -404.565358) (xy 427.880061 -404.558486) (xy 427.876466 -404.545223)
			(xy 427.87316 -404.539196) (xy 427.856856 -404.510825) (xy 427.831135 -404.450656) (xy 427.813724 -404.387579)
			(xy 427.804938 -404.322737) (xy 427.804936 -404.257301) (xy 427.813717 -404.192458) (xy 427.831123 -404.12938)
			(xy 427.856839 -404.069209) (xy 427.87316 -404.040848) (xy 427.87649 -404.034831) (xy 427.880086 -404.021561)
			(xy 427.880272 -404.014686) (xy 427.880272 -403.728682) (xy 427.88065 -403.718505) (xy 427.888447 -403.699703)
			(xy 427.902847 -403.685318) (xy 427.921657 -403.67754) (xy 427.931834 -403.67712) (xy 428.648114 -403.67712)
			(xy 428.65827 -403.677622) (xy 428.677036 -403.685397) (xy 428.6914 -403.69976) (xy 428.699178 -403.718526)
			(xy 428.699676 -403.728682) (xy 428.699676 -404.014686) (xy 428.699876 -404.021559) (xy 428.703479 -404.034821)
			(xy 428.706788 -404.040848) (xy 428.723128 -404.069199) (xy 428.748842 -404.129373) (xy 428.766248 -404.192454)
			(xy 428.775028 -404.2573) (xy 428.775026 -404.322738) (xy 428.76624 -404.387583) (xy 428.74883 -404.450663)
			(xy 428.723111 -404.510834) (xy 428.706788 -404.539196) (xy 428.703474 -404.545221) (xy 428.699868 -404.558484)
			(xy 428.699676 -404.565358) (xy 428.699676 -405.314658) (xy 428.699887 -405.32153) (xy 428.703482 -405.334793)
			(xy 428.706788 -405.34082) (xy 428.723104 -405.369184) (xy 428.748821 -405.429355) (xy 428.766229 -405.492433)
			(xy 428.775012 -405.557277) (xy 428.775013 -405.622713) (xy 428.766231 -405.687557) (xy 428.748824 -405.750635)
			(xy 428.723109 -405.810806) (xy 428.706788 -405.839168) (xy 428.703484 -405.845198) (xy 428.699872 -405.858458)
			(xy 428.699676 -405.86533) (xy 428.699676 -406.151334) (xy 428.699195 -406.161492) (xy 428.691412 -406.180259)
			(xy 428.677043 -406.194623) (xy 428.658272 -406.202399) (xy 428.648114 -406.202896) (xy 427.931834 -406.202896)
			(xy 427.921683 -406.202339) (xy 427.902921 -406.194583) (xy 427.888556 -406.180236) (xy 427.880774 -406.161485)
			(xy 427.880272 -406.151334) (xy 427.880272 -405.86533) (xy 427.880072 -405.858457) (xy 427.87647 -405.845194)
			(xy 427.87316 -405.839168) (xy 427.856832 -405.81081) (xy 427.831114 -405.750638) (xy 427.813705 -405.687559)
			(xy 427.804922 -405.622714) (xy 426.516169 -405.622714) (xy 426.50664 -405.63927) (xy 426.503339 -405.645302)
			(xy 426.499724 -405.65856) (xy 426.499528 -405.665432) (xy 426.499528 -406.414732) (xy 426.499704 -406.421606)
			(xy 426.503323 -406.434869) (xy 426.50664 -406.440894) (xy 426.522936 -406.46927) (xy 426.548657 -406.529437)
			(xy 426.566069 -406.592513) (xy 426.574856 -406.657355) (xy 426.574858 -406.690068) (xy 430.00422 -406.690068)
			(xy 430.004791 -406.657339) (xy 430.013645 -406.59248) (xy 430.031134 -406.5294) (xy 430.05694 -406.469242)
			(xy 430.073308 -406.440894) (xy 430.076625 -406.434871) (xy 430.080229 -406.421606) (xy 430.08042 -406.414732)
			(xy 430.08042 -405.665432) (xy 430.080213 -405.65856) (xy 430.076615 -405.645297) (xy 430.073308 -405.63927)
			(xy 430.056931 -405.610927) (xy 430.031132 -405.550765) (xy 430.013645 -405.487684) (xy 430.004788 -405.422826)
			(xy 430.00422 -405.390096) (xy 430.004759 -405.357365) (xy 430.013622 -405.292506) (xy 430.03112 -405.229426)
			(xy 430.056936 -405.169269) (xy 430.073308 -405.140922) (xy 430.076615 -405.134894) (xy 430.080226 -405.121633)
			(xy 430.08042 -405.11476) (xy 430.08042 -404.828756) (xy 430.08085 -404.818642) (xy 430.088605 -404.799959)
			(xy 430.102919 -404.785665) (xy 430.121613 -404.777935) (xy 430.131728 -404.777448) (xy 430.848008 -404.777448)
			(xy 430.858111 -404.777977) (xy 430.876779 -404.785708) (xy 430.891072 -404.799991) (xy 430.898815 -404.818654)
			(xy 430.899316 -404.828756) (xy 430.899316 -405.11476) (xy 430.899521 -405.121632) (xy 430.90312 -405.134895)
			(xy 430.906428 -405.140922) (xy 430.922805 -405.169265) (xy 430.948603 -405.229427) (xy 430.96609 -405.292508)
			(xy 430.974947 -405.357366) (xy 430.975516 -405.390096) (xy 430.974969 -405.422826) (xy 430.966107 -405.487685)
			(xy 430.948612 -405.550765) (xy 430.922799 -405.610923) (xy 430.91599 -405.622713) (xy 432.204712 -405.622713)
			(xy 432.204713 -405.557276) (xy 432.213497 -405.492431) (xy 432.230906 -405.429352) (xy 432.256625 -405.369181)
			(xy 432.272948 -405.34082) (xy 432.276251 -405.33479) (xy 432.279865 -405.32153) (xy 432.28006 -405.314658)
			(xy 432.28006 -404.565358) (xy 432.279851 -404.558486) (xy 432.276255 -404.545223) (xy 432.272948 -404.539196)
			(xy 432.256644 -404.510825) (xy 432.230924 -404.450656) (xy 432.213514 -404.387579) (xy 432.204728 -404.322737)
			(xy 432.204725 -404.257301) (xy 432.213506 -404.192458) (xy 432.230912 -404.12938) (xy 432.256627 -404.069209)
			(xy 432.272948 -404.040848) (xy 432.276277 -404.03483) (xy 432.279874 -404.021561) (xy 432.28006 -404.014686)
			(xy 432.28006 -403.728682) (xy 432.28045 -403.718507) (xy 432.288245 -403.699707) (xy 432.302641 -403.685322)
			(xy 432.321446 -403.677542) (xy 432.331622 -403.67712) (xy 433.047902 -403.67712) (xy 433.058058 -403.677631)
			(xy 433.076823 -403.685403) (xy 433.091188 -403.699763) (xy 433.098965 -403.718526) (xy 433.099464 -403.728682)
			(xy 433.099464 -404.014686) (xy 433.099666 -404.021558) (xy 433.103268 -404.034821) (xy 433.106576 -404.040848)
			(xy 433.122916 -404.069199) (xy 433.148631 -404.129373) (xy 433.166037 -404.192454) (xy 433.174818 -404.2573)
			(xy 433.174816 -404.290022) (xy 436.603656 -404.290022) (xy 436.607647 -404.227855) (xy 436.619556 -404.166708)
			(xy 436.639185 -404.107587) (xy 436.666214 -404.051461) (xy 436.700198 -403.999252) (xy 436.74058 -403.951817)
			(xy 436.786696 -403.909936) (xy 436.837788 -403.874296) (xy 436.893019 -403.845482) (xy 436.951481 -403.823968)
			(xy 437.012215 -403.810106) (xy 437.074222 -403.804124) (xy 437.136485 -403.80612) (xy 437.197982 -403.816063)
			(xy 437.257703 -403.833787) (xy 437.314666 -403.859004) (xy 437.367937 -403.891297) (xy 437.416642 -403.930137)
			(xy 437.459979 -403.974887) (xy 437.497239 -404.024811) (xy 437.507272 -404.042626) (xy 446.93027 -404.042626)
			(xy 446.934341 -403.987004) (xy 446.946467 -403.932567) (xy 446.96639 -403.880476) (xy 446.993686 -403.831841)
			(xy 447.027772 -403.787698) (xy 447.067921 -403.748989) (xy 447.113279 -403.716538) (xy 447.162879 -403.691037)
			(xy 447.215663 -403.67303) (xy 447.270506 -403.6629) (xy 447.32624 -403.660863) (xy 447.381677 -403.666963)
			(xy 447.435634 -403.681069) (xy 447.486963 -403.702881) (xy 447.534569 -403.731935) (xy 447.577437 -403.76761)
			(xy 447.614654 -403.809147) (xy 447.645427 -403.85566) (xy 447.669099 -403.906157) (xy 447.685167 -403.959564)
			(xy 447.693287 -404.01474) (xy 447.693796 -404.042626) (xy 447.693287 -404.070512) (xy 447.685167 -404.125688)
			(xy 447.669099 -404.179095) (xy 447.645427 -404.229592) (xy 447.614654 -404.276105) (xy 447.577437 -404.317642)
			(xy 447.534569 -404.353317) (xy 447.486963 -404.382371) (xy 447.435634 -404.404183) (xy 447.381677 -404.418289)
			(xy 447.32624 -404.424389) (xy 447.270506 -404.422352) (xy 447.215663 -404.412222) (xy 447.162879 -404.394215)
			(xy 447.113279 -404.368714) (xy 447.067921 -404.336263) (xy 447.027772 -404.297554) (xy 446.993686 -404.253411)
			(xy 446.96639 -404.204776) (xy 446.946467 -404.152685) (xy 446.934341 -404.098248) (xy 446.93027 -404.042626)
			(xy 437.507272 -404.042626) (xy 437.527808 -404.07909) (xy 437.551186 -404.136833) (xy 437.566987 -404.197091)
			(xy 437.574953 -404.258874) (xy 437.575452 -404.290022) (xy 437.574953 -404.32117) (xy 437.566987 -404.382953)
			(xy 437.551186 -404.443211) (xy 437.527808 -404.500954) (xy 437.497239 -404.555233) (xy 437.459979 -404.605157)
			(xy 437.416642 -404.649907) (xy 437.367937 -404.688747) (xy 437.314666 -404.72104) (xy 437.257703 -404.746257)
			(xy 437.197982 -404.763981) (xy 437.136485 -404.773924) (xy 437.074222 -404.77592) (xy 437.012215 -404.769938)
			(xy 436.951481 -404.756076) (xy 436.893019 -404.734562) (xy 436.837788 -404.705748) (xy 436.786696 -404.670108)
			(xy 436.74058 -404.628227) (xy 436.700198 -404.580792) (xy 436.666214 -404.528583) (xy 436.639185 -404.472457)
			(xy 436.619556 -404.413336) (xy 436.607647 -404.352189) (xy 436.603656 -404.290022) (xy 433.174816 -404.290022)
			(xy 433.174815 -404.322738) (xy 433.166029 -404.387583) (xy 433.148619 -404.450663) (xy 433.122899 -404.510835)
			(xy 433.106576 -404.539196) (xy 433.103261 -404.54522) (xy 433.099656 -404.558484) (xy 433.099464 -404.565358)
			(xy 433.099464 -405.314658) (xy 433.099676 -405.32153) (xy 433.103271 -405.334792) (xy 433.106576 -405.34082)
			(xy 433.122893 -405.369184) (xy 433.14861 -405.429355) (xy 433.166018 -405.492433) (xy 433.174802 -405.557277)
			(xy 433.174803 -405.622713) (xy 433.16602 -405.687557) (xy 433.148613 -405.750635) (xy 433.122897 -405.810807)
			(xy 433.106576 -405.839168) (xy 433.103271 -405.845197) (xy 433.09966 -405.858457) (xy 433.099464 -405.86533)
			(xy 433.099464 -406.151334) (xy 433.098995 -406.161494) (xy 433.091209 -406.180263) (xy 433.076836 -406.194627)
			(xy 433.058062 -406.202401) (xy 433.047902 -406.202896) (xy 432.331622 -406.202896) (xy 432.32147 -406.20235)
			(xy 432.302708 -406.194589) (xy 432.288343 -406.180239) (xy 432.280561 -406.161486) (xy 432.28006 -406.151334)
			(xy 432.28006 -405.86533) (xy 432.279862 -405.858457) (xy 432.276258 -405.845194) (xy 432.272948 -405.839168)
			(xy 432.25662 -405.81081) (xy 432.230903 -405.750638) (xy 432.213495 -405.687559) (xy 432.204712 -405.622713)
			(xy 430.91599 -405.622713) (xy 430.906428 -405.63927) (xy 430.903126 -405.645301) (xy 430.899512 -405.65856)
			(xy 430.899316 -405.665432) (xy 430.899316 -406.414732) (xy 430.899494 -406.421606) (xy 430.903111 -406.434869)
			(xy 430.906428 -406.440894) (xy 430.922794 -406.469243) (xy 430.948595 -406.529403) (xy 430.966084 -406.592482)
			(xy 430.974945 -406.657339) (xy 430.975516 -406.690068) (xy 430.974956 -406.722792) (xy 434.404852 -406.722792)
			(xy 434.404856 -406.657353) (xy 434.413643 -406.592508) (xy 434.431053 -406.529428) (xy 434.456773 -406.469256)
			(xy 434.473096 -406.440894) (xy 434.476413 -406.43487) (xy 434.480017 -406.421606) (xy 434.480208 -406.414732)
			(xy 434.480208 -405.665432) (xy 434.480003 -405.65856) (xy 434.476404 -405.645297) (xy 434.473096 -405.63927)
			(xy 434.456772 -405.61091) (xy 434.431057 -405.550738) (xy 434.413651 -405.487659) (xy 434.404868 -405.422815)
			(xy 434.404869 -405.357378) (xy 434.413652 -405.292534) (xy 434.431059 -405.229455) (xy 434.456775 -405.169284)
			(xy 434.473096 -405.140922) (xy 434.476403 -405.134893) (xy 434.480013 -405.121633) (xy 434.480208 -405.11476)
			(xy 434.480208 -404.828756) (xy 434.480586 -404.818598) (xy 434.488397 -404.799843) (xy 434.502807 -404.785521)
			(xy 434.52161 -404.777824) (xy 434.53177 -404.777448) (xy 435.24805 -404.777448) (xy 435.258175 -404.777968)
			(xy 435.276896 -404.785681) (xy 435.291254 -404.799957) (xy 435.299074 -404.818634) (xy 435.299612 -404.828756)
			(xy 435.299612 -405.11476) (xy 435.299818 -405.121632) (xy 435.303417 -405.134895) (xy 435.306724 -405.140922)
			(xy 435.323044 -405.169285) (xy 435.348764 -405.229455) (xy 435.366174 -405.292534) (xy 435.374958 -405.357378)
			(xy 435.374959 -405.422815) (xy 435.366175 -405.48766) (xy 435.348766 -405.550738) (xy 435.331987 -405.589994)
			(xy 436.603656 -405.589994) (xy 436.607647 -405.527827) (xy 436.619556 -405.46668) (xy 436.639185 -405.407559)
			(xy 436.666214 -405.351433) (xy 436.700198 -405.299224) (xy 436.74058 -405.251789) (xy 436.786696 -405.209908)
			(xy 436.837788 -405.174268) (xy 436.893019 -405.145454) (xy 436.951481 -405.12394) (xy 437.012215 -405.110078)
			(xy 437.074222 -405.104096) (xy 437.136485 -405.106092) (xy 437.197982 -405.116035) (xy 437.257703 -405.133759)
			(xy 437.314666 -405.158976) (xy 437.367937 -405.191269) (xy 437.416642 -405.230109) (xy 437.459979 -405.274859)
			(xy 437.497239 -405.324783) (xy 437.527808 -405.379062) (xy 437.532275 -405.390096) (xy 438.803804 -405.390096)
			(xy 438.807795 -405.327929) (xy 438.819704 -405.266782) (xy 438.839333 -405.207661) (xy 438.866362 -405.151535)
			(xy 438.900346 -405.099326) (xy 438.940728 -405.051891) (xy 438.986844 -405.01001) (xy 439.037936 -404.97437)
			(xy 439.093167 -404.945556) (xy 439.151629 -404.924042) (xy 439.212363 -404.91018) (xy 439.27437 -404.904198)
			(xy 439.336633 -404.906194) (xy 439.39813 -404.916137) (xy 439.457851 -404.933861) (xy 439.514814 -404.959078)
			(xy 439.568085 -404.991371) (xy 439.61679 -405.030211) (xy 439.660127 -405.074961) (xy 439.697387 -405.124885)
			(xy 439.727956 -405.179164) (xy 439.751334 -405.236907) (xy 439.767135 -405.297165) (xy 439.775101 -405.358948)
			(xy 439.7756 -405.390096) (xy 439.775101 -405.421244) (xy 439.767135 -405.483027) (xy 439.751334 -405.543285)
			(xy 439.727956 -405.601028) (xy 439.697387 -405.655307) (xy 439.660127 -405.705231) (xy 439.61679 -405.749981)
			(xy 439.568085 -405.788821) (xy 439.514814 -405.821114) (xy 439.457851 -405.846331) (xy 439.39813 -405.864055)
			(xy 439.336633 -405.873998) (xy 439.27437 -405.875994) (xy 439.212363 -405.870012) (xy 439.151629 -405.85615)
			(xy 439.093167 -405.834636) (xy 439.037936 -405.805822) (xy 438.986844 -405.770182) (xy 438.940728 -405.728301)
			(xy 438.900346 -405.680866) (xy 438.866362 -405.628657) (xy 438.839333 -405.572531) (xy 438.819704 -405.51341)
			(xy 438.807795 -405.452263) (xy 438.803804 -405.390096) (xy 437.532275 -405.390096) (xy 437.551186 -405.436805)
			(xy 437.566987 -405.497063) (xy 437.574953 -405.558846) (xy 437.575452 -405.589994) (xy 437.574953 -405.621142)
			(xy 437.566987 -405.682925) (xy 437.551186 -405.743183) (xy 437.527808 -405.800926) (xy 437.497239 -405.855205)
			(xy 437.459979 -405.905129) (xy 437.416642 -405.949879) (xy 437.367937 -405.988719) (xy 437.314666 -406.021012)
			(xy 437.257703 -406.046229) (xy 437.197982 -406.063953) (xy 437.136485 -406.073896) (xy 437.074222 -406.075892)
			(xy 437.012215 -406.06991) (xy 436.951481 -406.056048) (xy 436.893019 -406.034534) (xy 436.837788 -406.00572)
			(xy 436.786696 -405.97008) (xy 436.74058 -405.928199) (xy 436.700198 -405.880764) (xy 436.666214 -405.828555)
			(xy 436.639185 -405.772429) (xy 436.619556 -405.713308) (xy 436.607647 -405.652161) (xy 436.603656 -405.589994)
			(xy 435.331987 -405.589994) (xy 435.323047 -405.610909) (xy 435.306724 -405.63927) (xy 435.303422 -405.645301)
			(xy 435.299808 -405.65856) (xy 435.299612 -405.665432) (xy 435.299612 -406.153366) (xy 446.64452 -406.153366)
			(xy 446.648591 -406.097744) (xy 446.660717 -406.043307) (xy 446.68064 -405.991216) (xy 446.707936 -405.942581)
			(xy 446.742022 -405.898438) (xy 446.782171 -405.859729) (xy 446.827529 -405.827278) (xy 446.877129 -405.801777)
			(xy 446.929913 -405.78377) (xy 446.984756 -405.77364) (xy 447.04049 -405.771603) (xy 447.095927 -405.777703)
			(xy 447.149884 -405.791809) (xy 447.201213 -405.813621) (xy 447.248819 -405.842675) (xy 447.291687 -405.87835)
			(xy 447.328904 -405.919887) (xy 447.359677 -405.9664) (xy 447.383349 -406.016897) (xy 447.399417 -406.070304)
			(xy 447.407537 -406.12548) (xy 447.408046 -406.153366) (xy 447.407537 -406.181252) (xy 447.399417 -406.236428)
			(xy 447.387573 -406.275794) (xy 447.938142 -406.275794) (xy 447.942213 -406.220172) (xy 447.954339 -406.165735)
			(xy 447.974262 -406.113644) (xy 448.001558 -406.065009) (xy 448.035644 -406.020866) (xy 448.075793 -405.982157)
			(xy 448.121151 -405.949706) (xy 448.170751 -405.924205) (xy 448.223535 -405.906198) (xy 448.278378 -405.896068)
			(xy 448.334112 -405.894031) (xy 448.389549 -405.900131) (xy 448.443506 -405.914237) (xy 448.494835 -405.936049)
			(xy 448.542441 -405.965103) (xy 448.585309 -406.000778) (xy 448.622526 -406.042315) (xy 448.653299 -406.088828)
			(xy 448.676971 -406.139325) (xy 448.693039 -406.192732) (xy 448.701159 -406.247908) (xy 448.701668 -406.275794)
			(xy 448.701159 -406.30368) (xy 448.693039 -406.358856) (xy 448.676971 -406.412263) (xy 448.653299 -406.46276)
			(xy 448.622526 -406.509273) (xy 448.585309 -406.55081) (xy 448.542441 -406.586485) (xy 448.494835 -406.615539)
			(xy 448.443506 -406.637351) (xy 448.389549 -406.651457) (xy 448.334112 -406.657557) (xy 448.278378 -406.65552)
			(xy 448.223535 -406.64539) (xy 448.170751 -406.627383) (xy 448.121151 -406.601882) (xy 448.075793 -406.569431)
			(xy 448.035644 -406.530722) (xy 448.001558 -406.486579) (xy 447.974262 -406.437944) (xy 447.954339 -406.385853)
			(xy 447.942213 -406.331416) (xy 447.938142 -406.275794) (xy 447.387573 -406.275794) (xy 447.383349 -406.289835)
			(xy 447.359677 -406.340332) (xy 447.328904 -406.386845) (xy 447.291687 -406.428382) (xy 447.248819 -406.464057)
			(xy 447.201213 -406.493111) (xy 447.149884 -406.514923) (xy 447.095927 -406.529029) (xy 447.04049 -406.535129)
			(xy 446.984756 -406.533092) (xy 446.929913 -406.522962) (xy 446.877129 -406.504955) (xy 446.827529 -406.479454)
			(xy 446.782171 -406.447003) (xy 446.742022 -406.408294) (xy 446.707936 -406.364151) (xy 446.68064 -406.315516)
			(xy 446.660717 -406.263425) (xy 446.648591 -406.208988) (xy 446.64452 -406.153366) (xy 435.299612 -406.153366)
			(xy 435.299612 -406.414732) (xy 435.29979 -406.421606) (xy 435.303408 -406.434869) (xy 435.306724 -406.440894)
			(xy 435.32302 -406.46927) (xy 435.348742 -406.529437) (xy 435.366155 -406.592513) (xy 435.374942 -406.657355)
			(xy 435.374944 -406.690068) (xy 438.803804 -406.690068) (xy 438.807795 -406.627901) (xy 438.819704 -406.566754)
			(xy 438.839333 -406.507633) (xy 438.866362 -406.451507) (xy 438.900346 -406.399298) (xy 438.940728 -406.351863)
			(xy 438.986844 -406.309982) (xy 439.037936 -406.274342) (xy 439.093167 -406.245528) (xy 439.151629 -406.224014)
			(xy 439.212363 -406.210152) (xy 439.27437 -406.20417) (xy 439.336633 -406.206166) (xy 439.39813 -406.216109)
			(xy 439.457851 -406.233833) (xy 439.514814 -406.25905) (xy 439.568085 -406.291343) (xy 439.61679 -406.330183)
			(xy 439.660127 -406.374933) (xy 439.697387 -406.424857) (xy 439.727956 -406.479136) (xy 439.751334 -406.536879)
			(xy 439.767135 -406.597137) (xy 439.775101 -406.65892) (xy 439.7756 -406.690068) (xy 439.775101 -406.721216)
			(xy 439.767135 -406.782999) (xy 439.751334 -406.843257) (xy 439.727956 -406.901) (xy 439.697387 -406.955279)
			(xy 439.660127 -407.005203) (xy 439.61679 -407.049953) (xy 439.568085 -407.088793) (xy 439.514814 -407.121086)
			(xy 439.457851 -407.146303) (xy 439.39813 -407.164027) (xy 439.336633 -407.17397) (xy 439.27437 -407.175966)
			(xy 439.212363 -407.169984) (xy 439.151629 -407.156122) (xy 439.093167 -407.134608) (xy 439.037936 -407.105794)
			(xy 438.986844 -407.070154) (xy 438.940728 -407.028273) (xy 438.900346 -406.980838) (xy 438.866362 -406.928629)
			(xy 438.839333 -406.872503) (xy 438.819704 -406.813382) (xy 438.807795 -406.752235) (xy 438.803804 -406.690068)
			(xy 435.374944 -406.690068) (xy 435.374946 -406.72279) (xy 435.366166 -406.787633) (xy 435.348761 -406.850711)
			(xy 435.323045 -406.910881) (xy 435.306724 -406.939242) (xy 435.303396 -406.94526) (xy 435.299798 -406.958529)
			(xy 435.299612 -406.965404) (xy 435.299612 -407.251408) (xy 435.299185 -407.261561) (xy 435.291389 -407.280311)
			(xy 435.276994 -407.294634) (xy 435.258205 -407.302335) (xy 435.24805 -407.302716) (xy 434.53177 -407.302716)
			(xy 434.521636 -407.302297) (xy 434.502906 -407.294551) (xy 434.488549 -407.280244) (xy 434.480739 -407.26154)
			(xy 434.480208 -407.251408) (xy 434.480208 -406.965404) (xy 434.480014 -406.958531) (xy 434.476407 -406.945268)
			(xy 434.473096 -406.939242) (xy 434.456748 -406.910895) (xy 434.431035 -406.85072) (xy 434.413632 -406.787639)
			(xy 434.404852 -406.722792) (xy 430.974956 -406.722792) (xy 430.974956 -406.722798) (xy 430.966099 -406.787656)
			(xy 430.948606 -406.850736) (xy 430.922797 -406.910894) (xy 430.906428 -406.939242) (xy 430.9031 -406.94526)
			(xy 430.899502 -406.958529) (xy 430.899316 -406.965404) (xy 430.899316 -407.251408) (xy 430.898822 -407.261515)
			(xy 430.891084 -407.28019) (xy 430.87679 -407.294484) (xy 430.858115 -407.302222) (xy 430.848008 -407.302716)
			(xy 430.131728 -407.302716) (xy 430.121609 -407.302262) (xy 430.102909 -407.294526) (xy 430.088595 -407.280221)
			(xy 430.080845 -407.261526) (xy 430.08042 -407.251408) (xy 430.08042 -406.965404) (xy 430.080224 -406.958531)
			(xy 430.076618 -406.945268) (xy 430.073308 -406.939242) (xy 430.05696 -406.910883) (xy 430.031154 -406.850727)
			(xy 430.013659 -406.787651) (xy 430.004793 -406.722796) (xy 430.00422 -406.690068) (xy 426.574858 -406.690068)
			(xy 426.57486 -406.72279) (xy 426.56608 -406.787633) (xy 426.548675 -406.850711) (xy 426.522961 -406.910881)
			(xy 426.50664 -406.939242) (xy 426.503314 -406.945261) (xy 426.499715 -406.958529) (xy 426.499528 -406.965404)
			(xy 426.499528 -407.251408) (xy 426.499085 -407.261559) (xy 426.491292 -407.280306) (xy 426.476903 -407.294628)
			(xy 426.458119 -407.302333) (xy 426.447966 -407.302716) (xy 425.731686 -407.302716) (xy 425.721553 -407.302283)
			(xy 425.702823 -407.294543) (xy 425.688466 -407.28024) (xy 425.680655 -407.261539) (xy 425.680124 -407.251408)
			(xy 425.680124 -406.965404) (xy 425.679928 -406.958531) (xy 425.676322 -406.945268) (xy 425.673012 -406.939242)
			(xy 425.656663 -406.910895) (xy 425.63095 -406.850721) (xy 425.613546 -406.787639) (xy 425.604766 -406.722792)
			(xy 422.17487 -406.722792) (xy 422.17487 -406.722798) (xy 422.166013 -406.787656) (xy 422.148521 -406.850736)
			(xy 422.122713 -406.910894) (xy 422.106344 -406.939242) (xy 422.103018 -406.945261) (xy 422.099419 -406.958529)
			(xy 422.099232 -406.965404) (xy 422.099232 -407.251408) (xy 422.098722 -407.261513) (xy 422.090988 -407.280185)
			(xy 422.076699 -407.294479) (xy 422.058029 -407.302219) (xy 422.047924 -407.302716) (xy 421.331644 -407.302716)
			(xy 421.321526 -407.302248) (xy 421.302827 -407.294518) (xy 421.288512 -407.280217) (xy 421.280762 -407.261525)
			(xy 421.280336 -407.251408) (xy 421.280336 -406.965404) (xy 421.280138 -406.958531) (xy 421.276533 -406.945269)
			(xy 421.273224 -406.939242) (xy 421.256877 -406.910882) (xy 421.23107 -406.850727) (xy 421.213575 -406.78765)
			(xy 421.204709 -406.722796) (xy 421.204136 -406.690068) (xy 414.915604 -406.690068) (xy 414.915604 -409.522889)
			(xy 419.004819 -409.522889) (xy 419.004823 -409.457449) (xy 419.013612 -409.392602) (xy 419.031026 -409.329522)
			(xy 419.05675 -409.269351) (xy 419.073076 -409.24099) (xy 419.076393 -409.234966) (xy 419.079998 -409.221702)
			(xy 419.080188 -409.214828) (xy 419.080188 -408.465528) (xy 419.079987 -408.458655) (xy 419.076385 -408.445393)
			(xy 419.073076 -408.439366) (xy 419.056746 -408.411009) (xy 419.031027 -408.350837) (xy 419.013618 -408.287758)
			(xy 419.004835 -408.222912) (xy 419.004836 -408.157474) (xy 419.013621 -408.092629) (xy 419.031031 -408.02955)
			(xy 419.056752 -407.969379) (xy 419.073076 -407.941018) (xy 419.076383 -407.934989) (xy 419.079994 -407.921729)
			(xy 419.080188 -407.914856) (xy 419.080188 -407.628852) (xy 419.080582 -407.618696) (xy 419.088391 -407.599945)
			(xy 419.102796 -407.585624) (xy 419.121592 -407.577924) (xy 419.13175 -407.577544) (xy 419.84803 -407.577544)
			(xy 419.858159 -407.578002) (xy 419.876882 -407.58574) (xy 419.891237 -407.600035) (xy 419.899055 -407.618725)
			(xy 419.899592 -407.628852) (xy 419.899592 -407.914856) (xy 419.899802 -407.921728) (xy 419.903398 -407.934991)
			(xy 419.906704 -407.941018) (xy 419.923018 -407.969383) (xy 419.948734 -408.029554) (xy 419.966141 -408.092632)
			(xy 419.974925 -408.157475) (xy 419.974926 -408.222911) (xy 419.966144 -408.287755) (xy 419.948739 -408.350833)
			(xy 419.923024 -408.411004) (xy 419.906704 -408.439366) (xy 419.903402 -408.445397) (xy 419.899788 -408.458656)
			(xy 419.899592 -408.465528) (xy 419.899592 -409.214828) (xy 419.899774 -409.221702) (xy 419.903389 -409.234965)
			(xy 419.906704 -409.24099) (xy 419.922994 -409.269369) (xy 419.948713 -409.329536) (xy 419.966122 -409.392611)
			(xy 419.974909 -409.457452) (xy 419.974913 -409.522886) (xy 419.966135 -409.587728) (xy 419.948733 -409.650805)
			(xy 419.923022 -409.710976) (xy 419.906704 -409.739338) (xy 419.903376 -409.745356) (xy 419.899779 -409.758625)
			(xy 419.899592 -409.7655) (xy 419.899592 -410.051504) (xy 419.899181 -410.061659) (xy 419.891383 -410.080413)
			(xy 419.876983 -410.094737) (xy 419.858187 -410.102435) (xy 419.84803 -410.102812) (xy 419.13175 -410.102812)
			(xy 419.121633 -410.102234) (xy 419.102923 -410.094532) (xy 419.088567 -410.080274) (xy 419.080736 -410.061618)
			(xy 419.080188 -410.051504) (xy 419.080188 -409.7655) (xy 419.079997 -409.758627) (xy 419.076388 -409.745364)
			(xy 419.073076 -409.739338) (xy 419.056722 -409.710994) (xy 419.031005 -409.650819) (xy 419.013599 -409.587737)
			(xy 419.004819 -409.522889) (xy 414.915604 -409.522889) (xy 414.915604 -410.589984) (xy 421.204136 -410.589984)
			(xy 421.204725 -410.557255) (xy 421.213576 -410.492398) (xy 421.231059 -410.429318) (xy 421.256859 -410.369159)
			(xy 421.273224 -410.34081) (xy 421.276537 -410.334785) (xy 421.280143 -410.321521) (xy 421.280336 -410.314648)
			(xy 421.280336 -409.565348) (xy 421.280121 -409.558476) (xy 421.276528 -409.545214) (xy 421.273224 -409.539186)
			(xy 421.256855 -409.510839) (xy 421.231054 -409.450679) (xy 421.213565 -409.387598) (xy 421.204706 -409.322741)
			(xy 421.204136 -409.290012) (xy 421.204693 -409.257282) (xy 421.213553 -409.192424) (xy 421.231046 -409.129344)
			(xy 421.256855 -409.069186) (xy 421.273224 -409.040838) (xy 421.276527 -409.034808) (xy 421.28014 -409.021548)
			(xy 421.280336 -409.014676) (xy 421.280336 -408.728672) (xy 421.280694 -408.718543) (xy 421.288458 -408.699832)
			(xy 421.302793 -408.685517) (xy 421.321515 -408.67778) (xy 421.331644 -408.677364) (xy 422.047924 -408.677364)
			(xy 422.05803 -408.677864) (xy 422.076702 -408.685603) (xy 422.090994 -408.699895) (xy 422.098735 -408.718566)
			(xy 422.099232 -408.728672) (xy 422.099232 -409.014676) (xy 422.099429 -409.021549) (xy 422.103033 -409.034812)
			(xy 422.106344 -409.040838) (xy 422.122719 -409.069182) (xy 422.14852 -409.129343) (xy 422.166007 -409.192424)
			(xy 422.174864 -409.257282) (xy 422.175432 -409.290012) (xy 422.174845 -409.322741) (xy 422.165995 -409.387598)
			(xy 422.14851 -409.450678) (xy 422.131575 -409.490164) (xy 423.404284 -409.490164) (xy 423.404858 -409.457435)
			(xy 423.413712 -409.392577) (xy 423.4312 -409.329497) (xy 423.457005 -409.269338) (xy 423.473372 -409.24099)
			(xy 423.476688 -409.234966) (xy 423.480293 -409.221702) (xy 423.480484 -409.214828) (xy 423.480484 -408.465528)
			(xy 423.480283 -408.458655) (xy 423.476681 -408.445393) (xy 423.473372 -408.439366) (xy 423.45699 -408.411026)
			(xy 423.431193 -408.350863) (xy 423.413708 -408.287781) (xy 423.404852 -408.222922) (xy 423.404284 -408.190192)
			(xy 423.404871 -408.157463) (xy 423.413721 -408.092606) (xy 423.431205 -408.029526) (xy 423.457006 -407.969367)
			(xy 423.473372 -407.941018) (xy 423.476678 -407.934989) (xy 423.48029 -407.921729) (xy 423.480484 -407.914856)
			(xy 423.480484 -407.628852) (xy 423.480946 -407.618742) (xy 423.488696 -407.600066) (xy 423.503 -407.585774)
			(xy 423.521682 -407.578038) (xy 423.531792 -407.577544) (xy 424.248072 -407.577544) (xy 424.258172 -407.578106)
			(xy 424.276839 -407.585825) (xy 424.291133 -407.600097) (xy 424.298879 -407.618753) (xy 424.29938 -407.628852)
			(xy 424.29938 -407.914856) (xy 424.299591 -407.921728) (xy 424.303186 -407.934991) (xy 424.306492 -407.941018)
			(xy 424.322864 -407.969364) (xy 424.348664 -408.029524) (xy 424.366152 -408.092605) (xy 424.375011 -408.157463)
			(xy 424.37558 -408.190192) (xy 424.375036 -408.222922) (xy 424.366174 -408.287781) (xy 424.348677 -408.350862)
			(xy 424.322864 -408.411019) (xy 424.306492 -408.439366) (xy 424.303189 -408.445396) (xy 424.299576 -408.458656)
			(xy 424.29938 -408.465528) (xy 424.29938 -409.214828) (xy 424.299564 -409.221702) (xy 424.303178 -409.234964)
			(xy 424.306492 -409.24099) (xy 424.322853 -409.269342) (xy 424.348656 -409.3295) (xy 424.366147 -409.392579)
			(xy 424.375009 -409.457435) (xy 424.37558 -409.490164) (xy 424.375023 -409.522894) (xy 424.366165 -409.587753)
			(xy 424.348672 -409.650833) (xy 424.322862 -409.71099) (xy 424.306492 -409.739338) (xy 424.303163 -409.745356)
			(xy 424.299567 -409.758625) (xy 424.29938 -409.7655) (xy 424.29938 -410.051504) (xy 424.298987 -410.061629)
			(xy 424.291234 -410.080337) (xy 424.27691 -410.094651) (xy 424.258197 -410.102393) (xy 424.248072 -410.102812)
			(xy 423.531792 -410.102812) (xy 423.521684 -410.102322) (xy 423.503008 -410.094584) (xy 423.488714 -410.080288)
			(xy 423.480978 -410.061612) (xy 423.480484 -410.051504) (xy 423.480484 -409.7655) (xy 423.480294 -409.758627)
			(xy 423.476684 -409.745364) (xy 423.473372 -409.739338) (xy 423.457019 -409.710982) (xy 423.431215 -409.650825)
			(xy 423.413722 -409.587747) (xy 423.404857 -409.522892) (xy 423.404284 -409.490164) (xy 422.131575 -409.490164)
			(xy 422.122709 -409.510837) (xy 422.106344 -409.539186) (xy 422.103038 -409.545215) (xy 422.099426 -409.558475)
			(xy 422.099232 -409.565348) (xy 422.099232 -410.314648) (xy 422.09944 -410.32152) (xy 422.103037 -410.334783)
			(xy 422.106344 -410.34081) (xy 422.122708 -410.36916) (xy 422.148512 -410.429319) (xy 422.166002 -410.492398)
			(xy 422.174862 -410.557255) (xy 422.175432 -410.589984) (xy 422.174877 -410.622705) (xy 425.604775 -410.622705)
			(xy 425.604777 -410.557268) (xy 425.613562 -410.492422) (xy 425.630971 -410.429343) (xy 425.65669 -410.369172)
			(xy 425.673012 -410.34081) (xy 425.676324 -410.334784) (xy 425.679931 -410.321521) (xy 425.680124 -410.314648)
			(xy 425.680124 -409.565348) (xy 425.679911 -409.558476) (xy 425.676317 -409.545214) (xy 425.673012 -409.539186)
			(xy 425.656701 -409.510819) (xy 425.630984 -409.450649) (xy 425.613575 -409.387571) (xy 425.604791 -409.322728)
			(xy 425.60479 -409.257293) (xy 425.613571 -409.192449) (xy 425.630977 -409.129371) (xy 425.656691 -409.0692)
			(xy 425.673012 -409.040838) (xy 425.676314 -409.034807) (xy 425.679927 -409.021548) (xy 425.680124 -409.014676)
			(xy 425.680124 -408.728672) (xy 425.680499 -408.718513) (xy 425.688308 -408.699755) (xy 425.70272 -408.685432)
			(xy 425.721525 -408.677738) (xy 425.731686 -408.677364) (xy 426.447966 -408.677364) (xy 426.458093 -408.677855)
			(xy 426.476818 -408.685576) (xy 426.491177 -408.699862) (xy 426.498993 -408.718547) (xy 426.499528 -408.728672)
			(xy 426.499528 -409.014676) (xy 426.499726 -409.021549) (xy 426.50333 -409.034812) (xy 426.50664 -409.040838)
			(xy 426.522973 -409.069193) (xy 426.548691 -409.129366) (xy 426.566099 -409.192446) (xy 426.574881 -409.257291)
			(xy 426.57488 -409.322729) (xy 426.566094 -409.387575) (xy 426.548684 -409.450654) (xy 426.522964 -409.510825)
			(xy 426.51602 -409.522889) (xy 427.804905 -409.522889) (xy 427.804909 -409.457449) (xy 427.813698 -409.392603)
			(xy 427.831111 -409.329523) (xy 427.856835 -409.269351) (xy 427.87316 -409.24099) (xy 427.876475 -409.234965)
			(xy 427.880081 -409.221702) (xy 427.880272 -409.214828) (xy 427.880272 -408.465528) (xy 427.880073 -408.458655)
			(xy 427.87647 -408.445392) (xy 427.87316 -408.439366) (xy 427.85683 -408.411009) (xy 427.831112 -408.350837)
			(xy 427.813704 -408.287757) (xy 427.804921 -408.222912) (xy 427.804922 -408.157474) (xy 427.813707 -408.092629)
			(xy 427.831117 -408.02955) (xy 427.856837 -407.969379) (xy 427.87316 -407.941018) (xy 427.876465 -407.934989)
			(xy 427.880077 -407.921729) (xy 427.880272 -407.914856) (xy 427.880272 -407.628852) (xy 427.880682 -407.618698)
			(xy 427.888488 -407.59995) (xy 427.902887 -407.58563) (xy 427.921678 -407.577927) (xy 427.931834 -407.577544)
			(xy 428.648114 -407.577544) (xy 428.658242 -407.578015) (xy 428.676964 -407.585749) (xy 428.69132 -407.600039)
			(xy 428.699138 -407.618726) (xy 428.699676 -407.628852) (xy 428.699676 -407.914856) (xy 428.699888 -407.921728)
			(xy 428.703483 -407.93499) (xy 428.706788 -407.941018) (xy 428.723103 -407.969383) (xy 428.748819 -408.029554)
			(xy 428.766227 -408.092632) (xy 428.775011 -408.157475) (xy 428.775012 -408.222911) (xy 428.76623 -408.287755)
			(xy 428.748824 -408.350833) (xy 428.723109 -408.411004) (xy 428.706788 -408.439366) (xy 428.703485 -408.445396)
			(xy 428.699872 -408.458656) (xy 428.699676 -408.465528) (xy 428.699676 -409.214828) (xy 428.69986 -409.221702)
			(xy 428.703474 -409.234964) (xy 428.706788 -409.24099) (xy 428.723079 -409.269368) (xy 428.748798 -409.329536)
			(xy 428.766208 -409.392611) (xy 428.774995 -409.457452) (xy 428.774999 -409.522886) (xy 428.766221 -409.587728)
			(xy 428.748818 -409.650806) (xy 428.723107 -409.710977) (xy 428.706788 -409.739338) (xy 428.703459 -409.745356)
			(xy 428.699863 -409.758625) (xy 428.699676 -409.7655) (xy 428.699676 -410.051504) (xy 428.699281 -410.061661)
			(xy 428.69148 -410.080418) (xy 428.677074 -410.094742) (xy 428.658274 -410.102438) (xy 428.648114 -410.102812)
			(xy 427.931834 -410.102812) (xy 427.921716 -410.102247) (xy 427.903005 -410.09454) (xy 427.88865 -410.080278)
			(xy 427.88082 -410.061619) (xy 427.880272 -410.051504) (xy 427.880272 -409.7655) (xy 427.880083 -409.758626)
			(xy 427.876473 -409.745364) (xy 427.87316 -409.739338) (xy 427.856807 -409.710994) (xy 427.831091 -409.650819)
			(xy 427.813685 -409.587737) (xy 427.804905 -409.522889) (xy 426.51602 -409.522889) (xy 426.50664 -409.539186)
			(xy 426.503334 -409.545215) (xy 426.499722 -409.558475) (xy 426.499528 -409.565348) (xy 426.499528 -410.314648)
			(xy 426.499736 -410.32152) (xy 426.503333 -410.334783) (xy 426.50664 -410.34081) (xy 426.522949 -410.369179)
			(xy 426.548669 -410.429348) (xy 426.56608 -410.492425) (xy 426.574865 -410.557268) (xy 426.574866 -410.589984)
			(xy 430.00422 -410.589984) (xy 430.004798 -410.557255) (xy 430.01365 -410.492397) (xy 430.031136 -410.429317)
			(xy 430.056941 -410.369158) (xy 430.073308 -410.34081) (xy 430.07662 -410.334784) (xy 430.080227 -410.321521)
			(xy 430.08042 -410.314648) (xy 430.08042 -409.565348) (xy 430.080207 -409.558476) (xy 430.076613 -409.545214)
			(xy 430.073308 -409.539186) (xy 430.056938 -409.510839) (xy 430.031137 -409.450679) (xy 430.013648 -409.387599)
			(xy 430.00479 -409.322741) (xy 430.00422 -409.290012) (xy 430.004766 -409.257282) (xy 430.013627 -409.192423)
			(xy 430.031123 -409.129343) (xy 430.056937 -409.069185) (xy 430.073308 -409.040838) (xy 430.07661 -409.034807)
			(xy 430.080223 -409.021548) (xy 430.08042 -409.014676) (xy 430.08042 -408.728672) (xy 430.080863 -408.718559)
			(xy 430.088613 -408.699876) (xy 430.102923 -408.685582) (xy 430.121614 -408.677852) (xy 430.131728 -408.677364)
			(xy 430.848008 -408.677364) (xy 430.858113 -408.677878) (xy 430.876784 -408.685611) (xy 430.891077 -408.699899)
			(xy 430.898818 -408.718567) (xy 430.899316 -408.728672) (xy 430.899316 -409.014676) (xy 430.899515 -409.021549)
			(xy 430.903118 -409.034812) (xy 430.906428 -409.040838) (xy 430.922811 -409.069177) (xy 430.948608 -409.129341)
			(xy 430.966093 -409.192423) (xy 430.974948 -409.257282) (xy 430.975516 -409.290012) (xy 430.974931 -409.322741)
			(xy 430.966081 -409.387598) (xy 430.948596 -409.450678) (xy 430.922794 -409.510837) (xy 430.915836 -409.522889)
			(xy 432.204695 -409.522889) (xy 432.204699 -409.457449) (xy 432.213487 -409.392603) (xy 432.2309 -409.329523)
			(xy 432.256623 -409.269351) (xy 432.272948 -409.24099) (xy 432.276262 -409.234965) (xy 432.279869 -409.221702)
			(xy 432.28006 -409.214828) (xy 432.28006 -408.465528) (xy 432.279862 -408.458655) (xy 432.276259 -408.445392)
			(xy 432.272948 -408.439366) (xy 432.256619 -408.411009) (xy 432.230901 -408.350837) (xy 432.213494 -408.287757)
			(xy 432.204711 -408.222912) (xy 432.204712 -408.157474) (xy 432.213496 -408.092629) (xy 432.230906 -408.02955)
			(xy 432.256625 -407.969379) (xy 432.272948 -407.941018) (xy 432.276252 -407.934988) (xy 432.279865 -407.921729)
			(xy 432.28006 -407.914856) (xy 432.28006 -407.628852) (xy 432.280482 -407.6187) (xy 432.288286 -407.599954)
			(xy 432.302681 -407.585634) (xy 432.321468 -407.577929) (xy 432.331622 -407.577544) (xy 433.047902 -407.577544)
			(xy 433.058029 -407.578025) (xy 433.076751 -407.585754) (xy 433.091108 -407.600042) (xy 433.098926 -407.618727)
			(xy 433.099464 -407.628852) (xy 433.099464 -407.914856) (xy 433.099677 -407.921728) (xy 433.103271 -407.93499)
			(xy 433.106576 -407.941018) (xy 433.122891 -407.969383) (xy 433.148608 -408.029554) (xy 433.166017 -408.092631)
			(xy 433.174801 -408.157475) (xy 433.174801 -408.190192) (xy 436.603656 -408.190192) (xy 436.607647 -408.128025)
			(xy 436.619556 -408.066878) (xy 436.639185 -408.007757) (xy 436.666214 -407.951631) (xy 436.700198 -407.899422)
			(xy 436.74058 -407.851987) (xy 436.786696 -407.810106) (xy 436.837788 -407.774466) (xy 436.893019 -407.745652)
			(xy 436.951481 -407.724138) (xy 437.012215 -407.710276) (xy 437.074222 -407.704294) (xy 437.136485 -407.70629)
			(xy 437.197982 -407.716233) (xy 437.257703 -407.733957) (xy 437.314666 -407.759174) (xy 437.367937 -407.791467)
			(xy 437.416642 -407.830307) (xy 437.459979 -407.875057) (xy 437.497239 -407.924981) (xy 437.527808 -407.97926)
			(xy 437.551186 -408.037003) (xy 437.566987 -408.097261) (xy 437.574953 -408.159044) (xy 437.575452 -408.190192)
			(xy 437.574953 -408.22134) (xy 437.566987 -408.283123) (xy 437.551186 -408.343381) (xy 437.527808 -408.401124)
			(xy 437.497239 -408.455403) (xy 437.459979 -408.505327) (xy 437.416642 -408.550077) (xy 437.367937 -408.588917)
			(xy 437.314666 -408.62121) (xy 437.257703 -408.646427) (xy 437.197982 -408.664151) (xy 437.136485 -408.674094)
			(xy 437.074222 -408.67609) (xy 437.012215 -408.670108) (xy 436.951481 -408.656246) (xy 436.893019 -408.634732)
			(xy 436.837788 -408.605918) (xy 436.786696 -408.570278) (xy 436.74058 -408.528397) (xy 436.700198 -408.480962)
			(xy 436.666214 -408.428753) (xy 436.639185 -408.372627) (xy 436.619556 -408.313506) (xy 436.607647 -408.252359)
			(xy 436.603656 -408.190192) (xy 433.174801 -408.190192) (xy 433.174802 -408.222911) (xy 433.16602 -408.287755)
			(xy 433.148613 -408.350833) (xy 433.122897 -408.411005) (xy 433.106576 -408.439366) (xy 433.103272 -408.445396)
			(xy 433.09966 -408.458656) (xy 433.099464 -408.465528) (xy 433.099464 -409.214828) (xy 433.09965 -409.221702)
			(xy 433.103263 -409.234964) (xy 433.106576 -409.24099) (xy 433.122867 -409.269368) (xy 433.148587 -409.329536)
			(xy 433.165998 -409.392611) (xy 433.174785 -409.457452) (xy 433.174789 -409.522886) (xy 433.16601 -409.587729)
			(xy 433.148607 -409.650806) (xy 433.122895 -409.710977) (xy 433.106576 -409.739338) (xy 433.103246 -409.745355)
			(xy 433.09965 -409.758625) (xy 433.099464 -409.7655) (xy 433.099464 -410.051504) (xy 433.099081 -410.061663)
			(xy 433.091277 -410.080422) (xy 433.076868 -410.094747) (xy 433.058063 -410.10244) (xy 433.047902 -410.102812)
			(xy 432.331622 -410.102812) (xy 432.321503 -410.102257) (xy 432.302792 -410.094546) (xy 432.288437 -410.080281)
			(xy 432.280608 -410.06162) (xy 432.28006 -410.051504) (xy 432.28006 -409.7655) (xy 432.279873 -409.758626)
			(xy 432.276262 -409.745363) (xy 432.272948 -409.739338) (xy 432.256595 -409.710994) (xy 432.23088 -409.650819)
			(xy 432.213475 -409.587736) (xy 432.204695 -409.522889) (xy 430.915836 -409.522889) (xy 430.906428 -409.539186)
			(xy 430.90312 -409.545214) (xy 430.89951 -409.558475) (xy 430.899316 -409.565348) (xy 430.899316 -410.314648)
			(xy 430.899526 -410.32152) (xy 430.903122 -410.334783) (xy 430.906428 -410.34081) (xy 430.9228 -410.369156)
			(xy 430.9486 -410.429317) (xy 430.966087 -410.492397) (xy 430.974946 -410.557255) (xy 430.975516 -410.589984)
			(xy 430.974964 -410.622705) (xy 434.404861 -410.622705) (xy 434.404863 -410.557268) (xy 434.413648 -410.492423)
			(xy 434.431057 -410.429344) (xy 434.456774 -410.369172) (xy 434.473096 -410.34081) (xy 434.476407 -410.334783)
			(xy 434.480015 -410.321521) (xy 434.480208 -410.314648) (xy 434.480208 -409.565348) (xy 434.479996 -409.558476)
			(xy 434.476401 -409.545214) (xy 434.473096 -409.539186) (xy 434.456785 -409.510819) (xy 434.431069 -409.450648)
			(xy 434.413661 -409.387571) (xy 434.404877 -409.322728) (xy 434.404876 -409.257293) (xy 434.413657 -409.192449)
			(xy 434.431062 -409.129371) (xy 434.456776 -409.0692) (xy 434.473096 -409.040838) (xy 434.476397 -409.034807)
			(xy 434.480011 -409.021548) (xy 434.480208 -409.014676) (xy 434.480208 -408.728672) (xy 434.480599 -408.718515)
			(xy 434.488405 -408.69976) (xy 434.502811 -408.685438) (xy 434.521611 -408.67774) (xy 434.53177 -408.677364)
			(xy 435.24805 -408.677364) (xy 435.258176 -408.677868) (xy 435.276901 -408.685584) (xy 435.29126 -408.699866)
			(xy 435.299077 -408.718548) (xy 435.299612 -408.728672) (xy 435.299612 -409.014676) (xy 435.299812 -409.021549)
			(xy 435.303415 -409.034811) (xy 435.306724 -409.040838) (xy 435.323058 -409.069193) (xy 435.348776 -409.129365)
			(xy 435.366185 -409.192445) (xy 435.374967 -409.257291) (xy 435.374966 -409.322729) (xy 435.36618 -409.387575)
			(xy 435.348769 -409.450654) (xy 435.33188 -409.490164) (xy 436.603656 -409.490164) (xy 436.607647 -409.427997)
			(xy 436.619556 -409.36685) (xy 436.639185 -409.307729) (xy 436.666214 -409.251603) (xy 436.700198 -409.199394)
			(xy 436.74058 -409.151959) (xy 436.786696 -409.110078) (xy 436.837788 -409.074438) (xy 436.893019 -409.045624)
			(xy 436.951481 -409.02411) (xy 437.012215 -409.010248) (xy 437.074222 -409.004266) (xy 437.136485 -409.006262)
			(xy 437.197982 -409.016205) (xy 437.257703 -409.033929) (xy 437.314666 -409.059146) (xy 437.367937 -409.091439)
			(xy 437.416642 -409.130279) (xy 437.459979 -409.175029) (xy 437.497239 -409.224953) (xy 437.527808 -409.279232)
			(xy 437.532172 -409.290012) (xy 438.803804 -409.290012) (xy 438.807795 -409.227845) (xy 438.819704 -409.166698)
			(xy 438.839333 -409.107577) (xy 438.866362 -409.051451) (xy 438.900346 -408.999242) (xy 438.940728 -408.951807)
			(xy 438.986844 -408.909926) (xy 439.037936 -408.874286) (xy 439.093167 -408.845472) (xy 439.151629 -408.823958)
			(xy 439.212363 -408.810096) (xy 439.27437 -408.804114) (xy 439.336633 -408.80611) (xy 439.39813 -408.816053)
			(xy 439.457851 -408.833777) (xy 439.514814 -408.858994) (xy 439.568085 -408.891287) (xy 439.61679 -408.930127)
			(xy 439.660127 -408.974877) (xy 439.697387 -409.024801) (xy 439.727956 -409.07908) (xy 439.751334 -409.136823)
			(xy 439.767135 -409.197081) (xy 439.775101 -409.258864) (xy 439.7756 -409.290012) (xy 439.775101 -409.32116)
			(xy 439.767135 -409.382943) (xy 439.751334 -409.443201) (xy 439.727956 -409.500944) (xy 439.697387 -409.555223)
			(xy 439.660127 -409.605147) (xy 439.61679 -409.649897) (xy 439.568085 -409.688737) (xy 439.514814 -409.72103)
			(xy 439.457851 -409.746247) (xy 439.39813 -409.763971) (xy 439.336633 -409.773914) (xy 439.27437 -409.77591)
			(xy 439.212363 -409.769928) (xy 439.151629 -409.756066) (xy 439.093167 -409.734552) (xy 439.037936 -409.705738)
			(xy 438.986844 -409.670098) (xy 438.940728 -409.628217) (xy 438.900346 -409.580782) (xy 438.866362 -409.528573)
			(xy 438.839333 -409.472447) (xy 438.819704 -409.413326) (xy 438.807795 -409.352179) (xy 438.803804 -409.290012)
			(xy 437.532172 -409.290012) (xy 437.551186 -409.336975) (xy 437.566987 -409.397233) (xy 437.574953 -409.459016)
			(xy 437.575452 -409.490164) (xy 437.574953 -409.521312) (xy 437.566987 -409.583095) (xy 437.551186 -409.643353)
			(xy 437.527808 -409.701096) (xy 437.497239 -409.755375) (xy 437.459979 -409.805299) (xy 437.416642 -409.850049)
			(xy 437.367937 -409.888889) (xy 437.314666 -409.921182) (xy 437.257703 -409.946399) (xy 437.197982 -409.964123)
			(xy 437.136485 -409.974066) (xy 437.074222 -409.976062) (xy 437.012215 -409.97008) (xy 436.951481 -409.956218)
			(xy 436.893019 -409.934704) (xy 436.837788 -409.90589) (xy 436.786696 -409.87025) (xy 436.74058 -409.828369)
			(xy 436.700198 -409.780934) (xy 436.666214 -409.728725) (xy 436.639185 -409.672599) (xy 436.619556 -409.613478)
			(xy 436.607647 -409.552331) (xy 436.603656 -409.490164) (xy 435.33188 -409.490164) (xy 435.323048 -409.510825)
			(xy 435.306724 -409.539186) (xy 435.303416 -409.545214) (xy 435.299806 -409.558475) (xy 435.299612 -409.565348)
			(xy 435.299612 -410.314648) (xy 435.299822 -410.32152) (xy 435.303418 -410.334783) (xy 435.306724 -410.34081)
			(xy 435.323034 -410.369178) (xy 435.348755 -410.429347) (xy 435.366166 -410.492425) (xy 435.374952 -410.557268)
			(xy 435.374952 -410.589984) (xy 438.803804 -410.589984) (xy 438.807795 -410.527817) (xy 438.819704 -410.46667)
			(xy 438.839333 -410.407549) (xy 438.866362 -410.351423) (xy 438.900346 -410.299214) (xy 438.940728 -410.251779)
			(xy 438.986844 -410.209898) (xy 439.037936 -410.174258) (xy 439.093167 -410.145444) (xy 439.151629 -410.12393)
			(xy 439.212363 -410.110068) (xy 439.27437 -410.104086) (xy 439.336633 -410.106082) (xy 439.39813 -410.116025)
			(xy 439.457851 -410.133749) (xy 439.514814 -410.158966) (xy 439.568085 -410.191259) (xy 439.61679 -410.230099)
			(xy 439.660127 -410.274849) (xy 439.697387 -410.324773) (xy 439.727956 -410.379052) (xy 439.751334 -410.436795)
			(xy 439.767135 -410.497053) (xy 439.775101 -410.558836) (xy 439.7756 -410.589984) (xy 439.775101 -410.621132)
			(xy 439.767135 -410.682915) (xy 439.751334 -410.743173) (xy 439.727956 -410.800916) (xy 439.697387 -410.855195)
			(xy 439.660127 -410.905119) (xy 439.61679 -410.949869) (xy 439.568085 -410.988709) (xy 439.514814 -411.021002)
			(xy 439.457851 -411.046219) (xy 439.39813 -411.063943) (xy 439.336633 -411.073886) (xy 439.27437 -411.075882)
			(xy 439.212363 -411.0699) (xy 439.151629 -411.056038) (xy 439.093167 -411.034524) (xy 439.037936 -411.00571)
			(xy 438.986844 -410.97007) (xy 438.940728 -410.928189) (xy 438.900346 -410.880754) (xy 438.866362 -410.828545)
			(xy 438.839333 -410.772419) (xy 438.819704 -410.713298) (xy 438.807795 -410.652151) (xy 438.803804 -410.589984)
			(xy 435.374952 -410.589984) (xy 435.374953 -410.622704) (xy 435.366171 -410.687548) (xy 435.348764 -410.750627)
			(xy 435.323046 -410.810797) (xy 435.306724 -410.839158) (xy 435.303426 -410.845191) (xy 435.299809 -410.858448)
			(xy 435.299612 -410.86532) (xy 435.299612 -411.151324) (xy 435.299198 -411.161478) (xy 435.291397 -411.180229)
			(xy 435.276998 -411.194551) (xy 435.258206 -411.202252) (xy 435.24805 -411.202632) (xy 434.53177 -411.202632)
			(xy 434.521638 -411.202197) (xy 434.502911 -411.194454) (xy 434.488554 -411.180152) (xy 434.480741 -411.161454)
			(xy 434.480208 -411.151324) (xy 434.480208 -410.86532) (xy 434.480008 -410.858447) (xy 434.476405 -410.845185)
			(xy 434.473096 -410.839158) (xy 434.456762 -410.810804) (xy 434.431047 -410.75063) (xy 434.413642 -410.68755)
			(xy 434.404861 -410.622705) (xy 430.974964 -410.622705) (xy 430.974964 -410.622714) (xy 430.966104 -410.687573)
			(xy 430.948609 -410.750653) (xy 430.922798 -410.81081) (xy 430.906428 -410.839158) (xy 430.90313 -410.845191)
			(xy 430.899513 -410.858448) (xy 430.899316 -410.86532) (xy 430.899316 -411.151324) (xy 430.898835 -411.161432)
			(xy 430.891092 -411.180108) (xy 430.876795 -411.194401) (xy 430.858116 -411.202138) (xy 430.848008 -411.202632)
			(xy 430.131728 -411.202632) (xy 430.121611 -411.202162) (xy 430.102914 -411.194429) (xy 430.0886 -411.180129)
			(xy 430.080848 -411.16144) (xy 430.08042 -411.151324) (xy 430.08042 -410.86532) (xy 430.080218 -410.858448)
			(xy 430.076616 -410.845185) (xy 430.073308 -410.839158) (xy 430.056926 -410.810818) (xy 430.031128 -410.750655)
			(xy 430.013643 -410.687573) (xy 430.004788 -410.622714) (xy 430.00422 -410.589984) (xy 426.574866 -410.589984)
			(xy 426.574867 -410.622704) (xy 426.566085 -410.687548) (xy 426.548678 -410.750626) (xy 426.522962 -410.810797)
			(xy 426.50664 -410.839158) (xy 426.503343 -410.845192) (xy 426.499726 -410.858448) (xy 426.499528 -410.86532)
			(xy 426.499528 -411.151324) (xy 426.499099 -411.161476) (xy 426.4913 -411.180224) (xy 426.476907 -411.194545)
			(xy 426.45812 -411.202249) (xy 426.447966 -411.202632) (xy 425.731686 -411.202632) (xy 425.721555 -411.202184)
			(xy 425.702828 -411.194446) (xy 425.688472 -411.180148) (xy 425.680658 -411.161453) (xy 425.680124 -411.151324)
			(xy 425.680124 -410.86532) (xy 425.679921 -410.858448) (xy 425.67632 -410.845185) (xy 425.673012 -410.839158)
			(xy 425.656677 -410.810804) (xy 425.630962 -410.750631) (xy 425.613557 -410.687551) (xy 425.604775 -410.622705)
			(xy 422.174877 -410.622705) (xy 422.174877 -410.622714) (xy 422.166018 -410.687572) (xy 422.148524 -410.750652)
			(xy 422.122714 -410.81081) (xy 422.106344 -410.839158) (xy 422.103048 -410.845192) (xy 422.09943 -410.858448)
			(xy 422.099232 -410.86532) (xy 422.099232 -411.151324) (xy 422.098735 -411.16143) (xy 422.090996 -411.180103)
			(xy 422.076703 -411.194396) (xy 422.05803 -411.202135) (xy 422.047924 -411.202632) (xy 421.331644 -411.202632)
			(xy 421.321528 -411.202149) (xy 421.302832 -411.194421) (xy 421.288517 -411.180125) (xy 421.280765 -411.161439)
			(xy 421.280336 -411.151324) (xy 421.280336 -410.86532) (xy 421.280132 -410.858448) (xy 421.276531 -410.845185)
			(xy 421.273224 -410.839158) (xy 421.256844 -410.810817) (xy 421.231045 -410.750654) (xy 421.213559 -410.687572)
			(xy 421.204704 -410.622714) (xy 421.204136 -410.589984) (xy 414.915604 -410.589984) (xy 414.915604 -412.090108)
			(xy 419.003742 -412.090108) (xy 419.007733 -412.027941) (xy 419.019642 -411.966794) (xy 419.039271 -411.907673)
			(xy 419.0663 -411.851547) (xy 419.100284 -411.799338) (xy 419.140666 -411.751903) (xy 419.186782 -411.710022)
			(xy 419.237874 -411.674382) (xy 419.293105 -411.645568) (xy 419.351567 -411.624054) (xy 419.412301 -411.610192)
			(xy 419.474308 -411.60421) (xy 419.536571 -411.606206) (xy 419.598068 -411.616149) (xy 419.657789 -411.633873)
			(xy 419.714752 -411.65909) (xy 419.768023 -411.691383) (xy 419.816728 -411.730223) (xy 419.860065 -411.774973)
			(xy 419.897325 -411.824897) (xy 419.927894 -411.879176) (xy 419.951272 -411.936919) (xy 419.967073 -411.997177)
			(xy 419.975039 -412.05896) (xy 419.975538 -412.090108) (xy 423.403784 -412.090108) (xy 423.407775 -412.027941)
			(xy 423.419684 -411.966794) (xy 423.439313 -411.907673) (xy 423.466342 -411.851547) (xy 423.500326 -411.799338)
			(xy 423.540708 -411.751903) (xy 423.586824 -411.710022) (xy 423.637916 -411.674382) (xy 423.693147 -411.645568)
			(xy 423.751609 -411.624054) (xy 423.812343 -411.610192) (xy 423.87435 -411.60421) (xy 423.936613 -411.606206)
			(xy 423.99811 -411.616149) (xy 424.057831 -411.633873) (xy 424.114794 -411.65909) (xy 424.168065 -411.691383)
			(xy 424.21677 -411.730223) (xy 424.260107 -411.774973) (xy 424.297367 -411.824897) (xy 424.327936 -411.879176)
			(xy 424.351314 -411.936919) (xy 424.367115 -411.997177) (xy 424.375081 -412.05896) (xy 424.37558 -412.090108)
			(xy 427.803826 -412.090108) (xy 427.807817 -412.027941) (xy 427.819726 -411.966794) (xy 427.839355 -411.907673)
			(xy 427.866384 -411.851547) (xy 427.900368 -411.799338) (xy 427.94075 -411.751903) (xy 427.986866 -411.710022)
			(xy 428.037958 -411.674382) (xy 428.093189 -411.645568) (xy 428.151651 -411.624054) (xy 428.212385 -411.610192)
			(xy 428.274392 -411.60421) (xy 428.336655 -411.606206) (xy 428.398152 -411.616149) (xy 428.457873 -411.633873)
			(xy 428.514836 -411.65909) (xy 428.568107 -411.691383) (xy 428.616812 -411.730223) (xy 428.660149 -411.774973)
			(xy 428.697409 -411.824897) (xy 428.727978 -411.879176) (xy 428.751356 -411.936919) (xy 428.767157 -411.997177)
			(xy 428.775123 -412.05896) (xy 428.775622 -412.090108) (xy 432.203614 -412.090108) (xy 432.207605 -412.027941)
			(xy 432.219514 -411.966794) (xy 432.239143 -411.907673) (xy 432.266172 -411.851547) (xy 432.300156 -411.799338)
			(xy 432.340538 -411.751903) (xy 432.386654 -411.710022) (xy 432.437746 -411.674382) (xy 432.492977 -411.645568)
			(xy 432.551439 -411.624054) (xy 432.612173 -411.610192) (xy 432.67418 -411.60421) (xy 432.736443 -411.606206)
			(xy 432.79794 -411.616149) (xy 432.857661 -411.633873) (xy 432.914624 -411.65909) (xy 432.967895 -411.691383)
			(xy 433.0166 -411.730223) (xy 433.059937 -411.774973) (xy 433.097197 -411.824897) (xy 433.127766 -411.879176)
			(xy 433.151144 -411.936919) (xy 433.166945 -411.997177) (xy 433.174911 -412.05896) (xy 433.17541 -412.090108)
			(xy 436.603656 -412.090108) (xy 436.607647 -412.027941) (xy 436.619556 -411.966794) (xy 436.639185 -411.907673)
			(xy 436.666214 -411.851547) (xy 436.700198 -411.799338) (xy 436.74058 -411.751903) (xy 436.786696 -411.710022)
			(xy 436.837788 -411.674382) (xy 436.893019 -411.645568) (xy 436.951481 -411.624054) (xy 437.012215 -411.610192)
			(xy 437.074222 -411.60421) (xy 437.136485 -411.606206) (xy 437.197982 -411.616149) (xy 437.257703 -411.633873)
			(xy 437.314666 -411.65909) (xy 437.367937 -411.691383) (xy 437.416642 -411.730223) (xy 437.459979 -411.774973)
			(xy 437.497239 -411.824897) (xy 437.527808 -411.879176) (xy 437.536286 -411.900116) (xy 444.291972 -411.900116)
			(xy 444.296043 -411.844494) (xy 444.308169 -411.790057) (xy 444.328092 -411.737966) (xy 444.355388 -411.689331)
			(xy 444.389474 -411.645188) (xy 444.429623 -411.606479) (xy 444.474981 -411.574028) (xy 444.524581 -411.548527)
			(xy 444.577365 -411.53052) (xy 444.632208 -411.52039) (xy 444.687942 -411.518353) (xy 444.743379 -411.524453)
			(xy 444.797336 -411.538559) (xy 444.848665 -411.560371) (xy 444.896271 -411.589425) (xy 444.939139 -411.6251)
			(xy 444.976356 -411.666637) (xy 445.007129 -411.71315) (xy 445.030801 -411.763647) (xy 445.046869 -411.817054)
			(xy 445.054989 -411.87223) (xy 445.055498 -411.900116) (xy 445.054989 -411.928002) (xy 445.046869 -411.983178)
			(xy 445.030801 -412.036585) (xy 445.007129 -412.087082) (xy 444.976356 -412.133595) (xy 444.939139 -412.175132)
			(xy 444.896271 -412.210807) (xy 444.848665 -412.239861) (xy 444.797336 -412.261673) (xy 444.743379 -412.275779)
			(xy 444.687942 -412.281879) (xy 444.632208 -412.279842) (xy 444.577365 -412.269712) (xy 444.524581 -412.251705)
			(xy 444.474981 -412.226204) (xy 444.429623 -412.193753) (xy 444.389474 -412.155044) (xy 444.355388 -412.110901)
			(xy 444.328092 -412.062266) (xy 444.308169 -412.010175) (xy 444.296043 -411.955738) (xy 444.291972 -411.900116)
			(xy 437.536286 -411.900116) (xy 437.551186 -411.936919) (xy 437.566987 -411.997177) (xy 437.574953 -412.05896)
			(xy 437.575452 -412.090108) (xy 437.574953 -412.121256) (xy 437.566987 -412.183039) (xy 437.551186 -412.243297)
			(xy 437.527808 -412.30104) (xy 437.497239 -412.355319) (xy 437.459979 -412.405243) (xy 437.416642 -412.449993)
			(xy 437.367937 -412.488833) (xy 437.314666 -412.521126) (xy 437.257703 -412.546343) (xy 437.197982 -412.564067)
			(xy 437.136485 -412.57401) (xy 437.074222 -412.576006) (xy 437.012215 -412.570024) (xy 436.951481 -412.556162)
			(xy 436.893019 -412.534648) (xy 436.837788 -412.505834) (xy 436.786696 -412.470194) (xy 436.74058 -412.428313)
			(xy 436.700198 -412.380878) (xy 436.666214 -412.328669) (xy 436.639185 -412.272543) (xy 436.619556 -412.213422)
			(xy 436.607647 -412.152275) (xy 436.603656 -412.090108) (xy 433.17541 -412.090108) (xy 433.174911 -412.121256)
			(xy 433.166945 -412.183039) (xy 433.151144 -412.243297) (xy 433.127766 -412.30104) (xy 433.097197 -412.355319)
			(xy 433.059937 -412.405243) (xy 433.0166 -412.449993) (xy 432.967895 -412.488833) (xy 432.914624 -412.521126)
			(xy 432.857661 -412.546343) (xy 432.79794 -412.564067) (xy 432.736443 -412.57401) (xy 432.67418 -412.576006)
			(xy 432.612173 -412.570024) (xy 432.551439 -412.556162) (xy 432.492977 -412.534648) (xy 432.437746 -412.505834)
			(xy 432.386654 -412.470194) (xy 432.340538 -412.428313) (xy 432.300156 -412.380878) (xy 432.266172 -412.328669)
			(xy 432.239143 -412.272543) (xy 432.219514 -412.213422) (xy 432.207605 -412.152275) (xy 432.203614 -412.090108)
			(xy 428.775622 -412.090108) (xy 428.775123 -412.121256) (xy 428.767157 -412.183039) (xy 428.751356 -412.243297)
			(xy 428.727978 -412.30104) (xy 428.697409 -412.355319) (xy 428.660149 -412.405243) (xy 428.616812 -412.449993)
			(xy 428.568107 -412.488833) (xy 428.514836 -412.521126) (xy 428.457873 -412.546343) (xy 428.398152 -412.564067)
			(xy 428.336655 -412.57401) (xy 428.274392 -412.576006) (xy 428.212385 -412.570024) (xy 428.151651 -412.556162)
			(xy 428.093189 -412.534648) (xy 428.037958 -412.505834) (xy 427.986866 -412.470194) (xy 427.94075 -412.428313)
			(xy 427.900368 -412.380878) (xy 427.866384 -412.328669) (xy 427.839355 -412.272543) (xy 427.819726 -412.213422)
			(xy 427.807817 -412.152275) (xy 427.803826 -412.090108) (xy 424.37558 -412.090108) (xy 424.375081 -412.121256)
			(xy 424.367115 -412.183039) (xy 424.351314 -412.243297) (xy 424.327936 -412.30104) (xy 424.297367 -412.355319)
			(xy 424.260107 -412.405243) (xy 424.21677 -412.449993) (xy 424.168065 -412.488833) (xy 424.114794 -412.521126)
			(xy 424.057831 -412.546343) (xy 423.99811 -412.564067) (xy 423.936613 -412.57401) (xy 423.87435 -412.576006)
			(xy 423.812343 -412.570024) (xy 423.751609 -412.556162) (xy 423.693147 -412.534648) (xy 423.637916 -412.505834)
			(xy 423.586824 -412.470194) (xy 423.540708 -412.428313) (xy 423.500326 -412.380878) (xy 423.466342 -412.328669)
			(xy 423.439313 -412.272543) (xy 423.419684 -412.213422) (xy 423.407775 -412.152275) (xy 423.403784 -412.090108)
			(xy 419.975538 -412.090108) (xy 419.975039 -412.121256) (xy 419.967073 -412.183039) (xy 419.951272 -412.243297)
			(xy 419.927894 -412.30104) (xy 419.897325 -412.355319) (xy 419.860065 -412.405243) (xy 419.816728 -412.449993)
			(xy 419.768023 -412.488833) (xy 419.714752 -412.521126) (xy 419.657789 -412.546343) (xy 419.598068 -412.564067)
			(xy 419.536571 -412.57401) (xy 419.474308 -412.576006) (xy 419.412301 -412.570024) (xy 419.351567 -412.556162)
			(xy 419.293105 -412.534648) (xy 419.237874 -412.505834) (xy 419.186782 -412.470194) (xy 419.140666 -412.428313)
			(xy 419.100284 -412.380878) (xy 419.0663 -412.328669) (xy 419.039271 -412.272543) (xy 419.019642 -412.213422)
			(xy 419.007733 -412.152275) (xy 419.003742 -412.090108) (xy 414.915604 -412.090108) (xy 414.915604 -414.403794)
			(xy 447.176396 -414.403794) (xy 447.180467 -414.348172) (xy 447.192593 -414.293735) (xy 447.212516 -414.241644)
			(xy 447.239812 -414.193009) (xy 447.273898 -414.148866) (xy 447.314047 -414.110157) (xy 447.359405 -414.077706)
			(xy 447.409005 -414.052205) (xy 447.461789 -414.034198) (xy 447.516632 -414.024068) (xy 447.572366 -414.022031)
			(xy 447.627803 -414.028131) (xy 447.68176 -414.042237) (xy 447.733089 -414.064049) (xy 447.780695 -414.093103)
			(xy 447.823563 -414.128778) (xy 447.86078 -414.170315) (xy 447.891553 -414.216828) (xy 447.915225 -414.267325)
			(xy 447.931293 -414.320732) (xy 447.939413 -414.375908) (xy 447.939922 -414.403794) (xy 447.939413 -414.43168)
			(xy 447.931293 -414.486856) (xy 447.915225 -414.540263) (xy 447.891801 -414.59023) (xy 448.79717 -414.59023)
			(xy 448.801241 -414.534608) (xy 448.813367 -414.480171) (xy 448.83329 -414.42808) (xy 448.860586 -414.379445)
			(xy 448.894672 -414.335302) (xy 448.934821 -414.296593) (xy 448.980179 -414.264142) (xy 449.029779 -414.238641)
			(xy 449.082563 -414.220634) (xy 449.137406 -414.210504) (xy 449.19314 -414.208467) (xy 449.248577 -414.214567)
			(xy 449.302534 -414.228673) (xy 449.353863 -414.250485) (xy 449.401469 -414.279539) (xy 449.444337 -414.315214)
			(xy 449.461574 -414.334452) (xy 450.168262 -414.334452) (xy 450.172333 -414.27883) (xy 450.184459 -414.224393)
			(xy 450.204382 -414.172302) (xy 450.231678 -414.123667) (xy 450.265764 -414.079524) (xy 450.305913 -414.040815)
			(xy 450.351271 -414.008364) (xy 450.400871 -413.982863) (xy 450.453655 -413.964856) (xy 450.508498 -413.954726)
			(xy 450.564232 -413.952689) (xy 450.619669 -413.958789) (xy 450.673626 -413.972895) (xy 450.724955 -413.994707)
			(xy 450.772561 -414.023761) (xy 450.815429 -414.059436) (xy 450.852646 -414.100973) (xy 450.883419 -414.147486)
			(xy 450.907091 -414.197983) (xy 450.923159 -414.25139) (xy 450.931279 -414.306566) (xy 450.931788 -414.334452)
			(xy 450.931279 -414.362338) (xy 450.923159 -414.417514) (xy 450.907091 -414.470921) (xy 450.883419 -414.521418)
			(xy 450.852646 -414.567931) (xy 450.815429 -414.609468) (xy 450.772561 -414.645143) (xy 450.724955 -414.674197)
			(xy 450.673626 -414.696009) (xy 450.619669 -414.710115) (xy 450.564232 -414.716215) (xy 450.508498 -414.714178)
			(xy 450.453655 -414.704048) (xy 450.400871 -414.686041) (xy 450.351271 -414.66054) (xy 450.305913 -414.628089)
			(xy 450.265764 -414.58938) (xy 450.231678 -414.545237) (xy 450.204382 -414.496602) (xy 450.184459 -414.444511)
			(xy 450.172333 -414.390074) (xy 450.168262 -414.334452) (xy 449.461574 -414.334452) (xy 449.481554 -414.356751)
			(xy 449.512327 -414.403264) (xy 449.535999 -414.453761) (xy 449.552067 -414.507168) (xy 449.560187 -414.562344)
			(xy 449.560696 -414.59023) (xy 449.560187 -414.618116) (xy 449.552067 -414.673292) (xy 449.535999 -414.726699)
			(xy 449.512327 -414.777196) (xy 449.481554 -414.823709) (xy 449.444337 -414.865246) (xy 449.401469 -414.900921)
			(xy 449.353863 -414.929975) (xy 449.302534 -414.951787) (xy 449.248577 -414.965893) (xy 449.19314 -414.971993)
			(xy 449.137406 -414.969956) (xy 449.082563 -414.959826) (xy 449.029779 -414.941819) (xy 448.980179 -414.916318)
			(xy 448.934821 -414.883867) (xy 448.894672 -414.845158) (xy 448.860586 -414.801015) (xy 448.83329 -414.75238)
			(xy 448.813367 -414.700289) (xy 448.801241 -414.645852) (xy 448.79717 -414.59023) (xy 447.891801 -414.59023)
			(xy 447.891553 -414.59076) (xy 447.86078 -414.637273) (xy 447.823563 -414.67881) (xy 447.780695 -414.714485)
			(xy 447.733089 -414.743539) (xy 447.68176 -414.765351) (xy 447.627803 -414.779457) (xy 447.572366 -414.785557)
			(xy 447.516632 -414.78352) (xy 447.461789 -414.77339) (xy 447.409005 -414.755383) (xy 447.359405 -414.729882)
			(xy 447.314047 -414.697431) (xy 447.273898 -414.658722) (xy 447.239812 -414.614579) (xy 447.212516 -414.565944)
			(xy 447.192593 -414.513853) (xy 447.180467 -414.459416) (xy 447.176396 -414.403794) (xy 414.915604 -414.403794)
			(xy 414.915604 -416.636962) (xy 446.76517 -416.636962) (xy 446.769241 -416.58134) (xy 446.781367 -416.526903)
			(xy 446.80129 -416.474812) (xy 446.828586 -416.426177) (xy 446.862672 -416.382034) (xy 446.902821 -416.343325)
			(xy 446.948179 -416.310874) (xy 446.997779 -416.285373) (xy 447.050563 -416.267366) (xy 447.105406 -416.257236)
			(xy 447.16114 -416.255199) (xy 447.216577 -416.261299) (xy 447.270534 -416.275405) (xy 447.321863 -416.297217)
			(xy 447.369469 -416.326271) (xy 447.412337 -416.361946) (xy 447.449554 -416.403483) (xy 447.480327 -416.449996)
			(xy 447.503999 -416.500493) (xy 447.520067 -416.5539) (xy 447.528187 -416.609076) (xy 447.528696 -416.636962)
			(xy 448.79717 -416.636962) (xy 448.801241 -416.58134) (xy 448.813367 -416.526903) (xy 448.83329 -416.474812)
			(xy 448.860586 -416.426177) (xy 448.894672 -416.382034) (xy 448.934821 -416.343325) (xy 448.980179 -416.310874)
			(xy 449.029779 -416.285373) (xy 449.082563 -416.267366) (xy 449.137406 -416.257236) (xy 449.19314 -416.255199)
			(xy 449.248577 -416.261299) (xy 449.302534 -416.275405) (xy 449.353863 -416.297217) (xy 449.401469 -416.326271)
			(xy 449.444337 -416.361946) (xy 449.481554 -416.403483) (xy 449.512327 -416.449996) (xy 449.535999 -416.500493)
			(xy 449.552067 -416.5539) (xy 449.560187 -416.609076) (xy 449.560696 -416.636962) (xy 449.81317 -416.636962)
			(xy 449.817241 -416.58134) (xy 449.829367 -416.526903) (xy 449.84929 -416.474812) (xy 449.876586 -416.426177)
			(xy 449.910672 -416.382034) (xy 449.950821 -416.343325) (xy 449.996179 -416.310874) (xy 450.045779 -416.285373)
			(xy 450.098563 -416.267366) (xy 450.153406 -416.257236) (xy 450.20914 -416.255199) (xy 450.264577 -416.261299)
			(xy 450.318534 -416.275405) (xy 450.369863 -416.297217) (xy 450.417469 -416.326271) (xy 450.460337 -416.361946)
			(xy 450.497554 -416.403483) (xy 450.528327 -416.449996) (xy 450.551999 -416.500493) (xy 450.568067 -416.5539)
			(xy 450.576187 -416.609076) (xy 450.576696 -416.636962) (xy 450.576187 -416.664848) (xy 450.568067 -416.720024)
			(xy 450.551999 -416.773431) (xy 450.528327 -416.823928) (xy 450.497554 -416.870441) (xy 450.460337 -416.911978)
			(xy 450.417469 -416.947653) (xy 450.369863 -416.976707) (xy 450.318534 -416.998519) (xy 450.264577 -417.012625)
			(xy 450.20914 -417.018725) (xy 450.153406 -417.016688) (xy 450.098563 -417.006558) (xy 450.045779 -416.988551)
			(xy 449.996179 -416.96305) (xy 449.950821 -416.930599) (xy 449.910672 -416.89189) (xy 449.876586 -416.847747)
			(xy 449.84929 -416.799112) (xy 449.829367 -416.747021) (xy 449.817241 -416.692584) (xy 449.81317 -416.636962)
			(xy 449.560696 -416.636962) (xy 449.560187 -416.664848) (xy 449.552067 -416.720024) (xy 449.535999 -416.773431)
			(xy 449.512327 -416.823928) (xy 449.481554 -416.870441) (xy 449.444337 -416.911978) (xy 449.401469 -416.947653)
			(xy 449.353863 -416.976707) (xy 449.302534 -416.998519) (xy 449.248577 -417.012625) (xy 449.19314 -417.018725)
			(xy 449.137406 -417.016688) (xy 449.082563 -417.006558) (xy 449.029779 -416.988551) (xy 448.980179 -416.96305)
			(xy 448.934821 -416.930599) (xy 448.894672 -416.89189) (xy 448.860586 -416.847747) (xy 448.83329 -416.799112)
			(xy 448.813367 -416.747021) (xy 448.801241 -416.692584) (xy 448.79717 -416.636962) (xy 447.528696 -416.636962)
			(xy 447.528187 -416.664848) (xy 447.520067 -416.720024) (xy 447.503999 -416.773431) (xy 447.480327 -416.823928)
			(xy 447.449554 -416.870441) (xy 447.412337 -416.911978) (xy 447.369469 -416.947653) (xy 447.321863 -416.976707)
			(xy 447.270534 -416.998519) (xy 447.216577 -417.012625) (xy 447.16114 -417.018725) (xy 447.105406 -417.016688)
			(xy 447.050563 -417.006558) (xy 446.997779 -416.988551) (xy 446.948179 -416.96305) (xy 446.902821 -416.930599)
			(xy 446.862672 -416.89189) (xy 446.828586 -416.847747) (xy 446.80129 -416.799112) (xy 446.781367 -416.747021)
			(xy 446.769241 -416.692584) (xy 446.76517 -416.636962) (xy 414.915604 -416.636962) (xy 414.915604 -417.553394)
			(xy 414.915743 -417.558834) (xy 414.918043 -417.569469) (xy 414.920176 -417.574476) (xy 414.915604 -417.574476)
			(xy 414.915604 -417.797742) (xy 400.95424 -417.797742) (xy 400.95424 -417.574476) (xy 326.621648 -417.574476)
			(xy 326.621648 -417.747958) (xy 313.065922 -417.747958) (xy 313.065922 -417.574476) (xy 274.757896 -417.574476)
			(xy 274.712278 -417.573956) (xy 274.621433 -417.565503) (xy 274.531761 -417.548679) (xy 274.44403 -417.523628)
			(xy 274.358994 -417.490566) (xy 274.277383 -417.449777) (xy 274.199897 -417.40161) (xy 274.1272 -417.346479)
			(xy 274.059918 -417.284856) (xy 274.028916 -417.251388) (xy 273.975737 -417.193452) (xy 273.864198 -417.082562)
			(xy 273.74703 -416.977639) (xy 273.624551 -416.878967) (xy 273.497093 -416.786815) (xy 273.365004 -416.701434)
			(xy 273.228643 -416.623056) (xy 273.088382 -416.551895) (xy 272.9446 -416.488143) (xy 272.79769 -416.431975)
			(xy 272.648052 -416.383543) (xy 272.496091 -416.342979) (xy 272.342223 -416.310393) (xy 272.186865 -416.285874)
			(xy 272.030439 -416.269488) (xy 271.873373 -416.261281) (xy 271.794732 -416.260788) (xy 203.445364 -416.260788)
			(xy 203.366716 -416.261295) (xy 203.209634 -416.269493) (xy 203.053193 -416.285871) (xy 202.897818 -416.310383)
			(xy 202.743933 -416.342963) (xy 202.591957 -416.383522) (xy 202.442301 -416.431951) (xy 202.295375 -416.488117)
			(xy 202.151576 -416.551867) (xy 202.011298 -416.623028) (xy 201.87492 -416.701407) (xy 201.742815 -416.78679)
			(xy 201.615341 -416.878945) (xy 201.492846 -416.977621) (xy 201.375663 -417.08255) (xy 201.26411 -417.193446)
			(xy 201.210926 -417.251388) (xy 201.179905 -417.284839) (xy 201.112632 -417.346472) (xy 201.039943 -417.401611)
			(xy 200.96246 -417.449784) (xy 200.880851 -417.490577) (xy 200.795815 -417.523638) (xy 200.708083 -417.548685)
			(xy 200.61841 -417.565501) (xy 200.527564 -417.573943) (xy 200.481946 -417.574476) (xy 154.673554 -417.574476)
			(xy 154.673554 -417.693856) (xy 141.027912 -417.693856) (xy 141.027912 -417.574476) (xy 66.745104 -417.574476)
			(xy 66.745104 -417.671758) (xy 53.039772 -417.671758) (xy 53.039772 -417.574476) (xy 1.999996 -417.574476)
			(xy 1.954504 -417.573951) (xy 1.863908 -417.565555) (xy 1.774473 -417.548837) (xy 1.686963 -417.523938)
			(xy 1.602123 -417.49107) (xy 1.520677 -417.450515) (xy 1.443321 -417.402618) (xy 1.370714 -417.347788)
			(xy 1.303476 -417.286492) (xy 1.242181 -417.219254) (xy 1.187351 -417.146647) (xy 1.139454 -417.069291)
			(xy 1.098899 -416.987845) (xy 1.066032 -416.903005) (xy 1.041133 -416.815495) (xy 1.024414 -416.72606)
			(xy 1.016019 -416.635464) (xy 1.015492 -416.589972) (xy 1.015492 -246.48795) (xy 1.015971 -246.444999)
			(xy 1.023477 -246.359425) (xy 1.038407 -246.27483) (xy 1.060648 -246.191857) (xy 1.090032 -246.111137)
			(xy 1.126334 -246.033282) (xy 1.16928 -245.958885) (xy 1.218542 -245.888512) (xy 1.273746 -245.822696)
			(xy 1.303782 -245.79199) (xy 3.93192 -243.163852) (xy 3.987399 -243.107671) (xy 4.093079 -242.990336)
			(xy 4.192472 -242.86763) (xy 4.285305 -242.739888) (xy 4.371323 -242.607463) (xy 4.450292 -242.470716)
			(xy 4.521994 -242.330023) (xy 4.586233 -242.185769) (xy 4.642833 -242.03835) (xy 4.691638 -241.888171)
			(xy 4.732514 -241.735642) (xy 4.765351 -241.581183) (xy 4.790056 -241.425217) (xy 4.806563 -241.268172)
			(xy 4.814827 -241.110477) (xy 4.815332 -241.031522) (xy 4.815332 -87.588344) (xy 4.814818 -87.509397)
			(xy 4.806542 -87.351721) (xy 4.790024 -87.194694) (xy 4.76531 -87.038746) (xy 4.732468 -86.884306)
			(xy 4.691587 -86.731797) (xy 4.642779 -86.581636) (xy 4.586179 -86.434236) (xy 4.521942 -86.29) (xy 4.450243 -86.149325)
			(xy 4.371279 -86.012595) (xy 4.285267 -85.880185) (xy 4.192443 -85.752459) (xy 4.09306 -85.629767)
			(xy 3.987392 -85.512444) (xy 3.93192 -85.456268) (xy 1.303528 -82.827876) (xy 1.273521 -82.79717)
			(xy 1.218366 -82.731365) (xy 1.169149 -82.66101) (xy 1.126242 -82.586638) (xy 1.089972 -82.508813)
			(xy 1.060615 -82.428126) (xy 1.038392 -82.34519) (xy 1.023472 -82.260634) (xy 1.01597 -82.175101)
			(xy 1.015492 -82.13217) (xy 1.015492 -1.999996) (xy 1.016017 -1.954504) (xy 1.024413 -1.863908) (xy 1.041131 -1.774473)
			(xy 1.06603 -1.686962) (xy 1.098898 -1.602122) (xy 1.139453 -1.520677) (xy 1.18735 -1.443321) (xy 1.24218 -1.370714)
			(xy 1.303476 -1.303476) (xy 1.370714 -1.24218) (xy 1.443321 -1.18735) (xy 1.520677 -1.139453) (xy 1.602122 -1.098898)
			(xy 1.686962 -1.06603) (xy 1.774473 -1.041131) (xy 1.863908 -1.024413) (xy 1.954504 -1.016017) (xy 1.999996 -1.015492)
			(xy 5.964936 -1.015492) (xy 6.010428 -1.016017) (xy 6.101024 -1.024413) (xy 6.190458 -1.041131) (xy 6.277969 -1.066031)
			(xy 6.362809 -1.098898) (xy 6.444254 -1.139454) (xy 6.52161 -1.187351) (xy 6.594217 -1.242181) (xy 6.661455 -1.303476)
			(xy 6.72275 -1.370714) (xy 6.77758 -1.443321) (xy 6.825477 -1.520677) (xy 6.866033 -1.602123) (xy 6.8989 -1.686963)
			(xy 6.923799 -1.774473) (xy 6.940518 -1.863908) (xy 6.948913 -1.954504) (xy 6.94944 -1.999996) (xy 6.94944 -11.850116)
			(xy 6.949945 -11.913435) (xy 6.957912 -12.039821) (xy 6.973799 -12.165458) (xy 6.997542 -12.289849)
			(xy 7.029049 -12.412504) (xy 7.068194 -12.532939) (xy 7.114823 -12.650679) (xy 7.168753 -12.765259)
			(xy 7.229771 -12.876227) (xy 7.297635 -12.983144) (xy 7.372078 -13.08559) (xy 7.452807 -13.18316)
			(xy 7.539502 -13.275469) (xy 7.631822 -13.362152) (xy 7.729402 -13.442869) (xy 7.831857 -13.517299)
			(xy 7.938784 -13.585149) (xy 8.049759 -13.646153) (xy 8.164346 -13.700068) (xy 8.282092 -13.746683)
			(xy 8.402532 -13.785813) (xy 8.525191 -13.817304) (xy 8.649585 -13.841031) (xy 8.775224 -13.856902)
			(xy 8.901611 -13.864853) (xy 8.96493 -13.865352) (xy 16.2814 -13.865352) (xy 16.371316 -13.775436)
			(xy 16.371316 -13.44803) (xy 16.2814 -13.358114) (xy 8.96493 -13.358114) (xy 8.911089 -13.357645)
			(xy 8.80368 -13.349963) (xy 8.697093 -13.334638) (xy 8.591871 -13.311748) (xy 8.48855 -13.28141)
			(xy 8.387656 -13.243779) (xy 8.289705 -13.199046) (xy 8.195194 -13.147439) (xy 8.104605 -13.089221)
			(xy 8.0184 -13.024689) (xy 7.937019 -12.954171) (xy 7.860876 -12.878028) (xy 7.790359 -12.796646)
			(xy 7.725827 -12.710442) (xy 7.667609 -12.619853) (xy 7.616002 -12.525342) (xy 7.57127 -12.42739)
			(xy 7.533638 -12.326496) (xy 7.503301 -12.223175) (xy 7.480411 -12.117953) (xy 7.465087 -12.011366)
			(xy 7.457405 -11.903957) (xy 7.456932 -11.850116) (xy 7.456932 -1.999996) (xy 7.45641 -1.944189)
			(xy 7.448069 -1.832887) (xy 7.431434 -1.72252) (xy 7.406597 -1.613704) (xy 7.373698 -1.507049) (xy 7.332921 -1.40315)
			(xy 7.284493 -1.30259) (xy 7.228686 -1.205929) (xy 7.165812 -1.113709) (xy 7.096221 -1.026446) (xy 7.020305 -0.944627)
			(xy 6.938486 -0.86871) (xy 6.851222 -0.79912) (xy 6.759003 -0.736245) (xy 6.662342 -0.680438) (xy 6.561782 -0.63201)
			(xy 6.457883 -0.591233) (xy 6.351228 -0.558334) (xy 6.242412 -0.533497) (xy 6.132045 -0.516861) (xy 6.020743 -0.50852)
			(xy 5.964936 -0.508) (xy 1.999996 -0.508) (xy 1.944189 -0.508522) (xy 1.832887 -0.516863) (xy 1.72252 -0.533498)
			(xy 1.613704 -0.558335) (xy 1.507049 -0.591234) (xy 1.403151 -0.632011) (xy 1.30259 -0.680439) (xy 1.205929 -0.736246)
			(xy 1.11371 -0.799121) (xy 1.026446 -0.868711) (xy 0.944628 -0.944628) (xy 0.868711 -1.026446) (xy 0.799121 -1.11371)
			(xy 0.736246 -1.205929) (xy 0.680439 -1.30259) (xy 0.632011 -1.403151) (xy 0.591234 -1.507049) (xy 0.558335 -1.613704)
			(xy 0.533498 -1.72252) (xy 0.516863 -1.832887) (xy 0.508522 -1.944189) (xy 0.508 -1.999996) (xy 0.508 -82.131916)
			(xy 0.508487 -82.185165) (xy 0.516104 -82.291392) (xy 0.531277 -82.396804) (xy 0.553928 -82.500867)
			(xy 0.583941 -82.603049) (xy 0.621164 -82.702831) (xy 0.665407 -82.799705) (xy 0.716446 -82.893178)
			(xy 0.774019 -82.982773) (xy 0.837835 -83.068035) (xy 0.907568 -83.14853) (xy 0.94488 -83.186524)
			(xy 3.573272 -85.81517) (xy 3.622687 -85.865245) (xy 3.716468 -85.970133) (xy 3.804219 -86.080117)
			(xy 3.885663 -86.194848) (xy 3.960544 -86.313966) (xy 4.028628 -86.437097) (xy 4.089698 -86.563852)
			(xy 4.143563 -86.693833) (xy 4.190054 -86.82663) (xy 4.229024 -86.961825) (xy 4.260351 -87.098994)
			(xy 4.283935 -87.237703) (xy 4.299703 -87.377516) (xy 4.307605 -87.517994) (xy 4.308094 -87.588344)
			(xy 4.308094 -241.031522) (xy 4.307605 -241.10188) (xy 4.299704 -241.242374) (xy 4.283937 -241.382205)
			(xy 4.260354 -241.52093) (xy 4.229028 -241.658116) (xy 4.190059 -241.793328) (xy 4.143568 -241.926143)
			(xy 4.089703 -242.056141) (xy 4.028633 -242.182915) (xy 3.960549 -242.306064) (xy 3.885667 -242.425201)
			(xy 3.804222 -242.539952) (xy 3.71647 -242.649955) (xy 3.622687 -242.754863) (xy 3.573272 -242.80495)
			(xy 0.94488 -245.433342) (xy 0.90756 -245.471344) (xy 0.837813 -245.551857) (xy 0.773985 -245.637139)
			(xy 0.716403 -245.726756) (xy 0.66536 -245.820253) (xy 0.621114 -245.917151) (xy 0.583893 -246.016959)
			(xy 0.553885 -246.119167) (xy 0.531243 -246.223255) (xy 0.516083 -246.328692) (xy 0.508481 -246.434943)
			(xy 0.508 -246.488204) (xy 0.508 -416.589972) (xy 0.508522 -416.645779) (xy 0.516863 -416.757081)
			(xy 0.533498 -416.867448) (xy 0.558335 -416.976264) (xy 0.591234 -417.082919) (xy 0.632011 -417.186818)
			(xy 0.680438 -417.287379) (xy 0.736245 -417.384039) (xy 0.79912 -417.476259) (xy 0.86871 -417.563523)
			(xy 0.944627 -417.645342) (xy 1.026446 -417.721259) (xy 1.113709 -417.790849) (xy 1.205929 -417.853724)
			(xy 1.302589 -417.909531) (xy 1.40315 -417.957958) (xy 1.507049 -417.998736) (xy 1.613704 -418.031635)
			(xy 1.72252 -418.056471) (xy 1.832887 -418.073107) (xy 1.944189 -418.081448) (xy 1.999996 -418.081968)
		)
		(stroke
			(width 0)
			(type solid)
		)
		(fill yes)
		(layer "In7.Cu")
		(net "GND")
	)
	(gr_poly
		(pts
			(xy 366.980978 -293.609014) (xy 366.981486 -293.609014) (xy 366.989008 -293.607419) (xy 367.002706 -293.600453)
			(xy 367.00841 -293.595298) (xy 367.774982 -292.828726) (xy 367.780174 -292.823046) (xy 367.787153 -292.809341)
			(xy 367.788698 -292.801802) (xy 367.788698 -292.801294) (xy 367.78946 -292.793166) (xy 367.78946 -287.729422)
			(xy 367.789899 -287.719359) (xy 367.79764 -287.700781) (xy 367.804446 -287.693354) (xy 368.392202 -287.105598)
			(xy 368.399601 -287.098752) (xy 368.418199 -287.091019) (xy 368.42827 -287.090612) (xy 370.985034 -287.090612)
			(xy 370.989606 -287.090866) (xy 379.591062 -287.090866) (xy 379.594618 -287.090612) (xy 379.602851 -287.089705)
			(xy 379.61814 -287.083362) (xy 379.62459 -287.078166) (xy 379.631448 -287.07207) (xy 379.63983 -287.056068)
			(xy 379.6411 -287.046416) (xy 379.645395 -287.016582) (xy 379.662168 -286.958692) (xy 379.687839 -286.90416)
			(xy 379.721768 -286.854346) (xy 379.763112 -286.81049) (xy 379.786642 -286.791654) (xy 379.789436 -286.789622)
			(xy 379.79604 -286.783018) (xy 379.800104 -286.777684) (xy 379.804303 -286.771574) (xy 379.809336 -286.757635)
			(xy 379.81001 -286.750252) (xy 379.810264 -286.724344) (xy 379.809707 -286.714511) (xy 379.802125 -286.696355)
			(xy 379.795532 -286.689038) (xy 379.791214 -286.68472) (xy 379.78588 -286.680656) (xy 379.784102 -286.679386)
			(xy 379.78334 -286.678624) (xy 379.781308 -286.6771) (xy 379.77953 -286.67583) (xy 379.75667 -286.658606)
			(xy 379.715336 -286.619011) (xy 379.679684 -286.574232) (xy 379.650357 -286.525077) (xy 379.627885 -286.472435)
			(xy 379.612674 -286.417255) (xy 379.604998 -286.360533) (xy 379.604524 -286.331914) (xy 379.605021 -286.302777)
			(xy 379.612956 -286.245046) (xy 379.628678 -286.188932) (xy 379.651895 -286.135483) (xy 379.682173 -286.085692)
			(xy 379.718949 -286.040488) (xy 379.761538 -286.000713) (xy 379.809146 -285.967107) (xy 379.860887 -285.940297)
			(xy 379.915796 -285.920783) (xy 379.972852 -285.908926) (xy 380.03099 -285.90495) (xy 380.089128 -285.908926)
			(xy 380.146184 -285.920783) (xy 380.157352 -285.924752) (xy 386.269242 -285.924752) (xy 386.273202 -285.875698)
			(xy 386.284979 -285.827914) (xy 386.30427 -285.782638) (xy 386.330573 -285.741042) (xy 386.363208 -285.704205)
			(xy 386.401329 -285.67308) (xy 386.44395 -285.648473) (xy 386.489966 -285.631021) (xy 386.538185 -285.621177)
			(xy 386.58736 -285.619196) (xy 386.636215 -285.625128) (xy 386.683486 -285.63882) (xy 386.727948 -285.659918)
			(xy 386.768451 -285.687874) (xy 386.803944 -285.721966) (xy 386.833509 -285.76131) (xy 386.85638 -285.804887)
			(xy 386.871964 -285.851568) (xy 386.879859 -285.900145) (xy 386.880354 -285.924752) (xy 387.219202 -285.924752)
			(xy 387.223162 -285.875698) (xy 387.234939 -285.827914) (xy 387.25423 -285.782638) (xy 387.280533 -285.741042)
			(xy 387.313168 -285.704205) (xy 387.351289 -285.67308) (xy 387.39391 -285.648473) (xy 387.439926 -285.631021)
			(xy 387.488145 -285.621177) (xy 387.53732 -285.619196) (xy 387.586175 -285.625128) (xy 387.633446 -285.63882)
			(xy 387.677908 -285.659918) (xy 387.718411 -285.687874) (xy 387.753904 -285.721966) (xy 387.783469 -285.76131)
			(xy 387.80634 -285.804887) (xy 387.821924 -285.851568) (xy 387.829819 -285.900145) (xy 387.830314 -285.924752)
			(xy 387.829819 -285.949359) (xy 387.821924 -285.997936) (xy 387.80634 -286.044617) (xy 387.783469 -286.088194)
			(xy 387.753904 -286.127538) (xy 387.718411 -286.16163) (xy 387.677908 -286.189586) (xy 387.633446 -286.210684)
			(xy 387.586175 -286.224376) (xy 387.53732 -286.230308) (xy 387.488145 -286.228327) (xy 387.439926 -286.218483)
			(xy 387.39391 -286.201031) (xy 387.351289 -286.176424) (xy 387.313168 -286.145299) (xy 387.280533 -286.108462)
			(xy 387.25423 -286.066866) (xy 387.234939 -286.02159) (xy 387.223162 -285.973806) (xy 387.219202 -285.924752)
			(xy 386.880354 -285.924752) (xy 386.879859 -285.949359) (xy 386.871964 -285.997936) (xy 386.85638 -286.044617)
			(xy 386.833509 -286.088194) (xy 386.803944 -286.127538) (xy 386.768451 -286.16163) (xy 386.727948 -286.189586)
			(xy 386.683486 -286.210684) (xy 386.636215 -286.224376) (xy 386.58736 -286.230308) (xy 386.538185 -286.228327)
			(xy 386.489966 -286.218483) (xy 386.44395 -286.201031) (xy 386.401329 -286.176424) (xy 386.363208 -286.145299)
			(xy 386.330573 -286.108462) (xy 386.30427 -286.066866) (xy 386.284979 -286.02159) (xy 386.273202 -285.973806)
			(xy 386.269242 -285.924752) (xy 380.157352 -285.924752) (xy 380.201093 -285.940297) (xy 380.252834 -285.967107)
			(xy 380.300442 -286.000713) (xy 380.343031 -286.040488) (xy 380.379807 -286.085692) (xy 380.410085 -286.135483)
			(xy 380.433302 -286.188932) (xy 380.449024 -286.245046) (xy 380.456959 -286.302777) (xy 380.457456 -286.331914)
			(xy 380.456921 -286.362236) (xy 380.448326 -286.422267) (xy 380.431312 -286.480474) (xy 380.406222 -286.535684)
			(xy 380.373561 -286.586781) (xy 380.33399 -286.632735) (xy 380.288307 -286.672618) (xy 380.263146 -286.689546)
			(xy 380.260098 -286.691578) (xy 380.253494 -286.697674) (xy 380.245874 -286.708088) (xy 380.24308 -286.713422)
			(xy 380.240286 -286.724852) (xy 380.239778 -286.755332) (xy 380.239778 -286.77108) (xy 380.249176 -286.786066)
			(xy 380.257558 -286.795464) (xy 380.260352 -286.79775) (xy 380.261114 -286.798512) (xy 380.283215 -286.817302)
			(xy 380.322024 -286.860416) (xy 380.353861 -286.908907) (xy 380.377991 -286.961657) (xy 380.39386 -287.017453)
			(xy 380.39802 -287.046162) (xy 380.39802 -287.046416) (xy 380.398274 -287.048194) (xy 380.400892 -287.060016)
			(xy 380.415206 -287.079503) (xy 380.425706 -287.085532) (xy 380.429973 -287.087543) (xy 380.43905 -287.090106)
			(xy 380.44374 -287.090612) (xy 380.444248 -287.090612) (xy 380.448312 -287.090866) (xy 380.988062 -287.090866)
			(xy 380.991618 -287.090612) (xy 380.999851 -287.089705) (xy 381.01514 -287.083362) (xy 381.02159 -287.078166)
			(xy 381.028448 -287.07207) (xy 381.03683 -287.056068) (xy 381.0381 -287.046416) (xy 381.042005 -287.019095)
			(xy 381.056667 -286.96589) (xy 381.078843 -286.915352) (xy 381.108072 -286.868539) (xy 381.143741 -286.826426)
			(xy 381.185107 -286.789893) (xy 381.231306 -286.759704) (xy 381.281374 -286.736487) (xy 381.334265 -286.720728)
			(xy 381.388875 -286.712756) (xy 381.444064 -286.712737) (xy 381.498679 -286.720671) (xy 381.551581 -286.736394)
			(xy 381.601664 -286.759576) (xy 381.647884 -286.789735) (xy 381.689275 -286.826239) (xy 381.724974 -286.868327)
			(xy 381.754234 -286.91512) (xy 381.776445 -286.965642) (xy 381.791144 -287.018838) (xy 381.79502 -287.046162)
			(xy 381.79502 -287.046416) (xy 381.795274 -287.048194) (xy 381.797892 -287.060016) (xy 381.812206 -287.079503)
			(xy 381.822706 -287.085532) (xy 381.826973 -287.087543) (xy 381.83605 -287.090106) (xy 381.84074 -287.090612)
			(xy 381.841248 -287.090612) (xy 381.845312 -287.090866) (xy 381.874522 -287.090866) (xy 381.878078 -287.090612)
			(xy 381.886307 -287.089696) (xy 381.901585 -287.083339) (xy 381.90805 -287.078166) (xy 381.914908 -287.07207)
			(xy 381.92329 -287.056068) (xy 381.92456 -287.046416) (xy 381.928465 -287.019099) (xy 381.943125 -286.965902)
			(xy 381.9653 -286.915374) (xy 381.994524 -286.868568) (xy 382.030189 -286.826462) (xy 382.071549 -286.789936)
			(xy 382.117742 -286.759752) (xy 382.167802 -286.73654) (xy 382.220685 -286.720784) (xy 382.275287 -286.712814)
			(xy 382.330467 -286.712797) (xy 382.385073 -286.720731) (xy 382.437967 -286.736452) (xy 382.488042 -286.759632)
			(xy 382.534254 -286.789786) (xy 382.575638 -286.826286) (xy 382.61133 -286.868368) (xy 382.640585 -286.915155)
			(xy 382.662792 -286.965669) (xy 382.677487 -287.018857) (xy 382.68148 -287.046162) (xy 382.68148 -287.046416)
			(xy 382.681734 -287.048194) (xy 382.684355 -287.060012) (xy 382.698677 -287.079486) (xy 382.709166 -287.085532)
			(xy 382.713434 -287.087538) (xy 382.722513 -287.09009) (xy 382.7272 -287.090612) (xy 382.727708 -287.090612)
			(xy 382.731772 -287.090866) (xy 384.283966 -287.090866) (xy 384.292094 -287.090104) (xy 384.292602 -287.090104)
			(xy 384.300123 -287.088507) (xy 384.313817 -287.081537) (xy 384.319526 -287.076388) (xy 384.324352 -287.071562)
			(xy 384.375406 -287.004252) (xy 384.377438 -286.999934) (xy 384.378454 -286.997902) (xy 384.380921 -286.992578)
			(xy 384.383626 -286.981162) (xy 384.383788 -286.975296) (xy 384.383788 -286.967422) (xy 384.381756 -286.960564)
			(xy 384.376071 -286.939687) (xy 384.369952 -286.896854) (xy 384.369564 -286.87522) (xy 384.369564 -286.868108)
			(xy 384.370535 -286.844471) (xy 384.378872 -286.797905) (xy 384.394294 -286.753183) (xy 384.416432 -286.711376)
			(xy 384.444755 -286.673486) (xy 384.478585 -286.640419) (xy 384.517112 -286.612968) (xy 384.559413 -286.59179)
			(xy 384.604475 -286.577392) (xy 384.651219 -286.57012) (xy 384.674872 -286.569658) (xy 384.698866 -286.570126)
			(xy 384.746263 -286.577629) (xy 384.791903 -286.592453) (xy 384.834662 -286.614235) (xy 384.873487 -286.642437)
			(xy 384.907422 -286.676366) (xy 384.935633 -286.715185) (xy 384.957423 -286.75794) (xy 384.972257 -286.803577)
			(xy 384.979769 -286.850972) (xy 384.98018 -286.874966) (xy 384.979907 -286.895142) (xy 384.974684 -286.935153)
			(xy 384.969766 -286.954722) (xy 384.967988 -286.961072) (xy 384.964686 -286.972502) (xy 384.966718 -286.983932)
			(xy 384.96875 -286.996378) (xy 385.024376 -287.070546) (xy 385.031977 -287.079653) (xy 385.053169 -287.09025)
			(xy 385.065016 -287.090866) (xy 385.233926 -287.090866) (xy 385.242054 -287.090104) (xy 385.242562 -287.090104)
			(xy 385.250078 -287.088499) (xy 385.263761 -287.081518) (xy 385.269486 -287.076388) (xy 385.274312 -287.071562)
			(xy 385.325366 -287.004252) (xy 385.327398 -286.999934) (xy 385.328414 -286.997902) (xy 385.330879 -286.992577)
			(xy 385.33358 -286.981161) (xy 385.333748 -286.975296) (xy 385.333748 -286.967422) (xy 385.331716 -286.960564)
			(xy 385.326032 -286.939687) (xy 385.319913 -286.896854) (xy 385.319524 -286.87522) (xy 385.319524 -286.868108)
			(xy 385.320495 -286.844469) (xy 385.328832 -286.797901) (xy 385.344253 -286.753177) (xy 385.36639 -286.711367)
			(xy 385.394713 -286.673473) (xy 385.428542 -286.640403) (xy 385.467069 -286.612947) (xy 385.50937 -286.591764)
			(xy 385.554432 -286.577361) (xy 385.601178 -286.570083) (xy 385.624832 -286.569658) (xy 385.648823 -286.570131)
			(xy 385.696212 -286.577641) (xy 385.741844 -286.592471) (xy 385.784595 -286.614255) (xy 385.823412 -286.642459)
			(xy 385.85734 -286.676386) (xy 385.885544 -286.715203) (xy 385.907329 -286.757954) (xy 385.922159 -286.803586)
			(xy 385.929669 -286.850975) (xy 385.93014 -286.874966) (xy 385.929867 -286.895142) (xy 385.924643 -286.935152)
			(xy 385.919726 -286.954722) (xy 385.917948 -286.961072) (xy 385.914646 -286.972502) (xy 385.916678 -286.983932)
			(xy 385.91871 -286.996378) (xy 385.974336 -287.070546) (xy 385.981935 -287.07966) (xy 386.003126 -287.090273)
			(xy 386.014976 -287.090866) (xy 396.020544 -287.090866) (xy 396.029942 -287.08985) (xy 396.03045 -287.08985)
			(xy 396.037613 -287.088151) (xy 396.050649 -287.081329) (xy 396.056104 -287.076388) (xy 396.139924 -286.992568)
			(xy 396.145114 -286.986888) (xy 396.152086 -286.97318) (xy 396.15364 -286.965644) (xy 396.15364 -286.965136)
			(xy 396.154402 -286.957008) (xy 396.154402 -283.481272) (xy 396.154038 -283.472257) (xy 396.147784 -283.455347)
			(xy 396.14221 -283.448252) (xy 396.126462 -283.431742) (xy 396.089124 -283.392626) (xy 396.086136 -283.390021)
			(xy 396.079498 -283.385688) (xy 396.075916 -283.38399) (xy 396.068042 -283.380434) (xy 396.057882 -283.379672)
			(xy 396.033593 -283.37784) (xy 395.98601 -283.367436) (xy 395.940683 -283.349608) (xy 395.898762 -283.324809)
			(xy 395.861311 -283.293667) (xy 395.829281 -283.256973) (xy 395.803485 -283.215658) (xy 395.784577 -283.170771)
			(xy 395.773036 -283.123451) (xy 395.769157 -283.074898) (xy 395.773037 -283.026346) (xy 395.784578 -282.979026)
			(xy 395.803486 -282.934139) (xy 395.829283 -282.892825) (xy 395.861314 -282.856131) (xy 395.898765 -282.824989)
			(xy 395.940686 -282.80019) (xy 395.986013 -282.782363) (xy 396.033596 -282.77196) (xy 396.057882 -282.770072)
			(xy 396.068042 -282.76931) (xy 396.075916 -282.765754) (xy 396.079727 -282.763916) (xy 396.086747 -282.759193)
			(xy 396.089886 -282.756356) (xy 396.135098 -282.709112) (xy 396.141448 -282.702508) (xy 396.14623 -282.696753)
			(xy 396.152562 -282.683201) (xy 396.153894 -282.675838) (xy 396.154402 -282.668726) (xy 396.154402 -278.75611)
			(xy 396.15364 -278.746966) (xy 396.151354 -278.738838) (xy 396.148306 -278.730964) (xy 396.142464 -278.724106)
			(xy 396.140432 -278.721312) (xy 396.09014 -278.668988) (xy 396.083398 -278.663117) (xy 396.067025 -278.655973)
			(xy 396.058136 -278.655018) (xy 396.0495 -278.654764) (xy 396.048992 -278.654764) (xy 396.024356 -278.65242)
			(xy 395.976125 -278.641349) (xy 395.93008 -278.62322) (xy 395.887246 -278.598439) (xy 395.848579 -278.567558)
			(xy 395.814939 -278.531265) (xy 395.787078 -278.490368) (xy 395.765615 -278.445779) (xy 395.751029 -278.398492)
			(xy 395.743644 -278.349561) (xy 395.743176 -278.324818) (xy 395.743176 -277.374858) (xy 395.744954 -277.340568)
			(xy 395.745546 -277.329241) (xy 395.73804 -277.30787) (xy 395.730476 -277.29942) (xy 395.666214 -277.235158)
			(xy 395.644624 -277.227792) (xy 395.639544 -277.2283) (xy 395.629675 -277.229393) (xy 395.609849 -277.230536)
			(xy 395.59992 -277.230586) (xy 395.574381 -277.230121) (xy 395.523908 -277.222288) (xy 395.475239 -277.206789)
			(xy 395.42953 -277.183994) (xy 395.387869 -277.154443) (xy 395.351245 -277.11884) (xy 395.320529 -277.07803)
			(xy 395.296452 -277.032983) (xy 395.279585 -276.984771) (xy 395.270329 -276.93454) (xy 395.269212 -276.909022)
			(xy 395.268958 -276.898354) (xy 395.245844 -276.864572) (xy 395.241523 -276.858636) (xy 395.23017 -276.849335)
			(xy 395.223492 -276.846284) (xy 395.178226 -276.826565) (xy 395.09157 -276.779229) (xy 395.050518 -276.751796)
			(xy 395.046962 -276.74951) (xy 395.033246 -276.74316) (xy 395.029944 -276.74189) (xy 395.018446 -276.73835)
			(xy 394.995945 -276.729834) (xy 394.984986 -276.724872) (xy 394.959968 -276.712561) (xy 394.914108 -276.680854)
			(xy 394.874203 -276.641916) (xy 394.841379 -276.596848) (xy 394.816564 -276.546921) (xy 394.807948 -276.520402)
			(xy 394.806932 -276.516846) (xy 394.800328 -276.502876) (xy 394.798042 -276.49932) (xy 394.783564 -276.477476)
			(xy 394.772854 -276.460635) (xy 394.752654 -276.426207) (xy 394.743178 -276.408642) (xy 394.737844 -276.40153)
			(xy 394.72997 -276.394672) (xy 394.726922 -276.39264) (xy 394.726668 -276.39264) (xy 394.701268 -276.375876)
			(xy 394.692378 -276.370034) (xy 394.681964 -276.368256) (xy 394.676715 -276.367396) (xy 394.666083 -276.367651)
			(xy 394.660882 -276.368764) (xy 394.58773 -276.386798) (xy 394.582584 -276.388181) (xy 394.572981 -276.392796)
			(xy 394.56868 -276.395942) (xy 394.560298 -276.402546) (xy 394.555218 -276.411944) (xy 394.53237 -276.453115)
			(xy 394.479843 -276.531267) (xy 394.420001 -276.60397) (xy 394.353405 -276.670542) (xy 394.280679 -276.730357)
			(xy 394.202508 -276.782856) (xy 394.119623 -276.827544) (xy 394.076428 -276.846284) (xy 394.069752 -276.849341)
			(xy 394.058392 -276.858632) (xy 394.054076 -276.864572) (xy 394.030962 -276.898354) (xy 394.030708 -276.909022)
			(xy 394.02951 -276.934527) (xy 394.020236 -276.984734) (xy 394.003359 -277.032921) (xy 393.97928 -277.077943)
			(xy 393.94857 -277.118732) (xy 393.911958 -277.154318) (xy 393.870314 -277.183857) (xy 393.824626 -277.206648)
			(xy 393.775979 -277.222149) (xy 393.725528 -277.229993) (xy 393.674472 -277.229993) (xy 393.624021 -277.222149)
			(xy 393.575374 -277.206648) (xy 393.529686 -277.183857) (xy 393.488042 -277.154318) (xy 393.45143 -277.118732)
			(xy 393.42072 -277.077943) (xy 393.396641 -277.032921) (xy 393.379764 -276.984734) (xy 393.37049 -276.934527)
			(xy 393.369292 -276.909022) (xy 393.369038 -276.898354) (xy 393.346178 -276.864572) (xy 393.341853 -276.858641)
			(xy 393.330494 -276.849353) (xy 393.323826 -276.846284) (xy 393.298426 -276.835108) (xy 393.271756 -276.822408)
			(xy 393.238446 -276.805673) (xy 393.174238 -276.767787) (xy 393.143486 -276.746716) (xy 393.137898 -276.744176)
			(xy 393.113606 -276.737043) (xy 393.067371 -276.716417) (xy 393.024821 -276.688985) (xy 393.005564 -276.672548)
			(xy 392.988561 -276.657039) (xy 392.958584 -276.622119) (xy 392.933743 -276.583378) (xy 392.914519 -276.541564)
			(xy 392.90752 -276.51964) (xy 392.906504 -276.516084) (xy 392.8999 -276.502114) (xy 392.897614 -276.498558)
			(xy 392.89482 -276.494748) (xy 392.89482 -276.49424) (xy 392.881423 -276.474153) (xy 392.856391 -276.43286)
			(xy 392.844782 -276.41169) (xy 392.83894 -276.4028) (xy 392.836244 -276.399864) (xy 392.830121 -276.394763)
			(xy 392.826748 -276.39264) (xy 392.823192 -276.3901) (xy 392.822684 -276.3901) (xy 392.79249 -276.370395)
			(xy 392.734774 -276.327169) (xy 392.707368 -276.30374) (xy 392.682222 -276.281134) (xy 392.680952 -276.279864)
			(xy 392.66241 -276.268942) (xy 392.656314 -276.267164) (xy 392.633617 -276.260024) (xy 392.590392 -276.240139)
			(xy 392.570208 -276.22754) (xy 392.550382 -276.214214) (xy 392.514423 -276.182768) (xy 392.483364 -276.146475)
			(xy 392.45785 -276.106089) (xy 392.438414 -276.062453) (xy 392.431524 -276.03958) (xy 392.431016 -276.038056)
			(xy 392.41984 -276.019006) (xy 392.41603 -276.014688) (xy 392.387311 -275.982978) (xy 392.334937 -275.915324)
			(xy 392.288715 -275.843327) (xy 392.268456 -275.805646) (xy 392.267694 -275.805646) (xy 392.242737 -275.804653)
			(xy 392.193534 -275.796081) (xy 392.146179 -275.780206) (xy 392.101751 -275.757389) (xy 392.06126 -275.728149)
			(xy 392.025628 -275.693151) (xy 391.995665 -275.653192) (xy 391.972054 -275.609181) (xy 391.955331 -275.562119)
			(xy 391.945876 -275.513078) (xy 391.944352 -275.488146) (xy 391.944098 -275.479002) (xy 391.936224 -275.460714)
			(xy 391.9347 -275.45665) (xy 391.926064 -275.442426) (xy 391.92327 -275.439124) (xy 391.898708 -275.409619)
			(xy 391.853845 -275.347313) (xy 391.814109 -275.281619) (xy 391.779754 -275.212958) (xy 391.765028 -275.177504)
			(xy 391.761218 -275.167598) (xy 391.432542 -274.838922) (xy 391.428811 -274.835401) (xy 391.420236 -274.829775)
			(xy 391.415524 -274.827746) (xy 391.406888 -274.82419) (xy 391.385806 -274.82419) (xy 391.38098 -274.824952)
			(xy 391.367078 -274.827427) (xy 391.338965 -274.830098) (xy 391.324846 -274.830286) (xy 391.300851 -274.829843)
			(xy 391.253451 -274.822342) (xy 391.207809 -274.807517) (xy 391.165048 -274.785734) (xy 391.126222 -274.757529)
			(xy 391.092287 -274.723596) (xy 391.064078 -274.684772) (xy 391.042292 -274.642013) (xy 391.027464 -274.596372)
			(xy 391.019959 -274.548973) (xy 391.019538 -274.524978) (xy 391.019725 -274.509696) (xy 391.022781 -274.479286)
			(xy 391.025634 -274.464272) (xy 391.025634 -274.464018) (xy 391.027448 -274.451618) (xy 391.020271 -274.427637)
			(xy 391.011918 -274.418298) (xy 390.979914 -274.386294) (xy 390.973067 -274.378896) (xy 390.965333 -274.360298)
			(xy 390.964928 -274.350226) (xy 390.964928 -273.55546) (xy 390.964818 -273.551845) (xy 390.963672 -273.544703)
			(xy 390.962642 -273.541236) (xy 390.956546 -273.52371) (xy 390.955127 -273.519758) (xy 390.951164 -273.512358)
			(xy 390.948672 -273.508978) (xy 390.92112 -273.472869) (xy 390.872195 -273.396337) (xy 390.830725 -273.315522)
			(xy 390.797082 -273.231149) (xy 390.771567 -273.143972) (xy 390.754409 -273.054774) (xy 390.745761 -272.964353)
			(xy 390.745218 -272.918936) (xy 390.745218 -272.88871) (xy 390.745472 -272.88871) (xy 390.745472 -272.785586)
			(xy 390.744985 -272.775585) (xy 390.737341 -272.757102) (xy 390.723217 -272.742939) (xy 390.704755 -272.735243)
			(xy 390.684754 -272.735182) (xy 390.666245 -272.742764) (xy 390.658858 -272.749518) (xy 390.64946 -272.758916)
			(xy 390.645904 -272.765774) (xy 390.634499 -272.786687) (xy 390.606207 -272.825006) (xy 390.57231 -272.85847)
			(xy 390.533629 -272.886265) (xy 390.491102 -272.907719) (xy 390.44576 -272.922311) (xy 390.398702 -272.929688)
			(xy 390.374886 -272.930112) (xy 390.350895 -272.92964) (xy 390.303505 -272.922133) (xy 390.257873 -272.907304)
			(xy 390.215122 -272.88552) (xy 390.176305 -272.857316) (xy 390.142377 -272.823388) (xy 390.114175 -272.78457)
			(xy 390.092392 -272.741818) (xy 390.077565 -272.696185) (xy 390.070059 -272.648795) (xy 390.069578 -272.624804)
			(xy 390.069578 -272.624296) (xy 390.069697 -272.612692) (xy 390.071479 -272.589554) (xy 390.073134 -272.578068)
			(xy 390.073896 -272.574004) (xy 390.073642 -272.574004) (xy 390.078196 -272.549917) (xy 390.09396 -272.503503)
			(xy 390.116932 -272.460201) (xy 390.146523 -272.421123) (xy 390.181974 -272.387271) (xy 390.222376 -272.359513)
			(xy 390.266692 -272.338563) (xy 390.313783 -272.324958) (xy 390.338056 -272.321528) (xy 390.350502 -272.320258)
			(xy 390.3599 -272.314416) (xy 390.364472 -272.311368) (xy 390.367713 -272.308688) (xy 390.373332 -272.302432)
			(xy 390.375648 -272.298922) (xy 390.418066 -272.23339) (xy 390.422679 -272.225645) (xy 390.426703 -272.208083)
			(xy 390.42594 -272.1991) (xy 390.424924 -272.191734) (xy 390.423654 -272.18767) (xy 390.409857 -272.141397)
			(xy 390.390534 -272.046786) (xy 390.380827 -271.95071) (xy 390.38022 -271.902428) (xy 390.38022 -271.526508)
			(xy 390.379712 -271.520158) (xy 390.37768 -271.509998) (xy 390.375394 -271.50187) (xy 390.374632 -271.499838)
			(xy 390.374124 -271.498314) (xy 390.358522 -271.456061) (xy 390.334177 -271.369336) (xy 390.317825 -271.280755)
			(xy 390.3096 -271.191054) (xy 390.3091 -271.146016) (xy 390.3091 -265.749278) (xy 390.30878 -265.740998)
			(xy 390.303463 -265.725315) (xy 390.298686 -265.718544) (xy 390.295892 -265.715496) (xy 390.295384 -265.714988)
			(xy 390.29386 -265.712956) (xy 390.289542 -265.708638) (xy 390.282865 -265.701238) (xy 390.275278 -265.682828)
			(xy 390.275289 -265.662916) (xy 390.27862 -265.65352) (xy 390.286494 -265.63447) (xy 390.288526 -265.62939)
			(xy 390.289034 -265.628374) (xy 390.29132 -265.624056) (xy 390.296654 -265.61669) (xy 390.30275 -265.609578)
			(xy 390.305798 -265.60145) (xy 390.307339 -265.597102) (xy 390.308995 -265.588028) (xy 390.3091 -265.583416)
			(xy 390.3091 -264.933684) (xy 390.308846 -264.927588) (xy 390.29005 -264.77341) (xy 390.16305 -263.71423)
			(xy 390.159784 -263.684685) (xy 390.156352 -263.625336) (xy 390.156192 -263.595612) (xy 390.156192 -262.316468)
			(xy 390.156192 -262.31596) (xy 390.214358 -256.364994) (xy 390.221216 -255.665478) (xy 390.220962 -255.66116)
			(xy 390.133078 -254.702818) (xy 389.447278 -247.394984) (xy 388.99592 -242.585748) (xy 388.845552 -240.984532)
			(xy 388.843569 -240.969548) (xy 388.832027 -240.941629) (xy 388.812826 -240.918305) (xy 388.787645 -240.901615)
			(xy 388.758684 -240.893016) (xy 388.728475 -240.893262) (xy 388.699657 -240.902329) (xy 388.67475 -240.919426)
			(xy 388.664958 -240.930938) (xy 388.646749 -240.953043) (xy 388.604832 -240.992065) (xy 388.557555 -241.024386)
			(xy 388.505979 -241.04928) (xy 388.451263 -241.066188) (xy 388.394635 -241.07473) (xy 388.366 -241.07521)
			(xy 388.351915 -241.075097) (xy 388.32382 -241.07306) (xy 388.309866 -241.071146) (xy 388.3025 -241.070638)
			(xy 388.295134 -241.071146) (xy 388.281181 -241.073074) (xy 388.253085 -241.075109) (xy 388.239 -241.07521)
			(xy 388.211727 -241.074723) (xy 388.157737 -241.066961) (xy 388.105401 -241.051594) (xy 388.055784 -241.028934)
			(xy 388.009898 -240.999445) (xy 387.968675 -240.963725) (xy 387.932955 -240.922502) (xy 387.903466 -240.876616)
			(xy 387.880806 -240.826999) (xy 387.865439 -240.774663) (xy 387.857677 -240.720673) (xy 387.857677 -240.666127)
			(xy 387.865439 -240.612137) (xy 387.880806 -240.559801) (xy 387.903466 -240.510184) (xy 387.932955 -240.464298)
			(xy 387.968675 -240.423075) (xy 388.009898 -240.387355) (xy 388.055784 -240.357866) (xy 388.105401 -240.335206)
			(xy 388.157737 -240.319839) (xy 388.211727 -240.312077) (xy 388.239 -240.311686) (xy 388.253085 -240.311799)
			(xy 388.28118 -240.313836) (xy 388.295134 -240.31575) (xy 388.3025 -240.316258) (xy 388.309866 -240.31575)
			(xy 388.323819 -240.313822) (xy 388.351915 -240.311787) (xy 388.366 -240.311686) (xy 388.393193 -240.312166)
			(xy 388.447028 -240.319879) (xy 388.499226 -240.335149) (xy 388.54873 -240.357668) (xy 388.59454 -240.38698)
			(xy 388.615428 -240.404396) (xy 388.627227 -240.413903) (xy 388.654914 -240.426175) (xy 388.684982 -240.429788)
			(xy 388.714788 -240.424426) (xy 388.741711 -240.410558) (xy 388.763384 -240.389405) (xy 388.777901 -240.362827)
			(xy 388.783986 -240.33316) (xy 388.783068 -240.318036) (xy 388.603998 -238.411004) (xy 388.593076 -238.294672)
			(xy 388.592568 -238.291878) (xy 388.419086 -237.375954) (xy 388.384288 -237.193074) (xy 388.381694 -237.184382)
			(xy 388.371415 -237.169451) (xy 388.356615 -237.158982) (xy 388.347966 -237.156244) (xy 388.341362 -237.154466)
			(xy 388.261352 -237.132114) (xy 388.252334 -237.129952) (xy 388.233874 -237.131539) (xy 388.2172 -237.139618)
			(xy 388.210552 -237.146084) (xy 388.209028 -237.147862) (xy 388.208266 -237.148878) (xy 388.205218 -237.152688)
			(xy 388.187085 -237.171499) (xy 388.146569 -237.204489) (xy 388.101934 -237.231648) (xy 388.054015 -237.252472)
			(xy 388.003705 -237.26657) (xy 387.951942 -237.27368) (xy 387.925818 -237.2741) (xy 387.91642 -237.273846)
			(xy 387.915912 -237.273846) (xy 387.907022 -237.273592) (xy 387.900418 -237.273084) (xy 387.900164 -237.273084)
			(xy 387.871559 -237.270645) (xy 387.815504 -237.258262) (xy 387.761936 -237.237618) (xy 387.712068 -237.20918)
			(xy 387.667024 -237.17359) (xy 387.627822 -237.131652) (xy 387.595347 -237.084312) (xy 387.570333 -237.032641)
			(xy 387.553345 -236.977805) (xy 387.544767 -236.921042) (xy 387.54431 -236.892338) (xy 387.544771 -236.865084)
			(xy 387.552523 -236.81113) (xy 387.567876 -236.758828) (xy 387.590517 -236.709245) (xy 387.619984 -236.663388)
			(xy 387.655678 -236.622192) (xy 387.696872 -236.586496) (xy 387.742727 -236.557027) (xy 387.79231 -236.534383)
			(xy 387.84461 -236.519028) (xy 387.898564 -236.511272) (xy 387.925818 -236.51083) (xy 387.92658 -236.51083)
			(xy 387.955243 -236.511339) (xy 388.011925 -236.519913) (xy 388.066682 -236.536884) (xy 388.092696 -236.54893)
			(xy 388.097522 -236.551216) (xy 388.109206 -236.55401) (xy 388.121398 -236.555534) (xy 388.121652 -236.555534)
			(xy 388.129869 -236.555186) (xy 388.145425 -236.54988) (xy 388.152132 -236.54512) (xy 388.152386 -236.54512)
			(xy 388.222744 -236.49178) (xy 388.229842 -236.485932) (xy 388.239663 -236.470398) (xy 388.243377 -236.452399)
			(xy 388.242302 -236.443266) (xy 387.890004 -234.582208) (xy 387.720586 -233.68762) (xy 387.302248 -231.479852)
			(xy 387.300742 -231.473402) (xy 387.294824 -231.461556) (xy 387.290564 -231.456484) (xy 387.28142 -231.44734)
			(xy 387.28142 -231.446832) (xy 387.269482 -231.43464) (xy 387.260084 -231.427528) (xy 387.255004 -231.42448)
			(xy 387.248146 -231.422448) (xy 387.219666 -231.414129) (xy 387.165283 -231.390408) (xy 387.114895 -231.359083)
			(xy 387.069558 -231.320811) (xy 387.030222 -231.276393) (xy 386.997712 -231.226762) (xy 386.972708 -231.172956)
			(xy 386.955736 -231.116104) (xy 386.94715 -231.057397) (xy 386.946648 -231.027732) (xy 386.947117 -230.999554)
			(xy 386.954849 -230.94373) (xy 386.970171 -230.889497) (xy 386.992794 -230.83788) (xy 387.022288 -230.789858)
			(xy 387.058096 -230.746339) (xy 387.099538 -230.708148) (xy 387.122416 -230.69169) (xy 387.124702 -230.690166)
			(xy 387.129813 -230.685957) (xy 387.137805 -230.675407) (xy 387.14045 -230.669338) (xy 387.143498 -230.66248)
			(xy 387.14426 -230.655114) (xy 387.143498 -230.641144) (xy 386.886196 -229.282498) (xy 386.882885 -229.271569)
			(xy 386.868451 -229.253914) (xy 386.847818 -229.244203) (xy 386.836412 -229.243636) (xy 386.833618 -229.243636)
			(xy 386.811774 -229.244398) (xy 386.81152 -229.244398) (xy 386.784263 -229.243893) (xy 386.730308 -229.236099)
			(xy 386.67801 -229.220709) (xy 386.628432 -229.198038) (xy 386.582584 -229.168545) (xy 386.541397 -229.13283)
			(xy 386.505709 -229.09162) (xy 386.476245 -229.045753) (xy 386.453605 -228.996162) (xy 386.438249 -228.943854)
			(xy 386.43049 -228.889894) (xy 386.430012 -228.862636) (xy 386.430457 -228.836229) (xy 386.437736 -228.783918)
			(xy 386.452159 -228.733111) (xy 386.473451 -228.684778) (xy 386.501205 -228.639843) (xy 386.534891 -228.599166)
			(xy 386.573865 -228.563522) (xy 386.595366 -228.548184) (xy 386.606456 -228.540054) (xy 386.624181 -228.519046)
			(xy 386.635651 -228.494066) (xy 386.64003 -228.466931) (xy 386.637003 -228.439611) (xy 386.626787 -228.414093)
			(xy 386.610127 -228.392231) (xy 386.59943 -228.383592) (xy 386.5764 -228.365428) (xy 386.535667 -228.323228)
			(xy 386.501869 -228.275293) (xy 386.4758 -228.222753) (xy 386.458075 -228.166843) (xy 386.44911 -228.10888)
			(xy 386.448554 -228.079554) (xy 386.449029 -228.052456) (xy 386.456688 -227.998805) (xy 386.471847 -227.946773)
			(xy 386.494201 -227.897403) (xy 386.523302 -227.851684) (xy 386.558568 -227.810532) (xy 386.578602 -227.79228)
			(xy 386.583428 -227.787454) (xy 386.586745 -227.78357) (xy 386.591873 -227.774739) (xy 386.593588 -227.769928)
			(xy 386.59562 -227.76434) (xy 386.596382 -227.751894) (xy 386.50418 -227.264214) (xy 385.820666 -223.65589)
			(xy 385.817463 -223.645077) (xy 385.803377 -223.6275) (xy 385.783149 -223.617593) (xy 385.771898 -223.616774)
			(xy 385.764024 -223.617028) (xy 385.749013 -223.619282) (xy 385.718751 -223.621698) (xy 385.703572 -223.621854)
			(xy 385.703318 -223.621854) (xy 385.676046 -223.621392) (xy 385.622058 -223.613632) (xy 385.569724 -223.598267)
			(xy 385.520109 -223.57561) (xy 385.474223 -223.546123) (xy 385.433002 -223.510405) (xy 385.397283 -223.469185)
			(xy 385.367795 -223.4233) (xy 385.345137 -223.373686) (xy 385.32977 -223.321352) (xy 385.322009 -223.267364)
			(xy 385.321556 -223.240092) (xy 385.322006 -223.213658) (xy 385.3293 -223.161296) (xy 385.343748 -223.110441)
			(xy 385.365074 -223.062065) (xy 385.392869 -223.017094) (xy 385.426603 -222.976387) (xy 385.46563 -222.940723)
			(xy 385.487164 -222.925386) (xy 385.499531 -222.916189) (xy 385.51851 -222.891926) (xy 385.529412 -222.863115)
			(xy 385.53125 -222.832366) (xy 385.523859 -222.802462) (xy 385.516374 -222.788988) (xy 385.503114 -222.766434)
			(xy 385.482215 -222.718468) (xy 385.468065 -222.668098) (xy 385.46093 -222.616266) (xy 385.460494 -222.590106)
			(xy 385.460494 -222.589852) (xy 385.461045 -222.561329) (xy 385.469581 -222.504923) (xy 385.486425 -222.450419)
			(xy 385.49834 -222.424498) (xy 385.498594 -222.423736) (xy 385.499102 -222.42272) (xy 385.499356 -222.422212)
			(xy 385.506214 -222.406972) (xy 385.514135 -222.395563) (xy 385.524123 -222.369659) (xy 385.526767 -222.342023)
			(xy 385.521873 -222.314695) (xy 385.509802 -222.289694) (xy 385.491444 -222.268867) (xy 385.480052 -222.260922)
			(xy 385.457417 -222.245775) (xy 385.416281 -222.210083) (xy 385.38064 -222.168903) (xy 385.351219 -222.123072)
			(xy 385.328617 -222.073522) (xy 385.313292 -222.021261) (xy 385.305557 -221.967351) (xy 385.305046 -221.94012)
			(xy 385.305465 -221.914691) (xy 385.312219 -221.864283) (xy 385.325609 -221.815219) (xy 385.345399 -221.768369)
			(xy 385.371237 -221.724564) (xy 385.402666 -221.684579) (xy 385.420616 -221.666562) (xy 385.421378 -221.6658)
			(xy 385.425553 -221.661451) (xy 385.43186 -221.651179) (xy 385.433824 -221.64548) (xy 385.435583 -221.639352)
			(xy 385.436358 -221.626629) (xy 385.435348 -221.620334) (xy 385.313936 -220.979238) (xy 384.595116 -217.18397)
			(xy 383.879852 -213.406736) (xy 383.725928 -212.59419) (xy 383.636266 -212.12048) (xy 383.634489 -212.113881)
			(xy 383.627923 -212.101902) (xy 383.623312 -212.096858) (xy 383.617978 -212.09127) (xy 383.60477 -212.084158)
			(xy 383.59715 -212.082634) (xy 383.571266 -212.076845) (xy 383.521295 -212.05907) (xy 383.474264 -212.034552)
			(xy 383.431079 -212.00376) (xy 383.39257 -211.967289) (xy 383.359479 -211.925839) (xy 383.332443 -211.880208)
			(xy 383.311982 -211.831276) (xy 383.298489 -211.779982) (xy 383.29489 -211.753704) (xy 383.293366 -211.73948)
			(xy 383.292096 -211.709) (xy 383.292569 -211.681954) (xy 383.300218 -211.628406) (xy 383.315361 -211.576477)
			(xy 383.337694 -211.527212) (xy 383.366769 -211.481599) (xy 383.402001 -211.440555) (xy 383.442683 -211.404906)
			(xy 383.46507 -211.389722) (xy 383.473452 -211.384134) (xy 383.479548 -211.375498) (xy 383.484014 -211.368697)
			(xy 383.488795 -211.353154) (xy 383.488946 -211.345018) (xy 383.48793 -211.336636) (xy 383.359152 -210.656932)
			(xy 383.318766 -210.444588) (xy 383.315793 -210.43454) (xy 383.303155 -210.417854) (xy 383.284927 -210.407561)
			(xy 383.27457 -210.40598) (xy 383.26949 -210.405726) (xy 380.854966 -210.405726) (xy 380.851361 -210.405791)
			(xy 380.844222 -210.406814) (xy 380.840742 -210.407758) (xy 380.83617 -210.409282) (xy 380.827026 -210.413092)
			(xy 380.451868 -210.78825) (xy 380.449582 -210.791552) (xy 380.4428 -210.800622) (xy 380.428313 -210.818033)
			(xy 380.420626 -210.82635) (xy 380.41961 -210.827366) (xy 380.41707 -210.829906) (xy 380.4158 -210.83143)
			(xy 380.415546 -210.831684) (xy 380.415038 -210.832192) (xy 380.3904 -210.85556) (xy 380.390146 -210.855814)
			(xy 380.367286 -210.873848) (xy 380.363984 -210.876134) (xy 379.606302 -211.633816) (xy 379.60278 -211.637546)
			(xy 379.597149 -211.646119) (xy 379.595126 -211.650834) (xy 379.59157 -211.65947) (xy 379.59157 -211.683346)
			(xy 379.59411 -211.690966) (xy 379.60293 -211.719567) (xy 379.612502 -211.778645) (xy 379.61316 -211.808568)
			(xy 379.61316 -211.811616) (xy 379.612571 -211.838795) (xy 379.604639 -211.892576) (xy 379.589153 -211.944686)
			(xy 379.566425 -211.99407) (xy 379.536917 -212.039727) (xy 379.501225 -212.080733) (xy 379.460074 -212.116255)
			(xy 379.414296 -212.145576) (xy 379.36482 -212.168101) (xy 379.312646 -212.183374) (xy 379.258833 -212.191085)
			(xy 379.231652 -212.1916) (xy 379.231144 -212.1916) (xy 379.200439 -212.190984) (xy 379.139821 -212.181159)
			(xy 379.110494 -212.172042) (xy 379.109224 -212.171534) (xy 379.098302 -212.168232) (xy 379.092206 -212.166454)
			(xy 379.078998 -212.170264) (xy 379.073726 -212.171851) (xy 379.063983 -212.176973) (xy 379.059694 -212.180424)
			(xy 379.054868 -212.184996) (xy 379.05436 -212.185504) (xy 379.05055 -212.189822) (xy 379.04801 -212.193886)
			(xy 379.045724 -212.19795) (xy 379.033532 -212.233002) (xy 379.033532 -212.23351) (xy 379.03023 -212.242146)
			(xy 379.030992 -212.262212) (xy 379.03531 -212.271356) (xy 379.039312 -212.279224) (xy 379.051662 -212.291817)
			(xy 379.05944 -212.295994) (xy 379.075188 -212.30209) (xy 379.081284 -212.301328) (xy 379.09242 -212.300118)
			(xy 379.114787 -212.298844) (xy 379.125988 -212.298788) (xy 379.12675 -212.298788) (xy 379.154005 -212.299248)
			(xy 379.207962 -212.306999) (xy 379.260266 -212.322351) (xy 379.309853 -212.34499) (xy 379.355712 -212.374457)
			(xy 379.396911 -212.410151) (xy 379.432611 -212.451344) (xy 379.462084 -212.4972) (xy 379.48473 -212.546783)
			(xy 379.500089 -212.599085) (xy 379.507848 -212.653041) (xy 379.508258 -212.680296) (xy 379.507754 -212.708032)
			(xy 379.49971 -212.762916) (xy 379.483805 -212.816059) (xy 379.460374 -212.866339) (xy 379.429912 -212.912697)
			(xy 379.393059 -212.954157) (xy 379.350592 -212.989845) (xy 379.303407 -213.01901) (xy 379.252496 -213.041036)
			(xy 379.198933 -213.055461) (xy 379.171454 -213.059264) (xy 379.156214 -213.061042) (xy 379.12675 -213.062058)
			(xy 379.09963 -213.061589) (xy 379.045934 -213.053937) (xy 378.993856 -213.038779) (xy 378.94444 -213.01642)
			(xy 378.898676 -212.987307) (xy 378.857482 -212.952023) (xy 378.821684 -212.911276) (xy 378.806456 -212.88883)
			(xy 378.804678 -212.886036) (xy 378.80417 -212.88502) (xy 378.803154 -212.88375) (xy 378.799344 -212.87994)
			(xy 378.790708 -212.873336) (xy 378.775976 -212.864192) (xy 378.772928 -212.86216) (xy 378.76988 -212.860128)
			(xy 378.763276 -212.857588) (xy 378.752354 -212.855048) (xy 378.704094 -212.84946) (xy 378.69495 -212.848444)
			(xy 378.68479 -212.847174) (xy 378.672598 -212.847174) (xy 378.664216 -212.849206) (xy 378.65685 -212.851746)
			(xy 378.64669 -212.858096) (xy 378.64288 -212.86216) (xy 378.621233 -212.88327) (xy 378.572505 -212.919065)
			(xy 378.518742 -212.946728) (xy 378.461289 -212.965567) (xy 378.401585 -212.97511) (xy 378.371354 -212.975698)
			(xy 378.361956 -212.975698) (xy 378.35106 -212.975351) (xy 378.32933 -212.973569) (xy 378.318522 -212.972142)
			(xy 378.304044 -212.969856) (xy 378.301758 -212.969348) (xy 378.292614 -212.968586) (xy 378.282653 -212.969076)
			(xy 378.264233 -212.976667) (xy 378.2568 -212.983318) (xy 377.264168 -213.97595) (xy 378.439932 -213.97595)
			(xy 378.444003 -213.920328) (xy 378.456129 -213.865891) (xy 378.476052 -213.8138) (xy 378.503348 -213.765165)
			(xy 378.537434 -213.721022) (xy 378.577583 -213.682313) (xy 378.622941 -213.649862) (xy 378.672541 -213.624361)
			(xy 378.725325 -213.606354) (xy 378.780168 -213.596224) (xy 378.835902 -213.594187) (xy 378.891339 -213.600287)
			(xy 378.945296 -213.614393) (xy 378.996625 -213.636205) (xy 379.044231 -213.665259) (xy 379.087099 -213.700934)
			(xy 379.124316 -213.742471) (xy 379.155089 -213.788984) (xy 379.178761 -213.839481) (xy 379.194829 -213.892888)
			(xy 379.202949 -213.948064) (xy 379.203458 -213.97595) (xy 379.202949 -214.003836) (xy 379.194829 -214.059012)
			(xy 379.178761 -214.112419) (xy 379.155089 -214.162916) (xy 379.124316 -214.209429) (xy 379.087099 -214.250966)
			(xy 379.044231 -214.286641) (xy 378.996625 -214.315695) (xy 378.945296 -214.337507) (xy 378.891339 -214.351613)
			(xy 378.835902 -214.357713) (xy 378.780168 -214.355676) (xy 378.725325 -214.345546) (xy 378.672541 -214.327539)
			(xy 378.622941 -214.302038) (xy 378.577583 -214.269587) (xy 378.537434 -214.230878) (xy 378.503348 -214.186735)
			(xy 378.476052 -214.1381) (xy 378.456129 -214.086009) (xy 378.444003 -214.031572) (xy 378.439932 -213.97595)
			(xy 377.264168 -213.97595) (xy 374.19407 -217.046048) (xy 374.186672 -217.052895) (xy 374.168074 -217.060627)
			(xy 374.158002 -217.061034) (xy 374.043702 -217.061034) (xy 374.03542 -217.06135) (xy 374.019729 -217.066655)
			(xy 374.012968 -217.071448) (xy 374.00992 -217.074242) (xy 374.009412 -217.07475) (xy 374.00738 -217.076274)
			(xy 372.564406 -218.519248) (xy 372.557566 -218.526649) (xy 372.549848 -218.545247) (xy 372.54942 -218.555316)
			(xy 372.54942 -218.783916) (xy 373.884188 -218.783916) (xy 373.888259 -218.728294) (xy 373.900385 -218.673857)
			(xy 373.920308 -218.621766) (xy 373.947604 -218.573131) (xy 373.98169 -218.528988) (xy 374.021839 -218.490279)
			(xy 374.067197 -218.457828) (xy 374.116797 -218.432327) (xy 374.169581 -218.41432) (xy 374.224424 -218.40419)
			(xy 374.280158 -218.402153) (xy 374.289401 -218.40317) (xy 380.707644 -218.40317) (xy 380.711715 -218.347548)
			(xy 380.723841 -218.293111) (xy 380.743764 -218.24102) (xy 380.77106 -218.192385) (xy 380.805146 -218.148242)
			(xy 380.845295 -218.109533) (xy 380.890653 -218.077082) (xy 380.940253 -218.051581) (xy 380.993037 -218.033574)
			(xy 381.04788 -218.023444) (xy 381.103614 -218.021407) (xy 381.159051 -218.027507) (xy 381.213008 -218.041613)
			(xy 381.264337 -218.063425) (xy 381.311943 -218.092479) (xy 381.354811 -218.128154) (xy 381.392028 -218.169691)
			(xy 381.422801 -218.216204) (xy 381.446473 -218.266701) (xy 381.462541 -218.320108) (xy 381.469382 -218.366594)
			(xy 381.872234 -218.366594) (xy 381.876305 -218.310972) (xy 381.888431 -218.256535) (xy 381.908354 -218.204444)
			(xy 381.93565 -218.155809) (xy 381.969736 -218.111666) (xy 382.009885 -218.072957) (xy 382.055243 -218.040506)
			(xy 382.104843 -218.015005) (xy 382.157627 -217.996998) (xy 382.21247 -217.986868) (xy 382.268204 -217.984831)
			(xy 382.323641 -217.990931) (xy 382.377598 -218.005037) (xy 382.428927 -218.026849) (xy 382.476533 -218.055903)
			(xy 382.519401 -218.091578) (xy 382.556618 -218.133115) (xy 382.587391 -218.179628) (xy 382.611063 -218.230125)
			(xy 382.627131 -218.283532) (xy 382.635251 -218.338708) (xy 382.63576 -218.366594) (xy 382.635251 -218.39448)
			(xy 382.627131 -218.449656) (xy 382.611063 -218.503063) (xy 382.587391 -218.55356) (xy 382.556618 -218.600073)
			(xy 382.519401 -218.64161) (xy 382.476533 -218.677285) (xy 382.428927 -218.706339) (xy 382.377598 -218.728151)
			(xy 382.323641 -218.742257) (xy 382.268204 -218.748357) (xy 382.21247 -218.74632) (xy 382.157627 -218.73619)
			(xy 382.104843 -218.718183) (xy 382.055243 -218.692682) (xy 382.009885 -218.660231) (xy 381.969736 -218.621522)
			(xy 381.93565 -218.577379) (xy 381.908354 -218.528744) (xy 381.888431 -218.476653) (xy 381.876305 -218.422216)
			(xy 381.872234 -218.366594) (xy 381.469382 -218.366594) (xy 381.470661 -218.375284) (xy 381.47117 -218.40317)
			(xy 381.470661 -218.431056) (xy 381.462541 -218.486232) (xy 381.446473 -218.539639) (xy 381.422801 -218.590136)
			(xy 381.392028 -218.636649) (xy 381.354811 -218.678186) (xy 381.311943 -218.713861) (xy 381.264337 -218.742915)
			(xy 381.213008 -218.764727) (xy 381.159051 -218.778833) (xy 381.103614 -218.784933) (xy 381.04788 -218.782896)
			(xy 380.993037 -218.772766) (xy 380.940253 -218.754759) (xy 380.890653 -218.729258) (xy 380.845295 -218.696807)
			(xy 380.805146 -218.658098) (xy 380.77106 -218.613955) (xy 380.743764 -218.56532) (xy 380.723841 -218.513229)
			(xy 380.711715 -218.458792) (xy 380.707644 -218.40317) (xy 374.289401 -218.40317) (xy 374.335595 -218.408253)
			(xy 374.389552 -218.422359) (xy 374.440881 -218.444171) (xy 374.488487 -218.473225) (xy 374.531355 -218.5089)
			(xy 374.568572 -218.550437) (xy 374.599345 -218.59695) (xy 374.623017 -218.647447) (xy 374.639085 -218.700854)
			(xy 374.647205 -218.75603) (xy 374.647714 -218.783916) (xy 374.647205 -218.811802) (xy 374.639085 -218.866978)
			(xy 374.623017 -218.920385) (xy 374.599345 -218.970882) (xy 374.568572 -219.017395) (xy 374.531355 -219.058932)
			(xy 374.488487 -219.094607) (xy 374.440881 -219.123661) (xy 374.389552 -219.145473) (xy 374.335595 -219.159579)
			(xy 374.280158 -219.165679) (xy 374.224424 -219.163642) (xy 374.169581 -219.153512) (xy 374.116797 -219.135505)
			(xy 374.067197 -219.110004) (xy 374.021839 -219.077553) (xy 373.98169 -219.038844) (xy 373.947604 -218.994701)
			(xy 373.920308 -218.946066) (xy 373.900385 -218.893975) (xy 373.888259 -218.839538) (xy 373.884188 -218.783916)
			(xy 372.54942 -218.783916) (xy 372.54942 -220.524324) (xy 374.238264 -220.524324) (xy 374.242335 -220.468702)
			(xy 374.254461 -220.414265) (xy 374.274384 -220.362174) (xy 374.30168 -220.313539) (xy 374.335766 -220.269396)
			(xy 374.375915 -220.230687) (xy 374.421273 -220.198236) (xy 374.470873 -220.172735) (xy 374.523657 -220.154728)
			(xy 374.5785 -220.144598) (xy 374.634234 -220.142561) (xy 374.689671 -220.148661) (xy 374.743628 -220.162767)
			(xy 374.794957 -220.184579) (xy 374.842563 -220.213633) (xy 374.885431 -220.249308) (xy 374.922648 -220.290845)
			(xy 374.944697 -220.324172) (xy 383.84683 -220.324172) (xy 383.850901 -220.26855) (xy 383.863027 -220.214113)
			(xy 383.88295 -220.162022) (xy 383.910246 -220.113387) (xy 383.944332 -220.069244) (xy 383.984481 -220.030535)
			(xy 384.029839 -219.998084) (xy 384.079439 -219.972583) (xy 384.132223 -219.954576) (xy 384.187066 -219.944446)
			(xy 384.2428 -219.942409) (xy 384.298237 -219.948509) (xy 384.352194 -219.962615) (xy 384.403523 -219.984427)
			(xy 384.451129 -220.013481) (xy 384.493997 -220.049156) (xy 384.531214 -220.090693) (xy 384.561987 -220.137206)
			(xy 384.585659 -220.187703) (xy 384.601727 -220.24111) (xy 384.609847 -220.296286) (xy 384.610356 -220.324172)
			(xy 384.609847 -220.352058) (xy 384.601727 -220.407234) (xy 384.585659 -220.460641) (xy 384.561987 -220.511138)
			(xy 384.531214 -220.557651) (xy 384.493997 -220.599188) (xy 384.451129 -220.634863) (xy 384.403523 -220.663917)
			(xy 384.352194 -220.685729) (xy 384.298237 -220.699835) (xy 384.2428 -220.705935) (xy 384.187066 -220.703898)
			(xy 384.132223 -220.693768) (xy 384.079439 -220.675761) (xy 384.029839 -220.65026) (xy 383.984481 -220.617809)
			(xy 383.944332 -220.5791) (xy 383.910246 -220.534957) (xy 383.88295 -220.486322) (xy 383.863027 -220.434231)
			(xy 383.850901 -220.379794) (xy 383.84683 -220.324172) (xy 374.944697 -220.324172) (xy 374.953421 -220.337358)
			(xy 374.977093 -220.387855) (xy 374.993161 -220.441262) (xy 375.001281 -220.496438) (xy 375.00179 -220.524324)
			(xy 375.001281 -220.55221) (xy 374.993161 -220.607386) (xy 374.977093 -220.660793) (xy 374.953421 -220.71129)
			(xy 374.922648 -220.757803) (xy 374.885431 -220.79934) (xy 374.842563 -220.835015) (xy 374.794957 -220.864069)
			(xy 374.743628 -220.885881) (xy 374.689671 -220.899987) (xy 374.634234 -220.906087) (xy 374.5785 -220.90405)
			(xy 374.523657 -220.89392) (xy 374.470873 -220.875913) (xy 374.421273 -220.850412) (xy 374.375915 -220.817961)
			(xy 374.335766 -220.779252) (xy 374.30168 -220.735109) (xy 374.274384 -220.686474) (xy 374.254461 -220.634383)
			(xy 374.242335 -220.579946) (xy 374.238264 -220.524324) (xy 372.54942 -220.524324) (xy 372.54942 -222.063818)
			(xy 373.879364 -222.063818) (xy 373.87985 -222.036567) (xy 373.887606 -221.982619) (xy 373.902961 -221.930324)
			(xy 373.925603 -221.880747) (xy 373.955069 -221.834897) (xy 373.99076 -221.793706) (xy 374.031951 -221.758015)
			(xy 374.077801 -221.728549) (xy 374.127378 -221.705907) (xy 374.179673 -221.690552) (xy 374.233621 -221.682796)
			(xy 374.288123 -221.682796) (xy 374.342071 -221.690552) (xy 374.394366 -221.705907) (xy 374.440026 -221.72676)
			(xy 376.14428 -221.72676) (xy 376.148351 -221.671138) (xy 376.160477 -221.616701) (xy 376.1804 -221.56461)
			(xy 376.207696 -221.515975) (xy 376.241782 -221.471832) (xy 376.281931 -221.433123) (xy 376.327289 -221.400672)
			(xy 376.376889 -221.375171) (xy 376.429673 -221.357164) (xy 376.484516 -221.347034) (xy 376.54025 -221.344997)
			(xy 376.595687 -221.351097) (xy 376.649644 -221.365203) (xy 376.700973 -221.387015) (xy 376.748579 -221.416069)
			(xy 376.791447 -221.451744) (xy 376.828664 -221.493281) (xy 376.859437 -221.539794) (xy 376.883109 -221.590291)
			(xy 376.899177 -221.643698) (xy 376.907297 -221.698874) (xy 376.907338 -221.701106) (xy 377.605034 -221.701106)
			(xy 377.609105 -221.645484) (xy 377.621231 -221.591047) (xy 377.641154 -221.538956) (xy 377.66845 -221.490321)
			(xy 377.702536 -221.446178) (xy 377.742685 -221.407469) (xy 377.788043 -221.375018) (xy 377.837643 -221.349517)
			(xy 377.890427 -221.33151) (xy 377.94527 -221.32138) (xy 378.001004 -221.319343) (xy 378.056441 -221.325443)
			(xy 378.110398 -221.339549) (xy 378.161727 -221.361361) (xy 378.209333 -221.390415) (xy 378.252201 -221.42609)
			(xy 378.289418 -221.467627) (xy 378.320191 -221.51414) (xy 378.343863 -221.564637) (xy 378.359931 -221.618044)
			(xy 378.368051 -221.67322) (xy 378.36856 -221.701106) (xy 378.368051 -221.728992) (xy 378.359931 -221.784168)
			(xy 378.343863 -221.837575) (xy 378.320191 -221.888072) (xy 378.289418 -221.934585) (xy 378.271031 -221.955106)
			(xy 380.780034 -221.955106) (xy 380.784105 -221.899484) (xy 380.796231 -221.845047) (xy 380.816154 -221.792956)
			(xy 380.84345 -221.744321) (xy 380.877536 -221.700178) (xy 380.917685 -221.661469) (xy 380.963043 -221.629018)
			(xy 381.012643 -221.603517) (xy 381.065427 -221.58551) (xy 381.12027 -221.57538) (xy 381.176004 -221.573343)
			(xy 381.231441 -221.579443) (xy 381.285398 -221.593549) (xy 381.336727 -221.615361) (xy 381.384333 -221.644415)
			(xy 381.427201 -221.68009) (xy 381.464418 -221.721627) (xy 381.495191 -221.76814) (xy 381.518863 -221.818637)
			(xy 381.534931 -221.872044) (xy 381.543051 -221.92722) (xy 381.54356 -221.955106) (xy 381.543051 -221.982992)
			(xy 381.534931 -222.038168) (xy 381.518863 -222.091575) (xy 381.495191 -222.142072) (xy 381.464418 -222.188585)
			(xy 381.427201 -222.230122) (xy 381.384333 -222.265797) (xy 381.336727 -222.294851) (xy 381.285398 -222.316663)
			(xy 381.231441 -222.330769) (xy 381.176004 -222.336869) (xy 381.12027 -222.334832) (xy 381.065427 -222.324702)
			(xy 381.012643 -222.306695) (xy 380.963043 -222.281194) (xy 380.917685 -222.248743) (xy 380.877536 -222.210034)
			(xy 380.84345 -222.165891) (xy 380.816154 -222.117256) (xy 380.796231 -222.065165) (xy 380.784105 -222.010728)
			(xy 380.780034 -221.955106) (xy 378.271031 -221.955106) (xy 378.252201 -221.976122) (xy 378.209333 -222.011797)
			(xy 378.161727 -222.040851) (xy 378.110398 -222.062663) (xy 378.056441 -222.076769) (xy 378.001004 -222.082869)
			(xy 377.94527 -222.080832) (xy 377.890427 -222.070702) (xy 377.837643 -222.052695) (xy 377.788043 -222.027194)
			(xy 377.742685 -221.994743) (xy 377.702536 -221.956034) (xy 377.66845 -221.911891) (xy 377.641154 -221.863256)
			(xy 377.621231 -221.811165) (xy 377.609105 -221.756728) (xy 377.605034 -221.701106) (xy 376.907338 -221.701106)
			(xy 376.907806 -221.72676) (xy 376.907297 -221.754646) (xy 376.899177 -221.809822) (xy 376.883109 -221.863229)
			(xy 376.859437 -221.913726) (xy 376.828664 -221.960239) (xy 376.791447 -222.001776) (xy 376.748579 -222.037451)
			(xy 376.700973 -222.066505) (xy 376.649644 -222.088317) (xy 376.595687 -222.102423) (xy 376.54025 -222.108523)
			(xy 376.484516 -222.106486) (xy 376.429673 -222.096356) (xy 376.376889 -222.078349) (xy 376.327289 -222.052848)
			(xy 376.281931 -222.020397) (xy 376.241782 -221.981688) (xy 376.207696 -221.937545) (xy 376.1804 -221.88891)
			(xy 376.160477 -221.836819) (xy 376.148351 -221.782382) (xy 376.14428 -221.72676) (xy 374.440026 -221.72676)
			(xy 374.443943 -221.728549) (xy 374.489793 -221.758015) (xy 374.530984 -221.793706) (xy 374.566675 -221.834897)
			(xy 374.596141 -221.880747) (xy 374.618783 -221.930324) (xy 374.634138 -221.982619) (xy 374.641894 -222.036567)
			(xy 374.64238 -222.063818) (xy 374.641899 -222.090681) (xy 374.634359 -222.143876) (xy 374.619432 -222.195488)
			(xy 374.597413 -222.244495) (xy 374.568736 -222.289929) (xy 374.551702 -222.310706) (xy 374.544082 -222.319596)
			(xy 374.53824 -222.342202) (xy 374.558814 -222.443548) (xy 374.573038 -222.46209) (xy 374.583198 -222.46717)
			(xy 374.606495 -222.479423) (xy 374.64977 -222.509392) (xy 374.688516 -222.545023) (xy 374.721997 -222.585642)
			(xy 374.749578 -222.630476) (xy 374.770736 -222.678676) (xy 374.785069 -222.729326) (xy 374.792305 -222.781465)
			(xy 374.792748 -222.807784) (xy 374.792262 -222.835035) (xy 374.784506 -222.888983) (xy 374.769151 -222.941278)
			(xy 374.746509 -222.990855) (xy 374.717043 -223.036705) (xy 374.681352 -223.077896) (xy 374.658028 -223.098106)
			(xy 377.605034 -223.098106) (xy 377.609105 -223.042484) (xy 377.621231 -222.988047) (xy 377.641154 -222.935956)
			(xy 377.66845 -222.887321) (xy 377.702536 -222.843178) (xy 377.742685 -222.804469) (xy 377.788043 -222.772018)
			(xy 377.837643 -222.746517) (xy 377.890427 -222.72851) (xy 377.94527 -222.71838) (xy 378.001004 -222.716343)
			(xy 378.056441 -222.722443) (xy 378.110398 -222.736549) (xy 378.161727 -222.758361) (xy 378.209333 -222.787415)
			(xy 378.252201 -222.82309) (xy 378.289418 -222.864627) (xy 378.320191 -222.91114) (xy 378.343863 -222.961637)
			(xy 378.359931 -223.015044) (xy 378.368051 -223.07022) (xy 378.36856 -223.098106) (xy 378.368051 -223.125992)
			(xy 378.359931 -223.181168) (xy 378.343863 -223.234575) (xy 378.320191 -223.285072) (xy 378.289418 -223.331585)
			(xy 378.252201 -223.373122) (xy 378.209333 -223.408797) (xy 378.161727 -223.437851) (xy 378.110398 -223.459663)
			(xy 378.056441 -223.473769) (xy 378.001004 -223.479869) (xy 377.94527 -223.477832) (xy 377.890427 -223.467702)
			(xy 377.837643 -223.449695) (xy 377.788043 -223.424194) (xy 377.742685 -223.391743) (xy 377.702536 -223.353034)
			(xy 377.66845 -223.308891) (xy 377.641154 -223.260256) (xy 377.621231 -223.208165) (xy 377.609105 -223.153728)
			(xy 377.605034 -223.098106) (xy 374.658028 -223.098106) (xy 374.640161 -223.113587) (xy 374.594311 -223.143053)
			(xy 374.544734 -223.165695) (xy 374.492439 -223.18105) (xy 374.438491 -223.188806) (xy 374.383989 -223.188806)
			(xy 374.330041 -223.18105) (xy 374.277746 -223.165695) (xy 374.228169 -223.143053) (xy 374.182319 -223.113587)
			(xy 374.141128 -223.077896) (xy 374.105437 -223.036705) (xy 374.075971 -222.990855) (xy 374.053329 -222.941278)
			(xy 374.037974 -222.888983) (xy 374.030218 -222.835035) (xy 374.029732 -222.807784) (xy 374.030177 -222.78092)
			(xy 374.037729 -222.727724) (xy 374.052665 -222.676113) (xy 374.074692 -222.627106) (xy 374.103374 -222.581673)
			(xy 374.12041 -222.560896) (xy 374.12803 -222.552006) (xy 374.133872 -222.5294) (xy 374.113298 -222.428054)
			(xy 374.099074 -222.409512) (xy 374.088914 -222.404432) (xy 374.06562 -222.392173) (xy 374.022345 -222.362205)
			(xy 373.983599 -222.326575) (xy 373.950117 -222.285957) (xy 373.922535 -222.241124) (xy 373.901377 -222.192925)
			(xy 373.887043 -222.142276) (xy 373.879807 -222.090137) (xy 373.879364 -222.063818) (xy 372.54942 -222.063818)
			(xy 372.54942 -224.067116) (xy 376.189746 -224.067116) (xy 376.193817 -224.011494) (xy 376.205943 -223.957057)
			(xy 376.225866 -223.904966) (xy 376.253162 -223.856331) (xy 376.287248 -223.812188) (xy 376.327397 -223.773479)
			(xy 376.372755 -223.741028) (xy 376.422355 -223.715527) (xy 376.475139 -223.69752) (xy 376.529982 -223.68739)
			(xy 376.585716 -223.685353) (xy 376.641153 -223.691453) (xy 376.69511 -223.705559) (xy 376.746439 -223.727371)
			(xy 376.794045 -223.756425) (xy 376.836913 -223.7921) (xy 376.87413 -223.833637) (xy 376.904903 -223.88015)
			(xy 376.928575 -223.930647) (xy 376.944643 -223.984054) (xy 376.952763 -224.03923) (xy 376.953272 -224.067116)
			(xy 376.952763 -224.095002) (xy 376.944643 -224.150178) (xy 376.928575 -224.203585) (xy 376.904903 -224.254082)
			(xy 376.87413 -224.300595) (xy 376.836913 -224.342132) (xy 376.794045 -224.377807) (xy 376.746439 -224.406861)
			(xy 376.69511 -224.428673) (xy 376.641153 -224.442779) (xy 376.585716 -224.448879) (xy 376.529982 -224.446842)
			(xy 376.475139 -224.436712) (xy 376.422355 -224.418705) (xy 376.372755 -224.393204) (xy 376.327397 -224.360753)
			(xy 376.287248 -224.322044) (xy 376.253162 -224.277901) (xy 376.225866 -224.229266) (xy 376.205943 -224.177175)
			(xy 376.193817 -224.122738) (xy 376.189746 -224.067116) (xy 372.54942 -224.067116) (xy 372.54942 -224.994978)
			(xy 376.095512 -224.994978) (xy 376.099583 -224.939356) (xy 376.111709 -224.884919) (xy 376.131632 -224.832828)
			(xy 376.158928 -224.784193) (xy 376.193014 -224.74005) (xy 376.233163 -224.701341) (xy 376.278521 -224.66889)
			(xy 376.328121 -224.643389) (xy 376.380905 -224.625382) (xy 376.435748 -224.615252) (xy 376.491482 -224.613215)
			(xy 376.546919 -224.619315) (xy 376.600876 -224.633421) (xy 376.652205 -224.655233) (xy 376.699811 -224.684287)
			(xy 376.742679 -224.719962) (xy 376.779896 -224.761499) (xy 376.810669 -224.808012) (xy 376.834341 -224.858509)
			(xy 376.850409 -224.911916) (xy 376.858529 -224.967092) (xy 376.859038 -224.994978) (xy 376.858529 -225.022864)
			(xy 376.850409 -225.07804) (xy 376.834341 -225.131447) (xy 376.810669 -225.181944) (xy 376.779896 -225.228457)
			(xy 376.742679 -225.269994) (xy 376.699811 -225.305669) (xy 376.652205 -225.334723) (xy 376.600876 -225.356535)
			(xy 376.546919 -225.370641) (xy 376.491482 -225.376741) (xy 376.435748 -225.374704) (xy 376.380905 -225.364574)
			(xy 376.328121 -225.346567) (xy 376.278521 -225.321066) (xy 376.233163 -225.288615) (xy 376.193014 -225.249906)
			(xy 376.158928 -225.205763) (xy 376.131632 -225.157128) (xy 376.111709 -225.105037) (xy 376.099583 -225.0506)
			(xy 376.095512 -224.994978) (xy 372.54942 -224.994978) (xy 372.54942 -226.324922) (xy 373.869964 -226.324922)
			(xy 373.874035 -226.2693) (xy 373.886161 -226.214863) (xy 373.906084 -226.162772) (xy 373.93338 -226.114137)
			(xy 373.967466 -226.069994) (xy 374.007615 -226.031285) (xy 374.052973 -225.998834) (xy 374.102573 -225.973333)
			(xy 374.155357 -225.955326) (xy 374.2102 -225.945196) (xy 374.265934 -225.943159) (xy 374.321371 -225.949259)
			(xy 374.375328 -225.963365) (xy 374.426657 -225.985177) (xy 374.474263 -226.014231) (xy 374.517131 -226.049906)
			(xy 374.554348 -226.091443) (xy 374.585121 -226.137956) (xy 374.608793 -226.188453) (xy 374.624861 -226.24186)
			(xy 374.632981 -226.297036) (xy 374.63349 -226.324922) (xy 374.632981 -226.352808) (xy 374.624861 -226.407984)
			(xy 374.608793 -226.461391) (xy 374.585121 -226.511888) (xy 374.554348 -226.558401) (xy 374.517131 -226.599938)
			(xy 374.474263 -226.635613) (xy 374.426657 -226.664667) (xy 374.375328 -226.686479) (xy 374.321371 -226.700585)
			(xy 374.265934 -226.706685) (xy 374.2102 -226.704648) (xy 374.155357 -226.694518) (xy 374.102573 -226.676511)
			(xy 374.052973 -226.65101) (xy 374.007615 -226.618559) (xy 373.967466 -226.57985) (xy 373.93338 -226.535707)
			(xy 373.906084 -226.487072) (xy 373.886161 -226.434981) (xy 373.874035 -226.380544) (xy 373.869964 -226.324922)
			(xy 372.54942 -226.324922) (xy 372.54942 -227.397056) (xy 379.336298 -227.397056) (xy 379.340369 -227.341434)
			(xy 379.352495 -227.286997) (xy 379.372418 -227.234906) (xy 379.399714 -227.186271) (xy 379.4338 -227.142128)
			(xy 379.473949 -227.103419) (xy 379.519307 -227.070968) (xy 379.568907 -227.045467) (xy 379.621691 -227.02746)
			(xy 379.676534 -227.01733) (xy 379.732268 -227.015293) (xy 379.787705 -227.021393) (xy 379.841662 -227.035499)
			(xy 379.892991 -227.057311) (xy 379.940597 -227.086365) (xy 379.983465 -227.12204) (xy 380.020682 -227.163577)
			(xy 380.051455 -227.21009) (xy 380.075127 -227.260587) (xy 380.091195 -227.313994) (xy 380.099315 -227.36917)
			(xy 380.099824 -227.397056) (xy 380.099315 -227.424942) (xy 380.091195 -227.480118) (xy 380.075127 -227.533525)
			(xy 380.051455 -227.584022) (xy 380.020682 -227.630535) (xy 379.983465 -227.672072) (xy 379.940597 -227.707747)
			(xy 379.892991 -227.736801) (xy 379.841662 -227.758613) (xy 379.787705 -227.772719) (xy 379.732268 -227.778819)
			(xy 379.676534 -227.776782) (xy 379.621691 -227.766652) (xy 379.568907 -227.748645) (xy 379.519307 -227.723144)
			(xy 379.473949 -227.690693) (xy 379.4338 -227.651984) (xy 379.399714 -227.607841) (xy 379.372418 -227.559206)
			(xy 379.352495 -227.507115) (xy 379.340369 -227.452678) (xy 379.336298 -227.397056) (xy 372.54942 -227.397056)
			(xy 372.54942 -227.94595) (xy 373.85828 -227.94595) (xy 373.862351 -227.890328) (xy 373.874477 -227.835891)
			(xy 373.8944 -227.7838) (xy 373.921696 -227.735165) (xy 373.955782 -227.691022) (xy 373.995931 -227.652313)
			(xy 374.041289 -227.619862) (xy 374.090889 -227.594361) (xy 374.143673 -227.576354) (xy 374.198516 -227.566224)
			(xy 374.25425 -227.564187) (xy 374.309687 -227.570287) (xy 374.363644 -227.584393) (xy 374.414973 -227.606205)
			(xy 374.462579 -227.635259) (xy 374.505447 -227.670934) (xy 374.542664 -227.712471) (xy 374.573437 -227.758984)
			(xy 374.597109 -227.809481) (xy 374.613177 -227.862888) (xy 374.621297 -227.918064) (xy 374.621806 -227.94595)
			(xy 374.621297 -227.973836) (xy 374.613177 -228.029012) (xy 374.597109 -228.082419) (xy 374.573437 -228.132916)
			(xy 374.542664 -228.179429) (xy 374.505447 -228.220966) (xy 374.462579 -228.256641) (xy 374.414973 -228.285695)
			(xy 374.363644 -228.307507) (xy 374.309687 -228.321613) (xy 374.25425 -228.327713) (xy 374.198516 -228.325676)
			(xy 374.143673 -228.315546) (xy 374.090889 -228.297539) (xy 374.041289 -228.272038) (xy 373.995931 -228.239587)
			(xy 373.955782 -228.200878) (xy 373.921696 -228.156735) (xy 373.8944 -228.1081) (xy 373.874477 -228.056009)
			(xy 373.862351 -228.001572) (xy 373.85828 -227.94595) (xy 372.54942 -227.94595) (xy 372.54942 -228.467666)
			(xy 381.166114 -228.467666) (xy 381.170185 -228.412044) (xy 381.182311 -228.357607) (xy 381.202234 -228.305516)
			(xy 381.22953 -228.256881) (xy 381.263616 -228.212738) (xy 381.303765 -228.174029) (xy 381.349123 -228.141578)
			(xy 381.398723 -228.116077) (xy 381.451507 -228.09807) (xy 381.50635 -228.08794) (xy 381.562084 -228.085903)
			(xy 381.617521 -228.092003) (xy 381.671478 -228.106109) (xy 381.722807 -228.127921) (xy 381.770413 -228.156975)
			(xy 381.813281 -228.19265) (xy 381.850498 -228.234187) (xy 381.881271 -228.2807) (xy 381.904943 -228.331197)
			(xy 381.921011 -228.384604) (xy 381.929131 -228.43978) (xy 381.92964 -228.467666) (xy 381.929131 -228.495552)
			(xy 381.921011 -228.550728) (xy 381.904943 -228.604135) (xy 381.881271 -228.654632) (xy 381.850498 -228.701145)
			(xy 381.813281 -228.742682) (xy 381.770413 -228.778357) (xy 381.722807 -228.807411) (xy 381.671478 -228.829223)
			(xy 381.617521 -228.843329) (xy 381.562084 -228.849429) (xy 381.50635 -228.847392) (xy 381.451507 -228.837262)
			(xy 381.398723 -228.819255) (xy 381.349123 -228.793754) (xy 381.303765 -228.761303) (xy 381.263616 -228.722594)
			(xy 381.22953 -228.678451) (xy 381.202234 -228.629816) (xy 381.182311 -228.577725) (xy 381.170185 -228.523288)
			(xy 381.166114 -228.467666) (xy 372.54942 -228.467666) (xy 372.54942 -230.245412) (xy 372.548895 -230.271437)
			(xy 372.540733 -230.322842) (xy 372.524642 -230.372343) (xy 372.501018 -230.418722) (xy 372.470439 -230.460843)
			(xy 372.452392 -230.4796) (xy 371.858032 -231.07396) (xy 381.686814 -231.07396) (xy 381.690885 -231.018338)
			(xy 381.703011 -230.963901) (xy 381.722934 -230.91181) (xy 381.75023 -230.863175) (xy 381.784316 -230.819032)
			(xy 381.824465 -230.780323) (xy 381.869823 -230.747872) (xy 381.919423 -230.722371) (xy 381.972207 -230.704364)
			(xy 382.02705 -230.694234) (xy 382.082784 -230.692197) (xy 382.138221 -230.698297) (xy 382.192178 -230.712403)
			(xy 382.243507 -230.734215) (xy 382.291113 -230.763269) (xy 382.333981 -230.798944) (xy 382.371198 -230.840481)
			(xy 382.401971 -230.886994) (xy 382.40975 -230.903589) (xy 383.216061 -230.903589) (xy 383.216061 -230.843611)
			(xy 383.22389 -230.784147) (xy 383.239413 -230.726213) (xy 383.262366 -230.670801) (xy 383.292355 -230.618858)
			(xy 383.328867 -230.571275) (xy 383.371278 -230.528865) (xy 383.418862 -230.492353) (xy 383.470804 -230.462364)
			(xy 383.526216 -230.439412) (xy 383.584151 -230.423889) (xy 383.643615 -230.416061) (xy 383.673604 -230.415592)
			(xy 384.537204 -230.415592) (xy 384.567185 -230.416174) (xy 384.626634 -230.424001) (xy 384.684553 -230.439521)
			(xy 384.739951 -230.462468) (xy 384.79188 -230.492449) (xy 384.839451 -230.528952) (xy 384.88185 -230.571352)
			(xy 384.918353 -230.618924) (xy 384.948334 -230.670853) (xy 384.97128 -230.726251) (xy 384.986799 -230.78417)
			(xy 384.994626 -230.843619) (xy 384.994626 -230.903581) (xy 384.986799 -230.96303) (xy 384.97128 -231.020949)
			(xy 384.948334 -231.076347) (xy 384.918353 -231.128276) (xy 384.88185 -231.175848) (xy 384.839451 -231.218248)
			(xy 384.79188 -231.254751) (xy 384.739951 -231.284732) (xy 384.684553 -231.307679) (xy 384.626634 -231.323199)
			(xy 384.567185 -231.331026) (xy 384.537204 -231.331516) (xy 383.673604 -231.331516) (xy 383.643615 -231.331139)
			(xy 383.584151 -231.323311) (xy 383.526216 -231.307788) (xy 383.470804 -231.284836) (xy 383.418862 -231.254847)
			(xy 383.371278 -231.218335) (xy 383.328867 -231.175925) (xy 383.292355 -231.128342) (xy 383.262366 -231.076399)
			(xy 383.239413 -231.020987) (xy 383.22389 -230.963053) (xy 383.216061 -230.903589) (xy 382.40975 -230.903589)
			(xy 382.425643 -230.937491) (xy 382.441711 -230.990898) (xy 382.449831 -231.046074) (xy 382.45034 -231.07396)
			(xy 382.449831 -231.101846) (xy 382.441711 -231.157022) (xy 382.425643 -231.210429) (xy 382.401971 -231.260926)
			(xy 382.371198 -231.307439) (xy 382.333981 -231.348976) (xy 382.291113 -231.384651) (xy 382.243507 -231.413705)
			(xy 382.192178 -231.435517) (xy 382.138221 -231.449623) (xy 382.082784 -231.455723) (xy 382.02705 -231.453686)
			(xy 381.972207 -231.443556) (xy 381.919423 -231.425549) (xy 381.869823 -231.400048) (xy 381.824465 -231.367597)
			(xy 381.784316 -231.328888) (xy 381.75023 -231.284745) (xy 381.722934 -231.23611) (xy 381.703011 -231.184019)
			(xy 381.690885 -231.129582) (xy 381.686814 -231.07396) (xy 371.858032 -231.07396) (xy 370.578888 -232.353104)
			(xy 375.625104 -232.353104) (xy 375.629175 -232.297482) (xy 375.641301 -232.243045) (xy 375.661224 -232.190954)
			(xy 375.68852 -232.142319) (xy 375.722606 -232.098176) (xy 375.762755 -232.059467) (xy 375.808113 -232.027016)
			(xy 375.857713 -232.001515) (xy 375.910497 -231.983508) (xy 375.96534 -231.973378) (xy 376.021074 -231.971341)
			(xy 376.076511 -231.977441) (xy 376.130468 -231.991547) (xy 376.181797 -232.013359) (xy 376.229403 -232.042413)
			(xy 376.272271 -232.078088) (xy 376.309488 -232.119625) (xy 376.340261 -232.166138) (xy 376.363933 -232.216635)
			(xy 376.380001 -232.270042) (xy 376.388121 -232.325218) (xy 376.38863 -232.353104) (xy 376.388121 -232.38099)
			(xy 376.380001 -232.436166) (xy 376.363933 -232.489573) (xy 376.340261 -232.54007) (xy 376.309488 -232.586583)
			(xy 376.272271 -232.62812) (xy 376.229403 -232.663795) (xy 376.181797 -232.692849) (xy 376.130468 -232.714661)
			(xy 376.076511 -232.728767) (xy 376.021074 -232.734867) (xy 375.96534 -232.73283) (xy 375.910497 -232.7227)
			(xy 375.857713 -232.704693) (xy 375.808113 -232.679192) (xy 375.762755 -232.646741) (xy 375.722606 -232.608032)
			(xy 375.68852 -232.563889) (xy 375.661224 -232.515254) (xy 375.641301 -232.463163) (xy 375.629175 -232.408726)
			(xy 375.625104 -232.353104) (xy 370.578888 -232.353104) (xy 369.105942 -233.82605) (xy 373.232932 -233.82605)
			(xy 373.237003 -233.770428) (xy 373.249129 -233.715991) (xy 373.269052 -233.6639) (xy 373.296348 -233.615265)
			(xy 373.330434 -233.571122) (xy 373.370583 -233.532413) (xy 373.415941 -233.499962) (xy 373.465541 -233.474461)
			(xy 373.518325 -233.456454) (xy 373.573168 -233.446324) (xy 373.628902 -233.444287) (xy 373.684339 -233.450387)
			(xy 373.738296 -233.464493) (xy 373.789625 -233.486305) (xy 373.837231 -233.515359) (xy 373.880099 -233.551034)
			(xy 373.917316 -233.592571) (xy 373.948089 -233.639084) (xy 373.971761 -233.689581) (xy 373.987829 -233.742988)
			(xy 373.995949 -233.798164) (xy 373.996458 -233.82605) (xy 373.995949 -233.853936) (xy 373.987829 -233.909112)
			(xy 373.971761 -233.962519) (xy 373.956553 -233.99496) (xy 381.97358 -233.99496) (xy 381.977651 -233.939338)
			(xy 381.989777 -233.884901) (xy 382.0097 -233.83281) (xy 382.036996 -233.784175) (xy 382.071082 -233.740032)
			(xy 382.111231 -233.701323) (xy 382.156589 -233.668872) (xy 382.206189 -233.643371) (xy 382.258973 -233.625364)
			(xy 382.313816 -233.615234) (xy 382.36955 -233.613197) (xy 382.424987 -233.619297) (xy 382.478944 -233.633403)
			(xy 382.530273 -233.655215) (xy 382.577879 -233.684269) (xy 382.620747 -233.719944) (xy 382.657964 -233.761481)
			(xy 382.688737 -233.807994) (xy 382.712409 -233.858491) (xy 382.728477 -233.911898) (xy 382.736597 -233.967074)
			(xy 382.737041 -233.991404) (xy 382.973578 -233.991404) (xy 382.977649 -233.935782) (xy 382.989775 -233.881345)
			(xy 383.009698 -233.829254) (xy 383.036994 -233.780619) (xy 383.07108 -233.736476) (xy 383.111229 -233.697767)
			(xy 383.156587 -233.665316) (xy 383.206187 -233.639815) (xy 383.258971 -233.621808) (xy 383.313814 -233.611678)
			(xy 383.369548 -233.609641) (xy 383.424985 -233.615741) (xy 383.478942 -233.629847) (xy 383.530271 -233.651659)
			(xy 383.577877 -233.680713) (xy 383.620745 -233.716388) (xy 383.657962 -233.757925) (xy 383.688735 -233.804438)
			(xy 383.712407 -233.854935) (xy 383.728475 -233.908342) (xy 383.735765 -233.957876) (xy 384.473448 -233.957876)
			(xy 384.477519 -233.902254) (xy 384.489645 -233.847817) (xy 384.509568 -233.795726) (xy 384.536864 -233.747091)
			(xy 384.57095 -233.702948) (xy 384.611099 -233.664239) (xy 384.656457 -233.631788) (xy 384.706057 -233.606287)
			(xy 384.758841 -233.58828) (xy 384.813684 -233.57815) (xy 384.869418 -233.576113) (xy 384.924855 -233.582213)
			(xy 384.978812 -233.596319) (xy 385.030141 -233.618131) (xy 385.077747 -233.647185) (xy 385.120615 -233.68286)
			(xy 385.157832 -233.724397) (xy 385.188605 -233.77091) (xy 385.212277 -233.821407) (xy 385.228345 -233.874814)
			(xy 385.236465 -233.92999) (xy 385.236974 -233.957876) (xy 385.973572 -233.957876) (xy 385.977643 -233.902254)
			(xy 385.989769 -233.847817) (xy 386.009692 -233.795726) (xy 386.036988 -233.747091) (xy 386.071074 -233.702948)
			(xy 386.111223 -233.664239) (xy 386.156581 -233.631788) (xy 386.206181 -233.606287) (xy 386.258965 -233.58828)
			(xy 386.313808 -233.57815) (xy 386.369542 -233.576113) (xy 386.424979 -233.582213) (xy 386.478936 -233.596319)
			(xy 386.530265 -233.618131) (xy 386.577871 -233.647185) (xy 386.620739 -233.68286) (xy 386.657956 -233.724397)
			(xy 386.688729 -233.77091) (xy 386.712401 -233.821407) (xy 386.728469 -233.874814) (xy 386.736589 -233.92999)
			(xy 386.737098 -233.957876) (xy 386.736589 -233.985762) (xy 386.728469 -234.040938) (xy 386.712401 -234.094345)
			(xy 386.688729 -234.144842) (xy 386.657956 -234.191355) (xy 386.620739 -234.232892) (xy 386.577871 -234.268567)
			(xy 386.530265 -234.297621) (xy 386.478936 -234.319433) (xy 386.424979 -234.333539) (xy 386.369542 -234.339639)
			(xy 386.313808 -234.337602) (xy 386.258965 -234.327472) (xy 386.206181 -234.309465) (xy 386.156581 -234.283964)
			(xy 386.111223 -234.251513) (xy 386.071074 -234.212804) (xy 386.036988 -234.168661) (xy 386.009692 -234.120026)
			(xy 385.989769 -234.067935) (xy 385.977643 -234.013498) (xy 385.973572 -233.957876) (xy 385.236974 -233.957876)
			(xy 385.236465 -233.985762) (xy 385.228345 -234.040938) (xy 385.212277 -234.094345) (xy 385.188605 -234.144842)
			(xy 385.157832 -234.191355) (xy 385.120615 -234.232892) (xy 385.077747 -234.268567) (xy 385.030141 -234.297621)
			(xy 384.978812 -234.319433) (xy 384.924855 -234.333539) (xy 384.869418 -234.339639) (xy 384.813684 -234.337602)
			(xy 384.758841 -234.327472) (xy 384.706057 -234.309465) (xy 384.656457 -234.283964) (xy 384.611099 -234.251513)
			(xy 384.57095 -234.212804) (xy 384.536864 -234.168661) (xy 384.509568 -234.120026) (xy 384.489645 -234.067935)
			(xy 384.477519 -234.013498) (xy 384.473448 -233.957876) (xy 383.735765 -233.957876) (xy 383.736595 -233.963518)
			(xy 383.737104 -233.991404) (xy 383.736595 -234.01929) (xy 383.728475 -234.074466) (xy 383.712407 -234.127873)
			(xy 383.688735 -234.17837) (xy 383.657962 -234.224883) (xy 383.620745 -234.26642) (xy 383.577877 -234.302095)
			(xy 383.530271 -234.331149) (xy 383.478942 -234.352961) (xy 383.424985 -234.367067) (xy 383.369548 -234.373167)
			(xy 383.313814 -234.37113) (xy 383.258971 -234.361) (xy 383.206187 -234.342993) (xy 383.156587 -234.317492)
			(xy 383.111229 -234.285041) (xy 383.07108 -234.246332) (xy 383.036994 -234.202189) (xy 383.009698 -234.153554)
			(xy 382.989775 -234.101463) (xy 382.977649 -234.047026) (xy 382.973578 -233.991404) (xy 382.737041 -233.991404)
			(xy 382.737106 -233.99496) (xy 382.736597 -234.022846) (xy 382.728477 -234.078022) (xy 382.712409 -234.131429)
			(xy 382.688737 -234.181926) (xy 382.657964 -234.228439) (xy 382.620747 -234.269976) (xy 382.577879 -234.305651)
			(xy 382.530273 -234.334705) (xy 382.478944 -234.356517) (xy 382.424987 -234.370623) (xy 382.36955 -234.376723)
			(xy 382.313816 -234.374686) (xy 382.258973 -234.364556) (xy 382.206189 -234.346549) (xy 382.156589 -234.321048)
			(xy 382.111231 -234.288597) (xy 382.071082 -234.249888) (xy 382.036996 -234.205745) (xy 382.0097 -234.15711)
			(xy 381.989777 -234.105019) (xy 381.977651 -234.050582) (xy 381.97358 -233.99496) (xy 373.956553 -233.99496)
			(xy 373.948089 -234.013016) (xy 373.917316 -234.059529) (xy 373.880099 -234.101066) (xy 373.837231 -234.136741)
			(xy 373.789625 -234.165795) (xy 373.738296 -234.187607) (xy 373.684339 -234.201713) (xy 373.628902 -234.207813)
			(xy 373.573168 -234.205776) (xy 373.518325 -234.195646) (xy 373.465541 -234.177639) (xy 373.415941 -234.152138)
			(xy 373.370583 -234.119687) (xy 373.330434 -234.080978) (xy 373.296348 -234.036835) (xy 373.269052 -233.9882)
			(xy 373.249129 -233.936109) (xy 373.237003 -233.881672) (xy 373.232932 -233.82605) (xy 369.105942 -233.82605)
			(xy 368.12093 -234.811062) (xy 377.376942 -234.811062) (xy 377.381013 -234.75544) (xy 377.393139 -234.701003)
			(xy 377.413062 -234.648912) (xy 377.440358 -234.600277) (xy 377.474444 -234.556134) (xy 377.514593 -234.517425)
			(xy 377.559951 -234.484974) (xy 377.609551 -234.459473) (xy 377.662335 -234.441466) (xy 377.717178 -234.431336)
			(xy 377.772912 -234.429299) (xy 377.828349 -234.435399) (xy 377.882306 -234.449505) (xy 377.933635 -234.471317)
			(xy 377.981241 -234.500371) (xy 378.024109 -234.536046) (xy 378.061326 -234.577583) (xy 378.092099 -234.624096)
			(xy 378.115771 -234.674593) (xy 378.131839 -234.728) (xy 378.139959 -234.783176) (xy 378.140468 -234.811062)
			(xy 378.139959 -234.838948) (xy 378.131839 -234.894124) (xy 378.115771 -234.947531) (xy 378.092099 -234.998028)
			(xy 378.061326 -235.044541) (xy 378.024109 -235.086078) (xy 377.981241 -235.121753) (xy 377.933635 -235.150807)
			(xy 377.882306 -235.172619) (xy 377.828349 -235.186725) (xy 377.772912 -235.192825) (xy 377.717178 -235.190788)
			(xy 377.662335 -235.180658) (xy 377.609551 -235.162651) (xy 377.559951 -235.13715) (xy 377.514593 -235.104699)
			(xy 377.474444 -235.06599) (xy 377.440358 -235.021847) (xy 377.413062 -234.973212) (xy 377.393139 -234.921121)
			(xy 377.381013 -234.866684) (xy 377.376942 -234.811062) (xy 368.12093 -234.811062) (xy 367.937542 -234.99445)
			(xy 367.91876 -235.01256) (xy 367.876561 -235.043238) (xy 367.83008 -235.066932) (xy 367.780462 -235.083057)
			(xy 367.728932 -235.091216) (xy 367.702846 -235.091732) (xy 367.693702 -235.091732) (xy 367.684912 -235.092101)
			(xy 367.668369 -235.098052) (xy 367.654817 -235.109252) (xy 367.650014 -235.116624) (xy 367.637568 -235.139484)
			(xy 367.606326 -235.197396) (xy 367.603291 -235.203491) (xy 367.600211 -235.216749) (xy 367.60023 -235.223558)
			(xy 367.600738 -235.23702) (xy 367.606326 -235.245402) (xy 367.621608 -235.269109) (xy 367.645789 -235.320064)
			(xy 367.662227 -235.374017) (xy 367.670566 -235.4298) (xy 367.671096 -235.458) (xy 367.670633 -235.485253)
			(xy 367.662876 -235.539203) (xy 367.662555 -235.540296) (xy 376.763278 -235.540296) (xy 376.767349 -235.484674)
			(xy 376.779475 -235.430237) (xy 376.799398 -235.378146) (xy 376.826694 -235.329511) (xy 376.86078 -235.285368)
			(xy 376.900929 -235.246659) (xy 376.946287 -235.214208) (xy 376.995887 -235.188707) (xy 377.048671 -235.1707)
			(xy 377.103514 -235.16057) (xy 377.159248 -235.158533) (xy 377.214685 -235.164633) (xy 377.268642 -235.178739)
			(xy 377.319971 -235.200551) (xy 377.367577 -235.229605) (xy 377.410445 -235.26528) (xy 377.447662 -235.306817)
			(xy 377.478435 -235.35333) (xy 377.502107 -235.403827) (xy 377.518175 -235.457234) (xy 377.526295 -235.51241)
			(xy 377.526804 -235.540296) (xy 377.526295 -235.568182) (xy 377.518175 -235.623358) (xy 377.502107 -235.676765)
			(xy 377.478435 -235.727262) (xy 377.447662 -235.773775) (xy 377.410445 -235.815312) (xy 377.367577 -235.850987)
			(xy 377.319971 -235.880041) (xy 377.268642 -235.901853) (xy 377.214685 -235.915959) (xy 377.159248 -235.922059)
			(xy 377.103514 -235.920022) (xy 377.048671 -235.909892) (xy 376.995887 -235.891885) (xy 376.946287 -235.866384)
			(xy 376.900929 -235.833933) (xy 376.86078 -235.795224) (xy 376.826694 -235.751081) (xy 376.799398 -235.702446)
			(xy 376.779475 -235.650355) (xy 376.767349 -235.595918) (xy 376.763278 -235.540296) (xy 367.662555 -235.540296)
			(xy 367.647519 -235.5915) (xy 367.624877 -235.641079) (xy 367.595409 -235.686932) (xy 367.559715 -235.728123)
			(xy 367.518522 -235.763816) (xy 367.472669 -235.793283) (xy 367.423089 -235.815924) (xy 367.370791 -235.831278)
			(xy 367.316841 -235.839034) (xy 367.289588 -235.839508) (xy 367.262533 -235.839035) (xy 367.208967 -235.831388)
			(xy 367.157019 -235.81625) (xy 367.10773 -235.793923) (xy 367.062091 -235.764856) (xy 367.021017 -235.729632)
			(xy 366.985332 -235.688957) (xy 366.955751 -235.643649) (xy 366.93287 -235.594616) (xy 366.917145 -235.542842)
			(xy 366.908894 -235.489365) (xy 366.90808 -235.462318) (xy 366.90808 -235.457746) (xy 366.908649 -235.428918)
			(xy 366.917403 -235.371928) (xy 366.934629 -235.316904) (xy 366.959934 -235.265096) (xy 366.975898 -235.241084)
			(xy 366.975898 -235.24083) (xy 366.979706 -235.234992) (xy 366.984352 -235.221857) (xy 366.985042 -235.214922)
			(xy 366.985804 -235.200952) (xy 366.935258 -235.105448) (xy 366.93272 -235.101539) (xy 366.926458 -235.094636)
			(xy 366.922812 -235.091732) (xy 356.40264 -235.091732) (xy 356.390448 -235.093256) (xy 356.385531 -235.094595)
			(xy 356.376321 -235.098951) (xy 356.37216 -235.101892) (xy 356.37089 -235.102908) (xy 356.227888 -235.24591)
			(xy 356.223316 -235.25226) (xy 356.220268 -235.257594) (xy 356.21976 -235.259372) (xy 356.211525 -235.285269)
			(xy 356.188749 -235.334606) (xy 356.159208 -235.380216) (xy 356.123499 -235.421177) (xy 356.082344 -235.456661)
			(xy 356.036573 -235.485952) (xy 355.987112 -235.508459) (xy 355.93496 -235.523725) (xy 355.88117 -235.531443)
			(xy 355.854 -235.531914) (xy 355.826749 -235.531428) (xy 355.772801 -235.523672) (xy 355.720505 -235.508317)
			(xy 355.670928 -235.485676) (xy 355.625077 -235.456209) (xy 355.583886 -235.420518) (xy 355.548194 -235.379328)
			(xy 355.518727 -235.333477) (xy 355.496085 -235.2839) (xy 355.48073 -235.231605) (xy 355.472972 -235.177657)
			(xy 355.472492 -235.150406) (xy 355.472953 -235.123482) (xy 355.480518 -235.070169) (xy 355.495499 -235.018448)
			(xy 355.517597 -234.969344) (xy 355.546376 -234.923833) (xy 355.581264 -234.882816) (xy 355.621569 -234.847108)
			(xy 355.66649 -234.817417) (xy 355.715138 -234.794333) (xy 355.740716 -234.785916) (xy 355.741224 -234.785916)
			(xy 355.746887 -234.783872) (xy 355.757151 -234.777587) (xy 355.761544 -234.77347) (xy 356.009956 -234.525058)
			(xy 356.028738 -234.506948) (xy 356.070936 -234.476269) (xy 356.117418 -234.452574) (xy 356.167035 -234.436448)
			(xy 356.218566 -234.428288) (xy 356.244652 -234.427776) (xy 367.529618 -234.427776) (xy 367.534698 -234.423458)
			(xy 369.715542 -232.242868) (xy 371.465094 -230.493316) (xy 371.470871 -230.487083) (xy 371.478293 -230.471804)
			(xy 371.480329 -230.454941) (xy 371.47881 -230.44658) (xy 371.478048 -230.44277) (xy 371.450616 -230.355902)
			(xy 371.44744 -230.347139) (xy 371.43588 -230.332537) (xy 371.419852 -230.323053) (xy 371.410738 -230.321104)
			(xy 371.384452 -230.316133) (xy 371.333509 -230.299807) (xy 371.285342 -230.276532) (xy 371.240895 -230.246762)
			(xy 371.201037 -230.211081) (xy 371.166548 -230.170188) (xy 371.138103 -230.124881) (xy 371.11626 -230.076048)
			(xy 371.101444 -230.024645) (xy 371.093947 -229.971678) (xy 371.093492 -229.94493) (xy 371.093953 -229.917676)
			(xy 371.101707 -229.863722) (xy 371.11706 -229.81142) (xy 371.139701 -229.761836) (xy 371.169168 -229.715979)
			(xy 371.204862 -229.674783) (xy 371.246055 -229.639086) (xy 371.29191 -229.609615) (xy 371.341492 -229.586971)
			(xy 371.393792 -229.571613) (xy 371.447746 -229.563855) (xy 371.475 -229.563422) (xy 371.475254 -229.563422)
			(xy 371.501955 -229.563868) (xy 371.554833 -229.571319) (xy 371.606154 -229.586081) (xy 371.654909 -229.607865)
			(xy 371.700145 -229.636245) (xy 371.720872 -229.653084) (xy 371.727476 -229.658672) (xy 371.73916 -229.663244)
			(xy 371.740684 -229.663752) (xy 371.743986 -229.665022) (xy 371.744748 -229.66553) (xy 371.7544 -229.669594)
			(xy 371.764306 -229.669594) (xy 371.769681 -229.669429) (xy 371.780182 -229.667118) (xy 371.785134 -229.665022)
			(xy 371.841776 -229.639622) (xy 371.866668 -229.628446) (xy 371.872293 -229.625686) (xy 371.882066 -229.617851)
			(xy 371.885972 -229.612952) (xy 371.885972 -219.225368) (xy 371.878375 -219.21625) (xy 371.857183 -219.205631)
			(xy 371.845332 -219.205048) (xy 368.389408 -219.205048) (xy 368.375956 -219.205499) (xy 368.350004 -219.2126)
			(xy 368.326808 -219.226232) (xy 368.307976 -219.245448) (xy 368.294816 -219.268916) (xy 368.288241 -219.295006)
			(xy 368.288708 -219.321908) (xy 368.296184 -219.347755) (xy 368.302794 -219.35948) (xy 368.315922 -219.381979)
			(xy 368.33663 -219.429777) (xy 368.350648 -219.479946) (xy 368.357716 -219.531555) (xy 368.358166 -219.5576)
			(xy 368.35768 -219.584869) (xy 368.349918 -219.638853) (xy 368.334553 -219.691183) (xy 368.311896 -219.740793)
			(xy 368.28241 -219.786674) (xy 368.246695 -219.827891) (xy 368.205478 -219.863606) (xy 368.159597 -219.893092)
			(xy 368.109987 -219.915749) (xy 368.057657 -219.931114) (xy 368.003673 -219.938876) (xy 367.949135 -219.938876)
			(xy 367.895151 -219.931114) (xy 367.842821 -219.915749) (xy 367.793211 -219.893092) (xy 367.74733 -219.863606)
			(xy 367.706113 -219.827891) (xy 367.670398 -219.786674) (xy 367.640912 -219.740793) (xy 367.618255 -219.691183)
			(xy 367.60289 -219.638853) (xy 367.595128 -219.584869) (xy 367.594642 -219.5576) (xy 367.595083 -219.531554)
			(xy 367.602157 -219.479945) (xy 367.616174 -219.429775) (xy 367.636874 -219.381972) (xy 367.650014 -219.35948)
			(xy 367.656666 -219.347764) (xy 367.664177 -219.321898) (xy 367.664665 -219.294969) (xy 367.658096 -219.268849)
			(xy 367.644927 -219.245354) (xy 367.626075 -219.226119) (xy 367.602849 -219.212481) (xy 367.576866 -219.205389)
			(xy 367.5634 -219.205048) (xy 364.868968 -219.205048) (xy 364.860688 -219.205369) (xy 364.845004 -219.210684)
			(xy 364.838234 -219.215462) (xy 364.835186 -219.218256) (xy 364.834678 -219.218764) (xy 364.832646 -219.220288)
			(xy 363.206284 -220.84665) (xy 364.12881 -220.84665) (xy 364.132881 -220.791028) (xy 364.145007 -220.736591)
			(xy 364.16493 -220.6845) (xy 364.192226 -220.635865) (xy 364.226312 -220.591722) (xy 364.266461 -220.553013)
			(xy 364.311819 -220.520562) (xy 364.361419 -220.495061) (xy 364.414203 -220.477054) (xy 364.469046 -220.466924)
			(xy 364.52478 -220.464887) (xy 364.580217 -220.470987) (xy 364.634174 -220.485093) (xy 364.685503 -220.506905)
			(xy 364.733109 -220.535959) (xy 364.775977 -220.571634) (xy 364.813194 -220.613171) (xy 364.843967 -220.659684)
			(xy 364.867639 -220.710181) (xy 364.883707 -220.763588) (xy 364.891827 -220.818764) (xy 364.892336 -220.84665)
			(xy 364.891827 -220.874536) (xy 364.883707 -220.929712) (xy 364.867639 -220.983119) (xy 364.843967 -221.033616)
			(xy 364.813194 -221.080129) (xy 364.775977 -221.121666) (xy 364.733109 -221.157341) (xy 364.685503 -221.186395)
			(xy 364.634174 -221.208207) (xy 364.580217 -221.222313) (xy 364.52478 -221.228413) (xy 364.469046 -221.226376)
			(xy 364.414203 -221.216246) (xy 364.361419 -221.198239) (xy 364.311819 -221.172738) (xy 364.266461 -221.140287)
			(xy 364.226312 -221.101578) (xy 364.192226 -221.057435) (xy 364.16493 -221.0088) (xy 364.145007 -220.956709)
			(xy 364.132881 -220.902272) (xy 364.12881 -220.84665) (xy 363.206284 -220.84665) (xy 362.720128 -221.332806)
			(xy 370.740684 -221.332806) (xy 370.744755 -221.277184) (xy 370.756881 -221.222747) (xy 370.776804 -221.170656)
			(xy 370.8041 -221.122021) (xy 370.838186 -221.077878) (xy 370.878335 -221.039169) (xy 370.923693 -221.006718)
			(xy 370.973293 -220.981217) (xy 371.026077 -220.96321) (xy 371.08092 -220.95308) (xy 371.136654 -220.951043)
			(xy 371.192091 -220.957143) (xy 371.246048 -220.971249) (xy 371.297377 -220.993061) (xy 371.344983 -221.022115)
			(xy 371.387851 -221.05779) (xy 371.425068 -221.099327) (xy 371.455841 -221.14584) (xy 371.479513 -221.196337)
			(xy 371.495581 -221.249744) (xy 371.503701 -221.30492) (xy 371.50421 -221.332806) (xy 371.503701 -221.360692)
			(xy 371.495581 -221.415868) (xy 371.479513 -221.469275) (xy 371.455841 -221.519772) (xy 371.425068 -221.566285)
			(xy 371.387851 -221.607822) (xy 371.344983 -221.643497) (xy 371.297377 -221.672551) (xy 371.246048 -221.694363)
			(xy 371.192091 -221.708469) (xy 371.136654 -221.714569) (xy 371.08092 -221.712532) (xy 371.026077 -221.702402)
			(xy 370.973293 -221.684395) (xy 370.923693 -221.658894) (xy 370.878335 -221.626443) (xy 370.838186 -221.587734)
			(xy 370.8041 -221.543591) (xy 370.776804 -221.494956) (xy 370.756881 -221.442865) (xy 370.744755 -221.388428)
			(xy 370.740684 -221.332806) (xy 362.720128 -221.332806) (xy 361.880658 -222.172276) (xy 364.118904 -222.172276)
			(xy 364.122975 -222.116654) (xy 364.135101 -222.062217) (xy 364.155024 -222.010126) (xy 364.18232 -221.961491)
			(xy 364.216406 -221.917348) (xy 364.256555 -221.878639) (xy 364.301913 -221.846188) (xy 364.351513 -221.820687)
			(xy 364.404297 -221.80268) (xy 364.45914 -221.79255) (xy 364.514874 -221.790513) (xy 364.570311 -221.796613)
			(xy 364.624268 -221.810719) (xy 364.675597 -221.832531) (xy 364.723203 -221.861585) (xy 364.766071 -221.89726)
			(xy 364.803288 -221.938797) (xy 364.811053 -221.950534) (xy 365.350296 -221.950534) (xy 365.354367 -221.894912)
			(xy 365.366493 -221.840475) (xy 365.386416 -221.788384) (xy 365.413712 -221.739749) (xy 365.447798 -221.695606)
			(xy 365.487947 -221.656897) (xy 365.533305 -221.624446) (xy 365.582905 -221.598945) (xy 365.635689 -221.580938)
			(xy 365.690532 -221.570808) (xy 365.746266 -221.568771) (xy 365.801703 -221.574871) (xy 365.85566 -221.588977)
			(xy 365.906989 -221.610789) (xy 365.954595 -221.639843) (xy 365.997463 -221.675518) (xy 366.03468 -221.717055)
			(xy 366.065453 -221.763568) (xy 366.089125 -221.814065) (xy 366.105193 -221.867472) (xy 366.113313 -221.922648)
			(xy 366.113822 -221.950534) (xy 366.113313 -221.97842) (xy 366.105193 -222.033596) (xy 366.089125 -222.087003)
			(xy 366.065453 -222.1375) (xy 366.03468 -222.184013) (xy 365.997463 -222.22555) (xy 365.954595 -222.261225)
			(xy 365.906989 -222.290279) (xy 365.85566 -222.312091) (xy 365.801703 -222.326197) (xy 365.746266 -222.332297)
			(xy 365.690532 -222.33026) (xy 365.635689 -222.32013) (xy 365.582905 -222.302123) (xy 365.533305 -222.276622)
			(xy 365.487947 -222.244171) (xy 365.447798 -222.205462) (xy 365.413712 -222.161319) (xy 365.386416 -222.112684)
			(xy 365.366493 -222.060593) (xy 365.354367 -222.006156) (xy 365.350296 -221.950534) (xy 364.811053 -221.950534)
			(xy 364.834061 -221.98531) (xy 364.857733 -222.035807) (xy 364.873801 -222.089214) (xy 364.881921 -222.14439)
			(xy 364.88243 -222.172276) (xy 364.881921 -222.200162) (xy 364.873801 -222.255338) (xy 364.857733 -222.308745)
			(xy 364.834061 -222.359242) (xy 364.803288 -222.405755) (xy 364.766071 -222.447292) (xy 364.723203 -222.482967)
			(xy 364.675597 -222.512021) (xy 364.624268 -222.533833) (xy 364.570311 -222.547939) (xy 364.514874 -222.554039)
			(xy 364.45914 -222.552002) (xy 364.404297 -222.541872) (xy 364.351513 -222.523865) (xy 364.301913 -222.498364)
			(xy 364.256555 -222.465913) (xy 364.216406 -222.427204) (xy 364.18232 -222.383061) (xy 364.155024 -222.334426)
			(xy 364.135101 -222.282335) (xy 364.122975 -222.227898) (xy 364.118904 -222.172276) (xy 361.880658 -222.172276)
			(xy 360.399584 -223.65335) (xy 360.398568 -223.65462) (xy 360.395266 -223.658176) (xy 360.395012 -223.65843)
			(xy 360.393996 -223.659446) (xy 360.393488 -223.659954) (xy 360.377994 -223.675194) (xy 360.376978 -223.675956)
			(xy 359.38841 -224.664524) (xy 359.384092 -224.675192) (xy 359.383838 -224.6757) (xy 359.373834 -224.699924)
			(xy 359.348136 -224.745603) (xy 359.316426 -224.787332) (xy 359.279299 -224.824325) (xy 359.237457 -224.855886)
			(xy 359.191686 -224.881419) (xy 359.16743 -224.891346) (xy 359.157524 -224.89541) (xy 359.049828 -225.003106)
			(xy 359.046304 -225.006835) (xy 359.040669 -225.015407) (xy 359.038652 -225.020124) (xy 359.035096 -225.02876)
			(xy 359.035096 -225.047302) (xy 359.035858 -225.05543) (xy 359.037636 -225.066352) (xy 359.061766 -225.144584)
			(xy 359.062274 -225.145854) (xy 359.064306 -225.150426) (xy 359.066525 -225.154455) (xy 359.072147 -225.161736)
			(xy 359.075482 -225.164904) (xy 359.075482 -225.165158) (xy 359.080066 -225.168986) (xy 359.090585 -225.174634)
			(xy 359.09631 -225.176334) (xy 359.10012 -225.177096) (xy 359.125977 -225.182453) (xy 359.176006 -225.19935)
			(xy 359.223225 -225.222987) (xy 359.266731 -225.252913) (xy 359.305693 -225.288554) (xy 359.339365 -225.32923)
			(xy 359.367104 -225.374162) (xy 359.388379 -225.422491) (xy 359.402783 -225.473294) (xy 359.41004 -225.525597)
			(xy 359.410508 -225.552) (xy 359.410359 -225.560382) (xy 368.588796 -225.560382) (xy 368.592867 -225.50476)
			(xy 368.604993 -225.450323) (xy 368.624916 -225.398232) (xy 368.652212 -225.349597) (xy 368.686298 -225.305454)
			(xy 368.726447 -225.266745) (xy 368.771805 -225.234294) (xy 368.821405 -225.208793) (xy 368.874189 -225.190786)
			(xy 368.929032 -225.180656) (xy 368.984766 -225.178619) (xy 369.040203 -225.184719) (xy 369.09416 -225.198825)
			(xy 369.145489 -225.220637) (xy 369.193095 -225.249691) (xy 369.235963 -225.285366) (xy 369.27318 -225.326903)
			(xy 369.303953 -225.373416) (xy 369.327625 -225.423913) (xy 369.343693 -225.47732) (xy 369.351813 -225.532496)
			(xy 369.352322 -225.560382) (xy 369.351813 -225.588268) (xy 369.343693 -225.643444) (xy 369.327625 -225.696851)
			(xy 369.304559 -225.746056) (xy 369.751354 -225.746056) (xy 369.755425 -225.690434) (xy 369.767551 -225.635997)
			(xy 369.787474 -225.583906) (xy 369.81477 -225.535271) (xy 369.848856 -225.491128) (xy 369.889005 -225.452419)
			(xy 369.934363 -225.419968) (xy 369.983963 -225.394467) (xy 370.036747 -225.37646) (xy 370.09159 -225.36633)
			(xy 370.147324 -225.364293) (xy 370.202761 -225.370393) (xy 370.256718 -225.384499) (xy 370.308047 -225.406311)
			(xy 370.355653 -225.435365) (xy 370.398521 -225.47104) (xy 370.435738 -225.512577) (xy 370.466511 -225.55909)
			(xy 370.490183 -225.609587) (xy 370.506251 -225.662994) (xy 370.514371 -225.71817) (xy 370.51488 -225.746056)
			(xy 370.514371 -225.773942) (xy 370.506251 -225.829118) (xy 370.490183 -225.882525) (xy 370.466511 -225.933022)
			(xy 370.435738 -225.979535) (xy 370.398521 -226.021072) (xy 370.355653 -226.056747) (xy 370.308047 -226.085801)
			(xy 370.256718 -226.107613) (xy 370.202761 -226.121719) (xy 370.147324 -226.127819) (xy 370.09159 -226.125782)
			(xy 370.036747 -226.115652) (xy 369.983963 -226.097645) (xy 369.934363 -226.072144) (xy 369.889005 -226.039693)
			(xy 369.848856 -226.000984) (xy 369.81477 -225.956841) (xy 369.787474 -225.908206) (xy 369.767551 -225.856115)
			(xy 369.755425 -225.801678) (xy 369.751354 -225.746056) (xy 369.304559 -225.746056) (xy 369.303953 -225.747348)
			(xy 369.27318 -225.793861) (xy 369.235963 -225.835398) (xy 369.193095 -225.871073) (xy 369.145489 -225.900127)
			(xy 369.09416 -225.921939) (xy 369.040203 -225.936045) (xy 368.984766 -225.942145) (xy 368.929032 -225.940108)
			(xy 368.874189 -225.929978) (xy 368.821405 -225.911971) (xy 368.771805 -225.88647) (xy 368.726447 -225.854019)
			(xy 368.686298 -225.81531) (xy 368.652212 -225.771167) (xy 368.624916 -225.722532) (xy 368.604993 -225.670441)
			(xy 368.592867 -225.616004) (xy 368.588796 -225.560382) (xy 359.410359 -225.560382) (xy 359.410022 -225.579251)
			(xy 359.402266 -225.633199) (xy 359.386911 -225.685494) (xy 359.364269 -225.735071) (xy 359.334803 -225.780921)
			(xy 359.299112 -225.822112) (xy 359.257921 -225.857803) (xy 359.212071 -225.887269) (xy 359.162494 -225.909911)
			(xy 359.110199 -225.925266) (xy 359.056251 -225.933022) (xy 359.029 -225.933508) (xy 359.028746 -225.933508)
			(xy 359.00313 -225.933095) (xy 358.952359 -225.926236) (xy 358.902965 -225.912635) (xy 358.855839 -225.892537)
			(xy 358.811831 -225.866306) (xy 358.79151 -225.850704) (xy 358.786938 -225.847148) (xy 358.783636 -225.844354)
			(xy 358.763846 -225.827222) (xy 358.728685 -225.788445) (xy 358.699162 -225.745221) (xy 358.675831 -225.698364)
			(xy 358.659131 -225.648756) (xy 358.653842 -225.62312) (xy 358.653588 -225.62058) (xy 358.652572 -225.616262)
			(xy 358.64673 -225.60407) (xy 358.640888 -225.59772) (xy 358.636336 -225.593109) (xy 358.62541 -225.586152)
			(xy 358.619298 -225.584004) (xy 358.530652 -225.556826) (xy 358.522106 -225.555129) (xy 358.504788 -225.556928)
			(xy 358.489054 -225.564386) (xy 358.482646 -225.570288) (xy 357.484934 -226.568) (xy 358.646982 -226.568)
			(xy 358.651053 -226.512378) (xy 358.663179 -226.457941) (xy 358.683102 -226.40585) (xy 358.710398 -226.357215)
			(xy 358.744484 -226.313072) (xy 358.784633 -226.274363) (xy 358.829991 -226.241912) (xy 358.879591 -226.216411)
			(xy 358.932375 -226.198404) (xy 358.987218 -226.188274) (xy 359.042952 -226.186237) (xy 359.098389 -226.192337)
			(xy 359.152346 -226.206443) (xy 359.203675 -226.228255) (xy 359.251281 -226.257309) (xy 359.294149 -226.292984)
			(xy 359.331366 -226.334521) (xy 359.362139 -226.381034) (xy 359.385811 -226.431531) (xy 359.401879 -226.484938)
			(xy 359.409999 -226.540114) (xy 359.410309 -226.557078) (xy 365.688624 -226.557078) (xy 365.692695 -226.501456)
			(xy 365.704821 -226.447019) (xy 365.724744 -226.394928) (xy 365.75204 -226.346293) (xy 365.786126 -226.30215)
			(xy 365.826275 -226.263441) (xy 365.871633 -226.23099) (xy 365.921233 -226.205489) (xy 365.974017 -226.187482)
			(xy 366.02886 -226.177352) (xy 366.084594 -226.175315) (xy 366.140031 -226.181415) (xy 366.193988 -226.195521)
			(xy 366.245317 -226.217333) (xy 366.292923 -226.246387) (xy 366.335791 -226.282062) (xy 366.373008 -226.323599)
			(xy 366.403781 -226.370112) (xy 366.427453 -226.420609) (xy 366.443521 -226.474016) (xy 366.451641 -226.529192)
			(xy 366.45183 -226.539552) (xy 366.7412 -226.539552) (xy 366.745271 -226.48393) (xy 366.757397 -226.429493)
			(xy 366.77732 -226.377402) (xy 366.804616 -226.328767) (xy 366.838702 -226.284624) (xy 366.878851 -226.245915)
			(xy 366.924209 -226.213464) (xy 366.973809 -226.187963) (xy 367.026593 -226.169956) (xy 367.081436 -226.159826)
			(xy 367.13717 -226.157789) (xy 367.192607 -226.163889) (xy 367.246564 -226.177995) (xy 367.297893 -226.199807)
			(xy 367.345499 -226.228861) (xy 367.388367 -226.264536) (xy 367.425584 -226.306073) (xy 367.456357 -226.352586)
			(xy 367.480029 -226.403083) (xy 367.496097 -226.45649) (xy 367.504217 -226.511666) (xy 367.504726 -226.539552)
			(xy 367.504217 -226.567438) (xy 367.496097 -226.622614) (xy 367.480029 -226.676021) (xy 367.456357 -226.726518)
			(xy 367.425584 -226.773031) (xy 367.388367 -226.814568) (xy 367.345499 -226.850243) (xy 367.297893 -226.879297)
			(xy 367.246564 -226.901109) (xy 367.192607 -226.915215) (xy 367.13717 -226.921315) (xy 367.081436 -226.919278)
			(xy 367.026593 -226.909148) (xy 366.973809 -226.891141) (xy 366.924209 -226.86564) (xy 366.878851 -226.833189)
			(xy 366.838702 -226.79448) (xy 366.804616 -226.750337) (xy 366.77732 -226.701702) (xy 366.757397 -226.649611)
			(xy 366.745271 -226.595174) (xy 366.7412 -226.539552) (xy 366.45183 -226.539552) (xy 366.45215 -226.557078)
			(xy 366.451641 -226.584964) (xy 366.443521 -226.64014) (xy 366.427453 -226.693547) (xy 366.403781 -226.744044)
			(xy 366.373008 -226.790557) (xy 366.335791 -226.832094) (xy 366.292923 -226.867769) (xy 366.245317 -226.896823)
			(xy 366.193988 -226.918635) (xy 366.140031 -226.932741) (xy 366.084594 -226.938841) (xy 366.02886 -226.936804)
			(xy 365.974017 -226.926674) (xy 365.921233 -226.908667) (xy 365.871633 -226.883166) (xy 365.826275 -226.850715)
			(xy 365.786126 -226.812006) (xy 365.75204 -226.767863) (xy 365.724744 -226.719228) (xy 365.704821 -226.667137)
			(xy 365.692695 -226.6127) (xy 365.688624 -226.557078) (xy 359.410309 -226.557078) (xy 359.410508 -226.568)
			(xy 359.409999 -226.595886) (xy 359.401879 -226.651062) (xy 359.385811 -226.704469) (xy 359.362139 -226.754966)
			(xy 359.331366 -226.801479) (xy 359.294149 -226.843016) (xy 359.251281 -226.878691) (xy 359.203675 -226.907745)
			(xy 359.152346 -226.929557) (xy 359.098389 -226.943663) (xy 359.042952 -226.949763) (xy 358.987218 -226.947726)
			(xy 358.932375 -226.937596) (xy 358.879591 -226.919589) (xy 358.829991 -226.894088) (xy 358.784633 -226.861637)
			(xy 358.744484 -226.822928) (xy 358.710398 -226.778785) (xy 358.683102 -226.73015) (xy 358.663179 -226.678059)
			(xy 358.651053 -226.623622) (xy 358.646982 -226.568) (xy 357.484934 -226.568) (xy 357.017828 -227.035106)
			(xy 357.014304 -227.038835) (xy 357.008669 -227.047407) (xy 357.006652 -227.052124) (xy 357.003096 -227.06076)
			(xy 357.003096 -227.079302) (xy 357.003858 -227.08743) (xy 357.005636 -227.098352) (xy 357.029766 -227.176584)
			(xy 357.030274 -227.177854) (xy 357.032306 -227.182426) (xy 357.034525 -227.186455) (xy 357.040147 -227.193736)
			(xy 357.043482 -227.196904) (xy 357.043482 -227.197158) (xy 357.048066 -227.200986) (xy 357.058585 -227.206634)
			(xy 357.06431 -227.208334) (xy 357.06812 -227.209096) (xy 357.093977 -227.214453) (xy 357.144006 -227.23135)
			(xy 357.191225 -227.254987) (xy 357.234731 -227.284913) (xy 357.273693 -227.320554) (xy 357.307365 -227.36123)
			(xy 357.335104 -227.406162) (xy 357.356379 -227.454491) (xy 357.370783 -227.505294) (xy 357.37804 -227.557597)
			(xy 357.378508 -227.584) (xy 359.556556 -227.584) (xy 359.560627 -227.528378) (xy 359.572753 -227.473941)
			(xy 359.592676 -227.42185) (xy 359.619972 -227.373215) (xy 359.654058 -227.329072) (xy 359.694207 -227.290363)
			(xy 359.739565 -227.257912) (xy 359.789165 -227.232411) (xy 359.841949 -227.214404) (xy 359.896792 -227.204274)
			(xy 359.952526 -227.202237) (xy 360.007963 -227.208337) (xy 360.06192 -227.222443) (xy 360.113249 -227.244255)
			(xy 360.160855 -227.273309) (xy 360.203723 -227.308984) (xy 360.24094 -227.350521) (xy 360.271713 -227.397034)
			(xy 360.295385 -227.447531) (xy 360.311453 -227.500938) (xy 360.319573 -227.556114) (xy 360.320082 -227.584)
			(xy 360.319573 -227.611886) (xy 360.311453 -227.667062) (xy 360.295385 -227.720469) (xy 360.271713 -227.770966)
			(xy 360.24094 -227.817479) (xy 360.203723 -227.859016) (xy 360.160855 -227.894691) (xy 360.113249 -227.923745)
			(xy 360.06192 -227.945557) (xy 360.007963 -227.959663) (xy 359.952526 -227.965763) (xy 359.896792 -227.963726)
			(xy 359.841949 -227.953596) (xy 359.789165 -227.935589) (xy 359.739565 -227.910088) (xy 359.694207 -227.877637)
			(xy 359.654058 -227.838928) (xy 359.619972 -227.794785) (xy 359.592676 -227.74615) (xy 359.572753 -227.694059)
			(xy 359.560627 -227.639622) (xy 359.556556 -227.584) (xy 357.378508 -227.584) (xy 357.378022 -227.611251)
			(xy 357.370266 -227.665199) (xy 357.354911 -227.717494) (xy 357.332269 -227.767071) (xy 357.302803 -227.812921)
			(xy 357.267112 -227.854112) (xy 357.225921 -227.889803) (xy 357.180071 -227.919269) (xy 357.130494 -227.941911)
			(xy 357.078199 -227.957266) (xy 357.024251 -227.965022) (xy 356.997 -227.965508) (xy 356.996746 -227.965508)
			(xy 356.97113 -227.965095) (xy 356.920359 -227.958236) (xy 356.870965 -227.944635) (xy 356.823839 -227.924537)
			(xy 356.779831 -227.898306) (xy 356.75951 -227.882704) (xy 356.754938 -227.879148) (xy 356.751636 -227.876354)
			(xy 356.731846 -227.859222) (xy 356.696685 -227.820445) (xy 356.667162 -227.777221) (xy 356.643831 -227.730364)
			(xy 356.627131 -227.680756) (xy 356.621842 -227.65512) (xy 356.621588 -227.65258) (xy 356.620572 -227.648262)
			(xy 356.61473 -227.63607) (xy 356.608888 -227.62972) (xy 356.604336 -227.625109) (xy 356.59341 -227.618152)
			(xy 356.587298 -227.616004) (xy 356.498652 -227.588826) (xy 356.490106 -227.587129) (xy 356.472788 -227.588928)
			(xy 356.457054 -227.596386) (xy 356.450646 -227.602288) (xy 356.043738 -228.009196) (xy 356.035827 -228.018043)
			(xy 356.028414 -228.040558) (xy 356.029514 -228.052376) (xy 356.20071 -228.223318) (xy 356.205061 -228.22749)
			(xy 356.215335 -228.23379) (xy 356.22103 -228.235764) (xy 356.221284 -228.235764) (xy 356.246841 -228.244201)
			(xy 356.295471 -228.267255) (xy 356.34038 -228.296913) (xy 356.380675 -228.332588) (xy 356.415558 -228.373571)
			(xy 356.444336 -228.419049) (xy 356.466439 -228.468119) (xy 356.481427 -228.519809) (xy 356.489003 -228.573091)
			(xy 356.489508 -228.6) (xy 358.646982 -228.6) (xy 358.651053 -228.544378) (xy 358.663179 -228.489941)
			(xy 358.683102 -228.43785) (xy 358.710398 -228.389215) (xy 358.744484 -228.345072) (xy 358.784633 -228.306363)
			(xy 358.829991 -228.273912) (xy 358.879591 -228.248411) (xy 358.932375 -228.230404) (xy 358.987218 -228.220274)
			(xy 359.042952 -228.218237) (xy 359.098389 -228.224337) (xy 359.140155 -228.235256) (xy 365.150144 -228.235256)
			(xy 365.154215 -228.179634) (xy 365.166341 -228.125197) (xy 365.186264 -228.073106) (xy 365.21356 -228.024471)
			(xy 365.247646 -227.980328) (xy 365.287795 -227.941619) (xy 365.333153 -227.909168) (xy 365.382753 -227.883667)
			(xy 365.435537 -227.86566) (xy 365.49038 -227.85553) (xy 365.546114 -227.853493) (xy 365.601551 -227.859593)
			(xy 365.655508 -227.873699) (xy 365.706837 -227.895511) (xy 365.754443 -227.924565) (xy 365.797311 -227.96024)
			(xy 365.834528 -228.001777) (xy 365.865301 -228.04829) (xy 365.888973 -228.098787) (xy 365.905041 -228.152194)
			(xy 365.913161 -228.20737) (xy 365.91367 -228.235256) (xy 365.913161 -228.263142) (xy 365.905041 -228.318318)
			(xy 365.896254 -228.347524) (xy 366.198656 -228.347524) (xy 366.202727 -228.291902) (xy 366.214853 -228.237465)
			(xy 366.234776 -228.185374) (xy 366.262072 -228.136739) (xy 366.296158 -228.092596) (xy 366.336307 -228.053887)
			(xy 366.381665 -228.021436) (xy 366.431265 -227.995935) (xy 366.484049 -227.977928) (xy 366.538892 -227.967798)
			(xy 366.594626 -227.965761) (xy 366.650063 -227.971861) (xy 366.70402 -227.985967) (xy 366.755349 -228.007779)
			(xy 366.802955 -228.036833) (xy 366.845823 -228.072508) (xy 366.88304 -228.114045) (xy 366.913813 -228.160558)
			(xy 366.937485 -228.211055) (xy 366.945301 -228.237034) (xy 367.222276 -228.237034) (xy 367.226347 -228.181412)
			(xy 367.238473 -228.126975) (xy 367.258396 -228.074884) (xy 367.285692 -228.026249) (xy 367.319778 -227.982106)
			(xy 367.359927 -227.943397) (xy 367.405285 -227.910946) (xy 367.454885 -227.885445) (xy 367.507669 -227.867438)
			(xy 367.562512 -227.857308) (xy 367.618246 -227.855271) (xy 367.673683 -227.861371) (xy 367.72764 -227.875477)
			(xy 367.778969 -227.897289) (xy 367.826575 -227.926343) (xy 367.869443 -227.962018) (xy 367.90666 -228.003555)
			(xy 367.937433 -228.050068) (xy 367.961105 -228.100565) (xy 367.977173 -228.153972) (xy 367.985293 -228.209148)
			(xy 367.9857 -228.231446) (xy 368.244626 -228.231446) (xy 368.248697 -228.175824) (xy 368.260823 -228.121387)
			(xy 368.280746 -228.069296) (xy 368.308042 -228.020661) (xy 368.342128 -227.976518) (xy 368.382277 -227.937809)
			(xy 368.427635 -227.905358) (xy 368.477235 -227.879857) (xy 368.530019 -227.86185) (xy 368.584862 -227.85172)
			(xy 368.640596 -227.849683) (xy 368.696033 -227.855783) (xy 368.74999 -227.869889) (xy 368.801319 -227.891701)
			(xy 368.848925 -227.920755) (xy 368.891793 -227.95643) (xy 368.92901 -227.997967) (xy 368.959783 -228.04448)
			(xy 368.983455 -228.094977) (xy 368.999523 -228.148384) (xy 369.007643 -228.20356) (xy 369.008152 -228.231446)
			(xy 369.007643 -228.259332) (xy 368.999523 -228.314508) (xy 368.983455 -228.367915) (xy 368.959783 -228.418412)
			(xy 368.92901 -228.464925) (xy 368.891793 -228.506462) (xy 368.848925 -228.542137) (xy 368.801319 -228.571191)
			(xy 368.74999 -228.593003) (xy 368.696033 -228.607109) (xy 368.640596 -228.613209) (xy 368.584862 -228.611172)
			(xy 368.530019 -228.601042) (xy 368.477235 -228.583035) (xy 368.427635 -228.557534) (xy 368.382277 -228.525083)
			(xy 368.342128 -228.486374) (xy 368.308042 -228.442231) (xy 368.280746 -228.393596) (xy 368.260823 -228.341505)
			(xy 368.248697 -228.287068) (xy 368.244626 -228.231446) (xy 367.9857 -228.231446) (xy 367.985802 -228.237034)
			(xy 367.985293 -228.26492) (xy 367.977173 -228.320096) (xy 367.961105 -228.373503) (xy 367.937433 -228.424)
			(xy 367.90666 -228.470513) (xy 367.869443 -228.51205) (xy 367.826575 -228.547725) (xy 367.778969 -228.576779)
			(xy 367.72764 -228.598591) (xy 367.673683 -228.612697) (xy 367.618246 -228.618797) (xy 367.562512 -228.61676)
			(xy 367.507669 -228.60663) (xy 367.454885 -228.588623) (xy 367.405285 -228.563122) (xy 367.359927 -228.530671)
			(xy 367.319778 -228.491962) (xy 367.285692 -228.447819) (xy 367.258396 -228.399184) (xy 367.238473 -228.347093)
			(xy 367.226347 -228.292656) (xy 367.222276 -228.237034) (xy 366.945301 -228.237034) (xy 366.953553 -228.264462)
			(xy 366.961673 -228.319638) (xy 366.962182 -228.347524) (xy 366.961673 -228.37541) (xy 366.953553 -228.430586)
			(xy 366.937485 -228.483993) (xy 366.913813 -228.53449) (xy 366.88304 -228.581003) (xy 366.845823 -228.62254)
			(xy 366.802955 -228.658215) (xy 366.755349 -228.687269) (xy 366.70402 -228.709081) (xy 366.650063 -228.723187)
			(xy 366.594626 -228.729287) (xy 366.538892 -228.72725) (xy 366.484049 -228.71712) (xy 366.431265 -228.699113)
			(xy 366.381665 -228.673612) (xy 366.336307 -228.641161) (xy 366.296158 -228.602452) (xy 366.262072 -228.558309)
			(xy 366.234776 -228.509674) (xy 366.214853 -228.457583) (xy 366.202727 -228.403146) (xy 366.198656 -228.347524)
			(xy 365.896254 -228.347524) (xy 365.888973 -228.371725) (xy 365.865301 -228.422222) (xy 365.834528 -228.468735)
			(xy 365.797311 -228.510272) (xy 365.754443 -228.545947) (xy 365.706837 -228.575001) (xy 365.655508 -228.596813)
			(xy 365.601551 -228.610919) (xy 365.546114 -228.617019) (xy 365.49038 -228.614982) (xy 365.435537 -228.604852)
			(xy 365.382753 -228.586845) (xy 365.333153 -228.561344) (xy 365.287795 -228.528893) (xy 365.247646 -228.490184)
			(xy 365.21356 -228.446041) (xy 365.186264 -228.397406) (xy 365.166341 -228.345315) (xy 365.154215 -228.290878)
			(xy 365.150144 -228.235256) (xy 359.140155 -228.235256) (xy 359.152346 -228.238443) (xy 359.203675 -228.260255)
			(xy 359.251281 -228.289309) (xy 359.294149 -228.324984) (xy 359.331366 -228.366521) (xy 359.362139 -228.413034)
			(xy 359.385811 -228.463531) (xy 359.401879 -228.516938) (xy 359.409999 -228.572114) (xy 359.410508 -228.6)
			(xy 359.409999 -228.627886) (xy 359.401879 -228.683062) (xy 359.385811 -228.736469) (xy 359.362139 -228.786966)
			(xy 359.331366 -228.833479) (xy 359.294149 -228.875016) (xy 359.251281 -228.910691) (xy 359.203675 -228.939745)
			(xy 359.152346 -228.961557) (xy 359.098389 -228.975663) (xy 359.049886 -228.981) (xy 364.297212 -228.981)
			(xy 364.301283 -228.925378) (xy 364.313409 -228.870941) (xy 364.333332 -228.81885) (xy 364.360628 -228.770215)
			(xy 364.394714 -228.726072) (xy 364.434863 -228.687363) (xy 364.480221 -228.654912) (xy 364.529821 -228.629411)
			(xy 364.582605 -228.611404) (xy 364.637448 -228.601274) (xy 364.693182 -228.599237) (xy 364.748619 -228.605337)
			(xy 364.802576 -228.619443) (xy 364.853905 -228.641255) (xy 364.901511 -228.670309) (xy 364.944379 -228.705984)
			(xy 364.981596 -228.747521) (xy 365.012369 -228.794034) (xy 365.036041 -228.844531) (xy 365.052109 -228.897938)
			(xy 365.060229 -228.953114) (xy 365.060738 -228.981) (xy 365.060229 -229.008886) (xy 365.052109 -229.064062)
			(xy 365.036041 -229.117469) (xy 365.012369 -229.167966) (xy 364.981596 -229.214479) (xy 364.944379 -229.256016)
			(xy 364.901511 -229.291691) (xy 364.853905 -229.320745) (xy 364.802576 -229.342557) (xy 364.748619 -229.356663)
			(xy 364.693182 -229.362763) (xy 364.637448 -229.360726) (xy 364.582605 -229.350596) (xy 364.529821 -229.332589)
			(xy 364.480221 -229.307088) (xy 364.434863 -229.274637) (xy 364.394714 -229.235928) (xy 364.360628 -229.191785)
			(xy 364.333332 -229.14315) (xy 364.313409 -229.091059) (xy 364.301283 -229.036622) (xy 364.297212 -228.981)
			(xy 359.049886 -228.981) (xy 359.042952 -228.981763) (xy 358.987218 -228.979726) (xy 358.932375 -228.969596)
			(xy 358.879591 -228.951589) (xy 358.829991 -228.926088) (xy 358.784633 -228.893637) (xy 358.744484 -228.854928)
			(xy 358.710398 -228.810785) (xy 358.683102 -228.76215) (xy 358.663179 -228.710059) (xy 358.651053 -228.655622)
			(xy 358.646982 -228.6) (xy 356.489508 -228.6) (xy 356.489508 -228.603302) (xy 356.488829 -228.629721)
			(xy 356.481079 -228.681997) (xy 356.466184 -228.732701) (xy 356.455726 -228.756972) (xy 356.455726 -228.757226)
			(xy 356.451944 -228.766767) (xy 356.451542 -228.787268) (xy 356.45923 -228.806277) (xy 356.46614 -228.813868)
			(xy 356.562914 -228.910642) (xy 356.562914 -228.910896) (xy 356.677976 -229.025958) (xy 356.683056 -229.030276)
			(xy 356.997 -229.030276) (xy 357.031086 -229.030771) (xy 357.098796 -229.038686) (xy 357.16513 -229.054407)
			(xy 357.22919 -229.077723) (xy 357.29011 -229.108318) (xy 357.347067 -229.145779) (xy 357.399289 -229.189599)
			(xy 357.446071 -229.239185) (xy 357.48678 -229.293867) (xy 357.520866 -229.352905) (xy 357.547867 -229.415501)
			(xy 357.567419 -229.480808) (xy 357.579257 -229.547944) (xy 357.583221 -229.616) (xy 358.646982 -229.616)
			(xy 358.651053 -229.560378) (xy 358.663179 -229.505941) (xy 358.683102 -229.45385) (xy 358.710398 -229.405215)
			(xy 358.744484 -229.361072) (xy 358.784633 -229.322363) (xy 358.829991 -229.289912) (xy 358.879591 -229.264411)
			(xy 358.932375 -229.246404) (xy 358.987218 -229.236274) (xy 359.042952 -229.234237) (xy 359.098389 -229.240337)
			(xy 359.152346 -229.254443) (xy 359.203675 -229.276255) (xy 359.251281 -229.305309) (xy 359.294149 -229.340984)
			(xy 359.331366 -229.382521) (xy 359.362139 -229.429034) (xy 359.385811 -229.479531) (xy 359.401879 -229.532938)
			(xy 359.409999 -229.588114) (xy 359.410508 -229.616) (xy 359.409999 -229.643886) (xy 359.401879 -229.699062)
			(xy 359.385811 -229.752469) (xy 359.362139 -229.802966) (xy 359.331366 -229.849479) (xy 359.294149 -229.891016)
			(xy 359.251281 -229.926691) (xy 359.221396 -229.94493) (xy 361.108242 -229.94493) (xy 361.112313 -229.889308)
			(xy 361.124439 -229.834871) (xy 361.144362 -229.78278) (xy 361.171658 -229.734145) (xy 361.205744 -229.690002)
			(xy 361.245893 -229.651293) (xy 361.291251 -229.618842) (xy 361.340851 -229.593341) (xy 361.393635 -229.575334)
			(xy 361.448478 -229.565204) (xy 361.504212 -229.563167) (xy 361.559649 -229.569267) (xy 361.613606 -229.583373)
			(xy 361.664935 -229.605185) (xy 361.712541 -229.634239) (xy 361.755409 -229.669914) (xy 361.792626 -229.711451)
			(xy 361.823399 -229.757964) (xy 361.847071 -229.808461) (xy 361.863139 -229.861868) (xy 361.871259 -229.917044)
			(xy 361.871768 -229.94493) (xy 361.871259 -229.972816) (xy 361.863139 -230.027992) (xy 361.847071 -230.081399)
			(xy 361.823399 -230.131896) (xy 361.792626 -230.178409) (xy 361.755409 -230.219946) (xy 361.712541 -230.255621)
			(xy 361.664935 -230.284675) (xy 361.613606 -230.306487) (xy 361.559649 -230.320593) (xy 361.504212 -230.326693)
			(xy 361.448478 -230.324656) (xy 361.393635 -230.314526) (xy 361.340851 -230.296519) (xy 361.291251 -230.271018)
			(xy 361.245893 -230.238567) (xy 361.205744 -230.199858) (xy 361.171658 -230.155715) (xy 361.144362 -230.10708)
			(xy 361.124439 -230.054989) (xy 361.112313 -230.000552) (xy 361.108242 -229.94493) (xy 359.221396 -229.94493)
			(xy 359.203675 -229.955745) (xy 359.152346 -229.977557) (xy 359.098389 -229.991663) (xy 359.042952 -229.997763)
			(xy 358.987218 -229.995726) (xy 358.932375 -229.985596) (xy 358.879591 -229.967589) (xy 358.829991 -229.942088)
			(xy 358.784633 -229.909637) (xy 358.744484 -229.870928) (xy 358.710398 -229.826785) (xy 358.683102 -229.77815)
			(xy 358.663179 -229.726059) (xy 358.651053 -229.671622) (xy 358.646982 -229.616) (xy 357.583221 -229.616)
			(xy 357.579257 -229.684056) (xy 357.567419 -229.751192) (xy 357.547867 -229.816499) (xy 357.520866 -229.879095)
			(xy 357.48678 -229.938133) (xy 357.446071 -229.992815) (xy 357.399289 -230.042401) (xy 357.347067 -230.086221)
			(xy 357.29011 -230.123682) (xy 357.22919 -230.154277) (xy 357.16513 -230.177593) (xy 357.098796 -230.193314)
			(xy 357.031086 -230.201229) (xy 356.997 -230.201724) (xy 356.107746 -230.201724) (xy 356.074891 -230.201266)
			(xy 356.009594 -230.193915) (xy 355.945531 -230.179299) (xy 355.883507 -230.157602) (xy 355.824302 -230.129098)
			(xy 355.76866 -230.094145) (xy 355.717282 -230.053181) (xy 355.693726 -230.030274) (xy 354.894134 -229.230428)
			(xy 354.890111 -229.226632) (xy 354.88075 -229.220743) (xy 354.875592 -229.218744) (xy 354.866906 -229.215943)
			(xy 354.84867 -229.216056) (xy 354.840032 -229.218998) (xy 354.83523 -229.220964) (xy 354.826519 -229.226598)
			(xy 354.82276 -229.230174) (xy 354.822506 -229.230428) (xy 354.653088 -229.399846) (xy 354.649568 -229.403578)
			(xy 354.643944 -229.412154) (xy 354.641912 -229.416864) (xy 354.638356 -229.4255) (xy 354.638356 -230.70058)
			(xy 355.77348 -230.70058) (xy 355.777551 -230.644958) (xy 355.789677 -230.590521) (xy 355.8096 -230.53843)
			(xy 355.836896 -230.489795) (xy 355.870982 -230.445652) (xy 355.911131 -230.406943) (xy 355.956489 -230.374492)
			(xy 356.006089 -230.348991) (xy 356.058873 -230.330984) (xy 356.113716 -230.320854) (xy 356.16945 -230.318817)
			(xy 356.224887 -230.324917) (xy 356.278844 -230.339023) (xy 356.330173 -230.360835) (xy 356.377779 -230.389889)
			(xy 356.420647 -230.425564) (xy 356.457864 -230.467101) (xy 356.488637 -230.513614) (xy 356.512309 -230.564111)
			(xy 356.528377 -230.617518) (xy 356.528839 -230.620654) (xy 357.727447 -230.620654) (xy 357.727447 -230.566146)
			(xy 357.735205 -230.512194) (xy 357.750561 -230.459895) (xy 357.773204 -230.410313) (xy 357.802673 -230.364459)
			(xy 357.838368 -230.323265) (xy 357.879562 -230.287571) (xy 357.925417 -230.258102) (xy 357.974998 -230.23546)
			(xy 358.027298 -230.220104) (xy 358.08125 -230.212347) (xy 358.108504 -230.211884) (xy 358.135875 -230.212327)
			(xy 358.190056 -230.220147) (xy 358.24256 -230.235641) (xy 358.292307 -230.258488) (xy 358.338272 -230.288219)
			(xy 358.359202 -230.305864) (xy 358.359456 -230.306118) (xy 358.36655 -230.311694) (xy 358.383461 -230.317947)
			(xy 358.392476 -230.31831) (xy 358.459532 -230.31831) (xy 358.46855 -230.317966) (xy 358.485467 -230.311709)
			(xy 358.492552 -230.306118) (xy 358.492552 -230.305864) (xy 358.492806 -230.305864) (xy 358.513739 -230.288223)
			(xy 358.559707 -230.258499) (xy 358.609453 -230.235653) (xy 358.661955 -230.220157) (xy 358.716133 -230.212328)
			(xy 358.770875 -230.212328) (xy 358.825053 -230.220157) (xy 358.877555 -230.235653) (xy 358.927301 -230.258499)
			(xy 358.973269 -230.288223) (xy 358.994202 -230.305864) (xy 358.994456 -230.306118) (xy 359.00155 -230.311694)
			(xy 359.018461 -230.317947) (xy 359.027476 -230.31831) (xy 359.094532 -230.31831) (xy 359.10355 -230.317966)
			(xy 359.120467 -230.311709) (xy 359.127552 -230.306118) (xy 359.127552 -230.305864) (xy 359.127806 -230.305864)
			(xy 359.148739 -230.288223) (xy 359.194707 -230.258499) (xy 359.244453 -230.235653) (xy 359.296955 -230.220157)
			(xy 359.351133 -230.212328) (xy 359.405875 -230.212328) (xy 359.460053 -230.220157) (xy 359.512555 -230.235653)
			(xy 359.562301 -230.258499) (xy 359.608269 -230.288223) (xy 359.629202 -230.305864) (xy 359.629456 -230.306118)
			(xy 359.63655 -230.311694) (xy 359.653461 -230.317947) (xy 359.662476 -230.31831) (xy 359.729532 -230.31831)
			(xy 359.73855 -230.317966) (xy 359.755467 -230.311709) (xy 359.762552 -230.306118) (xy 359.762552 -230.305864)
			(xy 359.762806 -230.305864) (xy 359.78372 -230.288203) (xy 359.829699 -230.258496) (xy 359.879451 -230.235665)
			(xy 359.931955 -230.220179) (xy 359.986134 -230.212355) (xy 360.013504 -230.211884) (xy 360.040755 -230.212374)
			(xy 360.094702 -230.220131) (xy 360.146996 -230.235486) (xy 360.196573 -230.258127) (xy 360.242423 -230.287593)
			(xy 360.283613 -230.323284) (xy 360.319304 -230.364474) (xy 360.348771 -230.410323) (xy 360.371412 -230.4599)
			(xy 360.386768 -230.512194) (xy 360.394526 -230.566141) (xy 360.395012 -230.593392) (xy 360.394556 -230.620941)
			(xy 360.386626 -230.675464) (xy 360.37093 -230.728278) (xy 360.347795 -230.778283) (xy 360.347284 -230.779066)
			(xy 362.598968 -230.779066) (xy 362.603039 -230.723444) (xy 362.615165 -230.669007) (xy 362.635088 -230.616916)
			(xy 362.662384 -230.568281) (xy 362.69647 -230.524138) (xy 362.736619 -230.485429) (xy 362.781977 -230.452978)
			(xy 362.831577 -230.427477) (xy 362.884361 -230.40947) (xy 362.939204 -230.39934) (xy 362.994938 -230.397303)
			(xy 363.050375 -230.403403) (xy 363.104332 -230.417509) (xy 363.155661 -230.439321) (xy 363.203267 -230.468375)
			(xy 363.246135 -230.50405) (xy 363.283352 -230.545587) (xy 363.314125 -230.5921) (xy 363.337797 -230.642597)
			(xy 363.353865 -230.696004) (xy 363.361985 -230.75118) (xy 363.362494 -230.779066) (xy 363.361985 -230.806952)
			(xy 363.353865 -230.862128) (xy 363.337797 -230.915535) (xy 363.314125 -230.966032) (xy 363.283352 -231.012545)
			(xy 363.246135 -231.054082) (xy 363.203267 -231.089757) (xy 363.155661 -231.118811) (xy 363.104332 -231.140623)
			(xy 363.050375 -231.154729) (xy 362.994938 -231.160829) (xy 362.939204 -231.158792) (xy 362.884361 -231.148662)
			(xy 362.831577 -231.130655) (xy 362.781977 -231.105154) (xy 362.736619 -231.072703) (xy 362.69647 -231.033994)
			(xy 362.662384 -230.989851) (xy 362.635088 -230.941216) (xy 362.615165 -230.889125) (xy 362.603039 -230.834688)
			(xy 362.598968 -230.779066) (xy 360.347284 -230.779066) (xy 360.317702 -230.824436) (xy 360.281279 -230.865777)
			(xy 360.239284 -230.901444) (xy 360.216196 -230.91648) (xy 360.205978 -230.923705) (xy 360.193587 -230.94541)
			(xy 360.192574 -230.957882) (xy 360.190034 -231.042464) (xy 360.190351 -231.055046) (xy 360.201519 -231.077561)
			(xy 360.21137 -231.08539) (xy 360.2323 -231.100762) (xy 360.270123 -231.136347) (xy 360.302772 -231.176731)
			(xy 360.32372 -231.211374) (xy 361.843572 -231.211374) (xy 361.847643 -231.155752) (xy 361.859769 -231.101315)
			(xy 361.879692 -231.049224) (xy 361.906988 -231.000589) (xy 361.941074 -230.956446) (xy 361.981223 -230.917737)
			(xy 362.026581 -230.885286) (xy 362.076181 -230.859785) (xy 362.128965 -230.841778) (xy 362.183808 -230.831648)
			(xy 362.239542 -230.829611) (xy 362.294979 -230.835711) (xy 362.348936 -230.849817) (xy 362.400265 -230.871629)
			(xy 362.447871 -230.900683) (xy 362.490739 -230.936358) (xy 362.527956 -230.977895) (xy 362.558729 -231.024408)
			(xy 362.582401 -231.074905) (xy 362.598469 -231.128312) (xy 362.606589 -231.183488) (xy 362.607098 -231.211374)
			(xy 362.606589 -231.23926) (xy 362.598469 -231.294436) (xy 362.582401 -231.347843) (xy 362.558729 -231.39834)
			(xy 362.527956 -231.444853) (xy 362.490739 -231.48639) (xy 362.447871 -231.522065) (xy 362.400265 -231.551119)
			(xy 362.348936 -231.572931) (xy 362.294979 -231.587037) (xy 362.239542 -231.593137) (xy 362.183808 -231.5911)
			(xy 362.128965 -231.58097) (xy 362.076181 -231.562963) (xy 362.026581 -231.537462) (xy 361.981223 -231.505011)
			(xy 361.941074 -231.466302) (xy 361.906988 -231.422159) (xy 361.879692 -231.373524) (xy 361.859769 -231.321433)
			(xy 361.847643 -231.266996) (xy 361.843572 -231.211374) (xy 360.32372 -231.211374) (xy 360.329643 -231.22117)
			(xy 360.35024 -231.268842) (xy 360.364182 -231.318867) (xy 360.371213 -231.37032) (xy 360.371644 -231.396286)
			(xy 360.371158 -231.423537) (xy 360.363402 -231.477485) (xy 360.348047 -231.52978) (xy 360.325405 -231.579357)
			(xy 360.295939 -231.625207) (xy 360.260248 -231.666398) (xy 360.219057 -231.702089) (xy 360.173207 -231.731555)
			(xy 360.12363 -231.754197) (xy 360.071335 -231.769552) (xy 360.017387 -231.777308) (xy 359.962885 -231.777308)
			(xy 359.908937 -231.769552) (xy 359.856642 -231.754197) (xy 359.807065 -231.731555) (xy 359.761215 -231.702089)
			(xy 359.720024 -231.666398) (xy 359.684333 -231.625207) (xy 359.654867 -231.579357) (xy 359.632225 -231.52978)
			(xy 359.61687 -231.477485) (xy 359.609114 -231.423537) (xy 359.608628 -231.396286) (xy 359.609125 -231.368739)
			(xy 359.617045 -231.314216) (xy 359.632733 -231.261402) (xy 359.655861 -231.211397) (xy 359.685948 -231.165243)
			(xy 359.722366 -231.123902) (xy 359.764357 -231.088234) (xy 359.787444 -231.073198) (xy 359.797679 -231.065994)
			(xy 359.810059 -231.044273) (xy 359.811066 -231.031796) (xy 359.813606 -230.947214) (xy 359.813325 -230.934628)
			(xy 359.802134 -230.912111) (xy 359.79227 -230.904288) (xy 359.762806 -230.88092) (xy 359.762552 -230.880666)
			(xy 359.755457 -230.875091) (xy 359.738547 -230.868839) (xy 359.729532 -230.868474) (xy 359.662476 -230.868474)
			(xy 359.653459 -230.868825) (xy 359.636542 -230.875077) (xy 359.629456 -230.880666) (xy 359.629456 -230.88092)
			(xy 359.629202 -230.88092) (xy 359.608269 -230.898561) (xy 359.562301 -230.928285) (xy 359.512555 -230.951131)
			(xy 359.460053 -230.966627) (xy 359.405875 -230.974456) (xy 359.351133 -230.974456) (xy 359.296955 -230.966627)
			(xy 359.244453 -230.951131) (xy 359.194707 -230.928285) (xy 359.148739 -230.898561) (xy 359.127806 -230.88092)
			(xy 359.127552 -230.880666) (xy 359.120457 -230.875091) (xy 359.103547 -230.868839) (xy 359.094532 -230.868474)
			(xy 359.027476 -230.868474) (xy 359.018459 -230.868825) (xy 359.001542 -230.875077) (xy 358.994456 -230.880666)
			(xy 358.994456 -230.88092) (xy 358.994202 -230.88092) (xy 358.973269 -230.898561) (xy 358.927301 -230.928285)
			(xy 358.877555 -230.951131) (xy 358.825053 -230.966627) (xy 358.770875 -230.974456) (xy 358.716133 -230.974456)
			(xy 358.661955 -230.966627) (xy 358.609453 -230.951131) (xy 358.559707 -230.928285) (xy 358.513739 -230.898561)
			(xy 358.492806 -230.88092) (xy 358.492552 -230.880666) (xy 358.485457 -230.875091) (xy 358.468547 -230.868839)
			(xy 358.459532 -230.868474) (xy 358.392476 -230.868474) (xy 358.383459 -230.868825) (xy 358.366542 -230.875077)
			(xy 358.359456 -230.880666) (xy 358.359456 -230.88092) (xy 358.359202 -230.88092) (xy 358.338283 -230.898575)
			(xy 358.292306 -230.928284) (xy 358.242555 -230.951116) (xy 358.190052 -230.966604) (xy 358.135874 -230.974428)
			(xy 358.108504 -230.9749) (xy 358.08125 -230.974453) (xy 358.027298 -230.966696) (xy 357.974998 -230.95134)
			(xy 357.925417 -230.928698) (xy 357.879562 -230.899229) (xy 357.838368 -230.863535) (xy 357.802673 -230.822341)
			(xy 357.773204 -230.776487) (xy 357.750561 -230.726905) (xy 357.735205 -230.674606) (xy 357.727447 -230.620654)
			(xy 356.528839 -230.620654) (xy 356.536497 -230.672694) (xy 356.537006 -230.70058) (xy 356.536497 -230.728466)
			(xy 356.528377 -230.783642) (xy 356.512309 -230.837049) (xy 356.488637 -230.887546) (xy 356.457864 -230.934059)
			(xy 356.420647 -230.975596) (xy 356.377779 -231.011271) (xy 356.330173 -231.040325) (xy 356.278844 -231.062137)
			(xy 356.224887 -231.076243) (xy 356.16945 -231.082343) (xy 356.113716 -231.080306) (xy 356.058873 -231.070176)
			(xy 356.006089 -231.052169) (xy 355.956489 -231.026668) (xy 355.911131 -230.994217) (xy 355.870982 -230.955508)
			(xy 355.836896 -230.911365) (xy 355.8096 -230.86273) (xy 355.789677 -230.810639) (xy 355.777551 -230.756202)
			(xy 355.77348 -230.70058) (xy 354.638356 -230.70058) (xy 354.638356 -231.428798) (xy 358.706164 -231.428798)
			(xy 358.710235 -231.373176) (xy 358.722361 -231.318739) (xy 358.742284 -231.266648) (xy 358.76958 -231.218013)
			(xy 358.803666 -231.17387) (xy 358.843815 -231.135161) (xy 358.889173 -231.10271) (xy 358.938773 -231.077209)
			(xy 358.991557 -231.059202) (xy 359.0464 -231.049072) (xy 359.102134 -231.047035) (xy 359.157571 -231.053135)
			(xy 359.211528 -231.067241) (xy 359.262857 -231.089053) (xy 359.310463 -231.118107) (xy 359.353331 -231.153782)
			(xy 359.390548 -231.195319) (xy 359.421321 -231.241832) (xy 359.444993 -231.292329) (xy 359.461061 -231.345736)
			(xy 359.469181 -231.400912) (xy 359.46969 -231.428798) (xy 359.469181 -231.456684) (xy 359.461061 -231.51186)
			(xy 359.444993 -231.565267) (xy 359.421321 -231.615764) (xy 359.390548 -231.662277) (xy 359.353331 -231.703814)
			(xy 359.310463 -231.739489) (xy 359.262857 -231.768543) (xy 359.211528 -231.790355) (xy 359.157571 -231.804461)
			(xy 359.102134 -231.810561) (xy 359.0464 -231.808524) (xy 358.991557 -231.798394) (xy 358.938773 -231.780387)
			(xy 358.889173 -231.754886) (xy 358.843815 -231.722435) (xy 358.803666 -231.683726) (xy 358.76958 -231.639583)
			(xy 358.742284 -231.590948) (xy 358.722361 -231.538857) (xy 358.710235 -231.48442) (xy 358.706164 -231.428798)
			(xy 354.638356 -231.428798) (xy 354.638356 -232.160572) (xy 354.638447 -232.164515) (xy 354.639729 -232.172298)
			(xy 354.640896 -232.176066) (xy 354.643436 -232.183686) (xy 354.64496 -232.186734) (xy 354.65688 -232.212185)
			(xy 354.673942 -232.265732) (xy 354.682955 -232.321204) (xy 354.683822 -232.349294) (xy 354.683822 -232.355644)
			(xy 354.683236 -232.385018) (xy 354.674153 -232.443062) (xy 354.6563 -232.499034) (xy 354.64369 -232.52557)
			(xy 354.640896 -232.531158) (xy 354.638356 -232.54208) (xy 354.638356 -232.602024) (xy 354.638978 -232.613869)
			(xy 354.649574 -232.635058) (xy 354.658676 -232.642664) (xy 356.1334 -232.642664) (xy 356.141593 -232.642354)
			(xy 356.157137 -232.637169) (xy 356.16388 -232.632504) (xy 356.169214 -232.627932) (xy 356.435152 -232.36174)
			(xy 356.439724 -232.35539) (xy 356.442772 -232.350056) (xy 356.44328 -232.348278) (xy 356.451518 -232.322385)
			(xy 356.474299 -232.273056) (xy 356.503844 -232.227455) (xy 356.539554 -232.186504) (xy 356.58071 -232.151028)
			(xy 356.62648 -232.121746) (xy 356.675939 -232.099248) (xy 356.728087 -232.083989) (xy 356.781872 -232.076278)
			(xy 356.80904 -232.075736) (xy 356.83629 -232.076202) (xy 356.890234 -232.083964) (xy 356.942525 -232.099324)
			(xy 356.992097 -232.121969) (xy 357.037942 -232.151439) (xy 357.079126 -232.187133) (xy 357.114811 -232.228325)
			(xy 357.144271 -232.274177) (xy 357.166906 -232.323754) (xy 357.182254 -232.376048) (xy 357.190004 -232.429994)
			(xy 357.190548 -232.457244) (xy 357.19006 -232.484482) (xy 357.182306 -232.538404) (xy 357.16696 -232.590675)
			(xy 357.144337 -232.640231) (xy 357.114894 -232.686066) (xy 357.079232 -232.727248) (xy 357.038075 -232.762938)
			(xy 356.99226 -232.792411) (xy 356.942719 -232.815069) (xy 356.916736 -232.823258) (xy 356.910386 -232.82529)
			(xy 356.526592 -233.209084) (xy 356.507034 -233.227118) (xy 356.497262 -233.235236) (xy 356.476664 -233.25011)
			(xy 356.465886 -233.256836) (xy 356.465124 -233.257344) (xy 356.456996 -233.263948) (xy 356.439978 -233.280966)
			(xy 356.43258 -233.287813) (xy 356.413982 -233.295545) (xy 356.40391 -233.295952) (xy 356.374192 -233.295952)
			(xy 356.36835 -233.297222) (xy 356.349573 -233.30137) (xy 356.311377 -233.305826) (xy 356.29215 -233.306112)
			(xy 354.658676 -233.306112) (xy 354.649569 -233.313715) (xy 354.638963 -233.334905) (xy 354.638356 -233.346752)
			(xy 354.638356 -236.583555) (xy 376.280851 -236.583555) (xy 376.280851 -236.529045) (xy 376.288609 -236.475091)
			(xy 376.303967 -236.42279) (xy 376.326613 -236.373207) (xy 376.356084 -236.327352) (xy 376.391782 -236.286158)
			(xy 376.432979 -236.250464) (xy 376.478837 -236.220996) (xy 376.528422 -236.198355) (xy 376.580724 -236.183002)
			(xy 376.634679 -236.175249) (xy 376.661934 -236.174788) (xy 376.688833 -236.175297) (xy 376.7421 -236.182847)
			(xy 376.793777 -236.197806) (xy 376.84284 -236.219877) (xy 376.888315 -236.248623) (xy 376.9293 -236.283474)
			(xy 376.964982 -236.323737) (xy 376.994652 -236.368614) (xy 377.017723 -236.417215) (xy 377.02617 -236.442758)
			(xy 377.02617 -236.443012) (xy 377.029879 -236.453021) (xy 377.044074 -236.468936) (xy 377.053602 -236.473746)
			(xy 377.132342 -236.509814) (xy 377.153678 -236.510068) (xy 377.163838 -236.505496) (xy 377.188006 -236.495391)
			(xy 377.238415 -236.481146) (xy 377.290301 -236.473942) (xy 377.316492 -236.473492) (xy 377.317 -236.473492)
			(xy 377.344251 -236.473978) (xy 377.398199 -236.481734) (xy 377.450494 -236.497089) (xy 377.500071 -236.519731)
			(xy 377.545921 -236.549197) (xy 377.587112 -236.584888) (xy 377.622803 -236.626079) (xy 377.652269 -236.671929)
			(xy 377.674911 -236.721506) (xy 377.690266 -236.773801) (xy 377.698022 -236.827749) (xy 377.698022 -236.882251)
			(xy 377.690266 -236.936199) (xy 377.674911 -236.988494) (xy 377.652269 -237.038071) (xy 377.622803 -237.083921)
			(xy 377.587112 -237.125112) (xy 377.545921 -237.160803) (xy 377.500071 -237.190269) (xy 377.450494 -237.212911)
			(xy 377.398199 -237.228266) (xy 377.344404 -237.236) (xy 379.871984 -237.236) (xy 379.876055 -237.180378)
			(xy 379.888181 -237.125941) (xy 379.908104 -237.07385) (xy 379.9354 -237.025215) (xy 379.969486 -236.981072)
			(xy 380.009635 -236.942363) (xy 380.054993 -236.909912) (xy 380.104593 -236.884411) (xy 380.157377 -236.866404)
			(xy 380.21222 -236.856274) (xy 380.267954 -236.854237) (xy 380.323391 -236.860337) (xy 380.377348 -236.874443)
			(xy 380.428677 -236.896255) (xy 380.476283 -236.925309) (xy 380.519151 -236.960984) (xy 380.556368 -237.002521)
			(xy 380.587141 -237.049034) (xy 380.610813 -237.099531) (xy 380.626881 -237.152938) (xy 380.635001 -237.208114)
			(xy 380.63551 -237.236) (xy 380.635001 -237.263886) (xy 380.626881 -237.319062) (xy 380.610813 -237.372469)
			(xy 380.587141 -237.422966) (xy 380.556368 -237.469479) (xy 380.519151 -237.511016) (xy 380.476283 -237.546691)
			(xy 380.428677 -237.575745) (xy 380.377348 -237.597557) (xy 380.323391 -237.611663) (xy 380.267954 -237.617763)
			(xy 380.21222 -237.615726) (xy 380.157377 -237.605596) (xy 380.104593 -237.587589) (xy 380.054993 -237.562088)
			(xy 380.009635 -237.529637) (xy 379.969486 -237.490928) (xy 379.9354 -237.446785) (xy 379.908104 -237.39815)
			(xy 379.888181 -237.346059) (xy 379.876055 -237.291622) (xy 379.871984 -237.236) (xy 377.344404 -237.236)
			(xy 377.344251 -237.236022) (xy 377.317 -237.236508) (xy 377.290099 -237.236061) (xy 377.236829 -237.228502)
			(xy 377.18515 -237.213534) (xy 377.136087 -237.191454) (xy 377.090612 -237.1627) (xy 377.049628 -237.127843)
			(xy 377.013948 -237.087573) (xy 376.984279 -237.04269) (xy 376.96121 -236.994083) (xy 376.952764 -236.968538)
			(xy 376.952764 -236.968284) (xy 376.949083 -236.958262) (xy 376.934869 -236.942352) (xy 376.925332 -236.93755)
			(xy 376.846592 -236.901482) (xy 376.825256 -236.901228) (xy 376.815096 -236.9058) (xy 376.790924 -236.915894)
			(xy 376.740517 -236.930143) (xy 376.688633 -236.937352) (xy 376.662442 -236.937804) (xy 376.661934 -236.937804)
			(xy 376.634679 -236.937351) (xy 376.580724 -236.929598) (xy 376.528422 -236.914245) (xy 376.478837 -236.891604)
			(xy 376.432979 -236.862136) (xy 376.391782 -236.826442) (xy 376.356084 -236.785248) (xy 376.326613 -236.739393)
			(xy 376.303967 -236.68981) (xy 376.288609 -236.637509) (xy 376.280851 -236.583555) (xy 354.638356 -236.583555)
			(xy 354.638356 -237.95863) (xy 359.48569 -237.95863) (xy 359.489761 -237.903008) (xy 359.501887 -237.848571)
			(xy 359.52181 -237.79648) (xy 359.549106 -237.747845) (xy 359.583192 -237.703702) (xy 359.623341 -237.664993)
			(xy 359.668699 -237.632542) (xy 359.718299 -237.607041) (xy 359.771083 -237.589034) (xy 359.825926 -237.578904)
			(xy 359.88166 -237.576867) (xy 359.937097 -237.582967) (xy 359.991054 -237.597073) (xy 360.042383 -237.618885)
			(xy 360.089989 -237.647939) (xy 360.132857 -237.683614) (xy 360.170074 -237.725151) (xy 360.200847 -237.771664)
			(xy 360.224519 -237.822161) (xy 360.240587 -237.875568) (xy 360.248707 -237.930744) (xy 360.248901 -237.941358)
			(xy 361.54182 -237.941358) (xy 361.545891 -237.885736) (xy 361.558017 -237.831299) (xy 361.57794 -237.779208)
			(xy 361.605236 -237.730573) (xy 361.639322 -237.68643) (xy 361.679471 -237.647721) (xy 361.724829 -237.61527)
			(xy 361.774429 -237.589769) (xy 361.827213 -237.571762) (xy 361.882056 -237.561632) (xy 361.93779 -237.559595)
			(xy 361.993227 -237.565695) (xy 362.047184 -237.579801) (xy 362.098513 -237.601613) (xy 362.146119 -237.630667)
			(xy 362.188987 -237.666342) (xy 362.226204 -237.707879) (xy 362.256977 -237.754392) (xy 362.280649 -237.804889)
			(xy 362.296717 -237.858296) (xy 362.304837 -237.913472) (xy 362.305346 -237.941358) (xy 362.304837 -237.969244)
			(xy 362.30068 -237.997492) (xy 362.81436 -237.997492) (xy 362.818431 -237.94187) (xy 362.830557 -237.887433)
			(xy 362.85048 -237.835342) (xy 362.877776 -237.786707) (xy 362.911862 -237.742564) (xy 362.952011 -237.703855)
			(xy 362.997369 -237.671404) (xy 363.046969 -237.645903) (xy 363.099753 -237.627896) (xy 363.154596 -237.617766)
			(xy 363.21033 -237.615729) (xy 363.265767 -237.621829) (xy 363.319724 -237.635935) (xy 363.371053 -237.657747)
			(xy 363.418659 -237.686801) (xy 363.461527 -237.722476) (xy 363.480812 -237.744) (xy 364.239046 -237.744)
			(xy 364.243117 -237.688378) (xy 364.255243 -237.633941) (xy 364.275166 -237.58185) (xy 364.302462 -237.533215)
			(xy 364.336548 -237.489072) (xy 364.376697 -237.450363) (xy 364.422055 -237.417912) (xy 364.471655 -237.392411)
			(xy 364.524439 -237.374404) (xy 364.579282 -237.364274) (xy 364.635016 -237.362237) (xy 364.690453 -237.368337)
			(xy 364.74441 -237.382443) (xy 364.795739 -237.404255) (xy 364.843345 -237.433309) (xy 364.886213 -237.468984)
			(xy 364.92343 -237.510521) (xy 364.954203 -237.557034) (xy 364.977875 -237.607531) (xy 364.993943 -237.660938)
			(xy 365.002063 -237.716114) (xy 365.002572 -237.744) (xy 365.002317 -237.75797) (xy 370.937534 -237.75797)
			(xy 370.941605 -237.702348) (xy 370.953731 -237.647911) (xy 370.973654 -237.59582) (xy 371.00095 -237.547185)
			(xy 371.035036 -237.503042) (xy 371.075185 -237.464333) (xy 371.120543 -237.431882) (xy 371.170143 -237.406381)
			(xy 371.222927 -237.388374) (xy 371.27777 -237.378244) (xy 371.333504 -237.376207) (xy 371.388941 -237.382307)
			(xy 371.442898 -237.396413) (xy 371.494227 -237.418225) (xy 371.541833 -237.447279) (xy 371.584701 -237.482954)
			(xy 371.621918 -237.524491) (xy 371.652691 -237.571004) (xy 371.676363 -237.621501) (xy 371.692431 -237.674908)
			(xy 371.700551 -237.730084) (xy 371.70106 -237.75797) (xy 371.700551 -237.785856) (xy 371.692431 -237.841032)
			(xy 371.676363 -237.894439) (xy 371.652691 -237.944936) (xy 371.621918 -237.991449) (xy 371.584701 -238.032986)
			(xy 371.541833 -238.068661) (xy 371.494227 -238.097715) (xy 371.442898 -238.119527) (xy 371.388941 -238.133633)
			(xy 371.333504 -238.139733) (xy 371.27777 -238.137696) (xy 371.222927 -238.127566) (xy 371.170143 -238.109559)
			(xy 371.120543 -238.084058) (xy 371.075185 -238.051607) (xy 371.035036 -238.012898) (xy 371.00095 -237.968755)
			(xy 370.973654 -237.92012) (xy 370.953731 -237.868029) (xy 370.941605 -237.813592) (xy 370.937534 -237.75797)
			(xy 365.002317 -237.75797) (xy 365.002063 -237.771886) (xy 364.993943 -237.827062) (xy 364.977875 -237.880469)
			(xy 364.954203 -237.930966) (xy 364.92343 -237.977479) (xy 364.886213 -238.019016) (xy 364.843345 -238.054691)
			(xy 364.795739 -238.083745) (xy 364.74441 -238.105557) (xy 364.690453 -238.119663) (xy 364.635016 -238.125763)
			(xy 364.579282 -238.123726) (xy 364.524439 -238.113596) (xy 364.471655 -238.095589) (xy 364.422055 -238.070088)
			(xy 364.376697 -238.037637) (xy 364.336548 -237.998928) (xy 364.302462 -237.954785) (xy 364.275166 -237.90615)
			(xy 364.255243 -237.854059) (xy 364.243117 -237.799622) (xy 364.239046 -237.744) (xy 363.480812 -237.744)
			(xy 363.498744 -237.764013) (xy 363.529517 -237.810526) (xy 363.553189 -237.861023) (xy 363.569257 -237.91443)
			(xy 363.577377 -237.969606) (xy 363.577886 -237.997492) (xy 363.577377 -238.025378) (xy 363.569257 -238.080554)
			(xy 363.553189 -238.133961) (xy 363.529517 -238.184458) (xy 363.498744 -238.230971) (xy 363.461527 -238.272508)
			(xy 363.418659 -238.308183) (xy 363.371053 -238.337237) (xy 363.319724 -238.359049) (xy 363.265767 -238.373155)
			(xy 363.21033 -238.379255) (xy 363.154596 -238.377218) (xy 363.099753 -238.367088) (xy 363.046969 -238.349081)
			(xy 362.997369 -238.32358) (xy 362.952011 -238.291129) (xy 362.911862 -238.25242) (xy 362.877776 -238.208277)
			(xy 362.85048 -238.159642) (xy 362.830557 -238.107551) (xy 362.818431 -238.053114) (xy 362.81436 -237.997492)
			(xy 362.30068 -237.997492) (xy 362.296717 -238.02442) (xy 362.280649 -238.077827) (xy 362.256977 -238.128324)
			(xy 362.226204 -238.174837) (xy 362.188987 -238.216374) (xy 362.146119 -238.252049) (xy 362.098513 -238.281103)
			(xy 362.047184 -238.302915) (xy 361.993227 -238.317021) (xy 361.93779 -238.323121) (xy 361.882056 -238.321084)
			(xy 361.827213 -238.310954) (xy 361.774429 -238.292947) (xy 361.724829 -238.267446) (xy 361.679471 -238.234995)
			(xy 361.639322 -238.196286) (xy 361.605236 -238.152143) (xy 361.57794 -238.103508) (xy 361.558017 -238.051417)
			(xy 361.545891 -237.99698) (xy 361.54182 -237.941358) (xy 360.248901 -237.941358) (xy 360.249216 -237.95863)
			(xy 360.248707 -237.986516) (xy 360.240587 -238.041692) (xy 360.224519 -238.095099) (xy 360.200847 -238.145596)
			(xy 360.170074 -238.192109) (xy 360.132857 -238.233646) (xy 360.089989 -238.269321) (xy 360.042383 -238.298375)
			(xy 359.991054 -238.320187) (xy 359.937097 -238.334293) (xy 359.88166 -238.340393) (xy 359.825926 -238.338356)
			(xy 359.771083 -238.328226) (xy 359.718299 -238.310219) (xy 359.668699 -238.284718) (xy 359.623341 -238.252267)
			(xy 359.583192 -238.213558) (xy 359.549106 -238.169415) (xy 359.52181 -238.12078) (xy 359.501887 -238.068689)
			(xy 359.489761 -238.014252) (xy 359.48569 -237.95863) (xy 354.638356 -237.95863) (xy 354.638356 -238.588296)
			(xy 376.382278 -238.588296) (xy 376.386349 -238.532674) (xy 376.398475 -238.478237) (xy 376.418398 -238.426146)
			(xy 376.445694 -238.377511) (xy 376.47978 -238.333368) (xy 376.519929 -238.294659) (xy 376.565287 -238.262208)
			(xy 376.614887 -238.236707) (xy 376.667671 -238.2187) (xy 376.722514 -238.20857) (xy 376.778248 -238.206533)
			(xy 376.833685 -238.212633) (xy 376.887642 -238.226739) (xy 376.938971 -238.248551) (xy 376.986577 -238.277605)
			(xy 377.029445 -238.31328) (xy 377.064889 -238.352838) (xy 381.07823 -238.352838) (xy 381.082301 -238.297216)
			(xy 381.094427 -238.242779) (xy 381.11435 -238.190688) (xy 381.141646 -238.142053) (xy 381.175732 -238.09791)
			(xy 381.215881 -238.059201) (xy 381.261239 -238.02675) (xy 381.310839 -238.001249) (xy 381.363623 -237.983242)
			(xy 381.418466 -237.973112) (xy 381.4742 -237.971075) (xy 381.529637 -237.977175) (xy 381.583594 -237.991281)
			(xy 381.599405 -237.998) (xy 383.030982 -237.998) (xy 383.035053 -237.942378) (xy 383.047179 -237.887941)
			(xy 383.067102 -237.83585) (xy 383.094398 -237.787215) (xy 383.128484 -237.743072) (xy 383.168633 -237.704363)
			(xy 383.213991 -237.671912) (xy 383.263591 -237.646411) (xy 383.316375 -237.628404) (xy 383.371218 -237.618274)
			(xy 383.426952 -237.616237) (xy 383.482389 -237.622337) (xy 383.536346 -237.636443) (xy 383.587675 -237.658255)
			(xy 383.635281 -237.687309) (xy 383.678149 -237.722984) (xy 383.715366 -237.764521) (xy 383.746139 -237.811034)
			(xy 383.769811 -237.861531) (xy 383.785879 -237.914938) (xy 383.793999 -237.970114) (xy 383.794508 -237.998)
			(xy 383.793999 -238.025886) (xy 383.785879 -238.081062) (xy 383.769811 -238.134469) (xy 383.746139 -238.184966)
			(xy 383.727668 -238.212884) (xy 386.259068 -238.212884) (xy 386.263139 -238.157262) (xy 386.275265 -238.102825)
			(xy 386.295188 -238.050734) (xy 386.322484 -238.002099) (xy 386.35657 -237.957956) (xy 386.396719 -237.919247)
			(xy 386.442077 -237.886796) (xy 386.491677 -237.861295) (xy 386.544461 -237.843288) (xy 386.599304 -237.833158)
			(xy 386.655038 -237.831121) (xy 386.710475 -237.837221) (xy 386.764432 -237.851327) (xy 386.815761 -237.873139)
			(xy 386.863367 -237.902193) (xy 386.906235 -237.937868) (xy 386.943452 -237.979405) (xy 386.974225 -238.025918)
			(xy 386.997897 -238.076415) (xy 387.013965 -238.129822) (xy 387.022085 -238.184998) (xy 387.022594 -238.212884)
			(xy 387.022085 -238.24077) (xy 387.013965 -238.295946) (xy 386.997897 -238.349353) (xy 386.974225 -238.39985)
			(xy 386.943452 -238.446363) (xy 386.906235 -238.4879) (xy 386.863367 -238.523575) (xy 386.815761 -238.552629)
			(xy 386.764432 -238.574441) (xy 386.710475 -238.588547) (xy 386.655038 -238.594647) (xy 386.599304 -238.59261)
			(xy 386.544461 -238.58248) (xy 386.491677 -238.564473) (xy 386.442077 -238.538972) (xy 386.396719 -238.506521)
			(xy 386.35657 -238.467812) (xy 386.322484 -238.423669) (xy 386.295188 -238.375034) (xy 386.275265 -238.322943)
			(xy 386.263139 -238.268506) (xy 386.259068 -238.212884) (xy 383.727668 -238.212884) (xy 383.715366 -238.231479)
			(xy 383.678149 -238.273016) (xy 383.635281 -238.308691) (xy 383.587675 -238.337745) (xy 383.536346 -238.359557)
			(xy 383.482389 -238.373663) (xy 383.426952 -238.379763) (xy 383.371218 -238.377726) (xy 383.316375 -238.367596)
			(xy 383.263591 -238.349589) (xy 383.213991 -238.324088) (xy 383.168633 -238.291637) (xy 383.128484 -238.252928)
			(xy 383.094398 -238.208785) (xy 383.067102 -238.16015) (xy 383.047179 -238.108059) (xy 383.035053 -238.053622)
			(xy 383.030982 -237.998) (xy 381.599405 -237.998) (xy 381.634923 -238.013093) (xy 381.682529 -238.042147)
			(xy 381.725397 -238.077822) (xy 381.762614 -238.119359) (xy 381.793387 -238.165872) (xy 381.817059 -238.216369)
			(xy 381.833127 -238.269776) (xy 381.841247 -238.324952) (xy 381.841756 -238.352838) (xy 381.841247 -238.380724)
			(xy 381.833127 -238.4359) (xy 381.817059 -238.489307) (xy 381.793387 -238.539804) (xy 381.762614 -238.586317)
			(xy 381.725397 -238.627854) (xy 381.682529 -238.663529) (xy 381.634923 -238.692583) (xy 381.583594 -238.714395)
			(xy 381.529637 -238.728501) (xy 381.4742 -238.734601) (xy 381.418466 -238.732564) (xy 381.363623 -238.722434)
			(xy 381.310839 -238.704427) (xy 381.261239 -238.678926) (xy 381.215881 -238.646475) (xy 381.175732 -238.607766)
			(xy 381.141646 -238.563623) (xy 381.11435 -238.514988) (xy 381.094427 -238.462897) (xy 381.082301 -238.40846)
			(xy 381.07823 -238.352838) (xy 377.064889 -238.352838) (xy 377.066662 -238.354817) (xy 377.097435 -238.40133)
			(xy 377.121107 -238.451827) (xy 377.137175 -238.505234) (xy 377.145295 -238.56041) (xy 377.145804 -238.588296)
			(xy 377.145295 -238.616182) (xy 377.137175 -238.671358) (xy 377.121107 -238.724765) (xy 377.097435 -238.775262)
			(xy 377.073755 -238.811054) (xy 379.62027 -238.811054) (xy 379.624341 -238.755432) (xy 379.636467 -238.700995)
			(xy 379.65639 -238.648904) (xy 379.683686 -238.600269) (xy 379.717772 -238.556126) (xy 379.757921 -238.517417)
			(xy 379.803279 -238.484966) (xy 379.852879 -238.459465) (xy 379.905663 -238.441458) (xy 379.960506 -238.431328)
			(xy 380.01624 -238.429291) (xy 380.071677 -238.435391) (xy 380.125634 -238.449497) (xy 380.176963 -238.471309)
			(xy 380.224569 -238.500363) (xy 380.267437 -238.536038) (xy 380.304654 -238.577575) (xy 380.335427 -238.624088)
			(xy 380.359099 -238.674585) (xy 380.375167 -238.727992) (xy 380.383287 -238.783168) (xy 380.383796 -238.811054)
			(xy 380.383287 -238.83894) (xy 380.375167 -238.894116) (xy 380.359099 -238.947523) (xy 380.335427 -238.99802)
			(xy 380.304654 -239.044533) (xy 380.267437 -239.08607) (xy 380.224569 -239.121745) (xy 380.176963 -239.150799)
			(xy 380.125634 -239.172611) (xy 380.071677 -239.186717) (xy 380.01624 -239.192817) (xy 379.960506 -239.19078)
			(xy 379.905663 -239.18065) (xy 379.852879 -239.162643) (xy 379.803279 -239.137142) (xy 379.757921 -239.104691)
			(xy 379.717772 -239.065982) (xy 379.683686 -239.021839) (xy 379.65639 -238.973204) (xy 379.636467 -238.921113)
			(xy 379.624341 -238.866676) (xy 379.62027 -238.811054) (xy 377.073755 -238.811054) (xy 377.066662 -238.821775)
			(xy 377.029445 -238.863312) (xy 376.986577 -238.898987) (xy 376.938971 -238.928041) (xy 376.887642 -238.949853)
			(xy 376.833685 -238.963959) (xy 376.778248 -238.970059) (xy 376.722514 -238.968022) (xy 376.667671 -238.957892)
			(xy 376.614887 -238.939885) (xy 376.565287 -238.914384) (xy 376.519929 -238.881933) (xy 376.47978 -238.843224)
			(xy 376.445694 -238.799081) (xy 376.418398 -238.750446) (xy 376.398475 -238.698355) (xy 376.386349 -238.643918)
			(xy 376.382278 -238.588296) (xy 354.638356 -238.588296) (xy 354.638356 -239.367651) (xy 359.344968 -239.367651)
			(xy 359.344968 -239.313149) (xy 359.352724 -239.259202) (xy 359.368078 -239.206908) (xy 359.390718 -239.157331)
			(xy 359.420183 -239.111481) (xy 359.455873 -239.07029) (xy 359.497061 -239.034597) (xy 359.54291 -239.00513)
			(xy 359.592485 -238.982487) (xy 359.644779 -238.967129) (xy 359.698725 -238.959369) (xy 359.725976 -238.958882)
			(xy 359.751859 -238.959321) (xy 359.80315 -238.966323) (xy 359.853022 -238.980201) (xy 359.900556 -239.000701)
			(xy 359.944879 -239.027445) (xy 359.985176 -239.05994) (xy 360.020704 -239.09759) (xy 360.03611 -239.118394)
			(xy 360.044539 -239.129337) (xy 360.066064 -239.14663) (xy 360.091429 -239.157537) (xy 360.118787 -239.161263)
			(xy 360.146145 -239.157537) (xy 360.17151 -239.14663) (xy 360.193035 -239.129337) (xy 360.201464 -239.118394)
			(xy 360.21688 -239.097598) (xy 360.252406 -239.059947) (xy 360.292701 -239.02745) (xy 360.337022 -239.000704)
			(xy 360.384555 -238.980202) (xy 360.434425 -238.966321) (xy 360.485715 -238.959315) (xy 360.511598 -238.958882)
			(xy 360.53885 -238.959365) (xy 360.5928 -238.967122) (xy 360.645097 -238.982477) (xy 360.694676 -239.005119)
			(xy 360.740528 -239.034586) (xy 360.78172 -239.070279) (xy 360.817413 -239.11147) (xy 360.84688 -239.157322)
			(xy 360.869522 -239.206901) (xy 360.884878 -239.259198) (xy 360.892635 -239.313148) (xy 360.892635 -239.367652)
			(xy 360.884878 -239.421602) (xy 360.869522 -239.473899) (xy 360.84688 -239.523478) (xy 360.817413 -239.56933)
			(xy 360.78172 -239.610521) (xy 360.740528 -239.646214) (xy 360.737774 -239.647984) (xy 375.566178 -239.647984)
			(xy 375.566664 -239.620733) (xy 375.57442 -239.566785) (xy 375.589775 -239.51449) (xy 375.612417 -239.464913)
			(xy 375.641883 -239.419063) (xy 375.677574 -239.377872) (xy 375.718765 -239.342181) (xy 375.764615 -239.312715)
			(xy 375.814192 -239.290073) (xy 375.866487 -239.274718) (xy 375.920435 -239.266962) (xy 375.974937 -239.266962)
			(xy 376.028885 -239.274718) (xy 376.08118 -239.290073) (xy 376.130757 -239.312715) (xy 376.176607 -239.342181)
			(xy 376.217798 -239.377872) (xy 376.253489 -239.419063) (xy 376.282955 -239.464913) (xy 376.305597 -239.51449)
			(xy 376.320952 -239.566785) (xy 376.328708 -239.620733) (xy 376.329194 -239.647984) (xy 376.328649 -239.677596)
			(xy 376.3195 -239.736109) (xy 376.301419 -239.792505) (xy 376.292104 -239.811052) (xy 383.030982 -239.811052)
			(xy 383.035053 -239.75543) (xy 383.047179 -239.700993) (xy 383.067102 -239.648902) (xy 383.094398 -239.600267)
			(xy 383.128484 -239.556124) (xy 383.168633 -239.517415) (xy 383.213991 -239.484964) (xy 383.263591 -239.459463)
			(xy 383.316375 -239.441456) (xy 383.371218 -239.431326) (xy 383.426952 -239.429289) (xy 383.482389 -239.435389)
			(xy 383.536346 -239.449495) (xy 383.587675 -239.471307) (xy 383.635281 -239.500361) (xy 383.678149 -239.536036)
			(xy 383.715366 -239.577573) (xy 383.746139 -239.624086) (xy 383.769811 -239.674583) (xy 383.785879 -239.72799)
			(xy 383.793999 -239.783166) (xy 383.794508 -239.811052) (xy 383.793999 -239.838938) (xy 383.785879 -239.894114)
			(xy 383.769811 -239.947521) (xy 383.746139 -239.998018) (xy 383.715366 -240.044531) (xy 383.678149 -240.086068)
			(xy 383.635281 -240.121743) (xy 383.587675 -240.150797) (xy 383.536346 -240.172609) (xy 383.482389 -240.186715)
			(xy 383.426952 -240.192815) (xy 383.371218 -240.190778) (xy 383.316375 -240.180648) (xy 383.263591 -240.162641)
			(xy 383.213991 -240.13714) (xy 383.168633 -240.104689) (xy 383.128484 -240.06598) (xy 383.094398 -240.021837)
			(xy 383.067102 -239.973202) (xy 383.047179 -239.921111) (xy 383.035053 -239.866674) (xy 383.030982 -239.811052)
			(xy 376.292104 -239.811052) (xy 376.274839 -239.845429) (xy 376.240401 -239.89361) (xy 376.198931 -239.935891)
			(xy 376.151425 -239.971256) (xy 376.125486 -239.98555) (xy 376.113296 -239.99239) (xy 376.092985 -240.011581)
			(xy 376.078637 -240.035561) (xy 376.071328 -240.062532) (xy 376.071605 -240.090474) (xy 376.079448 -240.117295)
			(xy 376.094268 -240.140985) (xy 376.114956 -240.15977) (xy 376.127264 -240.166398) (xy 376.150661 -240.178638)
			(xy 376.194185 -240.208533) (xy 376.233167 -240.244148) (xy 376.266861 -240.284802) (xy 376.294624 -240.329715)
			(xy 376.315924 -240.37803) (xy 376.330354 -240.428822) (xy 376.337637 -240.481119) (xy 376.338084 -240.50752)
			(xy 376.337598 -240.534771) (xy 376.329842 -240.588719) (xy 376.314487 -240.641014) (xy 376.303533 -240.665)
			(xy 384.808982 -240.665) (xy 384.813053 -240.609378) (xy 384.825179 -240.554941) (xy 384.845102 -240.50285)
			(xy 384.872398 -240.454215) (xy 384.906484 -240.410072) (xy 384.946633 -240.371363) (xy 384.991991 -240.338912)
			(xy 385.041591 -240.313411) (xy 385.094375 -240.295404) (xy 385.149218 -240.285274) (xy 385.204952 -240.283237)
			(xy 385.260389 -240.289337) (xy 385.314346 -240.303443) (xy 385.365675 -240.325255) (xy 385.413281 -240.354309)
			(xy 385.456149 -240.389984) (xy 385.493366 -240.431521) (xy 385.524139 -240.478034) (xy 385.547811 -240.528531)
			(xy 385.563879 -240.581938) (xy 385.571999 -240.637114) (xy 385.572508 -240.665) (xy 386.078982 -240.665)
			(xy 386.083053 -240.609378) (xy 386.095179 -240.554941) (xy 386.115102 -240.50285) (xy 386.142398 -240.454215)
			(xy 386.176484 -240.410072) (xy 386.216633 -240.371363) (xy 386.261991 -240.338912) (xy 386.311591 -240.313411)
			(xy 386.364375 -240.295404) (xy 386.419218 -240.285274) (xy 386.474952 -240.283237) (xy 386.530389 -240.289337)
			(xy 386.584346 -240.303443) (xy 386.635675 -240.325255) (xy 386.683281 -240.354309) (xy 386.726149 -240.389984)
			(xy 386.763366 -240.431521) (xy 386.794139 -240.478034) (xy 386.817811 -240.528531) (xy 386.833879 -240.581938)
			(xy 386.841999 -240.637114) (xy 386.842508 -240.665) (xy 386.841999 -240.692886) (xy 386.833879 -240.748062)
			(xy 386.817811 -240.801469) (xy 386.794139 -240.851966) (xy 386.763366 -240.898479) (xy 386.726149 -240.940016)
			(xy 386.683281 -240.975691) (xy 386.635675 -241.004745) (xy 386.584346 -241.026557) (xy 386.530389 -241.040663)
			(xy 386.474952 -241.046763) (xy 386.419218 -241.044726) (xy 386.364375 -241.034596) (xy 386.311591 -241.016589)
			(xy 386.261991 -240.991088) (xy 386.216633 -240.958637) (xy 386.176484 -240.919928) (xy 386.142398 -240.875785)
			(xy 386.115102 -240.82715) (xy 386.095179 -240.775059) (xy 386.083053 -240.720622) (xy 386.078982 -240.665)
			(xy 385.572508 -240.665) (xy 385.571999 -240.692886) (xy 385.563879 -240.748062) (xy 385.547811 -240.801469)
			(xy 385.524139 -240.851966) (xy 385.493366 -240.898479) (xy 385.456149 -240.940016) (xy 385.413281 -240.975691)
			(xy 385.365675 -241.004745) (xy 385.314346 -241.026557) (xy 385.260389 -241.040663) (xy 385.204952 -241.046763)
			(xy 385.149218 -241.044726) (xy 385.094375 -241.034596) (xy 385.041591 -241.016589) (xy 384.991991 -240.991088)
			(xy 384.946633 -240.958637) (xy 384.906484 -240.919928) (xy 384.872398 -240.875785) (xy 384.845102 -240.82715)
			(xy 384.825179 -240.775059) (xy 384.813053 -240.720622) (xy 384.808982 -240.665) (xy 376.303533 -240.665)
			(xy 376.291845 -240.690591) (xy 376.262379 -240.736441) (xy 376.226688 -240.777632) (xy 376.185497 -240.813323)
			(xy 376.139647 -240.842789) (xy 376.09007 -240.865431) (xy 376.037775 -240.880786) (xy 375.983827 -240.888542)
			(xy 375.929325 -240.888542) (xy 375.875377 -240.880786) (xy 375.823082 -240.865431) (xy 375.773505 -240.842789)
			(xy 375.727655 -240.813323) (xy 375.686464 -240.777632) (xy 375.650773 -240.736441) (xy 375.621307 -240.690591)
			(xy 375.598665 -240.641014) (xy 375.58331 -240.588719) (xy 375.575554 -240.534771) (xy 375.575068 -240.50752)
			(xy 375.575583 -240.477907) (xy 375.584733 -240.419391) (xy 375.602818 -240.362993) (xy 375.629401 -240.310067)
			(xy 375.663845 -240.261885) (xy 375.705321 -240.219606) (xy 375.752833 -240.184245) (xy 375.778776 -240.169954)
			(xy 375.790956 -240.163103) (xy 375.811255 -240.143908) (xy 375.825593 -240.119932) (xy 375.832897 -240.092966)
			(xy 375.83262 -240.065031) (xy 375.824784 -240.038216) (xy 375.809974 -240.014527) (xy 375.789299 -239.995739)
			(xy 375.776998 -239.989106) (xy 375.753594 -239.97688) (xy 375.710072 -239.946981) (xy 375.671091 -239.911363)
			(xy 375.637398 -239.870707) (xy 375.609637 -239.825792) (xy 375.588337 -239.777476) (xy 375.573908 -239.726683)
			(xy 375.566625 -239.674385) (xy 375.566178 -239.647984) (xy 360.737774 -239.647984) (xy 360.694676 -239.675681)
			(xy 360.645097 -239.698323) (xy 360.5928 -239.713678) (xy 360.53885 -239.721435) (xy 360.511598 -239.721898)
			(xy 360.485716 -239.721445) (xy 360.434427 -239.714442) (xy 360.384557 -239.700563) (xy 360.337023 -239.680065)
			(xy 360.2927 -239.653324) (xy 360.252403 -239.620832) (xy 360.216872 -239.583187) (xy 360.201464 -239.562386)
			(xy 360.193063 -239.551399) (xy 360.171559 -239.534022) (xy 360.146179 -239.523058) (xy 360.118787 -239.519312)
			(xy 360.091395 -239.523058) (xy 360.066015 -239.534022) (xy 360.044511 -239.551399) (xy 360.03611 -239.562386)
			(xy 360.020704 -239.58319) (xy 359.985177 -239.620841) (xy 359.944881 -239.653339) (xy 359.900558 -239.680084)
			(xy 359.853023 -239.700585) (xy 359.803151 -239.714464) (xy 359.75186 -239.721466) (xy 359.725976 -239.721898)
			(xy 359.698725 -239.721431) (xy 359.644779 -239.713671) (xy 359.592485 -239.698313) (xy 359.54291 -239.67567)
			(xy 359.497061 -239.646203) (xy 359.455873 -239.61051) (xy 359.420183 -239.569319) (xy 359.390718 -239.523469)
			(xy 359.368078 -239.473892) (xy 359.352724 -239.421598) (xy 359.344968 -239.367651) (xy 354.638356 -239.367651)
			(xy 354.638356 -239.941608) (xy 354.639118 -239.949736) (xy 354.639118 -239.950244) (xy 354.640721 -239.957761)
			(xy 354.647701 -239.971446) (xy 354.652834 -239.977168) (xy 355.833426 -241.15776) (xy 367.44478 -241.15776)
			(xy 367.448851 -241.102138) (xy 367.460977 -241.047701) (xy 367.4809 -240.99561) (xy 367.508196 -240.946975)
			(xy 367.542282 -240.902832) (xy 367.582431 -240.864123) (xy 367.627789 -240.831672) (xy 367.677389 -240.806171)
			(xy 367.730173 -240.788164) (xy 367.785016 -240.778034) (xy 367.84075 -240.775997) (xy 367.896187 -240.782097)
			(xy 367.950144 -240.796203) (xy 368.001473 -240.818015) (xy 368.049079 -240.847069) (xy 368.091947 -240.882744)
			(xy 368.129164 -240.924281) (xy 368.159937 -240.970794) (xy 368.183609 -241.021291) (xy 368.199677 -241.074698)
			(xy 368.207797 -241.129874) (xy 368.208306 -241.15776) (xy 368.207797 -241.185646) (xy 368.199677 -241.240822)
			(xy 368.183609 -241.294229) (xy 368.159937 -241.344726) (xy 368.129164 -241.391239) (xy 368.097122 -241.427)
			(xy 383.030982 -241.427) (xy 383.035053 -241.371378) (xy 383.047179 -241.316941) (xy 383.067102 -241.26485)
			(xy 383.094398 -241.216215) (xy 383.128484 -241.172072) (xy 383.168633 -241.133363) (xy 383.213991 -241.100912)
			(xy 383.263591 -241.075411) (xy 383.316375 -241.057404) (xy 383.371218 -241.047274) (xy 383.426952 -241.045237)
			(xy 383.482389 -241.051337) (xy 383.536346 -241.065443) (xy 383.587675 -241.087255) (xy 383.635281 -241.116309)
			(xy 383.678149 -241.151984) (xy 383.715366 -241.193521) (xy 383.746139 -241.240034) (xy 383.769811 -241.290531)
			(xy 383.785879 -241.343938) (xy 383.793999 -241.399114) (xy 383.794508 -241.427) (xy 383.793999 -241.454886)
			(xy 383.785879 -241.510062) (xy 383.769811 -241.563469) (xy 383.746139 -241.613966) (xy 383.715366 -241.660479)
			(xy 383.678149 -241.702016) (xy 383.635281 -241.737691) (xy 383.587675 -241.766745) (xy 383.536346 -241.788557)
			(xy 383.482389 -241.802663) (xy 383.426952 -241.808763) (xy 383.371218 -241.806726) (xy 383.316375 -241.796596)
			(xy 383.263591 -241.778589) (xy 383.213991 -241.753088) (xy 383.168633 -241.720637) (xy 383.128484 -241.681928)
			(xy 383.094398 -241.637785) (xy 383.067102 -241.58915) (xy 383.047179 -241.537059) (xy 383.035053 -241.482622)
			(xy 383.030982 -241.427) (xy 368.097122 -241.427) (xy 368.091947 -241.432776) (xy 368.049079 -241.468451)
			(xy 368.001473 -241.497505) (xy 367.950144 -241.519317) (xy 367.896187 -241.533423) (xy 367.84075 -241.539523)
			(xy 367.785016 -241.537486) (xy 367.730173 -241.527356) (xy 367.677389 -241.509349) (xy 367.627789 -241.483848)
			(xy 367.582431 -241.451397) (xy 367.542282 -241.412688) (xy 367.508196 -241.368545) (xy 367.4809 -241.31991)
			(xy 367.460977 -241.267819) (xy 367.448851 -241.213382) (xy 367.44478 -241.15776) (xy 355.833426 -241.15776)
			(xy 356.538022 -241.862356) (xy 375.643138 -241.862356) (xy 375.647209 -241.806734) (xy 375.659335 -241.752297)
			(xy 375.679258 -241.700206) (xy 375.706554 -241.651571) (xy 375.74064 -241.607428) (xy 375.780789 -241.568719)
			(xy 375.826147 -241.536268) (xy 375.875747 -241.510767) (xy 375.928531 -241.49276) (xy 375.983374 -241.48263)
			(xy 376.039108 -241.480593) (xy 376.094545 -241.486693) (xy 376.148502 -241.500799) (xy 376.199831 -241.522611)
			(xy 376.247437 -241.551665) (xy 376.290305 -241.58734) (xy 376.327522 -241.628877) (xy 376.358295 -241.67539)
			(xy 376.381967 -241.725887) (xy 376.398035 -241.779294) (xy 376.402708 -241.811048) (xy 377.376942 -241.811048)
			(xy 377.381013 -241.755426) (xy 377.393139 -241.700989) (xy 377.413062 -241.648898) (xy 377.440358 -241.600263)
			(xy 377.474444 -241.55612) (xy 377.514593 -241.517411) (xy 377.559951 -241.48496) (xy 377.609551 -241.459459)
			(xy 377.662335 -241.441452) (xy 377.717178 -241.431322) (xy 377.772912 -241.429285) (xy 377.828349 -241.435385)
			(xy 377.882306 -241.449491) (xy 377.933635 -241.471303) (xy 377.981241 -241.500357) (xy 378.024109 -241.536032)
			(xy 378.061326 -241.577569) (xy 378.092099 -241.624082) (xy 378.115771 -241.674579) (xy 378.131839 -241.727986)
			(xy 378.139959 -241.783162) (xy 378.140468 -241.811048) (xy 378.139959 -241.838934) (xy 378.131839 -241.89411)
			(xy 378.115771 -241.947517) (xy 378.092099 -241.998014) (xy 378.061326 -242.044527) (xy 378.024109 -242.086064)
			(xy 377.981241 -242.121739) (xy 377.933635 -242.150793) (xy 377.882306 -242.172605) (xy 377.828349 -242.186711)
			(xy 377.772912 -242.192811) (xy 377.717178 -242.190774) (xy 377.662335 -242.180644) (xy 377.609551 -242.162637)
			(xy 377.559951 -242.137136) (xy 377.514593 -242.104685) (xy 377.474444 -242.065976) (xy 377.440358 -242.021833)
			(xy 377.413062 -241.973198) (xy 377.393139 -241.921107) (xy 377.381013 -241.86667) (xy 377.376942 -241.811048)
			(xy 376.402708 -241.811048) (xy 376.406155 -241.83447) (xy 376.406664 -241.862356) (xy 376.406155 -241.890242)
			(xy 376.398035 -241.945418) (xy 376.381967 -241.998825) (xy 376.358295 -242.049322) (xy 376.327522 -242.095835)
			(xy 376.290305 -242.137372) (xy 376.247437 -242.173047) (xy 376.199831 -242.202101) (xy 376.148502 -242.223913)
			(xy 376.094545 -242.238019) (xy 376.039108 -242.244119) (xy 375.983374 -242.242082) (xy 375.928531 -242.231952)
			(xy 375.875747 -242.213945) (xy 375.826147 -242.188444) (xy 375.780789 -242.155993) (xy 375.74064 -242.117284)
			(xy 375.706554 -242.073141) (xy 375.679258 -242.024506) (xy 375.659335 -241.972415) (xy 375.647209 -241.917978)
			(xy 375.643138 -241.862356) (xy 356.538022 -241.862356) (xy 356.98684 -242.311174) (xy 379.62027 -242.311174)
			(xy 379.624341 -242.255552) (xy 379.636467 -242.201115) (xy 379.65639 -242.149024) (xy 379.683686 -242.100389)
			(xy 379.717772 -242.056246) (xy 379.757921 -242.017537) (xy 379.803279 -241.985086) (xy 379.852879 -241.959585)
			(xy 379.905663 -241.941578) (xy 379.960506 -241.931448) (xy 380.01624 -241.929411) (xy 380.071677 -241.935511)
			(xy 380.125634 -241.949617) (xy 380.176963 -241.971429) (xy 380.224569 -242.000483) (xy 380.267437 -242.036158)
			(xy 380.285585 -242.056412) (xy 388.016494 -242.056412) (xy 388.020565 -242.00079) (xy 388.032691 -241.946353)
			(xy 388.052614 -241.894262) (xy 388.07991 -241.845627) (xy 388.113996 -241.801484) (xy 388.154145 -241.762775)
			(xy 388.199503 -241.730324) (xy 388.249103 -241.704823) (xy 388.301887 -241.686816) (xy 388.35673 -241.676686)
			(xy 388.412464 -241.674649) (xy 388.467901 -241.680749) (xy 388.521858 -241.694855) (xy 388.573187 -241.716667)
			(xy 388.620793 -241.745721) (xy 388.663661 -241.781396) (xy 388.700878 -241.822933) (xy 388.731651 -241.869446)
			(xy 388.755323 -241.919943) (xy 388.771391 -241.97335) (xy 388.779511 -242.028526) (xy 388.78002 -242.056412)
			(xy 388.779511 -242.084298) (xy 388.771391 -242.139474) (xy 388.755323 -242.192881) (xy 388.731651 -242.243378)
			(xy 388.700878 -242.289891) (xy 388.663661 -242.331428) (xy 388.620793 -242.367103) (xy 388.573187 -242.396157)
			(xy 388.521858 -242.417969) (xy 388.467901 -242.432075) (xy 388.412464 -242.438175) (xy 388.35673 -242.436138)
			(xy 388.301887 -242.426008) (xy 388.249103 -242.408001) (xy 388.199503 -242.3825) (xy 388.154145 -242.350049)
			(xy 388.113996 -242.31134) (xy 388.07991 -242.267197) (xy 388.052614 -242.218562) (xy 388.032691 -242.166471)
			(xy 388.020565 -242.112034) (xy 388.016494 -242.056412) (xy 380.285585 -242.056412) (xy 380.304654 -242.077695)
			(xy 380.335427 -242.124208) (xy 380.359099 -242.174705) (xy 380.375167 -242.228112) (xy 380.383287 -242.283288)
			(xy 380.383796 -242.311174) (xy 380.383287 -242.33906) (xy 380.375167 -242.394236) (xy 380.359099 -242.447643)
			(xy 380.335427 -242.49814) (xy 380.304654 -242.544653) (xy 380.267437 -242.58619) (xy 380.224569 -242.621865)
			(xy 380.176963 -242.650919) (xy 380.125634 -242.672731) (xy 380.071677 -242.686837) (xy 380.01624 -242.692937)
			(xy 379.960506 -242.6909) (xy 379.905663 -242.68077) (xy 379.852879 -242.662763) (xy 379.803279 -242.637262)
			(xy 379.757921 -242.604811) (xy 379.717772 -242.566102) (xy 379.683686 -242.521959) (xy 379.65639 -242.473324)
			(xy 379.636467 -242.421233) (xy 379.624341 -242.366796) (xy 379.62027 -242.311174) (xy 356.98684 -242.311174)
			(xy 363.756956 -249.08129) (xy 363.762386 -249.086271) (xy 363.775426 -249.093116) (xy 363.78261 -249.094752)
			(xy 363.783118 -249.094752) (xy 363.792516 -249.095768) (xy 363.862366 -249.095768) (xy 363.869986 -249.095006)
			(xy 363.88167 -249.093736) (xy 363.908848 -249.077734) (xy 363.918246 -249.070368) (xy 363.922056 -249.066812)
			(xy 363.925358 -249.061732) (xy 363.932216 -249.052588) (xy 363.938286 -249.044807) (xy 363.951119 -249.029814)
			(xy 363.95787 -249.022616) (xy 363.963966 -249.016012) (xy 363.97311 -248.995438) (xy 363.976292 -248.986333)
			(xy 363.976329 -248.967061) (xy 363.969268 -248.949129) (xy 363.96295 -248.941844) (xy 360.364278 -245.343172)
			(xy 360.357427 -245.335776) (xy 360.349691 -245.317177) (xy 360.349292 -245.307104) (xy 360.349292 -243.257324)
			(xy 360.349729 -243.24726) (xy 360.357461 -243.228674) (xy 360.364278 -243.221256) (xy 360.491278 -243.094256)
			(xy 360.491786 -243.093748) (xy 360.504486 -243.081048) (xy 360.504994 -243.08054) (xy 360.631994 -242.95354)
			(xy 360.63939 -242.946688) (xy 360.657989 -242.938945) (xy 360.668062 -242.938554) (xy 360.846624 -242.938554)
			(xy 360.856784 -242.9383) (xy 360.858308 -242.9383) (xy 360.868468 -242.938554) (xy 361.04703 -242.938554)
			(xy 361.057097 -242.938984) (xy 361.075688 -242.946712) (xy 361.083098 -242.95354) (xy 361.210098 -243.08054)
			(xy 361.210606 -243.081048) (xy 361.223306 -243.093748) (xy 361.223814 -243.094256) (xy 361.350814 -243.221256)
			(xy 361.357661 -243.228653) (xy 361.365388 -243.247253) (xy 361.3658 -243.257324) (xy 361.3658 -244.57914)
			(xy 361.366562 -244.587268) (xy 361.366562 -244.587776) (xy 361.368155 -244.595299) (xy 361.375116 -244.609001)
			(xy 361.380278 -244.6147) (xy 362.014262 -245.248684) (xy 363.051088 -245.248684) (xy 363.055159 -245.193062)
			(xy 363.067285 -245.138625) (xy 363.087208 -245.086534) (xy 363.114504 -245.037899) (xy 363.14859 -244.993756)
			(xy 363.188739 -244.955047) (xy 363.234097 -244.922596) (xy 363.283697 -244.897095) (xy 363.336481 -244.879088)
			(xy 363.391324 -244.868958) (xy 363.447058 -244.866921) (xy 363.502495 -244.873021) (xy 363.556452 -244.887127)
			(xy 363.607781 -244.908939) (xy 363.655387 -244.937993) (xy 363.698255 -244.973668) (xy 363.735472 -245.015205)
			(xy 363.766245 -245.061718) (xy 363.789917 -245.112215) (xy 363.805985 -245.165622) (xy 363.814105 -245.220798)
			(xy 363.814614 -245.248684) (xy 363.814105 -245.27657) (xy 363.805985 -245.331746) (xy 363.789917 -245.385153)
			(xy 363.766245 -245.43565) (xy 363.735472 -245.482163) (xy 363.698255 -245.5237) (xy 363.655387 -245.559375)
			(xy 363.607781 -245.588429) (xy 363.556452 -245.610241) (xy 363.502495 -245.624347) (xy 363.447058 -245.630447)
			(xy 363.391324 -245.62841) (xy 363.336481 -245.61828) (xy 363.283697 -245.600273) (xy 363.234097 -245.574772)
			(xy 363.188739 -245.542321) (xy 363.14859 -245.503612) (xy 363.114504 -245.459469) (xy 363.087208 -245.410834)
			(xy 363.067285 -245.358743) (xy 363.055159 -245.304306) (xy 363.051088 -245.248684) (xy 362.014262 -245.248684)
			(xy 364.773464 -248.007886) (xy 365.654334 -248.007886) (xy 365.658405 -247.952264) (xy 365.670531 -247.897827)
			(xy 365.690454 -247.845736) (xy 365.71775 -247.797101) (xy 365.751836 -247.752958) (xy 365.791985 -247.714249)
			(xy 365.837343 -247.681798) (xy 365.886943 -247.656297) (xy 365.939727 -247.63829) (xy 365.99457 -247.62816)
			(xy 366.050304 -247.626123) (xy 366.105741 -247.632223) (xy 366.159698 -247.646329) (xy 366.211027 -247.668141)
			(xy 366.258633 -247.697195) (xy 366.301501 -247.73287) (xy 366.338718 -247.774407) (xy 366.369491 -247.82092)
			(xy 366.393163 -247.871417) (xy 366.409231 -247.924824) (xy 366.417351 -247.98) (xy 366.41786 -248.007886)
			(xy 366.417351 -248.035772) (xy 366.409231 -248.090948) (xy 366.393163 -248.144355) (xy 366.369491 -248.194852)
			(xy 366.338718 -248.241365) (xy 366.301501 -248.282902) (xy 366.258633 -248.318577) (xy 366.211027 -248.347631)
			(xy 366.159698 -248.369443) (xy 366.105741 -248.383549) (xy 366.050304 -248.389649) (xy 365.99457 -248.387612)
			(xy 365.939727 -248.377482) (xy 365.886943 -248.359475) (xy 365.837343 -248.333974) (xy 365.791985 -248.301523)
			(xy 365.751836 -248.262814) (xy 365.71775 -248.218671) (xy 365.690454 -248.170036) (xy 365.670531 -248.117945)
			(xy 365.658405 -248.063508) (xy 365.654334 -248.007886) (xy 364.773464 -248.007886) (xy 365.383826 -248.618248)
			(xy 365.384588 -248.618756) (xy 365.410242 -248.64441) (xy 365.41075 -248.645172) (xy 365.531146 -248.765568)
			(xy 365.537988 -248.772967) (xy 365.545706 -248.791566) (xy 365.546132 -248.801636) (xy 365.546132 -248.971562)
			(xy 365.546132 -248.973594) (xy 365.54664 -248.988834) (xy 365.547148 -248.99493) (xy 365.549708 -249.009838)
			(xy 365.562331 -249.037309) (xy 365.582443 -249.059881) (xy 365.608282 -249.075576) (xy 365.637584 -249.083019)
			(xy 365.66778 -249.081557) (xy 365.696227 -249.07132) (xy 365.708692 -249.062748) (xy 365.733639 -249.044784)
			(xy 365.788076 -249.016227) (xy 365.846387 -248.996768) (xy 365.907064 -248.986911) (xy 365.9378 -248.986294)
			(xy 365.965051 -248.98678) (xy 366.018999 -248.994536) (xy 366.071293 -249.009891) (xy 366.12087 -249.032532)
			(xy 366.16672 -249.061998) (xy 366.20791 -249.09769) (xy 366.243602 -249.13888) (xy 366.273068 -249.18473)
			(xy 366.295709 -249.234307) (xy 366.311064 -249.286601) (xy 366.31882 -249.340549) (xy 366.31882 -249.395051)
			(xy 366.311064 -249.448999) (xy 366.295709 -249.501293) (xy 366.273068 -249.55087) (xy 366.243602 -249.59672)
			(xy 366.20791 -249.63791) (xy 366.16672 -249.673602) (xy 366.12087 -249.703068) (xy 366.071293 -249.725709)
			(xy 366.018999 -249.741064) (xy 365.965051 -249.74882) (xy 365.9378 -249.74931) (xy 365.909323 -249.748781)
			(xy 365.853002 -249.740312) (xy 365.798567 -249.723562) (xy 365.747227 -249.698904) (xy 365.700125 -249.666886)
			(xy 365.658308 -249.628219) (xy 365.640112 -249.606308) (xy 365.639096 -249.604784) (xy 365.636556 -249.60199)
			(xy 365.630426 -249.59592) (xy 365.615151 -249.587925) (xy 365.598092 -249.585433) (xy 365.589566 -249.58675)
			(xy 365.567722 -249.597672) (xy 365.561372 -249.601736) (xy 365.556038 -249.606054) (xy 365.551212 -249.616214)
			(xy 365.549566 -249.619789) (xy 365.54727 -249.627315) (xy 365.54664 -249.6312) (xy 365.54664 -249.673872)
			(xy 365.546894 -249.675396) (xy 365.546894 -249.675904) (xy 365.548491 -249.683425) (xy 365.555462 -249.697119)
			(xy 365.56061 -249.702828) (xy 369.524788 -253.667006) (xy 369.531646 -253.673864) (xy 369.612418 -253.754636)
			(xy 369.615318 -253.75742) (xy 369.621825 -253.762142) (xy 369.625372 -253.764034) (xy 369.632943 -253.767477)
			(xy 369.649401 -253.769811) (xy 369.65763 -253.768606) (xy 369.66271 -253.767336) (xy 369.667757 -253.765719)
			(xy 369.6771 -253.760724) (xy 369.681252 -253.75743) (xy 369.6843 -253.754382) (xy 369.687985 -253.750453)
			(xy 369.693753 -253.741358) (xy 369.69573 -253.736348) (xy 369.699032 -253.726188) (xy 369.699286 -253.713742)
			(xy 369.697762 -253.707138) (xy 369.693131 -253.685849) (xy 369.688161 -253.642563) (xy 369.687856 -253.620778)
			(xy 369.688393 -253.591839) (xy 369.697136 -253.534625) (xy 369.714418 -253.479387) (xy 369.739842 -253.427392)
			(xy 369.772826 -253.379832) (xy 369.812613 -253.337798) (xy 369.858292 -253.302253) (xy 369.908813 -253.274014)
			(xy 369.963019 -253.253727) (xy 370.019667 -253.241857) (xy 370.048536 -253.239778) (xy 370.056664 -253.23927)
			(xy 370.069872 -253.234444) (xy 370.075714 -253.23038) (xy 370.080537 -253.226551) (xy 370.088359 -253.217045)
			(xy 370.091208 -253.211584) (xy 370.091716 -253.211076) (xy 370.092986 -253.208028) (xy 370.128038 -253.116334)
			(xy 370.130794 -253.10409) (xy 370.125472 -253.07959) (xy 370.117878 -253.069598) (xy 369.967002 -252.918722)
			(xy 369.8113 -252.762766) (xy 368.588798 -251.540518) (xy 368.56678 -251.5178) (xy 368.528266 -251.467607)
			(xy 368.496637 -251.412814) (xy 368.472432 -251.354361) (xy 368.456066 -251.293248) (xy 368.44782 -251.230521)
			(xy 368.44732 -251.198888) (xy 368.44732 -246.888762) (xy 368.447254 -246.885157) (xy 368.44623 -246.878019)
			(xy 368.445288 -246.874538) (xy 368.443764 -246.869966) (xy 368.439954 -246.860822) (xy 365.172244 -243.593112)
			(xy 365.153519 -243.573874) (xy 365.119995 -243.53194) (xy 365.091326 -243.486548) (xy 365.07928 -243.462556)
			(xy 365.071779 -243.446792) (xy 365.058808 -243.414376) (xy 365.053372 -243.397786) (xy 365.053372 -243.397278)
			(xy 365.045752 -243.370354) (xy 365.045752 -243.369846) (xy 365.03888 -243.340867) (xy 365.031493 -243.281769)
			(xy 365.03102 -243.25199) (xy 365.03102 -243.251482) (xy 365.031538 -243.219868) (xy 365.039793 -243.157181)
			(xy 365.056159 -243.096108) (xy 365.080356 -243.037694) (xy 365.11197 -242.982937) (xy 365.150461 -242.932775)
			(xy 365.195169 -242.888066) (xy 365.245331 -242.849575) (xy 365.300087 -242.817959) (xy 365.358501 -242.793761)
			(xy 365.419574 -242.777394) (xy 365.48226 -242.769139) (xy 365.513874 -242.768628) (xy 365.542231 -242.769004)
			(xy 365.598562 -242.775583) (xy 365.653735 -242.78871) (xy 365.680498 -242.798092) (xy 365.713047 -242.810689)
			(xy 365.774428 -242.843909) (xy 365.830389 -242.885617) (xy 365.855504 -242.909852) (xy 366.023652 -243.078)
			(xy 370.965982 -243.078) (xy 370.970053 -243.022378) (xy 370.982179 -242.967941) (xy 371.002102 -242.91585)
			(xy 371.029398 -242.867215) (xy 371.063484 -242.823072) (xy 371.103633 -242.784363) (xy 371.148991 -242.751912)
			(xy 371.198591 -242.726411) (xy 371.251375 -242.708404) (xy 371.306218 -242.698274) (xy 371.361952 -242.696237)
			(xy 371.417389 -242.702337) (xy 371.471346 -242.716443) (xy 371.522675 -242.738255) (xy 371.570281 -242.767309)
			(xy 371.613149 -242.802984) (xy 371.650366 -242.844521) (xy 371.681139 -242.891034) (xy 371.704811 -242.941531)
			(xy 371.720879 -242.994938) (xy 371.728999 -243.050114) (xy 371.729508 -243.078) (xy 371.728999 -243.105886)
			(xy 371.720879 -243.161062) (xy 371.704811 -243.214469) (xy 371.704368 -243.215414) (xy 383.706876 -243.215414)
			(xy 383.710947 -243.159792) (xy 383.723073 -243.105355) (xy 383.742996 -243.053264) (xy 383.770292 -243.004629)
			(xy 383.804378 -242.960486) (xy 383.844527 -242.921777) (xy 383.889885 -242.889326) (xy 383.939485 -242.863825)
			(xy 383.992269 -242.845818) (xy 384.047112 -242.835688) (xy 384.102846 -242.833651) (xy 384.158283 -242.839751)
			(xy 384.21224 -242.853857) (xy 384.263569 -242.875669) (xy 384.311175 -242.904723) (xy 384.354043 -242.940398)
			(xy 384.39126 -242.981935) (xy 384.422033 -243.028448) (xy 384.445705 -243.078945) (xy 384.461773 -243.132352)
			(xy 384.466483 -243.16436) (xy 385.973572 -243.16436) (xy 385.977643 -243.108738) (xy 385.989769 -243.054301)
			(xy 386.009692 -243.00221) (xy 386.036988 -242.953575) (xy 386.071074 -242.909432) (xy 386.111223 -242.870723)
			(xy 386.156581 -242.838272) (xy 386.206181 -242.812771) (xy 386.258965 -242.794764) (xy 386.313808 -242.784634)
			(xy 386.369542 -242.782597) (xy 386.424979 -242.788697) (xy 386.478936 -242.802803) (xy 386.530265 -242.824615)
			(xy 386.577871 -242.853669) (xy 386.620739 -242.889344) (xy 386.657956 -242.930881) (xy 386.688729 -242.977394)
			(xy 386.712401 -243.027891) (xy 386.728469 -243.081298) (xy 386.736589 -243.136474) (xy 386.737098 -243.16436)
			(xy 386.736589 -243.192246) (xy 386.728469 -243.247422) (xy 386.712401 -243.300829) (xy 386.688729 -243.351326)
			(xy 386.657956 -243.397839) (xy 386.620739 -243.439376) (xy 386.577871 -243.475051) (xy 386.530265 -243.504105)
			(xy 386.478936 -243.525917) (xy 386.424979 -243.540023) (xy 386.369542 -243.546123) (xy 386.313808 -243.544086)
			(xy 386.258965 -243.533956) (xy 386.206181 -243.515949) (xy 386.156581 -243.490448) (xy 386.111223 -243.457997)
			(xy 386.071074 -243.419288) (xy 386.036988 -243.375145) (xy 386.009692 -243.32651) (xy 385.989769 -243.274419)
			(xy 385.977643 -243.219982) (xy 385.973572 -243.16436) (xy 384.466483 -243.16436) (xy 384.469893 -243.187528)
			(xy 384.470402 -243.215414) (xy 384.469893 -243.2433) (xy 384.461773 -243.298476) (xy 384.445705 -243.351883)
			(xy 384.422033 -243.40238) (xy 384.39126 -243.448893) (xy 384.354043 -243.49043) (xy 384.311175 -243.526105)
			(xy 384.263569 -243.555159) (xy 384.21224 -243.576971) (xy 384.158283 -243.591077) (xy 384.102846 -243.597177)
			(xy 384.047112 -243.59514) (xy 383.992269 -243.58501) (xy 383.939485 -243.567003) (xy 383.889885 -243.541502)
			(xy 383.844527 -243.509051) (xy 383.804378 -243.470342) (xy 383.770292 -243.426199) (xy 383.742996 -243.377564)
			(xy 383.723073 -243.325473) (xy 383.710947 -243.271036) (xy 383.706876 -243.215414) (xy 371.704368 -243.215414)
			(xy 371.681139 -243.264966) (xy 371.650366 -243.311479) (xy 371.613149 -243.353016) (xy 371.570281 -243.388691)
			(xy 371.522675 -243.417745) (xy 371.471346 -243.439557) (xy 371.417389 -243.453663) (xy 371.361952 -243.459763)
			(xy 371.306218 -243.457726) (xy 371.251375 -243.447596) (xy 371.198591 -243.429589) (xy 371.148991 -243.404088)
			(xy 371.103633 -243.371637) (xy 371.063484 -243.332928) (xy 371.029398 -243.288785) (xy 371.002102 -243.24015)
			(xy 370.982179 -243.188059) (xy 370.970053 -243.133622) (xy 370.965982 -243.078) (xy 366.023652 -243.078)
			(xy 366.858804 -243.913152) (xy 370.00129 -243.913152) (xy 370.005361 -243.85753) (xy 370.017487 -243.803093)
			(xy 370.03741 -243.751002) (xy 370.064706 -243.702367) (xy 370.098792 -243.658224) (xy 370.138941 -243.619515)
			(xy 370.184299 -243.587064) (xy 370.233899 -243.561563) (xy 370.286683 -243.543556) (xy 370.341526 -243.533426)
			(xy 370.39726 -243.531389) (xy 370.452697 -243.537489) (xy 370.506654 -243.551595) (xy 370.557983 -243.573407)
			(xy 370.605589 -243.602461) (xy 370.648457 -243.638136) (xy 370.685674 -243.679673) (xy 370.716447 -243.726186)
			(xy 370.740119 -243.776683) (xy 370.756187 -243.83009) (xy 370.764307 -243.885266) (xy 370.764816 -243.913152)
			(xy 370.764307 -243.941038) (xy 370.756187 -243.996214) (xy 370.740119 -244.049621) (xy 370.716447 -244.100118)
			(xy 370.685674 -244.146631) (xy 370.648457 -244.188168) (xy 370.605589 -244.223843) (xy 370.557983 -244.252897)
			(xy 370.506654 -244.274709) (xy 370.452697 -244.288815) (xy 370.39726 -244.294915) (xy 370.341526 -244.292878)
			(xy 370.286683 -244.282748) (xy 370.233899 -244.264741) (xy 370.184299 -244.23924) (xy 370.138941 -244.206789)
			(xy 370.098792 -244.16808) (xy 370.064706 -244.123937) (xy 370.03741 -244.075302) (xy 370.017487 -244.023211)
			(xy 370.005361 -243.968774) (xy 370.00129 -243.913152) (xy 366.858804 -243.913152) (xy 367.278666 -244.333014)
			(xy 375.395996 -244.333014) (xy 375.400067 -244.277392) (xy 375.412193 -244.222955) (xy 375.432116 -244.170864)
			(xy 375.459412 -244.122229) (xy 375.493498 -244.078086) (xy 375.533647 -244.039377) (xy 375.579005 -244.006926)
			(xy 375.628605 -243.981425) (xy 375.681389 -243.963418) (xy 375.736232 -243.953288) (xy 375.791966 -243.951251)
			(xy 375.847403 -243.957351) (xy 375.90136 -243.971457) (xy 375.952689 -243.993269) (xy 376.000295 -244.022323)
			(xy 376.043163 -244.057998) (xy 376.075421 -244.094) (xy 379.875032 -244.094) (xy 379.879103 -244.038378)
			(xy 379.891229 -243.983941) (xy 379.911152 -243.93185) (xy 379.938448 -243.883215) (xy 379.972534 -243.839072)
			(xy 380.012683 -243.800363) (xy 380.058041 -243.767912) (xy 380.107641 -243.742411) (xy 380.160425 -243.724404)
			(xy 380.215268 -243.714274) (xy 380.271002 -243.712237) (xy 380.326439 -243.718337) (xy 380.380396 -243.732443)
			(xy 380.431725 -243.754255) (xy 380.479331 -243.783309) (xy 380.522199 -243.818984) (xy 380.559416 -243.860521)
			(xy 380.590189 -243.907034) (xy 380.613861 -243.957531) (xy 380.629929 -244.010938) (xy 380.638049 -244.066114)
			(xy 380.638558 -244.094) (xy 380.638049 -244.121886) (xy 380.629929 -244.177062) (xy 380.613861 -244.230469)
			(xy 380.590189 -244.280966) (xy 380.559416 -244.327479) (xy 380.522199 -244.369016) (xy 380.479331 -244.404691)
			(xy 380.431725 -244.433745) (xy 380.380396 -244.455557) (xy 380.326439 -244.469663) (xy 380.271002 -244.475763)
			(xy 380.215268 -244.473726) (xy 380.160425 -244.463596) (xy 380.107641 -244.445589) (xy 380.058041 -244.420088)
			(xy 380.012683 -244.387637) (xy 379.972534 -244.348928) (xy 379.938448 -244.304785) (xy 379.911152 -244.25615)
			(xy 379.891229 -244.204059) (xy 379.879103 -244.149622) (xy 379.875032 -244.094) (xy 376.075421 -244.094)
			(xy 376.08038 -244.099535) (xy 376.111153 -244.146048) (xy 376.134825 -244.196545) (xy 376.150893 -244.249952)
			(xy 376.159013 -244.305128) (xy 376.159522 -244.333014) (xy 376.159013 -244.3609) (xy 376.150893 -244.416076)
			(xy 376.134825 -244.469483) (xy 376.111153 -244.51998) (xy 376.08038 -244.566493) (xy 376.043163 -244.60803)
			(xy 376.000295 -244.643705) (xy 375.952689 -244.672759) (xy 375.90136 -244.694571) (xy 375.847403 -244.708677)
			(xy 375.791966 -244.714777) (xy 375.736232 -244.71274) (xy 375.681389 -244.70261) (xy 375.628605 -244.684603)
			(xy 375.579005 -244.659102) (xy 375.533647 -244.626651) (xy 375.493498 -244.587942) (xy 375.459412 -244.543799)
			(xy 375.432116 -244.495164) (xy 375.412193 -244.443073) (xy 375.400067 -244.388636) (xy 375.395996 -244.333014)
			(xy 367.278666 -244.333014) (xy 368.4905 -245.544848) (xy 369.93398 -245.544848) (xy 369.938051 -245.489226)
			(xy 369.950177 -245.434789) (xy 369.9701 -245.382698) (xy 369.997396 -245.334063) (xy 370.031482 -245.28992)
			(xy 370.071631 -245.251211) (xy 370.116989 -245.21876) (xy 370.166589 -245.193259) (xy 370.219373 -245.175252)
			(xy 370.274216 -245.165122) (xy 370.32995 -245.163085) (xy 370.385387 -245.169185) (xy 370.439344 -245.183291)
			(xy 370.490673 -245.205103) (xy 370.538279 -245.234157) (xy 370.581147 -245.269832) (xy 370.618364 -245.311369)
			(xy 370.649137 -245.357882) (xy 370.655339 -245.371112) (xy 376.10618 -245.371112) (xy 376.110251 -245.31549)
			(xy 376.122377 -245.261053) (xy 376.1423 -245.208962) (xy 376.169596 -245.160327) (xy 376.203682 -245.116184)
			(xy 376.243831 -245.077475) (xy 376.289189 -245.045024) (xy 376.338789 -245.019523) (xy 376.391573 -245.001516)
			(xy 376.446416 -244.991386) (xy 376.50215 -244.989349) (xy 376.557587 -244.995449) (xy 376.611544 -245.009555)
			(xy 376.662873 -245.031367) (xy 376.710479 -245.060421) (xy 376.753347 -245.096096) (xy 376.790564 -245.137633)
			(xy 376.821337 -245.184146) (xy 376.845009 -245.234643) (xy 376.861077 -245.28805) (xy 376.869197 -245.343226)
			(xy 376.869706 -245.371112) (xy 376.869197 -245.398998) (xy 376.861077 -245.454174) (xy 376.845009 -245.507581)
			(xy 376.821337 -245.558078) (xy 376.790564 -245.604591) (xy 376.753347 -245.646128) (xy 376.710479 -245.681803)
			(xy 376.662873 -245.710857) (xy 376.611544 -245.732669) (xy 376.557587 -245.746775) (xy 376.50215 -245.752875)
			(xy 376.446416 -245.750838) (xy 376.391573 -245.740708) (xy 376.338789 -245.722701) (xy 376.289189 -245.6972)
			(xy 376.243831 -245.664749) (xy 376.203682 -245.62604) (xy 376.169596 -245.581897) (xy 376.1423 -245.533262)
			(xy 376.122377 -245.481171) (xy 376.110251 -245.426734) (xy 376.10618 -245.371112) (xy 370.655339 -245.371112)
			(xy 370.672809 -245.408379) (xy 370.688877 -245.461786) (xy 370.696997 -245.516962) (xy 370.697506 -245.544848)
			(xy 370.696997 -245.572734) (xy 370.688877 -245.62791) (xy 370.672809 -245.681317) (xy 370.649137 -245.731814)
			(xy 370.618364 -245.778327) (xy 370.581147 -245.819864) (xy 370.538279 -245.855539) (xy 370.490673 -245.884593)
			(xy 370.439344 -245.906405) (xy 370.385387 -245.920511) (xy 370.32995 -245.926611) (xy 370.274216 -245.924574)
			(xy 370.219373 -245.914444) (xy 370.166589 -245.896437) (xy 370.116989 -245.870936) (xy 370.071631 -245.838485)
			(xy 370.031482 -245.799776) (xy 369.997396 -245.755633) (xy 369.9701 -245.706998) (xy 369.950177 -245.654907)
			(xy 369.938051 -245.60047) (xy 369.93398 -245.544848) (xy 368.4905 -245.544848) (xy 369.272058 -246.326406)
			(xy 369.294077 -246.349123) (xy 369.317769 -246.38) (xy 375.333766 -246.38) (xy 375.337837 -246.324378)
			(xy 375.349963 -246.269941) (xy 375.369886 -246.21785) (xy 375.397182 -246.169215) (xy 375.431268 -246.125072)
			(xy 375.471417 -246.086363) (xy 375.516775 -246.053912) (xy 375.566375 -246.028411) (xy 375.619159 -246.010404)
			(xy 375.674002 -246.000274) (xy 375.729736 -245.998237) (xy 375.73667 -245.999) (xy 387.116064 -245.999)
			(xy 387.120135 -245.943378) (xy 387.132261 -245.888941) (xy 387.152184 -245.83685) (xy 387.17948 -245.788215)
			(xy 387.213566 -245.744072) (xy 387.253715 -245.705363) (xy 387.299073 -245.672912) (xy 387.348673 -245.647411)
			(xy 387.401457 -245.629404) (xy 387.4563 -245.619274) (xy 387.512034 -245.617237) (xy 387.567471 -245.623337)
			(xy 387.621428 -245.637443) (xy 387.672757 -245.659255) (xy 387.720363 -245.688309) (xy 387.763231 -245.723984)
			(xy 387.800448 -245.765521) (xy 387.831221 -245.812034) (xy 387.854893 -245.862531) (xy 387.870961 -245.915938)
			(xy 387.879081 -245.971114) (xy 387.87959 -245.999) (xy 387.879081 -246.026886) (xy 387.870961 -246.082062)
			(xy 387.854893 -246.135469) (xy 387.831221 -246.185966) (xy 387.800448 -246.232479) (xy 387.763231 -246.274016)
			(xy 387.720363 -246.309691) (xy 387.672757 -246.338745) (xy 387.621428 -246.360557) (xy 387.567471 -246.374663)
			(xy 387.512034 -246.380763) (xy 387.4563 -246.378726) (xy 387.401457 -246.368596) (xy 387.348673 -246.350589)
			(xy 387.299073 -246.325088) (xy 387.253715 -246.292637) (xy 387.213566 -246.253928) (xy 387.17948 -246.209785)
			(xy 387.152184 -246.16115) (xy 387.132261 -246.109059) (xy 387.120135 -246.054622) (xy 387.116064 -245.999)
			(xy 375.73667 -245.999) (xy 375.785173 -246.004337) (xy 375.83913 -246.018443) (xy 375.890459 -246.040255)
			(xy 375.938065 -246.069309) (xy 375.980933 -246.104984) (xy 376.01815 -246.146521) (xy 376.048923 -246.193034)
			(xy 376.072595 -246.243531) (xy 376.088663 -246.296938) (xy 376.096783 -246.352114) (xy 376.097292 -246.38)
			(xy 376.096783 -246.407886) (xy 376.088663 -246.463062) (xy 376.075444 -246.507) (xy 383.411982 -246.507)
			(xy 383.416053 -246.451378) (xy 383.428179 -246.396941) (xy 383.448102 -246.34485) (xy 383.475398 -246.296215)
			(xy 383.509484 -246.252072) (xy 383.549633 -246.213363) (xy 383.594991 -246.180912) (xy 383.644591 -246.155411)
			(xy 383.697375 -246.137404) (xy 383.752218 -246.127274) (xy 383.807952 -246.125237) (xy 383.863389 -246.131337)
			(xy 383.917346 -246.145443) (xy 383.968675 -246.167255) (xy 384.016281 -246.196309) (xy 384.059149 -246.231984)
			(xy 384.096366 -246.273521) (xy 384.127139 -246.320034) (xy 384.150811 -246.370531) (xy 384.166879 -246.423938)
			(xy 384.174999 -246.479114) (xy 384.175508 -246.507) (xy 384.174999 -246.534886) (xy 384.166879 -246.590062)
			(xy 384.150811 -246.643469) (xy 384.127139 -246.693966) (xy 384.096366 -246.740479) (xy 384.059149 -246.782016)
			(xy 384.016281 -246.817691) (xy 383.968675 -246.846745) (xy 383.917346 -246.868557) (xy 383.863389 -246.882663)
			(xy 383.807952 -246.888763) (xy 383.752218 -246.886726) (xy 383.697375 -246.876596) (xy 383.644591 -246.858589)
			(xy 383.594991 -246.833088) (xy 383.549633 -246.800637) (xy 383.509484 -246.761928) (xy 383.475398 -246.717785)
			(xy 383.448102 -246.66915) (xy 383.428179 -246.617059) (xy 383.416053 -246.562622) (xy 383.411982 -246.507)
			(xy 376.075444 -246.507) (xy 376.072595 -246.516469) (xy 376.048923 -246.566966) (xy 376.01815 -246.613479)
			(xy 375.980933 -246.655016) (xy 375.938065 -246.690691) (xy 375.890459 -246.719745) (xy 375.83913 -246.741557)
			(xy 375.785173 -246.755663) (xy 375.729736 -246.761763) (xy 375.674002 -246.759726) (xy 375.619159 -246.749596)
			(xy 375.566375 -246.731589) (xy 375.516775 -246.706088) (xy 375.471417 -246.673637) (xy 375.431268 -246.634928)
			(xy 375.397182 -246.590785) (xy 375.369886 -246.54215) (xy 375.349963 -246.490059) (xy 375.337837 -246.435622)
			(xy 375.333766 -246.38) (xy 369.317769 -246.38) (xy 369.332591 -246.399316) (xy 369.364221 -246.454108)
			(xy 369.388425 -246.512562) (xy 369.40479 -246.573675) (xy 369.413033 -246.636403) (xy 369.413536 -246.668036)
			(xy 369.413536 -247.396) (xy 374.648982 -247.396) (xy 374.653053 -247.340378) (xy 374.665179 -247.285941)
			(xy 374.685102 -247.23385) (xy 374.712398 -247.185215) (xy 374.746484 -247.141072) (xy 374.786633 -247.102363)
			(xy 374.831991 -247.069912) (xy 374.881591 -247.044411) (xy 374.934375 -247.026404) (xy 374.989218 -247.016274)
			(xy 375.044952 -247.014237) (xy 375.051886 -247.015) (xy 377.950982 -247.015) (xy 377.955053 -246.959378)
			(xy 377.967179 -246.904941) (xy 377.987102 -246.85285) (xy 378.014398 -246.804215) (xy 378.048484 -246.760072)
			(xy 378.088633 -246.721363) (xy 378.133991 -246.688912) (xy 378.183591 -246.663411) (xy 378.236375 -246.645404)
			(xy 378.291218 -246.635274) (xy 378.346952 -246.633237) (xy 378.402389 -246.639337) (xy 378.456346 -246.653443)
			(xy 378.507675 -246.675255) (xy 378.555281 -246.704309) (xy 378.598149 -246.739984) (xy 378.635366 -246.781521)
			(xy 378.666139 -246.828034) (xy 378.689811 -246.878531) (xy 378.705879 -246.931938) (xy 378.713999 -246.987114)
			(xy 378.714508 -247.015) (xy 379.474982 -247.015) (xy 379.479053 -246.959378) (xy 379.491179 -246.904941)
			(xy 379.511102 -246.85285) (xy 379.538398 -246.804215) (xy 379.572484 -246.760072) (xy 379.612633 -246.721363)
			(xy 379.657991 -246.688912) (xy 379.707591 -246.663411) (xy 379.760375 -246.645404) (xy 379.815218 -246.635274)
			(xy 379.870952 -246.633237) (xy 379.926389 -246.639337) (xy 379.980346 -246.653443) (xy 380.031675 -246.675255)
			(xy 380.079281 -246.704309) (xy 380.122149 -246.739984) (xy 380.159366 -246.781521) (xy 380.190139 -246.828034)
			(xy 380.213811 -246.878531) (xy 380.229879 -246.931938) (xy 380.237999 -246.987114) (xy 380.238508 -247.015)
			(xy 380.237999 -247.042886) (xy 380.229879 -247.098062) (xy 380.213811 -247.151469) (xy 380.190139 -247.201966)
			(xy 380.159366 -247.248479) (xy 380.122149 -247.290016) (xy 380.079281 -247.325691) (xy 380.031675 -247.354745)
			(xy 379.980346 -247.376557) (xy 379.926389 -247.390663) (xy 379.870952 -247.396763) (xy 379.815218 -247.394726)
			(xy 379.760375 -247.384596) (xy 379.707591 -247.366589) (xy 379.657991 -247.341088) (xy 379.612633 -247.308637)
			(xy 379.572484 -247.269928) (xy 379.538398 -247.225785) (xy 379.511102 -247.17715) (xy 379.491179 -247.125059)
			(xy 379.479053 -247.070622) (xy 379.474982 -247.015) (xy 378.714508 -247.015) (xy 378.713999 -247.042886)
			(xy 378.705879 -247.098062) (xy 378.689811 -247.151469) (xy 378.666139 -247.201966) (xy 378.635366 -247.248479)
			(xy 378.598149 -247.290016) (xy 378.555281 -247.325691) (xy 378.507675 -247.354745) (xy 378.456346 -247.376557)
			(xy 378.402389 -247.390663) (xy 378.346952 -247.396763) (xy 378.291218 -247.394726) (xy 378.236375 -247.384596)
			(xy 378.183591 -247.366589) (xy 378.133991 -247.341088) (xy 378.088633 -247.308637) (xy 378.048484 -247.269928)
			(xy 378.014398 -247.225785) (xy 377.987102 -247.17715) (xy 377.967179 -247.125059) (xy 377.955053 -247.070622)
			(xy 377.950982 -247.015) (xy 375.051886 -247.015) (xy 375.100389 -247.020337) (xy 375.154346 -247.034443)
			(xy 375.205675 -247.056255) (xy 375.253281 -247.085309) (xy 375.296149 -247.120984) (xy 375.333366 -247.162521)
			(xy 375.364139 -247.209034) (xy 375.387811 -247.259531) (xy 375.403879 -247.312938) (xy 375.411999 -247.368114)
			(xy 375.412508 -247.396) (xy 375.411999 -247.423886) (xy 375.403879 -247.479062) (xy 375.387811 -247.532469)
			(xy 375.364139 -247.582966) (xy 375.333366 -247.629479) (xy 375.300414 -247.666256) (xy 375.643138 -247.666256)
			(xy 375.647209 -247.610634) (xy 375.659335 -247.556197) (xy 375.679258 -247.504106) (xy 375.706554 -247.455471)
			(xy 375.74064 -247.411328) (xy 375.780789 -247.372619) (xy 375.826147 -247.340168) (xy 375.875747 -247.314667)
			(xy 375.928531 -247.29666) (xy 375.983374 -247.28653) (xy 376.039108 -247.284493) (xy 376.094545 -247.290593)
			(xy 376.148502 -247.304699) (xy 376.199831 -247.326511) (xy 376.247437 -247.355565) (xy 376.290305 -247.39124)
			(xy 376.327522 -247.432777) (xy 376.358295 -247.47929) (xy 376.381967 -247.529787) (xy 376.398035 -247.583194)
			(xy 376.406155 -247.63837) (xy 376.406664 -247.666256) (xy 376.406155 -247.694142) (xy 376.398035 -247.749318)
			(xy 376.394062 -247.762522) (xy 380.357124 -247.762522) (xy 380.361195 -247.7069) (xy 380.373321 -247.652463)
			(xy 380.393244 -247.600372) (xy 380.42054 -247.551737) (xy 380.454626 -247.507594) (xy 380.494775 -247.468885)
			(xy 380.540133 -247.436434) (xy 380.589733 -247.410933) (xy 380.642517 -247.392926) (xy 380.69736 -247.382796)
			(xy 380.753094 -247.380759) (xy 380.808531 -247.386859) (xy 380.862488 -247.400965) (xy 380.913817 -247.422777)
			(xy 380.961423 -247.451831) (xy 380.992919 -247.478042) (xy 386.969252 -247.478042) (xy 386.973323 -247.42242)
			(xy 386.985449 -247.367983) (xy 387.005372 -247.315892) (xy 387.032668 -247.267257) (xy 387.066754 -247.223114)
			(xy 387.106903 -247.184405) (xy 387.152261 -247.151954) (xy 387.201861 -247.126453) (xy 387.254645 -247.108446)
			(xy 387.309488 -247.098316) (xy 387.365222 -247.096279) (xy 387.420659 -247.102379) (xy 387.474616 -247.116485)
			(xy 387.523302 -247.137174) (xy 388.4328 -247.137174) (xy 388.436871 -247.081552) (xy 388.448997 -247.027115)
			(xy 388.46892 -246.975024) (xy 388.496216 -246.926389) (xy 388.530302 -246.882246) (xy 388.570451 -246.843537)
			(xy 388.615809 -246.811086) (xy 388.665409 -246.785585) (xy 388.718193 -246.767578) (xy 388.773036 -246.757448)
			(xy 388.82877 -246.755411) (xy 388.884207 -246.761511) (xy 388.938164 -246.775617) (xy 388.989493 -246.797429)
			(xy 389.037099 -246.826483) (xy 389.079967 -246.862158) (xy 389.117184 -246.903695) (xy 389.147957 -246.950208)
			(xy 389.171629 -247.000705) (xy 389.187697 -247.054112) (xy 389.195817 -247.109288) (xy 389.196326 -247.137174)
			(xy 389.195817 -247.16506) (xy 389.187697 -247.220236) (xy 389.171629 -247.273643) (xy 389.147957 -247.32414)
			(xy 389.117184 -247.370653) (xy 389.079967 -247.41219) (xy 389.037099 -247.447865) (xy 388.989493 -247.476919)
			(xy 388.938164 -247.498731) (xy 388.884207 -247.512837) (xy 388.82877 -247.518937) (xy 388.773036 -247.5169)
			(xy 388.718193 -247.50677) (xy 388.665409 -247.488763) (xy 388.615809 -247.463262) (xy 388.570451 -247.430811)
			(xy 388.530302 -247.392102) (xy 388.496216 -247.347959) (xy 388.46892 -247.299324) (xy 388.448997 -247.247233)
			(xy 388.436871 -247.192796) (xy 388.4328 -247.137174) (xy 387.523302 -247.137174) (xy 387.525945 -247.138297)
			(xy 387.573551 -247.167351) (xy 387.616419 -247.203026) (xy 387.653636 -247.244563) (xy 387.684409 -247.291076)
			(xy 387.708081 -247.341573) (xy 387.724149 -247.39498) (xy 387.732269 -247.450156) (xy 387.732778 -247.478042)
			(xy 387.732269 -247.505928) (xy 387.724149 -247.561104) (xy 387.708081 -247.614511) (xy 387.684409 -247.665008)
			(xy 387.653636 -247.711521) (xy 387.616419 -247.753058) (xy 387.573551 -247.788733) (xy 387.525945 -247.817787)
			(xy 387.474616 -247.839599) (xy 387.420659 -247.853705) (xy 387.365222 -247.859805) (xy 387.309488 -247.857768)
			(xy 387.254645 -247.847638) (xy 387.201861 -247.829631) (xy 387.152261 -247.80413) (xy 387.106903 -247.771679)
			(xy 387.066754 -247.73297) (xy 387.032668 -247.688827) (xy 387.005372 -247.640192) (xy 386.985449 -247.588101)
			(xy 386.973323 -247.533664) (xy 386.969252 -247.478042) (xy 380.992919 -247.478042) (xy 381.004291 -247.487506)
			(xy 381.041508 -247.529043) (xy 381.072281 -247.575556) (xy 381.095953 -247.626053) (xy 381.112021 -247.67946)
			(xy 381.120141 -247.734636) (xy 381.12065 -247.762522) (xy 381.120141 -247.790408) (xy 381.112021 -247.845584)
			(xy 381.095953 -247.898991) (xy 381.072281 -247.949488) (xy 381.041508 -247.996001) (xy 381.004291 -248.037538)
			(xy 380.961423 -248.073213) (xy 380.913817 -248.102267) (xy 380.862488 -248.124079) (xy 380.808531 -248.138185)
			(xy 380.753094 -248.144285) (xy 380.69736 -248.142248) (xy 380.642517 -248.132118) (xy 380.589733 -248.114111)
			(xy 380.540133 -248.08861) (xy 380.494775 -248.056159) (xy 380.454626 -248.01745) (xy 380.42054 -247.973307)
			(xy 380.393244 -247.924672) (xy 380.373321 -247.872581) (xy 380.361195 -247.818144) (xy 380.357124 -247.762522)
			(xy 376.394062 -247.762522) (xy 376.381967 -247.802725) (xy 376.358295 -247.853222) (xy 376.327522 -247.899735)
			(xy 376.290305 -247.941272) (xy 376.247437 -247.976947) (xy 376.199831 -248.006001) (xy 376.148502 -248.027813)
			(xy 376.094545 -248.041919) (xy 376.039108 -248.048019) (xy 375.983374 -248.045982) (xy 375.928531 -248.035852)
			(xy 375.875747 -248.017845) (xy 375.826147 -247.992344) (xy 375.780789 -247.959893) (xy 375.74064 -247.921184)
			(xy 375.706554 -247.877041) (xy 375.679258 -247.828406) (xy 375.659335 -247.776315) (xy 375.647209 -247.721878)
			(xy 375.643138 -247.666256) (xy 375.300414 -247.666256) (xy 375.296149 -247.671016) (xy 375.253281 -247.706691)
			(xy 375.205675 -247.735745) (xy 375.154346 -247.757557) (xy 375.100389 -247.771663) (xy 375.044952 -247.777763)
			(xy 374.989218 -247.775726) (xy 374.934375 -247.765596) (xy 374.881591 -247.747589) (xy 374.831991 -247.722088)
			(xy 374.786633 -247.689637) (xy 374.746484 -247.650928) (xy 374.712398 -247.606785) (xy 374.685102 -247.55815)
			(xy 374.665179 -247.506059) (xy 374.653053 -247.451622) (xy 374.648982 -247.396) (xy 369.413536 -247.396)
			(xy 369.413536 -247.974358) (xy 369.78539 -247.974358) (xy 369.789461 -247.918736) (xy 369.801587 -247.864299)
			(xy 369.82151 -247.812208) (xy 369.848806 -247.763573) (xy 369.882892 -247.71943) (xy 369.923041 -247.680721)
			(xy 369.968399 -247.64827) (xy 370.017999 -247.622769) (xy 370.070783 -247.604762) (xy 370.125626 -247.594632)
			(xy 370.18136 -247.592595) (xy 370.236797 -247.598695) (xy 370.290754 -247.612801) (xy 370.342083 -247.634613)
			(xy 370.389689 -247.663667) (xy 370.432557 -247.699342) (xy 370.469774 -247.740879) (xy 370.500547 -247.787392)
			(xy 370.524219 -247.837889) (xy 370.540287 -247.891296) (xy 370.548407 -247.946472) (xy 370.548916 -247.974358)
			(xy 370.548407 -248.002244) (xy 370.540287 -248.05742) (xy 370.524219 -248.110827) (xy 370.500547 -248.161324)
			(xy 370.469774 -248.207837) (xy 370.432557 -248.249374) (xy 370.389689 -248.285049) (xy 370.342083 -248.314103)
			(xy 370.328681 -248.319798) (xy 385.663184 -248.319798) (xy 385.667255 -248.264176) (xy 385.679381 -248.209739)
			(xy 385.699304 -248.157648) (xy 385.7266 -248.109013) (xy 385.760686 -248.06487) (xy 385.800835 -248.026161)
			(xy 385.846193 -247.99371) (xy 385.895793 -247.968209) (xy 385.948577 -247.950202) (xy 386.00342 -247.940072)
			(xy 386.059154 -247.938035) (xy 386.114591 -247.944135) (xy 386.168548 -247.958241) (xy 386.219877 -247.980053)
			(xy 386.267483 -248.009107) (xy 386.310351 -248.044782) (xy 386.347568 -248.086319) (xy 386.378341 -248.132832)
			(xy 386.402013 -248.183329) (xy 386.418081 -248.236736) (xy 386.426201 -248.291912) (xy 386.42671 -248.319798)
			(xy 386.426201 -248.347684) (xy 386.418081 -248.40286) (xy 386.402013 -248.456267) (xy 386.378341 -248.506764)
			(xy 386.347568 -248.553277) (xy 386.310351 -248.594814) (xy 386.267483 -248.630489) (xy 386.219877 -248.659543)
			(xy 386.168548 -248.681355) (xy 386.114591 -248.695461) (xy 386.059154 -248.701561) (xy 386.00342 -248.699524)
			(xy 385.948577 -248.689394) (xy 385.895793 -248.671387) (xy 385.846193 -248.645886) (xy 385.800835 -248.613435)
			(xy 385.760686 -248.574726) (xy 385.7266 -248.530583) (xy 385.699304 -248.481948) (xy 385.679381 -248.429857)
			(xy 385.667255 -248.37542) (xy 385.663184 -248.319798) (xy 370.328681 -248.319798) (xy 370.290754 -248.335915)
			(xy 370.236797 -248.350021) (xy 370.18136 -248.356121) (xy 370.125626 -248.354084) (xy 370.070783 -248.343954)
			(xy 370.017999 -248.325947) (xy 369.968399 -248.300446) (xy 369.923041 -248.267995) (xy 369.882892 -248.229286)
			(xy 369.848806 -248.185143) (xy 369.82151 -248.136508) (xy 369.801587 -248.084417) (xy 369.789461 -248.02998)
			(xy 369.78539 -247.974358) (xy 369.413536 -247.974358) (xy 369.413536 -249.00382) (xy 373.276366 -249.00382)
			(xy 373.280437 -248.948198) (xy 373.292563 -248.893761) (xy 373.312486 -248.84167) (xy 373.339782 -248.793035)
			(xy 373.373868 -248.748892) (xy 373.414017 -248.710183) (xy 373.459375 -248.677732) (xy 373.508975 -248.652231)
			(xy 373.561759 -248.634224) (xy 373.616602 -248.624094) (xy 373.672336 -248.622057) (xy 373.727773 -248.628157)
			(xy 373.78173 -248.642263) (xy 373.833059 -248.664075) (xy 373.880665 -248.693129) (xy 373.923533 -248.728804)
			(xy 373.96075 -248.770341) (xy 373.991523 -248.816854) (xy 374.015195 -248.867351) (xy 374.031263 -248.920758)
			(xy 374.039383 -248.975934) (xy 374.039892 -249.00382) (xy 374.292366 -249.00382) (xy 374.296437 -248.948198)
			(xy 374.308563 -248.893761) (xy 374.328486 -248.84167) (xy 374.355782 -248.793035) (xy 374.389868 -248.748892)
			(xy 374.430017 -248.710183) (xy 374.475375 -248.677732) (xy 374.524975 -248.652231) (xy 374.577759 -248.634224)
			(xy 374.632602 -248.624094) (xy 374.688336 -248.622057) (xy 374.743773 -248.628157) (xy 374.79773 -248.642263)
			(xy 374.849059 -248.664075) (xy 374.896665 -248.693129) (xy 374.939533 -248.728804) (xy 374.97675 -248.770341)
			(xy 375.007523 -248.816854) (xy 375.031195 -248.867351) (xy 375.043367 -248.907808) (xy 388.388858 -248.907808)
			(xy 388.392929 -248.852186) (xy 388.405055 -248.797749) (xy 388.424978 -248.745658) (xy 388.452274 -248.697023)
			(xy 388.48636 -248.65288) (xy 388.526509 -248.614171) (xy 388.571867 -248.58172) (xy 388.621467 -248.556219)
			(xy 388.674251 -248.538212) (xy 388.729094 -248.528082) (xy 388.784828 -248.526045) (xy 388.840265 -248.532145)
			(xy 388.894222 -248.546251) (xy 388.945551 -248.568063) (xy 388.993157 -248.597117) (xy 389.036025 -248.632792)
			(xy 389.073242 -248.674329) (xy 389.104015 -248.720842) (xy 389.127687 -248.771339) (xy 389.143755 -248.824746)
			(xy 389.151875 -248.879922) (xy 389.152384 -248.907808) (xy 389.151875 -248.935694) (xy 389.143755 -248.99087)
			(xy 389.127687 -249.044277) (xy 389.104015 -249.094774) (xy 389.073242 -249.141287) (xy 389.036025 -249.182824)
			(xy 388.993157 -249.218499) (xy 388.945551 -249.247553) (xy 388.894222 -249.269365) (xy 388.840265 -249.283471)
			(xy 388.784828 -249.289571) (xy 388.729094 -249.287534) (xy 388.674251 -249.277404) (xy 388.621467 -249.259397)
			(xy 388.571867 -249.233896) (xy 388.526509 -249.201445) (xy 388.48636 -249.162736) (xy 388.452274 -249.118593)
			(xy 388.424978 -249.069958) (xy 388.405055 -249.017867) (xy 388.392929 -248.96343) (xy 388.388858 -248.907808)
			(xy 375.043367 -248.907808) (xy 375.047263 -248.920758) (xy 375.055383 -248.975934) (xy 375.055892 -249.00382)
			(xy 375.055383 -249.031706) (xy 375.047263 -249.086882) (xy 375.031195 -249.140289) (xy 375.007523 -249.190786)
			(xy 374.97675 -249.237299) (xy 374.939533 -249.278836) (xy 374.896665 -249.314511) (xy 374.849059 -249.343565)
			(xy 374.79773 -249.365377) (xy 374.743773 -249.379483) (xy 374.688336 -249.385583) (xy 374.632602 -249.383546)
			(xy 374.577759 -249.373416) (xy 374.524975 -249.355409) (xy 374.475375 -249.329908) (xy 374.430017 -249.297457)
			(xy 374.389868 -249.258748) (xy 374.355782 -249.214605) (xy 374.328486 -249.16597) (xy 374.308563 -249.113879)
			(xy 374.296437 -249.059442) (xy 374.292366 -249.00382) (xy 374.039892 -249.00382) (xy 374.039383 -249.031706)
			(xy 374.031263 -249.086882) (xy 374.015195 -249.140289) (xy 373.991523 -249.190786) (xy 373.96075 -249.237299)
			(xy 373.923533 -249.278836) (xy 373.880665 -249.314511) (xy 373.833059 -249.343565) (xy 373.78173 -249.365377)
			(xy 373.727773 -249.379483) (xy 373.672336 -249.385583) (xy 373.616602 -249.383546) (xy 373.561759 -249.373416)
			(xy 373.508975 -249.355409) (xy 373.459375 -249.329908) (xy 373.414017 -249.297457) (xy 373.373868 -249.258748)
			(xy 373.339782 -249.214605) (xy 373.312486 -249.16597) (xy 373.292563 -249.113879) (xy 373.280437 -249.059442)
			(xy 373.276366 -249.00382) (xy 369.413536 -249.00382) (xy 369.413536 -250.977654) (xy 369.414552 -250.987052)
			(xy 369.414552 -250.98756) (xy 369.416252 -250.994722) (xy 369.423076 -251.007756) (xy 369.428014 -251.013214)
			(xy 369.730528 -251.315728) (xy 370.335808 -251.315728) (xy 370.339879 -251.260106) (xy 370.352005 -251.205669)
			(xy 370.371928 -251.153578) (xy 370.399224 -251.104943) (xy 370.43331 -251.0608) (xy 370.473459 -251.022091)
			(xy 370.518817 -250.98964) (xy 370.568417 -250.964139) (xy 370.621201 -250.946132) (xy 370.676044 -250.936002)
			(xy 370.731778 -250.933965) (xy 370.787215 -250.940065) (xy 370.841172 -250.954171) (xy 370.892501 -250.975983)
			(xy 370.940107 -251.005037) (xy 370.982975 -251.040712) (xy 371.020192 -251.082249) (xy 371.050965 -251.128762)
			(xy 371.064907 -251.158502) (xy 372.260366 -251.158502) (xy 372.264437 -251.10288) (xy 372.276563 -251.048443)
			(xy 372.296486 -250.996352) (xy 372.323782 -250.947717) (xy 372.357868 -250.903574) (xy 372.398017 -250.864865)
			(xy 372.443375 -250.832414) (xy 372.492975 -250.806913) (xy 372.545759 -250.788906) (xy 372.600602 -250.778776)
			(xy 372.656336 -250.776739) (xy 372.711773 -250.782839) (xy 372.76573 -250.796945) (xy 372.817059 -250.818757)
			(xy 372.864665 -250.847811) (xy 372.907533 -250.883486) (xy 372.94475 -250.925023) (xy 372.975523 -250.971536)
			(xy 372.999195 -251.022033) (xy 373.015263 -251.07544) (xy 373.023383 -251.130616) (xy 373.023892 -251.158502)
			(xy 373.327166 -251.158502) (xy 373.331237 -251.10288) (xy 373.343363 -251.048443) (xy 373.363286 -250.996352)
			(xy 373.390582 -250.947717) (xy 373.424668 -250.903574) (xy 373.464817 -250.864865) (xy 373.510175 -250.832414)
			(xy 373.559775 -250.806913) (xy 373.612559 -250.788906) (xy 373.667402 -250.778776) (xy 373.723136 -250.776739)
			(xy 373.778573 -250.782839) (xy 373.83253 -250.796945) (xy 373.883859 -250.818757) (xy 373.931465 -250.847811)
			(xy 373.974333 -250.883486) (xy 374.01155 -250.925023) (xy 374.042323 -250.971536) (xy 374.065995 -251.022033)
			(xy 374.082063 -251.07544) (xy 374.090183 -251.130616) (xy 374.090692 -251.158502) (xy 374.292366 -251.158502)
			(xy 374.296437 -251.10288) (xy 374.308563 -251.048443) (xy 374.328486 -250.996352) (xy 374.355782 -250.947717)
			(xy 374.389868 -250.903574) (xy 374.430017 -250.864865) (xy 374.475375 -250.832414) (xy 374.524975 -250.806913)
			(xy 374.577759 -250.788906) (xy 374.632602 -250.778776) (xy 374.688336 -250.776739) (xy 374.743773 -250.782839)
			(xy 374.79773 -250.796945) (xy 374.849059 -250.818757) (xy 374.896665 -250.847811) (xy 374.939533 -250.883486)
			(xy 374.97675 -250.925023) (xy 375.007523 -250.971536) (xy 375.031195 -251.022033) (xy 375.047263 -251.07544)
			(xy 375.055383 -251.130616) (xy 375.055892 -251.158502) (xy 375.308366 -251.158502) (xy 375.312437 -251.10288)
			(xy 375.324563 -251.048443) (xy 375.344486 -250.996352) (xy 375.371782 -250.947717) (xy 375.405868 -250.903574)
			(xy 375.446017 -250.864865) (xy 375.491375 -250.832414) (xy 375.540975 -250.806913) (xy 375.593759 -250.788906)
			(xy 375.648602 -250.778776) (xy 375.704336 -250.776739) (xy 375.759773 -250.782839) (xy 375.81373 -250.796945)
			(xy 375.865059 -250.818757) (xy 375.912665 -250.847811) (xy 375.955533 -250.883486) (xy 375.99275 -250.925023)
			(xy 376.023523 -250.971536) (xy 376.047195 -251.022033) (xy 376.063263 -251.07544) (xy 376.071383 -251.130616)
			(xy 376.071892 -251.158502) (xy 376.324366 -251.158502) (xy 376.328437 -251.10288) (xy 376.340563 -251.048443)
			(xy 376.360486 -250.996352) (xy 376.387782 -250.947717) (xy 376.421868 -250.903574) (xy 376.462017 -250.864865)
			(xy 376.507375 -250.832414) (xy 376.556975 -250.806913) (xy 376.609759 -250.788906) (xy 376.664602 -250.778776)
			(xy 376.720336 -250.776739) (xy 376.775773 -250.782839) (xy 376.82973 -250.796945) (xy 376.881059 -250.818757)
			(xy 376.928665 -250.847811) (xy 376.971533 -250.883486) (xy 377.00875 -250.925023) (xy 377.039523 -250.971536)
			(xy 377.063195 -251.022033) (xy 377.079263 -251.07544) (xy 377.087383 -251.130616) (xy 377.087892 -251.158502)
			(xy 377.340366 -251.158502) (xy 377.344437 -251.10288) (xy 377.356563 -251.048443) (xy 377.376486 -250.996352)
			(xy 377.403782 -250.947717) (xy 377.437868 -250.903574) (xy 377.478017 -250.864865) (xy 377.523375 -250.832414)
			(xy 377.572975 -250.806913) (xy 377.625759 -250.788906) (xy 377.680602 -250.778776) (xy 377.736336 -250.776739)
			(xy 377.791773 -250.782839) (xy 377.84573 -250.796945) (xy 377.897059 -250.818757) (xy 377.944665 -250.847811)
			(xy 377.987533 -250.883486) (xy 378.02475 -250.925023) (xy 378.055523 -250.971536) (xy 378.079195 -251.022033)
			(xy 378.095263 -251.07544) (xy 378.103383 -251.130616) (xy 378.103892 -251.158502) (xy 378.356366 -251.158502)
			(xy 378.360437 -251.10288) (xy 378.372563 -251.048443) (xy 378.392486 -250.996352) (xy 378.419782 -250.947717)
			(xy 378.453868 -250.903574) (xy 378.494017 -250.864865) (xy 378.539375 -250.832414) (xy 378.588975 -250.806913)
			(xy 378.641759 -250.788906) (xy 378.696602 -250.778776) (xy 378.752336 -250.776739) (xy 378.807773 -250.782839)
			(xy 378.86173 -250.796945) (xy 378.913059 -250.818757) (xy 378.960665 -250.847811) (xy 379.003533 -250.883486)
			(xy 379.04075 -250.925023) (xy 379.071523 -250.971536) (xy 379.095195 -251.022033) (xy 379.111263 -251.07544)
			(xy 379.119383 -251.130616) (xy 379.119892 -251.158502) (xy 379.372366 -251.158502) (xy 379.376437 -251.10288)
			(xy 379.388563 -251.048443) (xy 379.408486 -250.996352) (xy 379.435782 -250.947717) (xy 379.469868 -250.903574)
			(xy 379.510017 -250.864865) (xy 379.555375 -250.832414) (xy 379.604975 -250.806913) (xy 379.657759 -250.788906)
			(xy 379.712602 -250.778776) (xy 379.768336 -250.776739) (xy 379.823773 -250.782839) (xy 379.87773 -250.796945)
			(xy 379.929059 -250.818757) (xy 379.976665 -250.847811) (xy 380.019533 -250.883486) (xy 380.05675 -250.925023)
			(xy 380.087523 -250.971536) (xy 380.111195 -251.022033) (xy 380.127263 -251.07544) (xy 380.135383 -251.130616)
			(xy 380.135892 -251.158502) (xy 380.388366 -251.158502) (xy 380.392437 -251.10288) (xy 380.404563 -251.048443)
			(xy 380.424486 -250.996352) (xy 380.451782 -250.947717) (xy 380.485868 -250.903574) (xy 380.526017 -250.864865)
			(xy 380.571375 -250.832414) (xy 380.620975 -250.806913) (xy 380.673759 -250.788906) (xy 380.728602 -250.778776)
			(xy 380.784336 -250.776739) (xy 380.839773 -250.782839) (xy 380.89373 -250.796945) (xy 380.945059 -250.818757)
			(xy 380.992665 -250.847811) (xy 381.035533 -250.883486) (xy 381.07275 -250.925023) (xy 381.103523 -250.971536)
			(xy 381.127195 -251.022033) (xy 381.143263 -251.07544) (xy 381.151383 -251.130616) (xy 381.151892 -251.158502)
			(xy 381.404366 -251.158502) (xy 381.408437 -251.10288) (xy 381.420563 -251.048443) (xy 381.440486 -250.996352)
			(xy 381.467782 -250.947717) (xy 381.501868 -250.903574) (xy 381.542017 -250.864865) (xy 381.587375 -250.832414)
			(xy 381.636975 -250.806913) (xy 381.689759 -250.788906) (xy 381.744602 -250.778776) (xy 381.800336 -250.776739)
			(xy 381.855773 -250.782839) (xy 381.90973 -250.796945) (xy 381.961059 -250.818757) (xy 382.008665 -250.847811)
			(xy 382.051533 -250.883486) (xy 382.08875 -250.925023) (xy 382.119523 -250.971536) (xy 382.143195 -251.022033)
			(xy 382.159263 -251.07544) (xy 382.167383 -251.130616) (xy 382.167892 -251.158502) (xy 382.420366 -251.158502)
			(xy 382.424437 -251.10288) (xy 382.436563 -251.048443) (xy 382.456486 -250.996352) (xy 382.483782 -250.947717)
			(xy 382.517868 -250.903574) (xy 382.558017 -250.864865) (xy 382.603375 -250.832414) (xy 382.652975 -250.806913)
			(xy 382.705759 -250.788906) (xy 382.760602 -250.778776) (xy 382.816336 -250.776739) (xy 382.871773 -250.782839)
			(xy 382.92573 -250.796945) (xy 382.977059 -250.818757) (xy 383.024665 -250.847811) (xy 383.067533 -250.883486)
			(xy 383.10475 -250.925023) (xy 383.135523 -250.971536) (xy 383.159195 -251.022033) (xy 383.175263 -251.07544)
			(xy 383.183383 -251.130616) (xy 383.183892 -251.158502) (xy 383.436366 -251.158502) (xy 383.440437 -251.10288)
			(xy 383.452563 -251.048443) (xy 383.472486 -250.996352) (xy 383.499782 -250.947717) (xy 383.533868 -250.903574)
			(xy 383.574017 -250.864865) (xy 383.619375 -250.832414) (xy 383.668975 -250.806913) (xy 383.721759 -250.788906)
			(xy 383.776602 -250.778776) (xy 383.832336 -250.776739) (xy 383.887773 -250.782839) (xy 383.94173 -250.796945)
			(xy 383.993059 -250.818757) (xy 384.040665 -250.847811) (xy 384.083533 -250.883486) (xy 384.12075 -250.925023)
			(xy 384.151523 -250.971536) (xy 384.175195 -251.022033) (xy 384.191263 -251.07544) (xy 384.199383 -251.130616)
			(xy 384.199892 -251.158502) (xy 384.452366 -251.158502) (xy 384.456437 -251.10288) (xy 384.468563 -251.048443)
			(xy 384.488486 -250.996352) (xy 384.515782 -250.947717) (xy 384.549868 -250.903574) (xy 384.590017 -250.864865)
			(xy 384.635375 -250.832414) (xy 384.684975 -250.806913) (xy 384.737759 -250.788906) (xy 384.792602 -250.778776)
			(xy 384.848336 -250.776739) (xy 384.903773 -250.782839) (xy 384.95773 -250.796945) (xy 385.009059 -250.818757)
			(xy 385.056665 -250.847811) (xy 385.099533 -250.883486) (xy 385.13675 -250.925023) (xy 385.167523 -250.971536)
			(xy 385.191195 -251.022033) (xy 385.207263 -251.07544) (xy 385.215383 -251.130616) (xy 385.215892 -251.158502)
			(xy 385.468366 -251.158502) (xy 385.472437 -251.10288) (xy 385.484563 -251.048443) (xy 385.504486 -250.996352)
			(xy 385.531782 -250.947717) (xy 385.565868 -250.903574) (xy 385.606017 -250.864865) (xy 385.651375 -250.832414)
			(xy 385.700975 -250.806913) (xy 385.753759 -250.788906) (xy 385.808602 -250.778776) (xy 385.864336 -250.776739)
			(xy 385.919773 -250.782839) (xy 385.97373 -250.796945) (xy 386.025059 -250.818757) (xy 386.072665 -250.847811)
			(xy 386.115533 -250.883486) (xy 386.15275 -250.925023) (xy 386.183523 -250.971536) (xy 386.207195 -251.022033)
			(xy 386.223263 -251.07544) (xy 386.231383 -251.130616) (xy 386.231892 -251.158502) (xy 386.484366 -251.158502)
			(xy 386.488437 -251.10288) (xy 386.500563 -251.048443) (xy 386.520486 -250.996352) (xy 386.547782 -250.947717)
			(xy 386.581868 -250.903574) (xy 386.622017 -250.864865) (xy 386.667375 -250.832414) (xy 386.716975 -250.806913)
			(xy 386.769759 -250.788906) (xy 386.824602 -250.778776) (xy 386.880336 -250.776739) (xy 386.935773 -250.782839)
			(xy 386.98973 -250.796945) (xy 387.041059 -250.818757) (xy 387.088665 -250.847811) (xy 387.131533 -250.883486)
			(xy 387.16875 -250.925023) (xy 387.199523 -250.971536) (xy 387.223195 -251.022033) (xy 387.239263 -251.07544)
			(xy 387.247383 -251.130616) (xy 387.247892 -251.158502) (xy 388.516366 -251.158502) (xy 388.520437 -251.10288)
			(xy 388.532563 -251.048443) (xy 388.552486 -250.996352) (xy 388.579782 -250.947717) (xy 388.613868 -250.903574)
			(xy 388.654017 -250.864865) (xy 388.699375 -250.832414) (xy 388.748975 -250.806913) (xy 388.801759 -250.788906)
			(xy 388.856602 -250.778776) (xy 388.912336 -250.776739) (xy 388.967773 -250.782839) (xy 389.02173 -250.796945)
			(xy 389.073059 -250.818757) (xy 389.120665 -250.847811) (xy 389.163533 -250.883486) (xy 389.20075 -250.925023)
			(xy 389.231523 -250.971536) (xy 389.255195 -251.022033) (xy 389.271263 -251.07544) (xy 389.279383 -251.130616)
			(xy 389.279892 -251.158502) (xy 389.279383 -251.186388) (xy 389.271263 -251.241564) (xy 389.255195 -251.294971)
			(xy 389.231523 -251.345468) (xy 389.20075 -251.391981) (xy 389.163533 -251.433518) (xy 389.120665 -251.469193)
			(xy 389.073059 -251.498247) (xy 389.02173 -251.520059) (xy 388.967773 -251.534165) (xy 388.912336 -251.540265)
			(xy 388.856602 -251.538228) (xy 388.801759 -251.528098) (xy 388.748975 -251.510091) (xy 388.699375 -251.48459)
			(xy 388.654017 -251.452139) (xy 388.613868 -251.41343) (xy 388.579782 -251.369287) (xy 388.552486 -251.320652)
			(xy 388.532563 -251.268561) (xy 388.520437 -251.214124) (xy 388.516366 -251.158502) (xy 387.247892 -251.158502)
			(xy 387.247383 -251.186388) (xy 387.239263 -251.241564) (xy 387.223195 -251.294971) (xy 387.199523 -251.345468)
			(xy 387.16875 -251.391981) (xy 387.131533 -251.433518) (xy 387.088665 -251.469193) (xy 387.041059 -251.498247)
			(xy 386.98973 -251.520059) (xy 386.935773 -251.534165) (xy 386.880336 -251.540265) (xy 386.824602 -251.538228)
			(xy 386.769759 -251.528098) (xy 386.716975 -251.510091) (xy 386.667375 -251.48459) (xy 386.622017 -251.452139)
			(xy 386.581868 -251.41343) (xy 386.547782 -251.369287) (xy 386.520486 -251.320652) (xy 386.500563 -251.268561)
			(xy 386.488437 -251.214124) (xy 386.484366 -251.158502) (xy 386.231892 -251.158502) (xy 386.231383 -251.186388)
			(xy 386.223263 -251.241564) (xy 386.207195 -251.294971) (xy 386.183523 -251.345468) (xy 386.15275 -251.391981)
			(xy 386.115533 -251.433518) (xy 386.072665 -251.469193) (xy 386.025059 -251.498247) (xy 385.97373 -251.520059)
			(xy 385.919773 -251.534165) (xy 385.864336 -251.540265) (xy 385.808602 -251.538228) (xy 385.753759 -251.528098)
			(xy 385.700975 -251.510091) (xy 385.651375 -251.48459) (xy 385.606017 -251.452139) (xy 385.565868 -251.41343)
			(xy 385.531782 -251.369287) (xy 385.504486 -251.320652) (xy 385.484563 -251.268561) (xy 385.472437 -251.214124)
			(xy 385.468366 -251.158502) (xy 385.215892 -251.158502) (xy 385.215383 -251.186388) (xy 385.207263 -251.241564)
			(xy 385.191195 -251.294971) (xy 385.167523 -251.345468) (xy 385.13675 -251.391981) (xy 385.099533 -251.433518)
			(xy 385.056665 -251.469193) (xy 385.009059 -251.498247) (xy 384.95773 -251.520059) (xy 384.903773 -251.534165)
			(xy 384.848336 -251.540265) (xy 384.792602 -251.538228) (xy 384.737759 -251.528098) (xy 384.684975 -251.510091)
			(xy 384.635375 -251.48459) (xy 384.590017 -251.452139) (xy 384.549868 -251.41343) (xy 384.515782 -251.369287)
			(xy 384.488486 -251.320652) (xy 384.468563 -251.268561) (xy 384.456437 -251.214124) (xy 384.452366 -251.158502)
			(xy 384.199892 -251.158502) (xy 384.199383 -251.186388) (xy 384.191263 -251.241564) (xy 384.175195 -251.294971)
			(xy 384.151523 -251.345468) (xy 384.12075 -251.391981) (xy 384.083533 -251.433518) (xy 384.040665 -251.469193)
			(xy 383.993059 -251.498247) (xy 383.94173 -251.520059) (xy 383.887773 -251.534165) (xy 383.832336 -251.540265)
			(xy 383.776602 -251.538228) (xy 383.721759 -251.528098) (xy 383.668975 -251.510091) (xy 383.619375 -251.48459)
			(xy 383.574017 -251.452139) (xy 383.533868 -251.41343) (xy 383.499782 -251.369287) (xy 383.472486 -251.320652)
			(xy 383.452563 -251.268561) (xy 383.440437 -251.214124) (xy 383.436366 -251.158502) (xy 383.183892 -251.158502)
			(xy 383.183383 -251.186388) (xy 383.175263 -251.241564) (xy 383.159195 -251.294971) (xy 383.135523 -251.345468)
			(xy 383.10475 -251.391981) (xy 383.067533 -251.433518) (xy 383.024665 -251.469193) (xy 382.977059 -251.498247)
			(xy 382.92573 -251.520059) (xy 382.871773 -251.534165) (xy 382.816336 -251.540265) (xy 382.760602 -251.538228)
			(xy 382.705759 -251.528098) (xy 382.652975 -251.510091) (xy 382.603375 -251.48459) (xy 382.558017 -251.452139)
			(xy 382.517868 -251.41343) (xy 382.483782 -251.369287) (xy 382.456486 -251.320652) (xy 382.436563 -251.268561)
			(xy 382.424437 -251.214124) (xy 382.420366 -251.158502) (xy 382.167892 -251.158502) (xy 382.167383 -251.186388)
			(xy 382.159263 -251.241564) (xy 382.143195 -251.294971) (xy 382.119523 -251.345468) (xy 382.08875 -251.391981)
			(xy 382.051533 -251.433518) (xy 382.008665 -251.469193) (xy 381.961059 -251.498247) (xy 381.90973 -251.520059)
			(xy 381.855773 -251.534165) (xy 381.800336 -251.540265) (xy 381.744602 -251.538228) (xy 381.689759 -251.528098)
			(xy 381.636975 -251.510091) (xy 381.587375 -251.48459) (xy 381.542017 -251.452139) (xy 381.501868 -251.41343)
			(xy 381.467782 -251.369287) (xy 381.440486 -251.320652) (xy 381.420563 -251.268561) (xy 381.408437 -251.214124)
			(xy 381.404366 -251.158502) (xy 381.151892 -251.158502) (xy 381.151383 -251.186388) (xy 381.143263 -251.241564)
			(xy 381.127195 -251.294971) (xy 381.103523 -251.345468) (xy 381.07275 -251.391981) (xy 381.035533 -251.433518)
			(xy 380.992665 -251.469193) (xy 380.945059 -251.498247) (xy 380.89373 -251.520059) (xy 380.839773 -251.534165)
			(xy 380.784336 -251.540265) (xy 380.728602 -251.538228) (xy 380.673759 -251.528098) (xy 380.620975 -251.510091)
			(xy 380.571375 -251.48459) (xy 380.526017 -251.452139) (xy 380.485868 -251.41343) (xy 380.451782 -251.369287)
			(xy 380.424486 -251.320652) (xy 380.404563 -251.268561) (xy 380.392437 -251.214124) (xy 380.388366 -251.158502)
			(xy 380.135892 -251.158502) (xy 380.135383 -251.186388) (xy 380.127263 -251.241564) (xy 380.111195 -251.294971)
			(xy 380.087523 -251.345468) (xy 380.05675 -251.391981) (xy 380.019533 -251.433518) (xy 379.976665 -251.469193)
			(xy 379.929059 -251.498247) (xy 379.87773 -251.520059) (xy 379.823773 -251.534165) (xy 379.768336 -251.540265)
			(xy 379.712602 -251.538228) (xy 379.657759 -251.528098) (xy 379.604975 -251.510091) (xy 379.555375 -251.48459)
			(xy 379.510017 -251.452139) (xy 379.469868 -251.41343) (xy 379.435782 -251.369287) (xy 379.408486 -251.320652)
			(xy 379.388563 -251.268561) (xy 379.376437 -251.214124) (xy 379.372366 -251.158502) (xy 379.119892 -251.158502)
			(xy 379.119383 -251.186388) (xy 379.111263 -251.241564) (xy 379.095195 -251.294971) (xy 379.071523 -251.345468)
			(xy 379.04075 -251.391981) (xy 379.003533 -251.433518) (xy 378.960665 -251.469193) (xy 378.913059 -251.498247)
			(xy 378.86173 -251.520059) (xy 378.807773 -251.534165) (xy 378.752336 -251.540265) (xy 378.696602 -251.538228)
			(xy 378.641759 -251.528098) (xy 378.588975 -251.510091) (xy 378.539375 -251.48459) (xy 378.494017 -251.452139)
			(xy 378.453868 -251.41343) (xy 378.419782 -251.369287) (xy 378.392486 -251.320652) (xy 378.372563 -251.268561)
			(xy 378.360437 -251.214124) (xy 378.356366 -251.158502) (xy 378.103892 -251.158502) (xy 378.103383 -251.186388)
			(xy 378.095263 -251.241564) (xy 378.079195 -251.294971) (xy 378.055523 -251.345468) (xy 378.02475 -251.391981)
			(xy 377.987533 -251.433518) (xy 377.944665 -251.469193) (xy 377.897059 -251.498247) (xy 377.84573 -251.520059)
			(xy 377.791773 -251.534165) (xy 377.736336 -251.540265) (xy 377.680602 -251.538228) (xy 377.625759 -251.528098)
			(xy 377.572975 -251.510091) (xy 377.523375 -251.48459) (xy 377.478017 -251.452139) (xy 377.437868 -251.41343)
			(xy 377.403782 -251.369287) (xy 377.376486 -251.320652) (xy 377.356563 -251.268561) (xy 377.344437 -251.214124)
			(xy 377.340366 -251.158502) (xy 377.087892 -251.158502) (xy 377.087383 -251.186388) (xy 377.079263 -251.241564)
			(xy 377.063195 -251.294971) (xy 377.039523 -251.345468) (xy 377.00875 -251.391981) (xy 376.971533 -251.433518)
			(xy 376.928665 -251.469193) (xy 376.881059 -251.498247) (xy 376.82973 -251.520059) (xy 376.775773 -251.534165)
			(xy 376.720336 -251.540265) (xy 376.664602 -251.538228) (xy 376.609759 -251.528098) (xy 376.556975 -251.510091)
			(xy 376.507375 -251.48459) (xy 376.462017 -251.452139) (xy 376.421868 -251.41343) (xy 376.387782 -251.369287)
			(xy 376.360486 -251.320652) (xy 376.340563 -251.268561) (xy 376.328437 -251.214124) (xy 376.324366 -251.158502)
			(xy 376.071892 -251.158502) (xy 376.071383 -251.186388) (xy 376.063263 -251.241564) (xy 376.047195 -251.294971)
			(xy 376.023523 -251.345468) (xy 375.99275 -251.391981) (xy 375.955533 -251.433518) (xy 375.912665 -251.469193)
			(xy 375.865059 -251.498247) (xy 375.81373 -251.520059) (xy 375.759773 -251.534165) (xy 375.704336 -251.540265)
			(xy 375.648602 -251.538228) (xy 375.593759 -251.528098) (xy 375.540975 -251.510091) (xy 375.491375 -251.48459)
			(xy 375.446017 -251.452139) (xy 375.405868 -251.41343) (xy 375.371782 -251.369287) (xy 375.344486 -251.320652)
			(xy 375.324563 -251.268561) (xy 375.312437 -251.214124) (xy 375.308366 -251.158502) (xy 375.055892 -251.158502)
			(xy 375.055383 -251.186388) (xy 375.047263 -251.241564) (xy 375.031195 -251.294971) (xy 375.007523 -251.345468)
			(xy 374.97675 -251.391981) (xy 374.939533 -251.433518) (xy 374.896665 -251.469193) (xy 374.849059 -251.498247)
			(xy 374.79773 -251.520059) (xy 374.743773 -251.534165) (xy 374.688336 -251.540265) (xy 374.632602 -251.538228)
			(xy 374.577759 -251.528098) (xy 374.524975 -251.510091) (xy 374.475375 -251.48459) (xy 374.430017 -251.452139)
			(xy 374.389868 -251.41343) (xy 374.355782 -251.369287) (xy 374.328486 -251.320652) (xy 374.308563 -251.268561)
			(xy 374.296437 -251.214124) (xy 374.292366 -251.158502) (xy 374.090692 -251.158502) (xy 374.090183 -251.186388)
			(xy 374.082063 -251.241564) (xy 374.065995 -251.294971) (xy 374.042323 -251.345468) (xy 374.01155 -251.391981)
			(xy 373.974333 -251.433518) (xy 373.931465 -251.469193) (xy 373.883859 -251.498247) (xy 373.83253 -251.520059)
			(xy 373.778573 -251.534165) (xy 373.723136 -251.540265) (xy 373.667402 -251.538228) (xy 373.612559 -251.528098)
			(xy 373.559775 -251.510091) (xy 373.510175 -251.48459) (xy 373.464817 -251.452139) (xy 373.424668 -251.41343)
			(xy 373.390582 -251.369287) (xy 373.363286 -251.320652) (xy 373.343363 -251.268561) (xy 373.331237 -251.214124)
			(xy 373.327166 -251.158502) (xy 373.023892 -251.158502) (xy 373.023383 -251.186388) (xy 373.015263 -251.241564)
			(xy 372.999195 -251.294971) (xy 372.975523 -251.345468) (xy 372.94475 -251.391981) (xy 372.907533 -251.433518)
			(xy 372.864665 -251.469193) (xy 372.817059 -251.498247) (xy 372.76573 -251.520059) (xy 372.711773 -251.534165)
			(xy 372.656336 -251.540265) (xy 372.600602 -251.538228) (xy 372.545759 -251.528098) (xy 372.492975 -251.510091)
			(xy 372.443375 -251.48459) (xy 372.398017 -251.452139) (xy 372.357868 -251.41343) (xy 372.323782 -251.369287)
			(xy 372.296486 -251.320652) (xy 372.276563 -251.268561) (xy 372.264437 -251.214124) (xy 372.260366 -251.158502)
			(xy 371.064907 -251.158502) (xy 371.074637 -251.179259) (xy 371.090705 -251.232666) (xy 371.098825 -251.287842)
			(xy 371.099334 -251.315728) (xy 371.098825 -251.343614) (xy 371.090705 -251.39879) (xy 371.074637 -251.452197)
			(xy 371.050965 -251.502694) (xy 371.020192 -251.549207) (xy 370.982975 -251.590744) (xy 370.940107 -251.626419)
			(xy 370.892501 -251.655473) (xy 370.841172 -251.677285) (xy 370.787215 -251.691391) (xy 370.731778 -251.697491)
			(xy 370.676044 -251.695454) (xy 370.621201 -251.685324) (xy 370.568417 -251.667317) (xy 370.518817 -251.641816)
			(xy 370.473459 -251.609365) (xy 370.43331 -251.570656) (xy 370.399224 -251.526513) (xy 370.371928 -251.477878)
			(xy 370.352005 -251.425787) (xy 370.339879 -251.37135) (xy 370.335808 -251.315728) (xy 369.730528 -251.315728)
			(xy 371.87124 -253.45644) (xy 387.500366 -253.45644) (xy 387.504437 -253.400818) (xy 387.516563 -253.346381)
			(xy 387.536486 -253.29429) (xy 387.563782 -253.245655) (xy 387.597868 -253.201512) (xy 387.638017 -253.162803)
			(xy 387.683375 -253.130352) (xy 387.732975 -253.104851) (xy 387.785759 -253.086844) (xy 387.840602 -253.076714)
			(xy 387.896336 -253.074677) (xy 387.951773 -253.080777) (xy 388.00573 -253.094883) (xy 388.057059 -253.116695)
			(xy 388.104665 -253.145749) (xy 388.147533 -253.181424) (xy 388.18475 -253.222961) (xy 388.215523 -253.269474)
			(xy 388.239195 -253.319971) (xy 388.255263 -253.373378) (xy 388.263383 -253.428554) (xy 388.263892 -253.45644)
			(xy 388.263383 -253.484326) (xy 388.255263 -253.539502) (xy 388.239195 -253.592909) (xy 388.215523 -253.643406)
			(xy 388.18475 -253.689919) (xy 388.147533 -253.731456) (xy 388.104665 -253.767131) (xy 388.057059 -253.796185)
			(xy 388.00573 -253.817997) (xy 387.951773 -253.832103) (xy 387.896336 -253.838203) (xy 387.840602 -253.836166)
			(xy 387.785759 -253.826036) (xy 387.732975 -253.808029) (xy 387.683375 -253.782528) (xy 387.638017 -253.750077)
			(xy 387.597868 -253.711368) (xy 387.563782 -253.667225) (xy 387.536486 -253.61859) (xy 387.516563 -253.566499)
			(xy 387.504437 -253.512062) (xy 387.500366 -253.45644) (xy 371.87124 -253.45644) (xy 373.037862 -254.623062)
			(xy 374.28373 -254.623062) (xy 374.287801 -254.56744) (xy 374.299927 -254.513003) (xy 374.31985 -254.460912)
			(xy 374.347146 -254.412277) (xy 374.381232 -254.368134) (xy 374.421381 -254.329425) (xy 374.466739 -254.296974)
			(xy 374.516339 -254.271473) (xy 374.569123 -254.253466) (xy 374.623966 -254.243336) (xy 374.6797 -254.241299)
			(xy 374.735137 -254.247399) (xy 374.789094 -254.261505) (xy 374.840423 -254.283317) (xy 374.888029 -254.312371)
			(xy 374.930897 -254.348046) (xy 374.968114 -254.389583) (xy 374.998887 -254.436096) (xy 375.022559 -254.486593)
			(xy 375.032515 -254.519684) (xy 377.383546 -254.519684) (xy 377.387617 -254.464062) (xy 377.399743 -254.409625)
			(xy 377.419666 -254.357534) (xy 377.446962 -254.308899) (xy 377.481048 -254.264756) (xy 377.521197 -254.226047)
			(xy 377.566555 -254.193596) (xy 377.616155 -254.168095) (xy 377.668939 -254.150088) (xy 377.723782 -254.139958)
			(xy 377.779516 -254.137921) (xy 377.834953 -254.144021) (xy 377.88891 -254.158127) (xy 377.940239 -254.179939)
			(xy 377.987845 -254.208993) (xy 378.030713 -254.244668) (xy 378.06793 -254.286205) (xy 378.098703 -254.332718)
			(xy 378.122375 -254.383215) (xy 378.138443 -254.436622) (xy 378.146563 -254.491798) (xy 378.147072 -254.519684)
			(xy 378.146563 -254.54757) (xy 378.138443 -254.602746) (xy 378.122375 -254.656153) (xy 378.098703 -254.70665)
			(xy 378.06793 -254.753163) (xy 378.030713 -254.7947) (xy 377.987845 -254.830375) (xy 377.940239 -254.859429)
			(xy 377.88891 -254.881241) (xy 377.834953 -254.895347) (xy 377.779516 -254.901447) (xy 377.723782 -254.89941)
			(xy 377.668939 -254.88928) (xy 377.616155 -254.871273) (xy 377.566555 -254.845772) (xy 377.521197 -254.813321)
			(xy 377.481048 -254.774612) (xy 377.446962 -254.730469) (xy 377.419666 -254.681834) (xy 377.399743 -254.629743)
			(xy 377.387617 -254.575306) (xy 377.383546 -254.519684) (xy 375.032515 -254.519684) (xy 375.038627 -254.54)
			(xy 375.046747 -254.595176) (xy 375.047256 -254.623062) (xy 375.046747 -254.650948) (xy 375.038627 -254.706124)
			(xy 375.022559 -254.759531) (xy 374.998887 -254.810028) (xy 374.968114 -254.856541) (xy 374.930897 -254.898078)
			(xy 374.888029 -254.933753) (xy 374.840423 -254.962807) (xy 374.789094 -254.984619) (xy 374.735137 -254.998725)
			(xy 374.6797 -255.004825) (xy 374.623966 -255.002788) (xy 374.569123 -254.992658) (xy 374.516339 -254.974651)
			(xy 374.466739 -254.94915) (xy 374.421381 -254.916699) (xy 374.381232 -254.87799) (xy 374.347146 -254.833847)
			(xy 374.31985 -254.785212) (xy 374.299927 -254.733121) (xy 374.287801 -254.678684) (xy 374.28373 -254.623062)
			(xy 373.037862 -254.623062) (xy 373.434356 -255.019556) (xy 373.453079 -255.038796) (xy 373.486598 -255.080733)
			(xy 373.515261 -255.126127) (xy 373.52732 -255.150112) (xy 373.534819 -255.165877) (xy 373.547785 -255.198294)
			(xy 373.553228 -255.214882) (xy 373.553228 -255.21539) (xy 373.555456 -255.223264) (xy 378.137672 -255.223264)
			(xy 378.141743 -255.167642) (xy 378.153869 -255.113205) (xy 378.173792 -255.061114) (xy 378.201088 -255.012479)
			(xy 378.235174 -254.968336) (xy 378.275323 -254.929627) (xy 378.320681 -254.897176) (xy 378.370281 -254.871675)
			(xy 378.423065 -254.853668) (xy 378.477908 -254.843538) (xy 378.533642 -254.841501) (xy 378.589079 -254.847601)
			(xy 378.643036 -254.861707) (xy 378.694365 -254.883519) (xy 378.741971 -254.912573) (xy 378.784839 -254.948248)
			(xy 378.822056 -254.989785) (xy 378.852829 -255.036298) (xy 378.876501 -255.086795) (xy 378.892569 -255.140202)
			(xy 378.900689 -255.195378) (xy 378.901198 -255.223264) (xy 378.900689 -255.25115) (xy 378.892569 -255.306326)
			(xy 378.876501 -255.359733) (xy 378.852829 -255.41023) (xy 378.822056 -255.456743) (xy 378.784839 -255.49828)
			(xy 378.741971 -255.533955) (xy 378.694365 -255.563009) (xy 378.643036 -255.584821) (xy 378.589079 -255.598927)
			(xy 378.533642 -255.605027) (xy 378.477908 -255.60299) (xy 378.423065 -255.59286) (xy 378.370281 -255.574853)
			(xy 378.320681 -255.549352) (xy 378.275323 -255.516901) (xy 378.235174 -255.478192) (xy 378.201088 -255.434049)
			(xy 378.173792 -255.385414) (xy 378.153869 -255.333323) (xy 378.141743 -255.278886) (xy 378.137672 -255.223264)
			(xy 373.555456 -255.223264) (xy 373.560848 -255.242314) (xy 373.560848 -255.242822) (xy 373.567722 -255.2718)
			(xy 373.575113 -255.330899) (xy 373.57558 -255.360678) (xy 373.57558 -256.1082) (xy 374.28373 -256.1082)
			(xy 374.287801 -256.052578) (xy 374.299927 -255.998141) (xy 374.31985 -255.94605) (xy 374.347146 -255.897415)
			(xy 374.381232 -255.853272) (xy 374.421381 -255.814563) (xy 374.466739 -255.782112) (xy 374.516339 -255.756611)
			(xy 374.569123 -255.738604) (xy 374.623966 -255.728474) (xy 374.6797 -255.726437) (xy 374.735137 -255.732537)
			(xy 374.789094 -255.746643) (xy 374.840423 -255.768455) (xy 374.888029 -255.797509) (xy 374.930897 -255.833184)
			(xy 374.968114 -255.874721) (xy 374.998887 -255.921234) (xy 375.022559 -255.971731) (xy 375.038627 -256.025138)
			(xy 375.046747 -256.080314) (xy 375.047256 -256.1082) (xy 375.046747 -256.136086) (xy 375.038627 -256.191262)
			(xy 375.022559 -256.244669) (xy 374.998887 -256.295166) (xy 374.968114 -256.341679) (xy 374.930897 -256.383216)
			(xy 374.888029 -256.418891) (xy 374.840423 -256.447945) (xy 374.789094 -256.469757) (xy 374.735137 -256.483863)
			(xy 374.6797 -256.489963) (xy 374.623966 -256.487926) (xy 374.569123 -256.477796) (xy 374.516339 -256.459789)
			(xy 374.466739 -256.434288) (xy 374.421381 -256.401837) (xy 374.381232 -256.363128) (xy 374.347146 -256.318985)
			(xy 374.31985 -256.27035) (xy 374.299927 -256.218259) (xy 374.287801 -256.163822) (xy 374.28373 -256.1082)
			(xy 373.57558 -256.1082) (xy 373.57558 -257.137916) (xy 382.596136 -257.137916) (xy 382.596671 -257.108533)
			(xy 382.605701 -257.050465) (xy 382.623533 -256.994471) (xy 382.649745 -256.941875) (xy 382.683717 -256.893924)
			(xy 382.724644 -256.851753) (xy 382.747774 -256.833624) (xy 382.756702 -256.826148) (xy 382.767158 -256.805371)
			(xy 382.76784 -256.793746) (xy 382.76911 -256.701798) (xy 382.759204 -256.680716) (xy 382.75006 -256.67335)
			(xy 382.728198 -256.655161) (xy 382.68966 -256.613337) (xy 382.657756 -256.566258) (xy 382.633192 -256.514965)
			(xy 382.616511 -256.460595) (xy 382.608084 -256.404352) (xy 382.607566 -256.375916) (xy 382.608052 -256.348665)
			(xy 382.615808 -256.294717) (xy 382.631163 -256.242422) (xy 382.653805 -256.192845) (xy 382.683271 -256.146995)
			(xy 382.718962 -256.105804) (xy 382.760153 -256.070113) (xy 382.806003 -256.040647) (xy 382.85558 -256.018005)
			(xy 382.907875 -256.00265) (xy 382.961823 -255.994894) (xy 383.016325 -255.994894) (xy 383.070273 -256.00265)
			(xy 383.122568 -256.018005) (xy 383.172145 -256.040647) (xy 383.217995 -256.070113) (xy 383.259186 -256.105804)
			(xy 383.294877 -256.146995) (xy 383.324343 -256.192845) (xy 383.346985 -256.242422) (xy 383.36234 -256.294717)
			(xy 383.370096 -256.348665) (xy 383.370582 -256.375916) (xy 383.370063 -256.405299) (xy 383.361029 -256.463367)
			(xy 383.343193 -256.519362) (xy 383.316978 -256.571958) (xy 383.283003 -256.619908) (xy 383.242074 -256.662079)
			(xy 383.218944 -256.680208) (xy 383.210005 -256.687673) (xy 383.199554 -256.708459) (xy 383.198878 -256.720086)
			(xy 383.197608 -256.812034) (xy 383.207514 -256.833116) (xy 383.216658 -256.840482) (xy 383.238471 -256.858728)
			(xy 383.277015 -256.900538) (xy 383.308928 -256.947604) (xy 383.333501 -256.998886) (xy 383.350191 -257.053247)
			(xy 383.358629 -257.109483) (xy 383.359152 -257.137916) (xy 383.992626 -257.137916) (xy 383.996697 -257.082294)
			(xy 384.008823 -257.027857) (xy 384.028746 -256.975766) (xy 384.056042 -256.927131) (xy 384.090128 -256.882988)
			(xy 384.130277 -256.844279) (xy 384.175635 -256.811828) (xy 384.225235 -256.786327) (xy 384.278019 -256.76832)
			(xy 384.332862 -256.75819) (xy 384.388596 -256.756153) (xy 384.444033 -256.762253) (xy 384.49799 -256.776359)
			(xy 384.549319 -256.798171) (xy 384.596925 -256.827225) (xy 384.639793 -256.8629) (xy 384.67701 -256.904437)
			(xy 384.707783 -256.95095) (xy 384.731455 -257.001447) (xy 384.747523 -257.054854) (xy 384.755643 -257.11003)
			(xy 384.756152 -257.137916) (xy 384.755643 -257.165802) (xy 384.747523 -257.220978) (xy 384.731455 -257.274385)
			(xy 384.707783 -257.324882) (xy 384.67701 -257.371395) (xy 384.639793 -257.412932) (xy 384.596925 -257.448607)
			(xy 384.549319 -257.477661) (xy 384.49799 -257.499473) (xy 384.444033 -257.513579) (xy 384.388596 -257.519679)
			(xy 384.332862 -257.517642) (xy 384.278019 -257.507512) (xy 384.225235 -257.489505) (xy 384.175635 -257.464004)
			(xy 384.130277 -257.431553) (xy 384.090128 -257.392844) (xy 384.056042 -257.348701) (xy 384.028746 -257.300066)
			(xy 384.008823 -257.247975) (xy 383.996697 -257.193538) (xy 383.992626 -257.137916) (xy 383.359152 -257.137916)
			(xy 383.358666 -257.165167) (xy 383.35091 -257.219115) (xy 383.335555 -257.27141) (xy 383.312913 -257.320987)
			(xy 383.283447 -257.366837) (xy 383.247756 -257.408028) (xy 383.206565 -257.443719) (xy 383.160715 -257.473185)
			(xy 383.111138 -257.495827) (xy 383.058843 -257.511182) (xy 383.004895 -257.518938) (xy 382.950393 -257.518938)
			(xy 382.896445 -257.511182) (xy 382.84415 -257.495827) (xy 382.794573 -257.473185) (xy 382.748723 -257.443719)
			(xy 382.707532 -257.408028) (xy 382.671841 -257.366837) (xy 382.642375 -257.320987) (xy 382.619733 -257.27141)
			(xy 382.604378 -257.219115) (xy 382.596622 -257.165167) (xy 382.596136 -257.137916) (xy 373.57558 -257.137916)
			(xy 373.57558 -257.263138) (xy 373.575834 -258.691126) (xy 373.57537 -258.721258) (xy 373.567872 -258.781054)
			(xy 373.552995 -258.839453) (xy 373.53097 -258.895548) (xy 373.50214 -258.948469) (xy 373.466952 -258.997393)
			(xy 373.446802 -259.019802) (xy 373.446548 -259.02031) (xy 373.446294 -259.020564) (xy 373.445278 -259.02158)
			(xy 373.44477 -259.021834) (xy 373.444262 -259.022342) (xy 373.44223 -259.024628) (xy 373.44096 -259.025898)
			(xy 373.440706 -259.026152) (xy 373.440198 -259.02666) (xy 373.431109 -259.037482) (xy 373.418737 -259.062879)
			(xy 373.41381 -259.090696) (xy 373.416704 -259.118797) (xy 373.427199 -259.145025) (xy 373.444488 -259.167367)
			(xy 373.467244 -259.184107) (xy 373.49372 -259.19396) (xy 373.507762 -259.19557) (xy 373.508778 -259.19557)
			(xy 373.51208 -259.195824) (xy 375.793254 -259.195824) (xy 375.801485 -259.194912) (xy 375.816768 -259.188562)
			(xy 375.823226 -259.183378) (xy 376.39625 -258.610354) (xy 377.09221 -257.914648) (xy 377.099068 -257.90779)
			(xy 377.226068 -257.78079) (xy 377.233466 -257.773945) (xy 377.252065 -257.766221) (xy 377.262136 -257.765804)
			(xy 377.641104 -257.765804) (xy 377.651174 -257.766228) (xy 377.669777 -257.773944) (xy 377.677172 -257.78079)
			(xy 377.804172 -257.90779) (xy 377.80468 -257.908298) (xy 377.81738 -257.920998) (xy 377.817888 -257.921506)
			(xy 377.944888 -258.048506) (xy 377.951735 -258.055904) (xy 377.959469 -258.074502) (xy 377.959874 -258.084574)
			(xy 377.959874 -258.263136) (xy 377.960128 -258.273296) (xy 377.960128 -258.274058) (xy 378.55474 -258.274058)
			(xy 378.558811 -258.218436) (xy 378.570937 -258.163999) (xy 378.59086 -258.111908) (xy 378.618156 -258.063273)
			(xy 378.652242 -258.01913) (xy 378.692391 -257.980421) (xy 378.737749 -257.94797) (xy 378.787349 -257.922469)
			(xy 378.840133 -257.904462) (xy 378.894976 -257.894332) (xy 378.95071 -257.892295) (xy 379.006147 -257.898395)
			(xy 379.060104 -257.912501) (xy 379.111433 -257.934313) (xy 379.159039 -257.963367) (xy 379.201907 -257.999042)
			(xy 379.239124 -258.040579) (xy 379.269897 -258.087092) (xy 379.293569 -258.137589) (xy 379.309637 -258.190996)
			(xy 379.317757 -258.246172) (xy 379.318266 -258.274058) (xy 379.317757 -258.301944) (xy 379.309637 -258.35712)
			(xy 379.293569 -258.410527) (xy 379.269897 -258.461024) (xy 379.239124 -258.507537) (xy 379.201907 -258.549074)
			(xy 379.159039 -258.584749) (xy 379.111433 -258.613803) (xy 379.060104 -258.635615) (xy 379.006147 -258.649721)
			(xy 378.95071 -258.655821) (xy 378.894976 -258.653784) (xy 378.840133 -258.643654) (xy 378.787349 -258.625647)
			(xy 378.737749 -258.600146) (xy 378.692391 -258.567695) (xy 378.652242 -258.528986) (xy 378.618156 -258.484843)
			(xy 378.59086 -258.436208) (xy 378.570937 -258.384117) (xy 378.558811 -258.32968) (xy 378.55474 -258.274058)
			(xy 377.960128 -258.274058) (xy 377.960128 -258.27482) (xy 377.959874 -258.28498) (xy 377.959874 -258.463542)
			(xy 377.959443 -258.473608) (xy 377.951715 -258.492199) (xy 377.944888 -258.49961) (xy 377.817888 -258.62661)
			(xy 377.81103 -258.633468) (xy 376.758454 -259.686044) (xy 376.748262 -259.697075) (xy 376.734217 -259.723606)
			(xy 376.728475 -259.753071) (xy 376.731531 -259.782933) (xy 376.74312 -259.810625) (xy 376.762246 -259.833762)
			(xy 376.774456 -259.842508) (xy 376.796622 -259.857716) (xy 376.836853 -259.89337) (xy 376.871676 -259.934321)
			(xy 376.9004 -259.979759) (xy 376.922457 -260.028781) (xy 376.937408 -260.080415) (xy 376.944958 -260.133638)
			(xy 376.945398 -260.160516) (xy 376.944911 -260.187766) (xy 376.937152 -260.241712) (xy 376.921796 -260.294004)
			(xy 376.901556 -260.338316) (xy 382.596136 -260.338316) (xy 382.596671 -260.308933) (xy 382.605701 -260.250865)
			(xy 382.623533 -260.194871) (xy 382.649745 -260.142275) (xy 382.683717 -260.094324) (xy 382.724644 -260.052153)
			(xy 382.747774 -260.034024) (xy 382.756702 -260.026548) (xy 382.767158 -260.005771) (xy 382.76784 -259.994146)
			(xy 382.76911 -259.902198) (xy 382.759204 -259.881116) (xy 382.75006 -259.87375) (xy 382.728198 -259.855561)
			(xy 382.68966 -259.813737) (xy 382.657756 -259.766658) (xy 382.633192 -259.715365) (xy 382.616511 -259.660995)
			(xy 382.608084 -259.604752) (xy 382.607566 -259.576316) (xy 382.608052 -259.549065) (xy 382.615808 -259.495117)
			(xy 382.631163 -259.442822) (xy 382.653805 -259.393245) (xy 382.683271 -259.347395) (xy 382.718962 -259.306204)
			(xy 382.760153 -259.270513) (xy 382.806003 -259.241047) (xy 382.85558 -259.218405) (xy 382.907875 -259.20305)
			(xy 382.961823 -259.195294) (xy 383.016325 -259.195294) (xy 383.070273 -259.20305) (xy 383.122568 -259.218405)
			(xy 383.172145 -259.241047) (xy 383.217995 -259.270513) (xy 383.259186 -259.306204) (xy 383.294877 -259.347395)
			(xy 383.324343 -259.393245) (xy 383.326982 -259.399024) (xy 386.435598 -259.399024) (xy 386.439669 -259.343402)
			(xy 386.451795 -259.288965) (xy 386.471718 -259.236874) (xy 386.499014 -259.188239) (xy 386.5331 -259.144096)
			(xy 386.573249 -259.105387) (xy 386.618607 -259.072936) (xy 386.668207 -259.047435) (xy 386.720991 -259.029428)
			(xy 386.775834 -259.019298) (xy 386.831568 -259.017261) (xy 386.887005 -259.023361) (xy 386.940962 -259.037467)
			(xy 386.992291 -259.059279) (xy 387.039897 -259.088333) (xy 387.082765 -259.124008) (xy 387.119982 -259.165545)
			(xy 387.150755 -259.212058) (xy 387.174427 -259.262555) (xy 387.190495 -259.315962) (xy 387.198615 -259.371138)
			(xy 387.199124 -259.399024) (xy 387.198615 -259.42691) (xy 387.190495 -259.482086) (xy 387.174427 -259.535493)
			(xy 387.150755 -259.58599) (xy 387.119982 -259.632503) (xy 387.082765 -259.67404) (xy 387.039897 -259.709715)
			(xy 386.992291 -259.738769) (xy 386.940962 -259.760581) (xy 386.887005 -259.774687) (xy 386.831568 -259.780787)
			(xy 386.775834 -259.77875) (xy 386.720991 -259.76862) (xy 386.668207 -259.750613) (xy 386.618607 -259.725112)
			(xy 386.573249 -259.692661) (xy 386.5331 -259.653952) (xy 386.499014 -259.609809) (xy 386.471718 -259.561174)
			(xy 386.451795 -259.509083) (xy 386.439669 -259.454646) (xy 386.435598 -259.399024) (xy 383.326982 -259.399024)
			(xy 383.346985 -259.442822) (xy 383.36234 -259.495117) (xy 383.370096 -259.549065) (xy 383.370582 -259.576316)
			(xy 383.370063 -259.605699) (xy 383.361029 -259.663767) (xy 383.343193 -259.719762) (xy 383.316978 -259.772358)
			(xy 383.283003 -259.820308) (xy 383.242074 -259.862479) (xy 383.218944 -259.880608) (xy 383.210005 -259.888073)
			(xy 383.199554 -259.908859) (xy 383.198878 -259.920486) (xy 383.197608 -260.012434) (xy 383.207514 -260.033516)
			(xy 383.216658 -260.040882) (xy 383.238471 -260.059128) (xy 383.277015 -260.100938) (xy 383.308928 -260.148004)
			(xy 383.333501 -260.199286) (xy 383.350191 -260.253647) (xy 383.358629 -260.309883) (xy 383.359152 -260.338316)
			(xy 383.992626 -260.338316) (xy 383.996697 -260.282694) (xy 384.008823 -260.228257) (xy 384.028746 -260.176166)
			(xy 384.056042 -260.127531) (xy 384.090128 -260.083388) (xy 384.130277 -260.044679) (xy 384.175635 -260.012228)
			(xy 384.225235 -259.986727) (xy 384.278019 -259.96872) (xy 384.332862 -259.95859) (xy 384.388596 -259.956553)
			(xy 384.444033 -259.962653) (xy 384.49799 -259.976759) (xy 384.549319 -259.998571) (xy 384.596925 -260.027625)
			(xy 384.639793 -260.0633) (xy 384.67701 -260.104837) (xy 384.707783 -260.15135) (xy 384.731455 -260.201847)
			(xy 384.747523 -260.255254) (xy 384.755643 -260.31043) (xy 384.756152 -260.338316) (xy 384.755643 -260.366202)
			(xy 384.754663 -260.37286) (xy 387.427722 -260.37286) (xy 387.431793 -260.317238) (xy 387.443919 -260.262801)
			(xy 387.463842 -260.21071) (xy 387.491138 -260.162075) (xy 387.525224 -260.117932) (xy 387.565373 -260.079223)
			(xy 387.610731 -260.046772) (xy 387.660331 -260.021271) (xy 387.713115 -260.003264) (xy 387.767958 -259.993134)
			(xy 387.823692 -259.991097) (xy 387.879129 -259.997197) (xy 387.933086 -260.011303) (xy 387.984415 -260.033115)
			(xy 388.032021 -260.062169) (xy 388.074889 -260.097844) (xy 388.112106 -260.139381) (xy 388.142879 -260.185894)
			(xy 388.166551 -260.236391) (xy 388.182619 -260.289798) (xy 388.190739 -260.344974) (xy 388.191248 -260.37286)
			(xy 388.190739 -260.400746) (xy 388.182619 -260.455922) (xy 388.166551 -260.509329) (xy 388.142879 -260.559826)
			(xy 388.112106 -260.606339) (xy 388.074889 -260.647876) (xy 388.032021 -260.683551) (xy 387.984415 -260.712605)
			(xy 387.933086 -260.734417) (xy 387.879129 -260.748523) (xy 387.823692 -260.754623) (xy 387.767958 -260.752586)
			(xy 387.713115 -260.742456) (xy 387.660331 -260.724449) (xy 387.610731 -260.698948) (xy 387.565373 -260.666497)
			(xy 387.525224 -260.627788) (xy 387.491138 -260.583645) (xy 387.463842 -260.53501) (xy 387.443919 -260.482919)
			(xy 387.431793 -260.428482) (xy 387.427722 -260.37286) (xy 384.754663 -260.37286) (xy 384.747523 -260.421378)
			(xy 384.731455 -260.474785) (xy 384.707783 -260.525282) (xy 384.67701 -260.571795) (xy 384.639793 -260.613332)
			(xy 384.596925 -260.649007) (xy 384.549319 -260.678061) (xy 384.49799 -260.699873) (xy 384.444033 -260.713979)
			(xy 384.388596 -260.720079) (xy 384.332862 -260.718042) (xy 384.278019 -260.707912) (xy 384.225235 -260.689905)
			(xy 384.175635 -260.664404) (xy 384.130277 -260.631953) (xy 384.090128 -260.593244) (xy 384.056042 -260.549101)
			(xy 384.028746 -260.500466) (xy 384.008823 -260.448375) (xy 383.996697 -260.393938) (xy 383.992626 -260.338316)
			(xy 383.359152 -260.338316) (xy 383.358666 -260.365567) (xy 383.35091 -260.419515) (xy 383.335555 -260.47181)
			(xy 383.312913 -260.521387) (xy 383.283447 -260.567237) (xy 383.247756 -260.608428) (xy 383.206565 -260.644119)
			(xy 383.160715 -260.673585) (xy 383.111138 -260.696227) (xy 383.058843 -260.711582) (xy 383.004895 -260.719338)
			(xy 382.950393 -260.719338) (xy 382.896445 -260.711582) (xy 382.84415 -260.696227) (xy 382.794573 -260.673585)
			(xy 382.748723 -260.644119) (xy 382.707532 -260.608428) (xy 382.671841 -260.567237) (xy 382.642375 -260.521387)
			(xy 382.619733 -260.47181) (xy 382.604378 -260.419515) (xy 382.596622 -260.365567) (xy 382.596136 -260.338316)
			(xy 376.901556 -260.338316) (xy 376.899153 -260.343578) (xy 376.869687 -260.389426) (xy 376.833995 -260.430613)
			(xy 376.792805 -260.466302) (xy 376.746955 -260.495766) (xy 376.697379 -260.518405) (xy 376.645086 -260.533758)
			(xy 376.59114 -260.541512) (xy 376.56389 -260.542024) (xy 376.53567 -260.541515) (xy 376.479845 -260.533198)
			(xy 376.425855 -260.516748) (xy 376.374877 -260.492523) (xy 376.328025 -260.461053) (xy 376.28632 -260.423023)
			(xy 376.250673 -260.379264) (xy 376.221861 -260.330731) (xy 376.200514 -260.278483) (xy 376.193304 -260.251194)
			(xy 376.191652 -260.245086) (xy 376.185731 -260.233907) (xy 376.18162 -260.229096) (xy 376.174752 -260.222194)
			(xy 376.157257 -260.213686) (xy 376.147584 -260.212586) (xy 376.032268 -260.212586) (xy 376.021346 -260.21284)
			(xy 373.079518 -260.21284) (xy 373.068596 -260.212586) (xy 372.890034 -260.212586) (xy 372.879969 -260.21215)
			(xy 372.861384 -260.204418) (xy 372.853966 -260.1976) (xy 372.842028 -260.185662) (xy 372.831614 -260.175971)
			(xy 372.806709 -260.162249) (xy 372.778987 -260.155918) (xy 372.750594 -260.157465) (xy 372.723724 -260.166771)
			(xy 372.700457 -260.183118) (xy 372.682591 -260.20524) (xy 372.676674 -260.218174) (xy 372.665391 -260.243804)
			(xy 372.636419 -260.291724) (xy 372.600754 -260.334894) (xy 372.559162 -260.372389) (xy 372.512536 -260.403402)
			(xy 372.461879 -260.427267) (xy 372.408277 -260.443472) (xy 372.352883 -260.451669) (xy 372.324884 -260.452108)
			(xy 372.297633 -260.451621) (xy 372.243687 -260.443863) (xy 372.191395 -260.428506) (xy 372.141819 -260.405864)
			(xy 372.095971 -260.376397) (xy 372.054783 -260.340706) (xy 372.019093 -260.299516) (xy 371.989628 -260.253666)
			(xy 371.966988 -260.20409) (xy 371.951634 -260.151797) (xy 371.943878 -260.097851) (xy 371.943376 -260.0706)
			(xy 371.943376 -260.055106) (xy 371.944545 -260.032903) (xy 371.951422 -259.988975) (xy 371.957092 -259.967476)
			(xy 371.958362 -259.961634) (xy 371.960109 -259.947758) (xy 371.956804 -259.919996) (xy 371.946074 -259.894179)
			(xy 371.928727 -259.872254) (xy 371.906071 -259.855873) (xy 371.879813 -259.84627) (xy 371.865906 -259.844794)
			(xy 371.86489 -259.844794) (xy 371.861842 -259.84454) (xy 371.258084 -259.84454) (xy 371.247162 -259.844286)
			(xy 371.0686 -259.844286) (xy 371.05853 -259.843863) (xy 371.039927 -259.836147) (xy 371.032532 -259.8293)
			(xy 370.905532 -259.7023) (xy 370.898674 -259.695442) (xy 370.259102 -259.05587) (xy 370.25199 -259.048758)
			(xy 368.970052 -257.76682) (xy 368.959089 -257.756597) (xy 368.932675 -257.742458) (xy 368.903294 -257.73659)
			(xy 368.873476 -257.739501) (xy 368.845784 -257.750939) (xy 368.822603 -257.76992) (xy 368.805927 -257.79481)
			(xy 368.79719 -257.823469) (xy 368.79657 -257.838448) (xy 368.79657 -258.104894) (xy 368.796147 -258.114964)
			(xy 368.788431 -258.133567) (xy 368.781584 -258.140962) (xy 368.58575 -258.336796) (xy 368.582229 -258.340527)
			(xy 368.5766 -258.349101) (xy 368.574574 -258.353814) (xy 368.571018 -258.36245) (xy 368.571018 -259.369052)
			(xy 368.571526 -259.37591) (xy 369.140486 -259.94487) (xy 369.513102 -259.94487) (xy 369.517173 -259.889248)
			(xy 369.529299 -259.834811) (xy 369.549222 -259.78272) (xy 369.576518 -259.734085) (xy 369.610604 -259.689942)
			(xy 369.650753 -259.651233) (xy 369.696111 -259.618782) (xy 369.745711 -259.593281) (xy 369.798495 -259.575274)
			(xy 369.853338 -259.565144) (xy 369.909072 -259.563107) (xy 369.964509 -259.569207) (xy 370.018466 -259.583313)
			(xy 370.069795 -259.605125) (xy 370.117401 -259.634179) (xy 370.160269 -259.669854) (xy 370.197486 -259.711391)
			(xy 370.228259 -259.757904) (xy 370.251931 -259.808401) (xy 370.267999 -259.861808) (xy 370.276119 -259.916984)
			(xy 370.276628 -259.94487) (xy 370.276119 -259.972756) (xy 370.267999 -260.027932) (xy 370.251931 -260.081339)
			(xy 370.228259 -260.131836) (xy 370.197486 -260.178349) (xy 370.160269 -260.219886) (xy 370.117401 -260.255561)
			(xy 370.069795 -260.284615) (xy 370.018466 -260.306427) (xy 369.964509 -260.320533) (xy 369.909072 -260.326633)
			(xy 369.853338 -260.324596) (xy 369.798495 -260.314466) (xy 369.745711 -260.296459) (xy 369.696111 -260.270958)
			(xy 369.650753 -260.238507) (xy 369.610604 -260.199798) (xy 369.576518 -260.155655) (xy 369.549222 -260.10702)
			(xy 369.529299 -260.054929) (xy 369.517173 -260.000492) (xy 369.513102 -259.94487) (xy 369.140486 -259.94487)
			(xy 370.05641 -260.860794) (xy 370.061998 -260.86562) (xy 370.068737 -260.870293) (xy 370.084283 -260.875484)
			(xy 370.092478 -260.87578) (xy 370.557806 -260.87578) (xy 370.563958 -260.875606) (xy 370.575901 -260.872646)
			(xy 370.581428 -260.869938) (xy 370.608506 -260.856345) (xy 370.665902 -260.836947) (xy 370.72564 -260.826846)
			(xy 370.755926 -260.825996) (xy 370.764562 -260.82625) (xy 370.764816 -260.82625) (xy 370.791818 -260.827096)
			(xy 370.845188 -260.835461) (xy 370.896845 -260.851272) (xy 370.945754 -260.874213) (xy 370.990938 -260.903824)
			(xy 371.031492 -260.939513) (xy 371.066606 -260.980566) (xy 371.095578 -261.026162) (xy 371.117827 -261.07539)
			(xy 371.132909 -261.127264) (xy 371.140522 -261.180747) (xy 371.14099 -261.207758) (xy 371.14052 -261.234732)
			(xy 371.132914 -261.288141) (xy 371.117861 -261.339946) (xy 371.095661 -261.389115) (xy 371.066758 -261.434667)
			(xy 371.031727 -261.475694) (xy 370.991267 -261.511379) (xy 370.946185 -261.541009) (xy 370.897378 -261.563994)
			(xy 370.845821 -261.579876) (xy 370.792541 -261.588338) (xy 370.765578 -261.589266) (xy 370.759228 -261.58952)
			(xy 370.758974 -261.58952) (xy 370.728218 -261.588859) (xy 370.667514 -261.578908) (xy 370.609192 -261.559348)
			(xy 370.581682 -261.545578) (xy 370.57615 -261.542887) (xy 370.564209 -261.539942) (xy 370.55806 -261.539736)
			(xy 369.933982 -261.539736) (xy 369.907895 -261.539248) (xy 369.856366 -261.531079) (xy 369.80675 -261.514944)
			(xy 369.760272 -261.491241) (xy 369.718077 -261.460555) (xy 369.699286 -261.442454) (xy 367.652808 -259.395976)
			(xy 367.634779 -259.377204) (xy 367.604206 -259.335086) (xy 367.580586 -259.288709) (xy 367.564499 -259.239212)
			(xy 367.556341 -259.18781) (xy 367.55578 -259.161788) (xy 367.55578 -255.556512) (xy 367.550954 -255.55067)
			(xy 362.217462 -250.217178) (xy 362.21373 -250.213658) (xy 362.205154 -250.208034) (xy 362.200444 -250.206002)
			(xy 362.191808 -250.202446) (xy 359.67543 -250.202446) (xy 359.671874 -250.202446) (xy 359.665975 -250.203043)
			(xy 359.654679 -250.206633) (xy 359.649522 -250.209558) (xy 359.639108 -250.217686) (xy 359.588054 -250.27001)
			(xy 359.584709 -250.273587) (xy 359.579336 -250.281773) (xy 359.577386 -250.286266) (xy 359.57637 -250.28906)
			(xy 359.57383 -250.295156) (xy 359.57383 -250.313444) (xy 359.573344 -250.340695) (xy 359.565588 -250.394643)
			(xy 359.550233 -250.446938) (xy 359.527591 -250.496515) (xy 359.498125 -250.542365) (xy 359.462434 -250.583556)
			(xy 359.421243 -250.619247) (xy 359.375393 -250.648713) (xy 359.325816 -250.671355) (xy 359.273521 -250.68671)
			(xy 359.219573 -250.694466) (xy 359.165071 -250.694466) (xy 359.111123 -250.68671) (xy 359.058828 -250.671355)
			(xy 359.009251 -250.648713) (xy 358.963401 -250.619247) (xy 358.92221 -250.583556) (xy 358.886519 -250.542365)
			(xy 358.857053 -250.496515) (xy 358.834411 -250.446938) (xy 358.819056 -250.394643) (xy 358.8113 -250.340695)
			(xy 358.810814 -250.313444) (xy 358.810814 -250.306078) (xy 358.811068 -250.295918) (xy 358.807258 -250.286266)
			(xy 358.805284 -250.281787) (xy 358.799911 -250.273606) (xy 358.79659 -250.27001) (xy 358.74452 -250.21667)
			(xy 358.737899 -250.21084) (xy 358.72179 -250.203686) (xy 358.713024 -250.2027) (xy 358.709214 -250.202446)
			(xy 338.121244 -250.202446) (xy 338.11122 -250.202859) (xy 338.092696 -250.210522) (xy 338.078521 -250.224698)
			(xy 338.070858 -250.243222) (xy 338.070444 -250.253246) (xy 338.070444 -250.598432) (xy 338.070811 -250.607508)
			(xy 338.077158 -250.624514) (xy 338.089069 -250.63821) (xy 338.09686 -250.642882) (xy 338.187284 -250.692666)
			(xy 338.214716 -250.69165) (xy 338.2264 -250.684284) (xy 338.249381 -250.670265) (xy 338.298452 -250.648131)
			(xy 338.35015 -250.633128) (xy 338.403446 -250.625556) (xy 338.430362 -250.625102) (xy 338.430616 -250.625102)
			(xy 338.457866 -250.625589) (xy 338.511812 -250.633348) (xy 338.564104 -250.648704) (xy 338.613678 -250.671347)
			(xy 338.659526 -250.700813) (xy 338.700713 -250.736505) (xy 338.736402 -250.777695) (xy 338.765866 -250.823545)
			(xy 338.788505 -250.873121) (xy 338.803858 -250.925414) (xy 338.811612 -250.97936) (xy 338.812124 -251.00661)
			(xy 338.81193 -251.023271) (xy 338.809003 -251.056465) (xy 338.806282 -251.072904) (xy 338.806282 -251.073158)
			(xy 338.805151 -251.081932) (xy 338.808239 -251.099338) (xy 338.817046 -251.114665) (xy 338.823554 -251.120656)
			(xy 338.900516 -251.186188) (xy 338.927186 -251.191014) (xy 338.939886 -251.186442) (xy 338.970599 -251.176365)
			(xy 339.034315 -251.165506) (xy 339.066632 -251.164852) (xy 339.06714 -251.164852) (xy 339.092177 -251.165246)
			(xy 339.141819 -251.171805) (xy 339.190172 -251.184819) (xy 339.213444 -251.194062) (xy 339.222007 -251.197283)
			(xy 339.240272 -251.198066) (xy 339.25765 -251.192388) (xy 339.265006 -251.18695) (xy 339.34527 -251.122434)
			(xy 339.354922 -251.09678) (xy 339.352636 -251.083064) (xy 339.350029 -251.066998) (xy 339.347229 -251.034569)
			(xy 339.347048 -251.018294) (xy 339.347048 -251.017786) (xy 339.347512 -250.99053) (xy 339.355272 -250.936572)
			(xy 339.370632 -250.884268) (xy 339.39328 -250.834682) (xy 339.422754 -250.788824) (xy 339.458454 -250.747628)
			(xy 339.499654 -250.711931) (xy 339.545515 -250.682462) (xy 339.595103 -250.659819) (xy 339.647409 -250.644464)
			(xy 339.701367 -250.636709) (xy 339.75588 -250.636713) (xy 339.809838 -250.644474) (xy 339.862142 -250.659836)
			(xy 339.911727 -250.682485) (xy 339.957584 -250.71196) (xy 339.991292 -250.741173) (xy 354.92786 -250.741173)
			(xy 354.935613 -250.687223) (xy 354.950965 -250.634926) (xy 354.973603 -250.585345) (xy 355.003067 -250.539492)
			(xy 355.038757 -250.498298) (xy 355.079945 -250.462602) (xy 355.125795 -250.433131) (xy 355.175371 -250.410485)
			(xy 355.227666 -250.395126) (xy 355.281615 -250.387364) (xy 355.336119 -250.387359) (xy 355.390069 -250.395111)
			(xy 355.442366 -250.410462) (xy 355.491947 -250.433099) (xy 355.537801 -250.462562) (xy 355.578996 -250.49825)
			(xy 355.614693 -250.539438) (xy 355.644165 -250.585287) (xy 355.666812 -250.634863) (xy 355.682173 -250.687158)
			(xy 355.689935 -250.741106) (xy 355.690424 -250.768358) (xy 355.690424 -250.768612) (xy 355.690209 -250.787019)
			(xy 355.686646 -250.82366) (xy 355.683312 -250.841764) (xy 355.681034 -250.856522) (xy 355.684063 -250.886212)
			(xy 355.695534 -250.913764) (xy 355.71447 -250.93683) (xy 355.73926 -250.953448) (xy 355.767791 -250.962201)
			(xy 355.797635 -250.962345) (xy 355.81209 -250.958604) (xy 355.838774 -250.951129) (xy 355.893603 -250.943096)
			(xy 355.92131 -250.942602) (xy 355.94856 -250.943089) (xy 356.002506 -250.950846) (xy 356.054798 -250.966202)
			(xy 356.104373 -250.988844) (xy 356.150221 -251.01831) (xy 356.191409 -251.054001) (xy 356.227098 -251.09519)
			(xy 356.256563 -251.141039) (xy 356.279202 -251.190614) (xy 356.294556 -251.242907) (xy 356.302312 -251.296853)
			(xy 356.302312 -251.32411) (xy 357.063292 -251.32411) (xy 357.067363 -251.268488) (xy 357.079489 -251.214051)
			(xy 357.099412 -251.16196) (xy 357.126708 -251.113325) (xy 357.160794 -251.069182) (xy 357.200943 -251.030473)
			(xy 357.246301 -250.998022) (xy 357.295901 -250.972521) (xy 357.348685 -250.954514) (xy 357.403528 -250.944384)
			(xy 357.459262 -250.942347) (xy 357.514699 -250.948447) (xy 357.568656 -250.962553) (xy 357.619985 -250.984365)
			(xy 357.667591 -251.013419) (xy 357.710459 -251.049094) (xy 357.747676 -251.090631) (xy 357.778449 -251.137144)
			(xy 357.802121 -251.187641) (xy 357.818189 -251.241048) (xy 357.826309 -251.296224) (xy 357.826818 -251.32411)
			(xy 357.826309 -251.351996) (xy 357.818189 -251.407172) (xy 357.802121 -251.460579) (xy 357.778449 -251.511076)
			(xy 357.747676 -251.557589) (xy 357.710459 -251.599126) (xy 357.667591 -251.634801) (xy 357.619985 -251.663855)
			(xy 357.568656 -251.685667) (xy 357.514699 -251.699773) (xy 357.459262 -251.705873) (xy 357.403528 -251.703836)
			(xy 357.348685 -251.693706) (xy 357.295901 -251.675699) (xy 357.246301 -251.650198) (xy 357.200943 -251.617747)
			(xy 357.160794 -251.579038) (xy 357.126708 -251.534895) (xy 357.099412 -251.48626) (xy 357.079489 -251.434169)
			(xy 357.067363 -251.379732) (xy 357.063292 -251.32411) (xy 356.302312 -251.32411) (xy 356.302312 -251.351354)
			(xy 356.294555 -251.405299) (xy 356.2792 -251.457592) (xy 356.25656 -251.507167) (xy 356.227094 -251.553016)
			(xy 356.191404 -251.594204) (xy 356.150216 -251.629894) (xy 356.104367 -251.65936) (xy 356.054792 -251.682)
			(xy 356.002499 -251.697355) (xy 355.948554 -251.705112) (xy 355.894053 -251.705112) (xy 355.840107 -251.697356)
			(xy 355.787814 -251.682002) (xy 355.738239 -251.659363) (xy 355.69239 -251.629898) (xy 355.651201 -251.594209)
			(xy 355.61551 -251.553021) (xy 355.586044 -251.507173) (xy 355.563402 -251.457598) (xy 355.548046 -251.405306)
			(xy 355.540289 -251.35136) (xy 355.539802 -251.32411) (xy 355.539802 -251.323856) (xy 355.540012 -251.305449)
			(xy 355.543579 -251.268808) (xy 355.546914 -251.250704) (xy 355.549191 -251.235948) (xy 355.546155 -251.206261)
			(xy 355.534681 -251.178715) (xy 355.515745 -251.155652) (xy 355.490958 -251.139035) (xy 355.462431 -251.130279)
			(xy 355.432591 -251.130128) (xy 355.418136 -251.133864) (xy 355.39145 -251.141333) (xy 355.336623 -251.14937)
			(xy 355.308916 -251.149866) (xy 355.281664 -251.149439) (xy 355.227714 -251.141685) (xy 355.175418 -251.126332)
			(xy 355.125838 -251.103692) (xy 355.079985 -251.074228) (xy 355.038791 -251.038537) (xy 355.003097 -250.997348)
			(xy 354.973627 -250.951498) (xy 354.950982 -250.901921) (xy 354.935624 -250.849625) (xy 354.927864 -250.795677)
			(xy 354.92786 -250.741173) (xy 339.991292 -250.741173) (xy 339.99878 -250.747662) (xy 340.034475 -250.788862)
			(xy 340.063943 -250.834724) (xy 340.086584 -250.884313) (xy 340.101938 -250.936619) (xy 340.109691 -250.990577)
			(xy 340.109687 -251.04509) (xy 340.101924 -251.099048) (xy 340.086561 -251.151351) (xy 340.06391 -251.200936)
			(xy 340.034434 -251.246792) (xy 339.998731 -251.287987) (xy 339.95753 -251.323681) (xy 339.911667 -251.353148)
			(xy 339.862078 -251.375788) (xy 339.809772 -251.39114) (xy 339.755813 -251.398892) (xy 339.728556 -251.399294)
			(xy 339.728302 -251.399294) (xy 339.703265 -251.398903) (xy 339.653621 -251.392348) (xy 339.605266 -251.379337)
			(xy 339.581998 -251.370084) (xy 339.573436 -251.366876) (xy 339.555181 -251.366113) (xy 339.537817 -251.371799)
			(xy 339.530436 -251.377196) (xy 339.450172 -251.441712) (xy 339.44052 -251.467366) (xy 339.442806 -251.481082)
			(xy 339.445411 -251.497148) (xy 339.448207 -251.529577) (xy 339.448394 -251.545852) (xy 339.448394 -251.54636)
			(xy 339.447908 -251.573611) (xy 339.440152 -251.627559) (xy 339.424797 -251.679854) (xy 339.402155 -251.729431)
			(xy 339.372689 -251.775281) (xy 339.336998 -251.816472) (xy 339.295807 -251.852163) (xy 339.249957 -251.881629)
			(xy 339.20038 -251.904271) (xy 339.148085 -251.919626) (xy 339.113724 -251.924566) (xy 350.94113 -251.924566)
			(xy 350.945201 -251.868944) (xy 350.957327 -251.814507) (xy 350.97725 -251.762416) (xy 351.004546 -251.713781)
			(xy 351.038632 -251.669638) (xy 351.078781 -251.630929) (xy 351.124139 -251.598478) (xy 351.173739 -251.572977)
			(xy 351.226523 -251.55497) (xy 351.281366 -251.54484) (xy 351.3371 -251.542803) (xy 351.392537 -251.548903)
			(xy 351.446494 -251.563009) (xy 351.497823 -251.584821) (xy 351.545429 -251.613875) (xy 351.588297 -251.64955)
			(xy 351.625514 -251.691087) (xy 351.656287 -251.7376) (xy 351.679959 -251.788097) (xy 351.696027 -251.841504)
			(xy 351.704147 -251.89668) (xy 351.704656 -251.924566) (xy 351.704147 -251.952452) (xy 351.696027 -252.007628)
			(xy 351.679959 -252.061035) (xy 351.656287 -252.111532) (xy 351.655797 -252.112272) (xy 352.47275 -252.112272)
			(xy 352.476821 -252.05665) (xy 352.488947 -252.002213) (xy 352.50887 -251.950122) (xy 352.536166 -251.901487)
			(xy 352.570252 -251.857344) (xy 352.610401 -251.818635) (xy 352.655759 -251.786184) (xy 352.705359 -251.760683)
			(xy 352.758143 -251.742676) (xy 352.812986 -251.732546) (xy 352.86872 -251.730509) (xy 352.924157 -251.736609)
			(xy 352.978114 -251.750715) (xy 353.029443 -251.772527) (xy 353.077049 -251.801581) (xy 353.119917 -251.837256)
			(xy 353.157134 -251.878793) (xy 353.187907 -251.925306) (xy 353.211579 -251.975803) (xy 353.227647 -252.02921)
			(xy 353.230115 -252.045978) (xy 359.438954 -252.045978) (xy 359.443025 -251.990356) (xy 359.455151 -251.935919)
			(xy 359.475074 -251.883828) (xy 359.50237 -251.835193) (xy 359.536456 -251.79105) (xy 359.576605 -251.752341)
			(xy 359.621963 -251.71989) (xy 359.671563 -251.694389) (xy 359.724347 -251.676382) (xy 359.77919 -251.666252)
			(xy 359.834924 -251.664215) (xy 359.890361 -251.670315) (xy 359.944318 -251.684421) (xy 359.995647 -251.706233)
			(xy 360.043253 -251.735287) (xy 360.086121 -251.770962) (xy 360.123338 -251.812499) (xy 360.154111 -251.859012)
			(xy 360.177783 -251.909509) (xy 360.193851 -251.962916) (xy 360.201971 -252.018092) (xy 360.20248 -252.045978)
			(xy 360.201971 -252.073864) (xy 360.193851 -252.12904) (xy 360.177783 -252.182447) (xy 360.154111 -252.232944)
			(xy 360.123338 -252.279457) (xy 360.086121 -252.320994) (xy 360.043253 -252.356669) (xy 359.995647 -252.385723)
			(xy 359.944318 -252.407535) (xy 359.890361 -252.421641) (xy 359.834924 -252.427741) (xy 359.77919 -252.425704)
			(xy 359.724347 -252.415574) (xy 359.671563 -252.397567) (xy 359.621963 -252.372066) (xy 359.576605 -252.339615)
			(xy 359.536456 -252.300906) (xy 359.50237 -252.256763) (xy 359.475074 -252.208128) (xy 359.455151 -252.156037)
			(xy 359.443025 -252.1016) (xy 359.438954 -252.045978) (xy 353.230115 -252.045978) (xy 353.235767 -252.084386)
			(xy 353.236276 -252.112272) (xy 353.235767 -252.140158) (xy 353.227647 -252.195334) (xy 353.211579 -252.248741)
			(xy 353.187907 -252.299238) (xy 353.157134 -252.345751) (xy 353.119917 -252.387288) (xy 353.077049 -252.422963)
			(xy 353.029443 -252.452017) (xy 352.978114 -252.473829) (xy 352.924157 -252.487935) (xy 352.86872 -252.494035)
			(xy 352.812986 -252.491998) (xy 352.758143 -252.481868) (xy 352.705359 -252.463861) (xy 352.655759 -252.43836)
			(xy 352.610401 -252.405909) (xy 352.570252 -252.3672) (xy 352.536166 -252.323057) (xy 352.50887 -252.274422)
			(xy 352.488947 -252.222331) (xy 352.476821 -252.167894) (xy 352.47275 -252.112272) (xy 351.655797 -252.112272)
			(xy 351.625514 -252.158045) (xy 351.588297 -252.199582) (xy 351.545429 -252.235257) (xy 351.497823 -252.264311)
			(xy 351.446494 -252.286123) (xy 351.392537 -252.300229) (xy 351.3371 -252.306329) (xy 351.281366 -252.304292)
			(xy 351.226523 -252.294162) (xy 351.173739 -252.276155) (xy 351.124139 -252.250654) (xy 351.078781 -252.218203)
			(xy 351.038632 -252.179494) (xy 351.004546 -252.135351) (xy 350.97725 -252.086716) (xy 350.957327 -252.034625)
			(xy 350.945201 -251.980188) (xy 350.94113 -251.924566) (xy 339.113724 -251.924566) (xy 339.094137 -251.927382)
			(xy 339.039635 -251.927382) (xy 338.985687 -251.919626) (xy 338.933392 -251.904271) (xy 338.883815 -251.881629)
			(xy 338.837965 -251.852163) (xy 338.796774 -251.816472) (xy 338.761083 -251.775281) (xy 338.731617 -251.729431)
			(xy 338.708975 -251.679854) (xy 338.69362 -251.627559) (xy 338.685864 -251.573611) (xy 338.685378 -251.54636)
			(xy 338.685574 -251.529699) (xy 338.688503 -251.496505) (xy 338.69122 -251.480066) (xy 338.69122 -251.479812)
			(xy 338.692346 -251.47104) (xy 338.68925 -251.453641) (xy 338.680439 -251.438322) (xy 338.673948 -251.432314)
			(xy 338.596986 -251.366782) (xy 338.570316 -251.361956) (xy 338.557616 -251.366528) (xy 338.526964 -251.37659)
			(xy 338.463378 -251.38745) (xy 338.431124 -251.388118) (xy 338.430616 -251.388118) (xy 338.404107 -251.387664)
			(xy 338.351599 -251.380328) (xy 338.300612 -251.365793) (xy 338.252128 -251.34434) (xy 338.207081 -251.316383)
			(xy 338.166337 -251.282459) (xy 338.148168 -251.26315) (xy 338.140962 -251.255825) (xy 338.122346 -251.247173)
			(xy 338.1121 -251.246386) (xy 338.103464 -251.246132) (xy 338.092761 -251.246315) (xy 338.072935 -251.254322)
			(xy 338.06511 -251.261626) (xy 338.057534 -251.269432) (xy 338.041649 -251.284299) (xy 338.03336 -251.291344)
			(xy 338.033106 -251.300742) (xy 338.035646 -251.31268) (xy 338.038186 -251.318014) (xy 338.049875 -251.343728)
			(xy 338.06639 -251.397743) (xy 338.074758 -251.453603) (xy 338.07527 -251.481844) (xy 338.07527 -251.482352)
			(xy 338.074687 -251.510794) (xy 338.066145 -251.567035) (xy 338.058252 -251.594366) (xy 338.056275 -251.601732)
			(xy 338.056261 -251.616976) (xy 338.058252 -251.624338) (xy 338.066159 -251.651666) (xy 338.074702 -251.707909)
			(xy 338.07527 -251.736352) (xy 338.074784 -251.763603) (xy 338.067028 -251.817551) (xy 338.051673 -251.869846)
			(xy 338.029031 -251.919423) (xy 337.999565 -251.965273) (xy 337.963874 -252.006464) (xy 337.922683 -252.042155)
			(xy 337.876833 -252.071621) (xy 337.827256 -252.094263) (xy 337.774961 -252.109618) (xy 337.721013 -252.117374)
			(xy 337.666511 -252.117374) (xy 337.612563 -252.109618) (xy 337.560268 -252.094263) (xy 337.510691 -252.071621)
			(xy 337.464841 -252.042155) (xy 337.42365 -252.006464) (xy 337.387959 -251.965273) (xy 337.358493 -251.919423)
			(xy 337.335851 -251.869846) (xy 337.320496 -251.817551) (xy 337.31274 -251.763603) (xy 337.312254 -251.736352)
			(xy 337.312837 -251.70791) (xy 337.321379 -251.651669) (xy 337.329272 -251.624338) (xy 337.331162 -251.616954)
			(xy 337.331024 -251.60172) (xy 337.329018 -251.594366) (xy 337.326224 -251.58446) (xy 337.323317 -251.57373)
			(xy 337.318618 -251.551998) (xy 337.316826 -251.541026) (xy 337.315115 -251.529409) (xy 337.312954 -251.506024)
			(xy 337.312508 -251.49429) (xy 337.312508 -251.493782) (xy 337.312 -251.48286) (xy 337.305904 -251.470414)
			(xy 337.303758 -251.466609) (xy 337.298393 -251.459717) (xy 337.295236 -251.456698) (xy 337.28406 -251.447554)
			(xy 337.283552 -251.447046) (xy 337.233768 -251.406914) (xy 337.229452 -251.403548) (xy 337.219714 -251.398558)
			(xy 337.214464 -251.397008) (xy 337.204304 -251.394468) (xy 337.196684 -251.395992) (xy 337.179126 -251.399026)
			(xy 337.143635 -251.402202) (xy 337.125818 -251.402342) (xy 337.093437 -251.4017) (xy 337.029594 -251.390842)
			(xy 336.998818 -251.380752) (xy 336.998564 -251.380752) (xy 336.992979 -251.378925) (xy 336.981299 -251.377644)
			(xy 336.97545 -251.378212) (xy 336.96402 -251.379482) (xy 336.886042 -251.431552) (xy 336.881164 -251.435045)
			(xy 336.873084 -251.443908) (xy 336.87004 -251.449078) (xy 336.864452 -251.458984) (xy 336.86369 -251.471176)
			(xy 336.86369 -251.47143) (xy 336.861832 -251.498105) (xy 336.851588 -251.550585) (xy 336.83412 -251.601122)
			(xy 336.80977 -251.648727) (xy 336.779015 -251.692468) (xy 336.742457 -251.731489) (xy 336.70081 -251.765026)
			(xy 336.654891 -251.792423) (xy 336.605598 -251.813143) (xy 336.553896 -251.826781) (xy 336.527394 -251.830332)
			(xy 336.514694 -251.831856) (xy 336.48269 -251.833126) (xy 336.454012 -251.832612) (xy 336.3973 -251.824041)
			(xy 336.342506 -251.807092) (xy 336.290859 -251.782146) (xy 336.243519 -251.749764) (xy 336.201549 -251.710672)
			(xy 336.165891 -251.665747) (xy 336.15122 -251.641102) (xy 336.147664 -251.635006) (xy 336.14106 -251.62764)
			(xy 336.13598 -251.624338) (xy 336.131326 -251.621408) (xy 336.121072 -251.617441) (xy 336.11566 -251.616464)
			(xy 336.03311 -251.605288) (xy 336.021699 -251.60472) (xy 336.000208 -251.612382) (xy 335.991708 -251.62002)
			(xy 335.04378 -252.567948) (xy 335.040261 -252.57168) (xy 335.034637 -252.580256) (xy 335.032604 -252.584966)
			(xy 335.029048 -252.593602) (xy 335.029048 -253.05512) (xy 350.523808 -253.05512) (xy 350.527879 -252.999498)
			(xy 350.540005 -252.945061) (xy 350.559928 -252.89297) (xy 350.587224 -252.844335) (xy 350.62131 -252.800192)
			(xy 350.661459 -252.761483) (xy 350.706817 -252.729032) (xy 350.756417 -252.703531) (xy 350.809201 -252.685524)
			(xy 350.864044 -252.675394) (xy 350.919778 -252.673357) (xy 350.975215 -252.679457) (xy 351.029172 -252.693563)
			(xy 351.080501 -252.715375) (xy 351.128107 -252.744429) (xy 351.170975 -252.780104) (xy 351.208192 -252.821641)
			(xy 351.238965 -252.868154) (xy 351.262637 -252.918651) (xy 351.278705 -252.972058) (xy 351.286825 -253.027234)
			(xy 351.287334 -253.05512) (xy 351.286825 -253.083006) (xy 351.278705 -253.138182) (xy 351.262637 -253.191589)
			(xy 351.238965 -253.242086) (xy 351.208192 -253.288599) (xy 351.170975 -253.330136) (xy 351.128107 -253.365811)
			(xy 351.091979 -253.38786) (xy 358.443274 -253.38786) (xy 358.447345 -253.332238) (xy 358.459471 -253.277801)
			(xy 358.479394 -253.22571) (xy 358.50669 -253.177075) (xy 358.540776 -253.132932) (xy 358.580925 -253.094223)
			(xy 358.626283 -253.061772) (xy 358.675883 -253.036271) (xy 358.728667 -253.018264) (xy 358.78351 -253.008134)
			(xy 358.839244 -253.006097) (xy 358.894681 -253.012197) (xy 358.948638 -253.026303) (xy 358.999967 -253.048115)
			(xy 359.047573 -253.077169) (xy 359.090441 -253.112844) (xy 359.127658 -253.154381) (xy 359.143657 -253.178564)
			(xy 360.485942 -253.178564) (xy 360.490013 -253.122942) (xy 360.502139 -253.068505) (xy 360.522062 -253.016414)
			(xy 360.549358 -252.967779) (xy 360.583444 -252.923636) (xy 360.623593 -252.884927) (xy 360.668951 -252.852476)
			(xy 360.718551 -252.826975) (xy 360.771335 -252.808968) (xy 360.826178 -252.798838) (xy 360.881912 -252.796801)
			(xy 360.937349 -252.802901) (xy 360.991306 -252.817007) (xy 361.042635 -252.838819) (xy 361.090241 -252.867873)
			(xy 361.133109 -252.903548) (xy 361.170326 -252.945085) (xy 361.201099 -252.991598) (xy 361.224771 -253.042095)
			(xy 361.240839 -253.095502) (xy 361.248959 -253.150678) (xy 361.249468 -253.178564) (xy 362.549438 -253.178564)
			(xy 362.553509 -253.122942) (xy 362.565635 -253.068505) (xy 362.585558 -253.016414) (xy 362.612854 -252.967779)
			(xy 362.64694 -252.923636) (xy 362.687089 -252.884927) (xy 362.732447 -252.852476) (xy 362.782047 -252.826975)
			(xy 362.834831 -252.808968) (xy 362.889674 -252.798838) (xy 362.945408 -252.796801) (xy 363.000845 -252.802901)
			(xy 363.054802 -252.817007) (xy 363.106131 -252.838819) (xy 363.153737 -252.867873) (xy 363.196605 -252.903548)
			(xy 363.233822 -252.945085) (xy 363.264595 -252.991598) (xy 363.288267 -253.042095) (xy 363.304335 -253.095502)
			(xy 363.312455 -253.150678) (xy 363.312964 -253.178564) (xy 363.312455 -253.20645) (xy 363.304335 -253.261626)
			(xy 363.288267 -253.315033) (xy 363.264595 -253.36553) (xy 363.233822 -253.412043) (xy 363.196605 -253.45358)
			(xy 363.153737 -253.489255) (xy 363.106131 -253.518309) (xy 363.054802 -253.540121) (xy 363.000845 -253.554227)
			(xy 362.945408 -253.560327) (xy 362.889674 -253.55829) (xy 362.834831 -253.54816) (xy 362.782047 -253.530153)
			(xy 362.732447 -253.504652) (xy 362.687089 -253.472201) (xy 362.64694 -253.433492) (xy 362.612854 -253.389349)
			(xy 362.585558 -253.340714) (xy 362.565635 -253.288623) (xy 362.553509 -253.234186) (xy 362.549438 -253.178564)
			(xy 361.249468 -253.178564) (xy 361.248959 -253.20645) (xy 361.240839 -253.261626) (xy 361.224771 -253.315033)
			(xy 361.201099 -253.36553) (xy 361.170326 -253.412043) (xy 361.133109 -253.45358) (xy 361.090241 -253.489255)
			(xy 361.042635 -253.518309) (xy 360.991306 -253.540121) (xy 360.937349 -253.554227) (xy 360.881912 -253.560327)
			(xy 360.826178 -253.55829) (xy 360.771335 -253.54816) (xy 360.718551 -253.530153) (xy 360.668951 -253.504652)
			(xy 360.623593 -253.472201) (xy 360.583444 -253.433492) (xy 360.549358 -253.389349) (xy 360.522062 -253.340714)
			(xy 360.502139 -253.288623) (xy 360.490013 -253.234186) (xy 360.485942 -253.178564) (xy 359.143657 -253.178564)
			(xy 359.158431 -253.200894) (xy 359.182103 -253.251391) (xy 359.198171 -253.304798) (xy 359.206291 -253.359974)
			(xy 359.2068 -253.38786) (xy 359.206291 -253.415746) (xy 359.198171 -253.470922) (xy 359.182103 -253.524329)
			(xy 359.158431 -253.574826) (xy 359.127658 -253.621339) (xy 359.090441 -253.662876) (xy 359.047573 -253.698551)
			(xy 358.999967 -253.727605) (xy 358.948638 -253.749417) (xy 358.894681 -253.763523) (xy 358.839244 -253.769623)
			(xy 358.78351 -253.767586) (xy 358.728667 -253.757456) (xy 358.675883 -253.739449) (xy 358.626283 -253.713948)
			(xy 358.580925 -253.681497) (xy 358.540776 -253.642788) (xy 358.50669 -253.598645) (xy 358.479394 -253.55001)
			(xy 358.459471 -253.497919) (xy 358.447345 -253.443482) (xy 358.443274 -253.38786) (xy 351.091979 -253.38786)
			(xy 351.080501 -253.394865) (xy 351.029172 -253.416677) (xy 350.975215 -253.430783) (xy 350.919778 -253.436883)
			(xy 350.864044 -253.434846) (xy 350.809201 -253.424716) (xy 350.756417 -253.406709) (xy 350.706817 -253.381208)
			(xy 350.661459 -253.348757) (xy 350.62131 -253.310048) (xy 350.587224 -253.265905) (xy 350.559928 -253.21727)
			(xy 350.540005 -253.165179) (xy 350.527879 -253.110742) (xy 350.523808 -253.05512) (xy 335.029048 -253.05512)
			(xy 335.029048 -254.148844) (xy 349.868234 -254.148844) (xy 349.872305 -254.093222) (xy 349.884431 -254.038785)
			(xy 349.904354 -253.986694) (xy 349.93165 -253.938059) (xy 349.965736 -253.893916) (xy 350.005885 -253.855207)
			(xy 350.051243 -253.822756) (xy 350.100843 -253.797255) (xy 350.153627 -253.779248) (xy 350.20847 -253.769118)
			(xy 350.264204 -253.767081) (xy 350.319641 -253.773181) (xy 350.373598 -253.787287) (xy 350.424927 -253.809099)
			(xy 350.472533 -253.838153) (xy 350.515401 -253.873828) (xy 350.552618 -253.915365) (xy 350.583391 -253.961878)
			(xy 350.594237 -253.985014) (xy 353.918772 -253.985014) (xy 353.922843 -253.929392) (xy 353.934969 -253.874955)
			(xy 353.954892 -253.822864) (xy 353.982188 -253.774229) (xy 354.016274 -253.730086) (xy 354.056423 -253.691377)
			(xy 354.101781 -253.658926) (xy 354.151381 -253.633425) (xy 354.204165 -253.615418) (xy 354.259008 -253.605288)
			(xy 354.314742 -253.603251) (xy 354.370179 -253.609351) (xy 354.424136 -253.623457) (xy 354.475465 -253.645269)
			(xy 354.523071 -253.674323) (xy 354.565939 -253.709998) (xy 354.603156 -253.751535) (xy 354.633929 -253.798048)
			(xy 354.657601 -253.848545) (xy 354.673669 -253.901952) (xy 354.681789 -253.957128) (xy 354.682298 -253.985014)
			(xy 354.681789 -254.0129) (xy 354.673669 -254.068076) (xy 354.657601 -254.121483) (xy 354.633929 -254.17198)
			(xy 354.618987 -254.194564) (xy 362.517942 -254.194564) (xy 362.522013 -254.138942) (xy 362.534139 -254.084505)
			(xy 362.554062 -254.032414) (xy 362.581358 -253.983779) (xy 362.615444 -253.939636) (xy 362.655593 -253.900927)
			(xy 362.700951 -253.868476) (xy 362.750551 -253.842975) (xy 362.803335 -253.824968) (xy 362.858178 -253.814838)
			(xy 362.913912 -253.812801) (xy 362.969349 -253.818901) (xy 363.023306 -253.833007) (xy 363.074635 -253.854819)
			(xy 363.122241 -253.883873) (xy 363.165109 -253.919548) (xy 363.202326 -253.961085) (xy 363.233099 -254.007598)
			(xy 363.256771 -254.058095) (xy 363.272839 -254.111502) (xy 363.280959 -254.166678) (xy 363.281468 -254.194564)
			(xy 363.280959 -254.22245) (xy 363.272839 -254.277626) (xy 363.256771 -254.331033) (xy 363.233099 -254.38153)
			(xy 363.202326 -254.428043) (xy 363.165109 -254.46958) (xy 363.122241 -254.505255) (xy 363.074635 -254.534309)
			(xy 363.023306 -254.556121) (xy 362.969349 -254.570227) (xy 362.913912 -254.576327) (xy 362.858178 -254.57429)
			(xy 362.803335 -254.56416) (xy 362.750551 -254.546153) (xy 362.700951 -254.520652) (xy 362.655593 -254.488201)
			(xy 362.615444 -254.449492) (xy 362.581358 -254.405349) (xy 362.554062 -254.356714) (xy 362.534139 -254.304623)
			(xy 362.522013 -254.250186) (xy 362.517942 -254.194564) (xy 354.618987 -254.194564) (xy 354.603156 -254.218493)
			(xy 354.565939 -254.26003) (xy 354.523071 -254.295705) (xy 354.475465 -254.324759) (xy 354.424136 -254.346571)
			(xy 354.370179 -254.360677) (xy 354.314742 -254.366777) (xy 354.259008 -254.36474) (xy 354.204165 -254.35461)
			(xy 354.151381 -254.336603) (xy 354.101781 -254.311102) (xy 354.056423 -254.278651) (xy 354.016274 -254.239942)
			(xy 353.982188 -254.195799) (xy 353.954892 -254.147164) (xy 353.934969 -254.095073) (xy 353.922843 -254.040636)
			(xy 353.918772 -253.985014) (xy 350.594237 -253.985014) (xy 350.607063 -254.012375) (xy 350.623131 -254.065782)
			(xy 350.631251 -254.120958) (xy 350.63176 -254.148844) (xy 350.631251 -254.17673) (xy 350.623131 -254.231906)
			(xy 350.607063 -254.285313) (xy 350.583391 -254.33581) (xy 350.552618 -254.382323) (xy 350.515401 -254.42386)
			(xy 350.472533 -254.459535) (xy 350.424927 -254.488589) (xy 350.373598 -254.510401) (xy 350.319641 -254.524507)
			(xy 350.264204 -254.530607) (xy 350.20847 -254.52857) (xy 350.153627 -254.51844) (xy 350.100843 -254.500433)
			(xy 350.051243 -254.474932) (xy 350.005885 -254.442481) (xy 349.965736 -254.403772) (xy 349.93165 -254.359629)
			(xy 349.904354 -254.310994) (xy 349.884431 -254.258903) (xy 349.872305 -254.204466) (xy 349.868234 -254.148844)
			(xy 335.029048 -254.148844) (xy 335.029048 -255.237856) (xy 346.269219 -255.237856) (xy 346.269219 -255.183344)
			(xy 346.276977 -255.129387) (xy 346.292335 -255.077084) (xy 346.31498 -255.027498) (xy 346.344452 -254.98164)
			(xy 346.38015 -254.940443) (xy 346.421348 -254.904746) (xy 346.467207 -254.875276) (xy 346.516793 -254.852631)
			(xy 346.569097 -254.837275) (xy 346.623054 -254.829518) (xy 346.65031 -254.829056) (xy 346.681683 -254.829689)
			(xy 346.743582 -254.839968) (xy 346.802967 -254.860231) (xy 346.830904 -254.874522) (xy 346.840746 -254.879176)
			(xy 346.862447 -254.880635) (xy 346.872814 -254.877316) (xy 346.944188 -254.850646) (xy 346.954196 -254.846328)
			(xy 346.9696 -254.83094) (xy 346.973906 -254.820928) (xy 346.984622 -254.794133) (xy 347.012917 -254.743842)
			(xy 347.048464 -254.698386) (xy 347.090451 -254.658801) (xy 347.137921 -254.625992) (xy 347.189791 -254.600706)
			(xy 347.244877 -254.583519) (xy 347.301924 -254.574825) (xy 347.330776 -254.574294) (xy 347.35803 -254.574752)
			(xy 347.411984 -254.582506) (xy 347.464285 -254.59786) (xy 347.513868 -254.620501) (xy 347.559725 -254.649969)
			(xy 347.60092 -254.685663) (xy 347.636617 -254.726856) (xy 347.666087 -254.772711) (xy 347.688732 -254.822293)
			(xy 347.704089 -254.874593) (xy 347.711847 -254.928546) (xy 347.711847 -254.983054) (xy 347.704089 -255.037007)
			(xy 347.688732 -255.089307) (xy 347.666087 -255.138889) (xy 347.636617 -255.184744) (xy 347.633171 -255.18872)
			(xy 348.495618 -255.18872) (xy 348.499689 -255.133098) (xy 348.511815 -255.078661) (xy 348.531738 -255.02657)
			(xy 348.559034 -254.977935) (xy 348.59312 -254.933792) (xy 348.633269 -254.895083) (xy 348.678627 -254.862632)
			(xy 348.728227 -254.837131) (xy 348.781011 -254.819124) (xy 348.835854 -254.808994) (xy 348.891588 -254.806957)
			(xy 348.947025 -254.813057) (xy 349.000982 -254.827163) (xy 349.052311 -254.848975) (xy 349.099917 -254.878029)
			(xy 349.142785 -254.913704) (xy 349.180002 -254.955241) (xy 349.210775 -255.001754) (xy 349.234447 -255.052251)
			(xy 349.250515 -255.105658) (xy 349.251338 -255.11125) (xy 353.193856 -255.11125) (xy 353.197927 -255.055628)
			(xy 353.210053 -255.001191) (xy 353.229976 -254.9491) (xy 353.257272 -254.900465) (xy 353.291358 -254.856322)
			(xy 353.331507 -254.817613) (xy 353.376865 -254.785162) (xy 353.426465 -254.759661) (xy 353.479249 -254.741654)
			(xy 353.534092 -254.731524) (xy 353.589826 -254.729487) (xy 353.645263 -254.735587) (xy 353.69922 -254.749693)
			(xy 353.750549 -254.771505) (xy 353.798155 -254.800559) (xy 353.841023 -254.836234) (xy 353.87824 -254.877771)
			(xy 353.909013 -254.924284) (xy 353.932685 -254.974781) (xy 353.948753 -255.028188) (xy 353.956873 -255.083364)
			(xy 353.957382 -255.11125) (xy 353.956873 -255.139136) (xy 353.948753 -255.194312) (xy 353.932685 -255.247719)
			(xy 353.909013 -255.298216) (xy 353.87824 -255.344729) (xy 353.861902 -255.362964) (xy 364.277908 -255.362964)
			(xy 364.281979 -255.307342) (xy 364.294105 -255.252905) (xy 364.314028 -255.200814) (xy 364.341324 -255.152179)
			(xy 364.37541 -255.108036) (xy 364.415559 -255.069327) (xy 364.460917 -255.036876) (xy 364.510517 -255.011375)
			(xy 364.563301 -254.993368) (xy 364.618144 -254.983238) (xy 364.673878 -254.981201) (xy 364.729315 -254.987301)
			(xy 364.783272 -255.001407) (xy 364.834601 -255.023219) (xy 364.882207 -255.052273) (xy 364.925075 -255.087948)
			(xy 364.962292 -255.129485) (xy 364.993065 -255.175998) (xy 365.016737 -255.226495) (xy 365.032805 -255.279902)
			(xy 365.040925 -255.335078) (xy 365.041434 -255.362964) (xy 365.040925 -255.39085) (xy 365.032805 -255.446026)
			(xy 365.016737 -255.499433) (xy 364.993065 -255.54993) (xy 364.962292 -255.596443) (xy 364.925075 -255.63798)
			(xy 364.882207 -255.673655) (xy 364.834601 -255.702709) (xy 364.783272 -255.724521) (xy 364.729315 -255.738627)
			(xy 364.673878 -255.744727) (xy 364.618144 -255.74269) (xy 364.563301 -255.73256) (xy 364.510517 -255.714553)
			(xy 364.460917 -255.689052) (xy 364.415559 -255.656601) (xy 364.37541 -255.617892) (xy 364.341324 -255.573749)
			(xy 364.314028 -255.525114) (xy 364.294105 -255.473023) (xy 364.281979 -255.418586) (xy 364.277908 -255.362964)
			(xy 353.861902 -255.362964) (xy 353.841023 -255.386266) (xy 353.798155 -255.421941) (xy 353.750549 -255.450995)
			(xy 353.69922 -255.472807) (xy 353.645263 -255.486913) (xy 353.589826 -255.493013) (xy 353.534092 -255.490976)
			(xy 353.479249 -255.480846) (xy 353.426465 -255.462839) (xy 353.376865 -255.437338) (xy 353.331507 -255.404887)
			(xy 353.291358 -255.366178) (xy 353.257272 -255.322035) (xy 353.229976 -255.2734) (xy 353.210053 -255.221309)
			(xy 353.197927 -255.166872) (xy 353.193856 -255.11125) (xy 349.251338 -255.11125) (xy 349.258635 -255.160834)
			(xy 349.259144 -255.18872) (xy 349.258635 -255.216606) (xy 349.250515 -255.271782) (xy 349.234447 -255.325189)
			(xy 349.210775 -255.375686) (xy 349.180002 -255.422199) (xy 349.142785 -255.463736) (xy 349.099917 -255.499411)
			(xy 349.052311 -255.528465) (xy 349.000982 -255.550277) (xy 348.947025 -255.564383) (xy 348.891588 -255.570483)
			(xy 348.835854 -255.568446) (xy 348.781011 -255.558316) (xy 348.728227 -255.540309) (xy 348.678627 -255.514808)
			(xy 348.633269 -255.482357) (xy 348.59312 -255.443648) (xy 348.559034 -255.399505) (xy 348.531738 -255.35087)
			(xy 348.511815 -255.298779) (xy 348.499689 -255.244342) (xy 348.495618 -255.18872) (xy 347.633171 -255.18872)
			(xy 347.60092 -255.225937) (xy 347.559725 -255.261631) (xy 347.513868 -255.291099) (xy 347.464285 -255.31374)
			(xy 347.411984 -255.329094) (xy 347.35803 -255.336848) (xy 347.330776 -255.33731) (xy 347.299402 -255.336686)
			(xy 347.237503 -255.326404) (xy 347.178118 -255.306137) (xy 347.150182 -255.291844) (xy 347.140343 -255.287181)
			(xy 347.118639 -255.285725) (xy 347.108272 -255.28905) (xy 347.036898 -255.31572) (xy 347.026872 -255.320004)
			(xy 347.011476 -255.335416) (xy 347.00718 -255.345438) (xy 346.996458 -255.37223) (xy 346.968165 -255.422523)
			(xy 346.93262 -255.467981) (xy 346.890634 -255.507566) (xy 346.843165 -255.540377) (xy 346.791295 -255.565663)
			(xy 346.736209 -255.582849) (xy 346.679162 -255.591542) (xy 346.65031 -255.592072) (xy 346.623054 -255.591682)
			(xy 346.569097 -255.583925) (xy 346.516793 -255.568569) (xy 346.467207 -255.545924) (xy 346.421348 -255.516454)
			(xy 346.38015 -255.480757) (xy 346.344452 -255.43956) (xy 346.31498 -255.393702) (xy 346.292335 -255.344116)
			(xy 346.276977 -255.291813) (xy 346.269219 -255.237856) (xy 335.029048 -255.237856) (xy 335.029048 -256.226564)
			(xy 358.420668 -256.226564) (xy 358.424739 -256.170942) (xy 358.436865 -256.116505) (xy 358.456788 -256.064414)
			(xy 358.484084 -256.015779) (xy 358.51817 -255.971636) (xy 358.558319 -255.932927) (xy 358.603677 -255.900476)
			(xy 358.653277 -255.874975) (xy 358.706061 -255.856968) (xy 358.760904 -255.846838) (xy 358.816638 -255.844801)
			(xy 358.872075 -255.850901) (xy 358.926032 -255.865007) (xy 358.977361 -255.886819) (xy 359.024967 -255.915873)
			(xy 359.067835 -255.951548) (xy 359.105052 -255.993085) (xy 359.135825 -256.039598) (xy 359.159497 -256.090095)
			(xy 359.175565 -256.143502) (xy 359.183685 -256.198678) (xy 359.184194 -256.226564) (xy 360.485942 -256.226564)
			(xy 360.490013 -256.170942) (xy 360.502139 -256.116505) (xy 360.522062 -256.064414) (xy 360.549358 -256.015779)
			(xy 360.583444 -255.971636) (xy 360.623593 -255.932927) (xy 360.668951 -255.900476) (xy 360.718551 -255.874975)
			(xy 360.771335 -255.856968) (xy 360.826178 -255.846838) (xy 360.881912 -255.844801) (xy 360.937349 -255.850901)
			(xy 360.991306 -255.865007) (xy 361.042635 -255.886819) (xy 361.090241 -255.915873) (xy 361.133109 -255.951548)
			(xy 361.170326 -255.993085) (xy 361.201099 -256.039598) (xy 361.224771 -256.090095) (xy 361.240839 -256.143502)
			(xy 361.248959 -256.198678) (xy 361.249468 -256.226564) (xy 361.248959 -256.25445) (xy 361.240839 -256.309626)
			(xy 361.224771 -256.363033) (xy 361.201099 -256.41353) (xy 361.170326 -256.460043) (xy 361.133109 -256.50158)
			(xy 361.090241 -256.537255) (xy 361.042635 -256.566309) (xy 360.991306 -256.588121) (xy 360.937349 -256.602227)
			(xy 360.91193 -256.605024) (xy 365.598708 -256.605024) (xy 365.602779 -256.549402) (xy 365.614905 -256.494965)
			(xy 365.634828 -256.442874) (xy 365.662124 -256.394239) (xy 365.69621 -256.350096) (xy 365.736359 -256.311387)
			(xy 365.781717 -256.278936) (xy 365.831317 -256.253435) (xy 365.884101 -256.235428) (xy 365.938944 -256.225298)
			(xy 365.994678 -256.223261) (xy 366.050115 -256.229361) (xy 366.104072 -256.243467) (xy 366.155401 -256.265279)
			(xy 366.203007 -256.294333) (xy 366.245875 -256.330008) (xy 366.283092 -256.371545) (xy 366.313865 -256.418058)
			(xy 366.337537 -256.468555) (xy 366.353605 -256.521962) (xy 366.361725 -256.577138) (xy 366.362234 -256.605024)
			(xy 366.361725 -256.63291) (xy 366.353605 -256.688086) (xy 366.337537 -256.741493) (xy 366.313865 -256.79199)
			(xy 366.283092 -256.838503) (xy 366.245875 -256.88004) (xy 366.203007 -256.915715) (xy 366.155401 -256.944769)
			(xy 366.104072 -256.966581) (xy 366.050115 -256.980687) (xy 365.994678 -256.986787) (xy 365.938944 -256.98475)
			(xy 365.884101 -256.97462) (xy 365.831317 -256.956613) (xy 365.781717 -256.931112) (xy 365.736359 -256.898661)
			(xy 365.69621 -256.859952) (xy 365.662124 -256.815809) (xy 365.634828 -256.767174) (xy 365.614905 -256.715083)
			(xy 365.602779 -256.660646) (xy 365.598708 -256.605024) (xy 360.91193 -256.605024) (xy 360.881912 -256.608327)
			(xy 360.826178 -256.60629) (xy 360.771335 -256.59616) (xy 360.718551 -256.578153) (xy 360.668951 -256.552652)
			(xy 360.623593 -256.520201) (xy 360.583444 -256.481492) (xy 360.549358 -256.437349) (xy 360.522062 -256.388714)
			(xy 360.502139 -256.336623) (xy 360.490013 -256.282186) (xy 360.485942 -256.226564) (xy 359.184194 -256.226564)
			(xy 359.183685 -256.25445) (xy 359.175565 -256.309626) (xy 359.159497 -256.363033) (xy 359.135825 -256.41353)
			(xy 359.105052 -256.460043) (xy 359.067835 -256.50158) (xy 359.024967 -256.537255) (xy 358.977361 -256.566309)
			(xy 358.926032 -256.588121) (xy 358.872075 -256.602227) (xy 358.816638 -256.608327) (xy 358.760904 -256.60629)
			(xy 358.706061 -256.59616) (xy 358.653277 -256.578153) (xy 358.603677 -256.552652) (xy 358.558319 -256.520201)
			(xy 358.51817 -256.481492) (xy 358.484084 -256.437349) (xy 358.456788 -256.388714) (xy 358.436865 -256.336623)
			(xy 358.424739 -256.282186) (xy 358.420668 -256.226564) (xy 335.029048 -256.226564) (xy 335.029048 -257.13055)
			(xy 348.495618 -257.13055) (xy 348.499689 -257.074928) (xy 348.511815 -257.020491) (xy 348.531738 -256.9684)
			(xy 348.559034 -256.919765) (xy 348.59312 -256.875622) (xy 348.633269 -256.836913) (xy 348.678627 -256.804462)
			(xy 348.728227 -256.778961) (xy 348.781011 -256.760954) (xy 348.835854 -256.750824) (xy 348.891588 -256.748787)
			(xy 348.947025 -256.754887) (xy 349.000982 -256.768993) (xy 349.052311 -256.790805) (xy 349.099917 -256.819859)
			(xy 349.142785 -256.855534) (xy 349.180002 -256.897071) (xy 349.210775 -256.943584) (xy 349.234447 -256.994081)
			(xy 349.250515 -257.047488) (xy 349.258635 -257.102664) (xy 349.25887 -257.115564) (xy 360.485942 -257.115564)
			(xy 360.490013 -257.059942) (xy 360.502139 -257.005505) (xy 360.522062 -256.953414) (xy 360.549358 -256.904779)
			(xy 360.583444 -256.860636) (xy 360.623593 -256.821927) (xy 360.668951 -256.789476) (xy 360.718551 -256.763975)
			(xy 360.771335 -256.745968) (xy 360.826178 -256.735838) (xy 360.881912 -256.733801) (xy 360.937349 -256.739901)
			(xy 360.991306 -256.754007) (xy 361.042635 -256.775819) (xy 361.090241 -256.804873) (xy 361.133109 -256.840548)
			(xy 361.170326 -256.882085) (xy 361.201099 -256.928598) (xy 361.224771 -256.979095) (xy 361.240839 -257.032502)
			(xy 361.248959 -257.087678) (xy 361.249468 -257.115564) (xy 361.248959 -257.14345) (xy 361.240839 -257.198626)
			(xy 361.224771 -257.252033) (xy 361.201099 -257.30253) (xy 361.170326 -257.349043) (xy 361.133109 -257.39058)
			(xy 361.090241 -257.426255) (xy 361.042635 -257.455309) (xy 360.991306 -257.477121) (xy 360.937349 -257.491227)
			(xy 360.881912 -257.497327) (xy 360.826178 -257.49529) (xy 360.771335 -257.48516) (xy 360.718551 -257.467153)
			(xy 360.668951 -257.441652) (xy 360.623593 -257.409201) (xy 360.583444 -257.370492) (xy 360.549358 -257.326349)
			(xy 360.522062 -257.277714) (xy 360.502139 -257.225623) (xy 360.490013 -257.171186) (xy 360.485942 -257.115564)
			(xy 349.25887 -257.115564) (xy 349.259144 -257.13055) (xy 349.258635 -257.158436) (xy 349.250515 -257.213612)
			(xy 349.234447 -257.267019) (xy 349.210775 -257.317516) (xy 349.180002 -257.364029) (xy 349.142785 -257.405566)
			(xy 349.099917 -257.441241) (xy 349.052311 -257.470295) (xy 349.000982 -257.492107) (xy 348.947025 -257.506213)
			(xy 348.891588 -257.512313) (xy 348.835854 -257.510276) (xy 348.781011 -257.500146) (xy 348.728227 -257.482139)
			(xy 348.678627 -257.456638) (xy 348.633269 -257.424187) (xy 348.59312 -257.385478) (xy 348.559034 -257.341335)
			(xy 348.531738 -257.2927) (xy 348.511815 -257.240609) (xy 348.499689 -257.186172) (xy 348.495618 -257.13055)
			(xy 335.029048 -257.13055) (xy 335.029048 -258.01955) (xy 348.623128 -258.01955) (xy 348.623602 -257.992297)
			(xy 348.631353 -257.938344) (xy 348.646705 -257.886044) (xy 348.669344 -257.836462) (xy 348.69881 -257.790607)
			(xy 348.734503 -257.749413) (xy 348.775696 -257.713718) (xy 348.82155 -257.684251) (xy 348.871131 -257.661609)
			(xy 348.923431 -257.646256) (xy 348.977383 -257.638503) (xy 349.004636 -257.638042) (xy 349.031693 -257.638468)
			(xy 349.085261 -257.646131) (xy 349.13721 -257.661285) (xy 349.186497 -257.683626) (xy 349.232134 -257.712706)
			(xy 349.273205 -257.74794) (xy 349.308887 -257.788624) (xy 349.338463 -257.83394) (xy 349.35033 -257.85826)
			(xy 349.354394 -257.866896) (xy 349.367602 -257.879596) (xy 349.447104 -257.913886) (xy 349.465646 -257.914648)
			(xy 349.474536 -257.9116) (xy 349.503804 -257.90251) (xy 349.564292 -257.892677) (xy 349.594932 -257.892042)
			(xy 349.595186 -257.892042) (xy 349.622443 -257.892404) (xy 349.676403 -257.90016) (xy 349.728709 -257.915517)
			(xy 349.778298 -257.938162) (xy 349.824158 -257.967633) (xy 349.865358 -258.003332) (xy 349.901058 -258.04453)
			(xy 349.930531 -258.09039) (xy 349.949335 -258.131564) (xy 358.458768 -258.131564) (xy 358.462839 -258.075942)
			(xy 358.474965 -258.021505) (xy 358.494888 -257.969414) (xy 358.522184 -257.920779) (xy 358.55627 -257.876636)
			(xy 358.596419 -257.837927) (xy 358.641777 -257.805476) (xy 358.691377 -257.779975) (xy 358.744161 -257.761968)
			(xy 358.799004 -257.751838) (xy 358.854738 -257.749801) (xy 358.910175 -257.755901) (xy 358.964132 -257.770007)
			(xy 359.015461 -257.791819) (xy 359.063067 -257.820873) (xy 359.105935 -257.856548) (xy 359.143152 -257.898085)
			(xy 359.173925 -257.944598) (xy 359.197597 -257.995095) (xy 359.213665 -258.048502) (xy 359.221785 -258.103678)
			(xy 359.222294 -258.131564) (xy 362.517942 -258.131564) (xy 362.522013 -258.075942) (xy 362.534139 -258.021505)
			(xy 362.554062 -257.969414) (xy 362.581358 -257.920779) (xy 362.615444 -257.876636) (xy 362.655593 -257.837927)
			(xy 362.700951 -257.805476) (xy 362.750551 -257.779975) (xy 362.803335 -257.761968) (xy 362.858178 -257.751838)
			(xy 362.913912 -257.749801) (xy 362.969349 -257.755901) (xy 363.023306 -257.770007) (xy 363.074635 -257.791819)
			(xy 363.122241 -257.820873) (xy 363.165109 -257.856548) (xy 363.202326 -257.898085) (xy 363.233099 -257.944598)
			(xy 363.256771 -257.995095) (xy 363.272839 -258.048502) (xy 363.280959 -258.103678) (xy 363.281468 -258.131564)
			(xy 363.280959 -258.15945) (xy 363.272839 -258.214626) (xy 363.256771 -258.268033) (xy 363.233099 -258.31853)
			(xy 363.202326 -258.365043) (xy 363.165109 -258.40658) (xy 363.122241 -258.442255) (xy 363.074635 -258.471309)
			(xy 363.023306 -258.493121) (xy 362.969349 -258.507227) (xy 362.913912 -258.513327) (xy 362.858178 -258.51129)
			(xy 362.803335 -258.50116) (xy 362.750551 -258.483153) (xy 362.700951 -258.457652) (xy 362.655593 -258.425201)
			(xy 362.615444 -258.386492) (xy 362.581358 -258.342349) (xy 362.554062 -258.293714) (xy 362.534139 -258.241623)
			(xy 362.522013 -258.187186) (xy 362.517942 -258.131564) (xy 359.222294 -258.131564) (xy 359.221785 -258.15945)
			(xy 359.213665 -258.214626) (xy 359.197597 -258.268033) (xy 359.173925 -258.31853) (xy 359.143152 -258.365043)
			(xy 359.105935 -258.40658) (xy 359.063067 -258.442255) (xy 359.015461 -258.471309) (xy 358.964132 -258.493121)
			(xy 358.910175 -258.507227) (xy 358.854738 -258.513327) (xy 358.799004 -258.51129) (xy 358.744161 -258.50116)
			(xy 358.691377 -258.483153) (xy 358.641777 -258.457652) (xy 358.596419 -258.425201) (xy 358.55627 -258.386492)
			(xy 358.522184 -258.342349) (xy 358.494888 -258.293714) (xy 358.474965 -258.241623) (xy 358.462839 -258.187186)
			(xy 358.458768 -258.131564) (xy 349.949335 -258.131564) (xy 349.953178 -258.139978) (xy 349.968537 -258.192284)
			(xy 349.976295 -258.246243) (xy 349.976295 -258.300757) (xy 349.968537 -258.354716) (xy 349.953178 -258.407022)
			(xy 349.930531 -258.45661) (xy 349.901058 -258.50247) (xy 349.865358 -258.543668) (xy 349.824158 -258.579367)
			(xy 349.778298 -258.608838) (xy 349.728709 -258.631483) (xy 349.676403 -258.64684) (xy 349.622443 -258.654596)
			(xy 349.595186 -258.655058) (xy 349.574638 -258.654758) (xy 349.533782 -258.650305) (xy 349.513652 -258.646168)
			(xy 349.513398 -258.646168) (xy 349.501664 -258.644425) (xy 349.478765 -258.650502) (xy 349.469456 -258.657852)
			(xy 349.39859 -258.720336) (xy 349.3897 -258.742688) (xy 349.390716 -258.754626) (xy 349.390716 -258.755134)
			(xy 349.392494 -258.79044) (xy 349.392008 -258.817691) (xy 349.384252 -258.871639) (xy 349.368897 -258.923934)
			(xy 349.346255 -258.973511) (xy 349.316789 -259.019361) (xy 349.281098 -259.060552) (xy 349.239907 -259.096243)
			(xy 349.194057 -259.125709) (xy 349.14448 -259.148351) (xy 349.092185 -259.163706) (xy 349.038237 -259.171462)
			(xy 348.983735 -259.171462) (xy 348.929787 -259.163706) (xy 348.877492 -259.148351) (xy 348.827915 -259.125709)
			(xy 348.782065 -259.096243) (xy 348.740874 -259.060552) (xy 348.705183 -259.019361) (xy 348.675717 -258.973511)
			(xy 348.653075 -258.923934) (xy 348.63772 -258.871639) (xy 348.629964 -258.817691) (xy 348.629478 -258.79044)
			(xy 348.630055 -258.761315) (xy 348.638916 -258.703744) (xy 348.656424 -258.648188) (xy 348.682173 -258.595939)
			(xy 348.715562 -258.548209) (xy 348.755818 -258.506109) (xy 348.778576 -258.487926) (xy 348.787566 -258.480272)
			(xy 348.797904 -258.459082) (xy 348.798388 -258.447286) (xy 348.797626 -258.354068) (xy 348.786704 -258.332986)
			(xy 348.777052 -258.325874) (xy 348.753624 -258.307704) (xy 348.712094 -258.265398) (xy 348.677603 -258.21718)
			(xy 348.650979 -258.164211) (xy 348.632864 -258.107762) (xy 348.623692 -258.049192) (xy 348.623128 -258.01955)
			(xy 335.029048 -258.01955) (xy 335.029048 -258.772152) (xy 335.02946 -258.782176) (xy 335.037123 -258.800701)
			(xy 335.051299 -258.814877) (xy 335.069824 -258.82254) (xy 335.079848 -258.822952) (xy 341.638128 -258.822952)
			(xy 341.648195 -258.823382) (xy 341.666787 -258.831109) (xy 341.674196 -258.837938) (xy 341.856822 -259.020564)
			(xy 344.490292 -259.020564) (xy 344.494363 -258.964942) (xy 344.506489 -258.910505) (xy 344.526412 -258.858414)
			(xy 344.553708 -258.809779) (xy 344.587794 -258.765636) (xy 344.627943 -258.726927) (xy 344.673301 -258.694476)
			(xy 344.722901 -258.668975) (xy 344.775685 -258.650968) (xy 344.830528 -258.640838) (xy 344.886262 -258.638801)
			(xy 344.941699 -258.644901) (xy 344.995656 -258.659007) (xy 345.046985 -258.680819) (xy 345.094591 -258.709873)
			(xy 345.137459 -258.745548) (xy 345.174676 -258.787085) (xy 345.205449 -258.833598) (xy 345.229121 -258.884095)
			(xy 345.245189 -258.937502) (xy 345.253309 -258.992678) (xy 345.253818 -259.020564) (xy 345.379292 -259.020564)
			(xy 345.383363 -258.964942) (xy 345.395489 -258.910505) (xy 345.415412 -258.858414) (xy 345.442708 -258.809779)
			(xy 345.476794 -258.765636) (xy 345.516943 -258.726927) (xy 345.562301 -258.694476) (xy 345.611901 -258.668975)
			(xy 345.664685 -258.650968) (xy 345.719528 -258.640838) (xy 345.775262 -258.638801) (xy 345.830699 -258.644901)
			(xy 345.884656 -258.659007) (xy 345.935985 -258.680819) (xy 345.983591 -258.709873) (xy 346.026459 -258.745548)
			(xy 346.063676 -258.787085) (xy 346.094449 -258.833598) (xy 346.118121 -258.884095) (xy 346.134189 -258.937502)
			(xy 346.142309 -258.992678) (xy 346.142818 -259.020564) (xy 346.142309 -259.04845) (xy 346.134189 -259.103626)
			(xy 346.118121 -259.157033) (xy 346.094449 -259.20753) (xy 346.063676 -259.254043) (xy 346.026459 -259.29558)
			(xy 345.983591 -259.331255) (xy 345.935985 -259.360309) (xy 345.884656 -259.382121) (xy 345.830699 -259.396227)
			(xy 345.775262 -259.402327) (xy 345.719528 -259.40029) (xy 345.664685 -259.39016) (xy 345.611901 -259.372153)
			(xy 345.562301 -259.346652) (xy 345.516943 -259.314201) (xy 345.476794 -259.275492) (xy 345.442708 -259.231349)
			(xy 345.415412 -259.182714) (xy 345.395489 -259.130623) (xy 345.383363 -259.076186) (xy 345.379292 -259.020564)
			(xy 345.253818 -259.020564) (xy 345.253309 -259.04845) (xy 345.245189 -259.103626) (xy 345.229121 -259.157033)
			(xy 345.205449 -259.20753) (xy 345.174676 -259.254043) (xy 345.137459 -259.29558) (xy 345.094591 -259.331255)
			(xy 345.046985 -259.360309) (xy 344.995656 -259.382121) (xy 344.941699 -259.396227) (xy 344.886262 -259.402327)
			(xy 344.830528 -259.40029) (xy 344.775685 -259.39016) (xy 344.722901 -259.372153) (xy 344.673301 -259.346652)
			(xy 344.627943 -259.314201) (xy 344.587794 -259.275492) (xy 344.553708 -259.231349) (xy 344.526412 -259.182714)
			(xy 344.506489 -259.130623) (xy 344.494363 -259.076186) (xy 344.490292 -259.020564) (xy 341.856822 -259.020564)
			(xy 342.227662 -259.391404) (xy 342.234512 -259.398801) (xy 342.242251 -259.417399) (xy 342.242648 -259.427472)
			(xy 342.242648 -259.535422) (xy 346.407738 -259.535422) (xy 346.411809 -259.4798) (xy 346.423935 -259.425363)
			(xy 346.443858 -259.373272) (xy 346.471154 -259.324637) (xy 346.50524 -259.280494) (xy 346.545389 -259.241785)
			(xy 346.590747 -259.209334) (xy 346.640347 -259.183833) (xy 346.693131 -259.165826) (xy 346.747974 -259.155696)
			(xy 346.803708 -259.153659) (xy 346.859145 -259.159759) (xy 346.913102 -259.173865) (xy 346.955213 -259.19176)
			(xy 355.780592 -259.19176) (xy 355.784663 -259.136138) (xy 355.796789 -259.081701) (xy 355.816712 -259.02961)
			(xy 355.844008 -258.980975) (xy 355.878094 -258.936832) (xy 355.918243 -258.898123) (xy 355.963601 -258.865672)
			(xy 356.013201 -258.840171) (xy 356.065985 -258.822164) (xy 356.120828 -258.812034) (xy 356.176562 -258.809997)
			(xy 356.231999 -258.816097) (xy 356.285956 -258.830203) (xy 356.337285 -258.852015) (xy 356.384891 -258.881069)
			(xy 356.427759 -258.916744) (xy 356.464976 -258.958281) (xy 356.495749 -259.004794) (xy 356.519421 -259.055291)
			(xy 356.535489 -259.108698) (xy 356.541209 -259.147564) (xy 362.539024 -259.147564) (xy 362.543095 -259.091942)
			(xy 362.555221 -259.037505) (xy 362.575144 -258.985414) (xy 362.60244 -258.936779) (xy 362.636526 -258.892636)
			(xy 362.676675 -258.853927) (xy 362.722033 -258.821476) (xy 362.771633 -258.795975) (xy 362.824417 -258.777968)
			(xy 362.87926 -258.767838) (xy 362.934994 -258.765801) (xy 362.990431 -258.771901) (xy 363.044388 -258.786007)
			(xy 363.095717 -258.807819) (xy 363.143323 -258.836873) (xy 363.186191 -258.872548) (xy 363.223408 -258.914085)
			(xy 363.254181 -258.960598) (xy 363.277853 -259.011095) (xy 363.293921 -259.064502) (xy 363.302041 -259.119678)
			(xy 363.30255 -259.147564) (xy 363.302041 -259.17545) (xy 363.293921 -259.230626) (xy 363.277853 -259.284033)
			(xy 363.254181 -259.33453) (xy 363.223408 -259.381043) (xy 363.186191 -259.42258) (xy 363.143323 -259.458255)
			(xy 363.095717 -259.487309) (xy 363.044388 -259.509121) (xy 362.990431 -259.523227) (xy 362.934994 -259.529327)
			(xy 362.87926 -259.52729) (xy 362.824417 -259.51716) (xy 362.771633 -259.499153) (xy 362.722033 -259.473652)
			(xy 362.676675 -259.441201) (xy 362.636526 -259.402492) (xy 362.60244 -259.358349) (xy 362.575144 -259.309714)
			(xy 362.555221 -259.257623) (xy 362.543095 -259.203186) (xy 362.539024 -259.147564) (xy 356.541209 -259.147564)
			(xy 356.543609 -259.163874) (xy 356.544118 -259.19176) (xy 356.543609 -259.219646) (xy 356.535489 -259.274822)
			(xy 356.519421 -259.328229) (xy 356.495749 -259.378726) (xy 356.464976 -259.425239) (xy 356.427759 -259.466776)
			(xy 356.384891 -259.502451) (xy 356.337285 -259.531505) (xy 356.285956 -259.553317) (xy 356.231999 -259.567423)
			(xy 356.176562 -259.573523) (xy 356.120828 -259.571486) (xy 356.065985 -259.561356) (xy 356.013201 -259.543349)
			(xy 355.963601 -259.517848) (xy 355.918243 -259.485397) (xy 355.878094 -259.446688) (xy 355.844008 -259.402545)
			(xy 355.816712 -259.35391) (xy 355.796789 -259.301819) (xy 355.784663 -259.247382) (xy 355.780592 -259.19176)
			(xy 346.955213 -259.19176) (xy 346.964431 -259.195677) (xy 347.012037 -259.224731) (xy 347.054905 -259.260406)
			(xy 347.092122 -259.301943) (xy 347.122895 -259.348456) (xy 347.146567 -259.398953) (xy 347.162635 -259.45236)
			(xy 347.170755 -259.507536) (xy 347.171264 -259.535422) (xy 347.170755 -259.563308) (xy 347.162635 -259.618484)
			(xy 347.146567 -259.671891) (xy 347.122895 -259.722388) (xy 347.092122 -259.768901) (xy 347.054905 -259.810438)
			(xy 347.012037 -259.846113) (xy 346.964431 -259.875167) (xy 346.913102 -259.896979) (xy 346.859145 -259.911085)
			(xy 346.803708 -259.917185) (xy 346.747974 -259.915148) (xy 346.693131 -259.905018) (xy 346.640347 -259.887011)
			(xy 346.590747 -259.86151) (xy 346.545389 -259.829059) (xy 346.50524 -259.79035) (xy 346.471154 -259.746207)
			(xy 346.443858 -259.697572) (xy 346.423935 -259.645481) (xy 346.411809 -259.591044) (xy 346.407738 -259.535422)
			(xy 342.242648 -259.535422) (xy 342.242648 -260.671564) (xy 344.363292 -260.671564) (xy 344.367363 -260.615942)
			(xy 344.379489 -260.561505) (xy 344.399412 -260.509414) (xy 344.426708 -260.460779) (xy 344.460794 -260.416636)
			(xy 344.500943 -260.377927) (xy 344.546301 -260.345476) (xy 344.595901 -260.319975) (xy 344.648685 -260.301968)
			(xy 344.703528 -260.291838) (xy 344.759262 -260.289801) (xy 344.814699 -260.295901) (xy 344.868656 -260.310007)
			(xy 344.919985 -260.331819) (xy 344.967591 -260.360873) (xy 345.010459 -260.396548) (xy 345.047676 -260.438085)
			(xy 345.078449 -260.484598) (xy 345.102121 -260.535095) (xy 345.118189 -260.588502) (xy 345.126309 -260.643678)
			(xy 345.126818 -260.671564) (xy 345.126309 -260.69945) (xy 345.118189 -260.754626) (xy 345.102121 -260.808033)
			(xy 345.078449 -260.85853) (xy 345.047676 -260.905043) (xy 345.010459 -260.94658) (xy 344.967591 -260.982255)
			(xy 344.919985 -261.011309) (xy 344.868656 -261.033121) (xy 344.814699 -261.047227) (xy 344.759262 -261.053327)
			(xy 344.703528 -261.05129) (xy 344.648685 -261.04116) (xy 344.595901 -261.023153) (xy 344.546301 -260.997652)
			(xy 344.500943 -260.965201) (xy 344.460794 -260.926492) (xy 344.426708 -260.882349) (xy 344.399412 -260.833714)
			(xy 344.379489 -260.781623) (xy 344.367363 -260.727186) (xy 344.363292 -260.671564) (xy 342.242648 -260.671564)
			(xy 342.242648 -261.217664) (xy 346.340428 -261.217664) (xy 346.344499 -261.162042) (xy 346.356625 -261.107605)
			(xy 346.376548 -261.055514) (xy 346.403844 -261.006879) (xy 346.43793 -260.962736) (xy 346.478079 -260.924027)
			(xy 346.523437 -260.891576) (xy 346.573037 -260.866075) (xy 346.625821 -260.848068) (xy 346.680664 -260.837938)
			(xy 346.736398 -260.835901) (xy 346.791835 -260.842001) (xy 346.845792 -260.856107) (xy 346.897121 -260.877919)
			(xy 346.944727 -260.906973) (xy 346.987595 -260.942648) (xy 347.024812 -260.984185) (xy 347.055585 -261.030698)
			(xy 347.079257 -261.081195) (xy 347.095325 -261.134602) (xy 347.103445 -261.189778) (xy 347.103954 -261.217664)
			(xy 347.103445 -261.24555) (xy 347.095325 -261.300726) (xy 347.079257 -261.354133) (xy 347.055585 -261.40463)
			(xy 347.024812 -261.451143) (xy 346.987595 -261.49268) (xy 346.959991 -261.515652) (xy 351.594883 -261.515652)
			(xy 351.594883 -261.461148) (xy 351.60264 -261.407198) (xy 351.617997 -261.354902) (xy 351.64064 -261.305324)
			(xy 351.670108 -261.259473) (xy 351.705802 -261.218282) (xy 351.746995 -261.182591) (xy 351.792848 -261.153126)
			(xy 351.842428 -261.130487) (xy 351.894726 -261.115135) (xy 351.948676 -261.107381) (xy 351.975928 -261.10692)
			(xy 352.004527 -261.107402) (xy 352.061083 -261.115945) (xy 352.115731 -261.132835) (xy 352.167244 -261.157694)
			(xy 352.214469 -261.189964) (xy 352.232231 -261.206488) (xy 364.15802 -261.206488) (xy 364.162091 -261.150866)
			(xy 364.174217 -261.096429) (xy 364.19414 -261.044338) (xy 364.221436 -260.995703) (xy 364.255522 -260.95156)
			(xy 364.295671 -260.912851) (xy 364.341029 -260.8804) (xy 364.390629 -260.854899) (xy 364.443413 -260.836892)
			(xy 364.498256 -260.826762) (xy 364.55399 -260.824725) (xy 364.609427 -260.830825) (xy 364.663384 -260.844931)
			(xy 364.714713 -260.866743) (xy 364.762319 -260.895797) (xy 364.805187 -260.931472) (xy 364.842404 -260.973009)
			(xy 364.873177 -261.019522) (xy 364.896849 -261.070019) (xy 364.912917 -261.123426) (xy 364.921037 -261.178602)
			(xy 364.921546 -261.206488) (xy 364.921037 -261.234374) (xy 364.912917 -261.28955) (xy 364.896849 -261.342957)
			(xy 364.873177 -261.393454) (xy 364.842404 -261.439967) (xy 364.805187 -261.481504) (xy 364.762319 -261.517179)
			(xy 364.714713 -261.546233) (xy 364.663384 -261.568045) (xy 364.609427 -261.582151) (xy 364.55399 -261.588251)
			(xy 364.498256 -261.586214) (xy 364.443413 -261.576084) (xy 364.390629 -261.558077) (xy 364.341029 -261.532576)
			(xy 364.295671 -261.500125) (xy 364.255522 -261.461416) (xy 364.221436 -261.417273) (xy 364.19414 -261.368638)
			(xy 364.174217 -261.316547) (xy 364.162091 -261.26211) (xy 364.15802 -261.206488) (xy 352.232231 -261.206488)
			(xy 352.256348 -261.228923) (xy 352.291941 -261.273698) (xy 352.320451 -261.323284) (xy 352.34124 -261.37657)
			(xy 352.348038 -261.404354) (xy 352.350455 -261.413351) (xy 352.360755 -261.428854) (xy 352.368104 -261.43458)
			(xy 352.42373 -261.474204) (xy 352.431597 -261.479254) (xy 352.449714 -261.483806) (xy 352.459036 -261.483094)
			(xy 352.45929 -261.483094) (xy 352.470548 -261.481798) (xy 352.49317 -261.480402) (xy 352.504502 -261.4803)
			(xy 352.531754 -261.48077) (xy 352.585702 -261.488527) (xy 352.637998 -261.503882) (xy 352.687576 -261.526524)
			(xy 352.733427 -261.555991) (xy 352.774618 -261.591683) (xy 352.81031 -261.632874) (xy 352.839777 -261.678726)
			(xy 352.862418 -261.728304) (xy 352.877774 -261.7806) (xy 352.883144 -261.817955) (xy 373.819343 -261.817955)
			(xy 373.819343 -261.763445) (xy 373.827101 -261.709491) (xy 373.842458 -261.65719) (xy 373.865103 -261.607607)
			(xy 373.894574 -261.561751) (xy 373.930271 -261.520557) (xy 373.971467 -261.484862) (xy 374.017324 -261.455393)
			(xy 374.066909 -261.432751) (xy 374.11921 -261.417396) (xy 374.173165 -261.409642) (xy 374.20042 -261.40918)
			(xy 374.229336 -261.409726) (xy 374.286508 -261.418445) (xy 374.341707 -261.435695) (xy 374.39367 -261.461082)
			(xy 374.441204 -261.494022) (xy 374.48322 -261.533761) (xy 374.50141 -261.556246) (xy 374.509015 -261.565055)
			(xy 374.529918 -261.575236) (xy 374.541542 -261.575804) (xy 374.621298 -261.575804) (xy 374.632928 -261.575248)
			(xy 374.653837 -261.565071) (xy 374.66143 -261.556246) (xy 374.67959 -261.533737) (xy 374.721618 -261.494006)
			(xy 374.76916 -261.461071) (xy 374.821127 -261.435688) (xy 374.876329 -261.418437) (xy 374.933502 -261.409713)
			(xy 374.96242 -261.40918) (xy 374.989669 -261.409692) (xy 375.043613 -261.41745) (xy 375.095904 -261.432807)
			(xy 375.145477 -261.455448) (xy 375.175055 -261.474458) (xy 377.069602 -261.474458) (xy 377.073673 -261.418836)
			(xy 377.085799 -261.364399) (xy 377.105722 -261.312308) (xy 377.133018 -261.263673) (xy 377.167104 -261.21953)
			(xy 377.207253 -261.180821) (xy 377.252611 -261.14837) (xy 377.302211 -261.122869) (xy 377.354995 -261.104862)
			(xy 377.409838 -261.094732) (xy 377.465572 -261.092695) (xy 377.521009 -261.098795) (xy 377.574966 -261.112901)
			(xy 377.626295 -261.134713) (xy 377.673901 -261.163767) (xy 377.716769 -261.199442) (xy 377.753986 -261.240979)
			(xy 377.784759 -261.287492) (xy 377.808431 -261.337989) (xy 377.824499 -261.391396) (xy 377.832619 -261.446572)
			(xy 377.833128 -261.474458) (xy 378.55474 -261.474458) (xy 378.558811 -261.418836) (xy 378.570937 -261.364399)
			(xy 378.59086 -261.312308) (xy 378.618156 -261.263673) (xy 378.652242 -261.21953) (xy 378.692391 -261.180821)
			(xy 378.737749 -261.14837) (xy 378.787349 -261.122869) (xy 378.840133 -261.104862) (xy 378.894976 -261.094732)
			(xy 378.95071 -261.092695) (xy 379.006147 -261.098795) (xy 379.060104 -261.112901) (xy 379.111433 -261.134713)
			(xy 379.159039 -261.163767) (xy 379.201907 -261.199442) (xy 379.239124 -261.240979) (xy 379.269897 -261.287492)
			(xy 379.293569 -261.337989) (xy 379.309637 -261.391396) (xy 379.317757 -261.446572) (xy 379.318266 -261.474458)
			(xy 379.317757 -261.502344) (xy 379.309637 -261.55752) (xy 379.293569 -261.610927) (xy 379.269897 -261.661424)
			(xy 379.239124 -261.707937) (xy 379.201907 -261.749474) (xy 379.159039 -261.785149) (xy 379.111433 -261.814203)
			(xy 379.060104 -261.836015) (xy 379.006147 -261.850121) (xy 378.95071 -261.856221) (xy 378.894976 -261.854184)
			(xy 378.840133 -261.844054) (xy 378.787349 -261.826047) (xy 378.737749 -261.800546) (xy 378.692391 -261.768095)
			(xy 378.652242 -261.729386) (xy 378.618156 -261.685243) (xy 378.59086 -261.636608) (xy 378.570937 -261.584517)
			(xy 378.558811 -261.53008) (xy 378.55474 -261.474458) (xy 377.833128 -261.474458) (xy 377.832619 -261.502344)
			(xy 377.824499 -261.55752) (xy 377.808431 -261.610927) (xy 377.784759 -261.661424) (xy 377.753986 -261.707937)
			(xy 377.716769 -261.749474) (xy 377.673901 -261.785149) (xy 377.626295 -261.814203) (xy 377.574966 -261.836015)
			(xy 377.521009 -261.850121) (xy 377.465572 -261.856221) (xy 377.409838 -261.854184) (xy 377.354995 -261.844054)
			(xy 377.302211 -261.826047) (xy 377.252611 -261.800546) (xy 377.207253 -261.768095) (xy 377.167104 -261.729386)
			(xy 377.133018 -261.685243) (xy 377.105722 -261.636608) (xy 377.085799 -261.584517) (xy 377.073673 -261.53008)
			(xy 377.069602 -261.474458) (xy 375.175055 -261.474458) (xy 375.191323 -261.484914) (xy 375.23251 -261.520604)
			(xy 375.268198 -261.561793) (xy 375.297662 -261.607641) (xy 375.3203 -261.657215) (xy 375.335654 -261.709506)
			(xy 375.34341 -261.763451) (xy 375.34341 -261.817949) (xy 375.335654 -261.871894) (xy 375.3203 -261.924185)
			(xy 375.297662 -261.973759) (xy 375.268198 -262.019607) (xy 375.23251 -262.060796) (xy 375.191323 -262.096486)
			(xy 375.145477 -262.125952) (xy 375.095904 -262.148593) (xy 375.043613 -262.16395) (xy 374.989669 -262.171708)
			(xy 374.96242 -262.172196) (xy 374.933504 -262.171665) (xy 374.876333 -262.162939) (xy 374.821134 -262.145683)
			(xy 374.769173 -262.120294) (xy 374.721638 -262.087353) (xy 374.679621 -262.047614) (xy 374.66143 -262.02513)
			(xy 374.653812 -262.016335) (xy 374.632919 -262.006147) (xy 374.621298 -262.005572) (xy 374.541542 -262.005572)
			(xy 374.529904 -262.006067) (xy 374.508993 -262.016284) (xy 374.50141 -262.02513) (xy 374.483221 -262.047615)
			(xy 374.4412 -262.087349) (xy 374.393664 -262.120287) (xy 374.341703 -262.145674) (xy 374.286505 -262.162931)
			(xy 374.229336 -262.17166) (xy 374.20042 -262.172196) (xy 374.173165 -262.171758) (xy 374.11921 -262.164004)
			(xy 374.066909 -262.148649) (xy 374.017324 -262.126007) (xy 373.971467 -262.096538) (xy 373.930271 -262.060843)
			(xy 373.894574 -262.019649) (xy 373.865103 -261.973793) (xy 373.842458 -261.92421) (xy 373.827101 -261.871909)
			(xy 373.819343 -261.817955) (xy 352.883144 -261.817955) (xy 352.88553 -261.834548) (xy 352.88553 -261.889052)
			(xy 352.877774 -261.943) (xy 352.862418 -261.995296) (xy 352.839777 -262.044874) (xy 352.81031 -262.090726)
			(xy 352.774618 -262.131917) (xy 352.733427 -262.167609) (xy 352.687576 -262.197076) (xy 352.637998 -262.219718)
			(xy 352.585702 -262.235073) (xy 352.531754 -262.24283) (xy 352.504502 -262.243316) (xy 352.475905 -262.242779)
			(xy 352.419353 -262.234242) (xy 352.364708 -262.217357) (xy 352.313196 -262.192505) (xy 352.265972 -262.160241)
			(xy 352.224093 -262.121289) (xy 352.188498 -262.076522) (xy 352.159985 -262.026943) (xy 352.139193 -261.973663)
			(xy 352.132392 -261.945882) (xy 352.129951 -261.936894) (xy 352.119667 -261.921386) (xy 352.112326 -261.915656)
			(xy 352.0567 -261.876032) (xy 352.048823 -261.870999) (xy 352.030714 -261.866435) (xy 352.021394 -261.867142)
			(xy 352.02114 -261.867142) (xy 352.009881 -261.868435) (xy 351.98726 -261.869833) (xy 351.975928 -261.869936)
			(xy 351.948676 -261.869419) (xy 351.894726 -261.861665) (xy 351.842428 -261.846313) (xy 351.792848 -261.823674)
			(xy 351.746995 -261.794209) (xy 351.705802 -261.758518) (xy 351.670108 -261.717327) (xy 351.64064 -261.671476)
			(xy 351.617997 -261.621898) (xy 351.60264 -261.569602) (xy 351.594883 -261.515652) (xy 346.959991 -261.515652)
			(xy 346.944727 -261.528355) (xy 346.897121 -261.557409) (xy 346.845792 -261.579221) (xy 346.791835 -261.593327)
			(xy 346.736398 -261.599427) (xy 346.680664 -261.59739) (xy 346.625821 -261.58726) (xy 346.573037 -261.569253)
			(xy 346.523437 -261.543752) (xy 346.478079 -261.511301) (xy 346.43793 -261.472592) (xy 346.403844 -261.428449)
			(xy 346.376548 -261.379814) (xy 346.356625 -261.327723) (xy 346.344499 -261.273286) (xy 346.340428 -261.217664)
			(xy 342.242648 -261.217664) (xy 342.242648 -261.677912) (xy 342.242221 -261.68798) (xy 342.234498 -261.706576)
			(xy 342.227662 -261.71398) (xy 341.746078 -262.195564) (xy 348.581978 -262.195564) (xy 348.586049 -262.139942)
			(xy 348.598175 -262.085505) (xy 348.618098 -262.033414) (xy 348.645394 -261.984779) (xy 348.67948 -261.940636)
			(xy 348.719629 -261.901927) (xy 348.764987 -261.869476) (xy 348.814587 -261.843975) (xy 348.867371 -261.825968)
			(xy 348.922214 -261.815838) (xy 348.977948 -261.813801) (xy 349.033385 -261.819901) (xy 349.087342 -261.834007)
			(xy 349.138671 -261.855819) (xy 349.186277 -261.884873) (xy 349.229145 -261.920548) (xy 349.266362 -261.962085)
			(xy 349.297135 -262.008598) (xy 349.320807 -262.059095) (xy 349.336875 -262.112502) (xy 349.344995 -262.167678)
			(xy 349.345504 -262.195564) (xy 349.344995 -262.22345) (xy 349.336875 -262.278626) (xy 349.320807 -262.332033)
			(xy 349.297135 -262.38253) (xy 349.266362 -262.429043) (xy 349.229145 -262.47058) (xy 349.186277 -262.506255)
			(xy 349.138671 -262.535309) (xy 349.087342 -262.557121) (xy 349.033385 -262.571227) (xy 348.977948 -262.577327)
			(xy 348.922214 -262.57529) (xy 348.867371 -262.56516) (xy 348.814587 -262.547153) (xy 348.764987 -262.521652)
			(xy 348.719629 -262.489201) (xy 348.67948 -262.450492) (xy 348.645394 -262.406349) (xy 348.618098 -262.357714)
			(xy 348.598175 -262.305623) (xy 348.586049 -262.251186) (xy 348.581978 -262.195564) (xy 341.746078 -262.195564)
			(xy 341.67445 -262.267192) (xy 341.667049 -262.274032) (xy 341.648451 -262.281749) (xy 341.638382 -262.282178)
			(xy 339.29701 -262.282178) (xy 339.286145 -262.282733) (xy 339.266397 -262.291811) (xy 339.25891 -262.299704)
			(xy 339.207094 -262.366252) (xy 339.200863 -262.375683) (xy 339.196514 -262.397836) (xy 339.198712 -262.408924)
			(xy 339.198712 -262.409178) (xy 339.199728 -262.412734) (xy 339.200236 -262.414766) (xy 339.205205 -262.436719)
			(xy 339.210551 -262.481414) (xy 339.210904 -262.50392) (xy 339.210904 -262.504682) (xy 339.210418 -262.531933)
			(xy 339.202662 -262.585881) (xy 339.187307 -262.638176) (xy 339.164665 -262.687753) (xy 339.154504 -262.703564)
			(xy 344.363292 -262.703564) (xy 344.367363 -262.647942) (xy 344.379489 -262.593505) (xy 344.399412 -262.541414)
			(xy 344.426708 -262.492779) (xy 344.460794 -262.448636) (xy 344.500943 -262.409927) (xy 344.546301 -262.377476)
			(xy 344.595901 -262.351975) (xy 344.648685 -262.333968) (xy 344.703528 -262.323838) (xy 344.759262 -262.321801)
			(xy 344.814699 -262.327901) (xy 344.868656 -262.342007) (xy 344.919985 -262.363819) (xy 344.967591 -262.392873)
			(xy 345.010459 -262.428548) (xy 345.047676 -262.470085) (xy 345.078449 -262.516598) (xy 345.102121 -262.567095)
			(xy 345.106269 -262.580882) (xy 351.353118 -262.580882) (xy 351.357189 -262.52526) (xy 351.369315 -262.470823)
			(xy 351.389238 -262.418732) (xy 351.416534 -262.370097) (xy 351.45062 -262.325954) (xy 351.490769 -262.287245)
			(xy 351.536127 -262.254794) (xy 351.585727 -262.229293) (xy 351.638511 -262.211286) (xy 351.693354 -262.201156)
			(xy 351.749088 -262.199119) (xy 351.804525 -262.205219) (xy 351.858482 -262.219325) (xy 351.909811 -262.241137)
			(xy 351.957417 -262.270191) (xy 352.000285 -262.305866) (xy 352.037502 -262.347403) (xy 352.068275 -262.393916)
			(xy 352.091947 -262.444413) (xy 352.108015 -262.49782) (xy 352.116135 -262.552996) (xy 352.116644 -262.580882)
			(xy 352.116135 -262.608768) (xy 352.108015 -262.663944) (xy 352.091947 -262.717351) (xy 352.068275 -262.767848)
			(xy 352.065097 -262.772652) (xy 381.52527 -262.772652) (xy 381.529341 -262.71703) (xy 381.541467 -262.662593)
			(xy 381.56139 -262.610502) (xy 381.588686 -262.561867) (xy 381.622772 -262.517724) (xy 381.662921 -262.479015)
			(xy 381.708279 -262.446564) (xy 381.757879 -262.421063) (xy 381.810663 -262.403056) (xy 381.865506 -262.392926)
			(xy 381.92124 -262.390889) (xy 381.976677 -262.396989) (xy 382.030634 -262.411095) (xy 382.081963 -262.432907)
			(xy 382.129569 -262.461961) (xy 382.172437 -262.497636) (xy 382.209654 -262.539173) (xy 382.240427 -262.585686)
			(xy 382.264099 -262.636183) (xy 382.280167 -262.68959) (xy 382.288287 -262.744766) (xy 382.288796 -262.772652)
			(xy 382.288287 -262.800538) (xy 382.280167 -262.855714) (xy 382.264099 -262.909121) (xy 382.240427 -262.959618)
			(xy 382.209654 -263.006131) (xy 382.195136 -263.022334) (xy 386.231128 -263.022334) (xy 386.235199 -262.966712)
			(xy 386.247325 -262.912275) (xy 386.267248 -262.860184) (xy 386.294544 -262.811549) (xy 386.32863 -262.767406)
			(xy 386.368779 -262.728697) (xy 386.414137 -262.696246) (xy 386.463737 -262.670745) (xy 386.516521 -262.652738)
			(xy 386.571364 -262.642608) (xy 386.627098 -262.640571) (xy 386.682535 -262.646671) (xy 386.736492 -262.660777)
			(xy 386.787821 -262.682589) (xy 386.835427 -262.711643) (xy 386.878295 -262.747318) (xy 386.915512 -262.788855)
			(xy 386.946285 -262.835368) (xy 386.969957 -262.885865) (xy 386.986025 -262.939272) (xy 386.994145 -262.994448)
			(xy 386.994654 -263.022334) (xy 386.994145 -263.05022) (xy 386.986025 -263.105396) (xy 386.969957 -263.158803)
			(xy 386.946285 -263.2093) (xy 386.915512 -263.255813) (xy 386.878295 -263.29735) (xy 386.835427 -263.333025)
			(xy 386.787821 -263.362079) (xy 386.736492 -263.383891) (xy 386.682535 -263.397997) (xy 386.627098 -263.404097)
			(xy 386.571364 -263.40206) (xy 386.516521 -263.39193) (xy 386.463737 -263.373923) (xy 386.414137 -263.348422)
			(xy 386.368779 -263.315971) (xy 386.32863 -263.277262) (xy 386.294544 -263.233119) (xy 386.267248 -263.184484)
			(xy 386.247325 -263.132393) (xy 386.235199 -263.077956) (xy 386.231128 -263.022334) (xy 382.195136 -263.022334)
			(xy 382.172437 -263.047668) (xy 382.129569 -263.083343) (xy 382.081963 -263.112397) (xy 382.030634 -263.134209)
			(xy 381.976677 -263.148315) (xy 381.92124 -263.154415) (xy 381.865506 -263.152378) (xy 381.810663 -263.142248)
			(xy 381.757879 -263.124241) (xy 381.708279 -263.09874) (xy 381.662921 -263.066289) (xy 381.622772 -263.02758)
			(xy 381.588686 -262.983437) (xy 381.56139 -262.934802) (xy 381.541467 -262.882711) (xy 381.529341 -262.828274)
			(xy 381.52527 -262.772652) (xy 352.065097 -262.772652) (xy 352.037502 -262.814361) (xy 352.000285 -262.855898)
			(xy 351.957417 -262.891573) (xy 351.909811 -262.920627) (xy 351.858482 -262.942439) (xy 351.804525 -262.956545)
			(xy 351.749088 -262.962645) (xy 351.693354 -262.960608) (xy 351.638511 -262.950478) (xy 351.585727 -262.932471)
			(xy 351.536127 -262.90697) (xy 351.490769 -262.874519) (xy 351.45062 -262.83581) (xy 351.416534 -262.791667)
			(xy 351.389238 -262.743032) (xy 351.369315 -262.690941) (xy 351.357189 -262.636504) (xy 351.353118 -262.580882)
			(xy 345.106269 -262.580882) (xy 345.118189 -262.620502) (xy 345.126309 -262.675678) (xy 345.126818 -262.703564)
			(xy 345.126309 -262.73145) (xy 345.118189 -262.786626) (xy 345.102121 -262.840033) (xy 345.078449 -262.89053)
			(xy 345.047676 -262.937043) (xy 345.010459 -262.97858) (xy 344.967591 -263.014255) (xy 344.919985 -263.043309)
			(xy 344.868656 -263.065121) (xy 344.842863 -263.071864) (xy 348.581978 -263.071864) (xy 348.586049 -263.016242)
			(xy 348.598175 -262.961805) (xy 348.618098 -262.909714) (xy 348.645394 -262.861079) (xy 348.67948 -262.816936)
			(xy 348.719629 -262.778227) (xy 348.764987 -262.745776) (xy 348.814587 -262.720275) (xy 348.867371 -262.702268)
			(xy 348.922214 -262.692138) (xy 348.977948 -262.690101) (xy 349.033385 -262.696201) (xy 349.087342 -262.710307)
			(xy 349.138671 -262.732119) (xy 349.186277 -262.761173) (xy 349.229145 -262.796848) (xy 349.266362 -262.838385)
			(xy 349.297135 -262.884898) (xy 349.320807 -262.935395) (xy 349.336875 -262.988802) (xy 349.344995 -263.043978)
			(xy 349.345504 -263.071864) (xy 349.344995 -263.09975) (xy 349.336875 -263.154926) (xy 349.328317 -263.18337)
			(xy 355.16896 -263.18337) (xy 355.173031 -263.127748) (xy 355.185157 -263.073311) (xy 355.20508 -263.02122)
			(xy 355.232376 -262.972585) (xy 355.266462 -262.928442) (xy 355.306611 -262.889733) (xy 355.351969 -262.857282)
			(xy 355.401569 -262.831781) (xy 355.454353 -262.813774) (xy 355.509196 -262.803644) (xy 355.56493 -262.801607)
			(xy 355.620367 -262.807707) (xy 355.674324 -262.821813) (xy 355.725653 -262.843625) (xy 355.773259 -262.872679)
			(xy 355.816127 -262.908354) (xy 355.853344 -262.949891) (xy 355.884117 -262.996404) (xy 355.907789 -263.046901)
			(xy 355.923857 -263.100308) (xy 355.931977 -263.155484) (xy 355.932486 -263.18337) (xy 355.931977 -263.211256)
			(xy 355.923857 -263.266432) (xy 355.907789 -263.319839) (xy 355.884117 -263.370336) (xy 355.853344 -263.416849)
			(xy 355.816127 -263.458386) (xy 355.773259 -263.494061) (xy 355.725653 -263.523115) (xy 355.674324 -263.544927)
			(xy 355.620367 -263.559033) (xy 355.56493 -263.565133) (xy 355.509196 -263.563096) (xy 355.454353 -263.552966)
			(xy 355.401569 -263.534959) (xy 355.351969 -263.509458) (xy 355.306611 -263.477007) (xy 355.266462 -263.438298)
			(xy 355.232376 -263.394155) (xy 355.20508 -263.34552) (xy 355.185157 -263.293429) (xy 355.173031 -263.238992)
			(xy 355.16896 -263.18337) (xy 349.328317 -263.18337) (xy 349.320807 -263.208333) (xy 349.297135 -263.25883)
			(xy 349.266362 -263.305343) (xy 349.229145 -263.34688) (xy 349.186277 -263.382555) (xy 349.138671 -263.411609)
			(xy 349.087342 -263.433421) (xy 349.033385 -263.447527) (xy 348.977948 -263.453627) (xy 348.922214 -263.45159)
			(xy 348.867371 -263.44146) (xy 348.814587 -263.423453) (xy 348.764987 -263.397952) (xy 348.719629 -263.365501)
			(xy 348.67948 -263.326792) (xy 348.645394 -263.282649) (xy 348.618098 -263.234014) (xy 348.598175 -263.181923)
			(xy 348.586049 -263.127486) (xy 348.581978 -263.071864) (xy 344.842863 -263.071864) (xy 344.814699 -263.079227)
			(xy 344.759262 -263.085327) (xy 344.703528 -263.08329) (xy 344.648685 -263.07316) (xy 344.595901 -263.055153)
			(xy 344.546301 -263.029652) (xy 344.500943 -262.997201) (xy 344.460794 -262.958492) (xy 344.426708 -262.914349)
			(xy 344.399412 -262.865714) (xy 344.379489 -262.813623) (xy 344.367363 -262.759186) (xy 344.363292 -262.703564)
			(xy 339.154504 -262.703564) (xy 339.135199 -262.733603) (xy 339.099508 -262.774794) (xy 339.058317 -262.810485)
			(xy 339.012467 -262.839951) (xy 338.96289 -262.862593) (xy 338.910595 -262.877948) (xy 338.856647 -262.885704)
			(xy 338.802145 -262.885704) (xy 338.748197 -262.877948) (xy 338.695902 -262.862593) (xy 338.646325 -262.839951)
			(xy 338.600475 -262.810485) (xy 338.559284 -262.774794) (xy 338.523593 -262.733603) (xy 338.494127 -262.687753)
			(xy 338.471485 -262.638176) (xy 338.45613 -262.585881) (xy 338.448374 -262.531933) (xy 338.447888 -262.504682)
			(xy 338.447888 -262.50392) (xy 338.448239 -262.481351) (xy 338.453592 -262.436531) (xy 338.458556 -262.414512)
			(xy 338.46008 -262.408416) (xy 338.46008 -262.383778) (xy 338.458681 -262.378849) (xy 338.454205 -262.369633)
			(xy 338.45119 -262.36549) (xy 338.449412 -262.363204) (xy 338.401406 -262.301228) (xy 338.394444 -262.293296)
			(xy 338.375814 -262.283432) (xy 338.365338 -262.282178) (xy 333.776828 -262.282178) (xy 333.770819 -262.282348)
			(xy 333.759139 -262.285175) (xy 333.753714 -262.287766) (xy 333.750238 -262.289603) (xy 333.743854 -262.294191)
			(xy 333.741014 -262.29691) (xy 332.756002 -263.281922) (xy 333.087724 -263.281922) (xy 333.091795 -263.2263)
			(xy 333.103921 -263.171863) (xy 333.123844 -263.119772) (xy 333.15114 -263.071137) (xy 333.185226 -263.026994)
			(xy 333.225375 -262.988285) (xy 333.270733 -262.955834) (xy 333.320333 -262.930333) (xy 333.373117 -262.912326)
			(xy 333.42796 -262.902196) (xy 333.483694 -262.900159) (xy 333.539131 -262.906259) (xy 333.593088 -262.920365)
			(xy 333.644417 -262.942177) (xy 333.692023 -262.971231) (xy 333.734891 -263.006906) (xy 333.772108 -263.048443)
			(xy 333.802881 -263.094956) (xy 333.826553 -263.145453) (xy 333.842621 -263.19886) (xy 333.850741 -263.254036)
			(xy 333.85125 -263.281922) (xy 333.850741 -263.309808) (xy 333.842621 -263.364984) (xy 333.826553 -263.418391)
			(xy 333.802881 -263.468888) (xy 333.772108 -263.515401) (xy 333.734891 -263.556938) (xy 333.692023 -263.592613)
			(xy 333.644417 -263.621667) (xy 333.593088 -263.643479) (xy 333.539131 -263.657585) (xy 333.483694 -263.663685)
			(xy 333.42796 -263.661648) (xy 333.373117 -263.651518) (xy 333.320333 -263.633511) (xy 333.270733 -263.60801)
			(xy 333.225375 -263.575559) (xy 333.185226 -263.53685) (xy 333.15114 -263.492707) (xy 333.123844 -263.444072)
			(xy 333.103921 -263.391981) (xy 333.091795 -263.337544) (xy 333.087724 -263.281922) (xy 332.756002 -263.281922)
			(xy 332.044548 -263.993376) (xy 333.820006 -263.993376) (xy 333.824077 -263.937754) (xy 333.836203 -263.883317)
			(xy 333.856126 -263.831226) (xy 333.883422 -263.782591) (xy 333.917508 -263.738448) (xy 333.957657 -263.699739)
			(xy 334.003015 -263.667288) (xy 334.052615 -263.641787) (xy 334.105399 -263.62378) (xy 334.160242 -263.61365)
			(xy 334.215976 -263.611613) (xy 334.271413 -263.617713) (xy 334.282089 -263.620504) (xy 335.037428 -263.620504)
			(xy 335.041499 -263.564882) (xy 335.053625 -263.510445) (xy 335.073548 -263.458354) (xy 335.100844 -263.409719)
			(xy 335.13493 -263.365576) (xy 335.175079 -263.326867) (xy 335.220437 -263.294416) (xy 335.270037 -263.268915)
			(xy 335.322821 -263.250908) (xy 335.377664 -263.240778) (xy 335.433398 -263.238741) (xy 335.488835 -263.244841)
			(xy 335.542792 -263.258947) (xy 335.594121 -263.280759) (xy 335.641727 -263.309813) (xy 335.684595 -263.345488)
			(xy 335.721812 -263.387025) (xy 335.752585 -263.433538) (xy 335.776257 -263.484035) (xy 335.792325 -263.537442)
			(xy 335.800445 -263.592618) (xy 335.800954 -263.620504) (xy 335.800445 -263.64839) (xy 335.792325 -263.703566)
			(xy 335.776257 -263.756973) (xy 335.752585 -263.80747) (xy 335.721812 -263.853983) (xy 335.684595 -263.89552)
			(xy 335.641727 -263.931195) (xy 335.594121 -263.960249) (xy 335.542792 -263.982061) (xy 335.488835 -263.996167)
			(xy 335.433398 -264.002267) (xy 335.377664 -264.00023) (xy 335.322821 -263.9901) (xy 335.270037 -263.972093)
			(xy 335.220437 -263.946592) (xy 335.175079 -263.914141) (xy 335.13493 -263.875432) (xy 335.100844 -263.831289)
			(xy 335.073548 -263.782654) (xy 335.053625 -263.730563) (xy 335.041499 -263.676126) (xy 335.037428 -263.620504)
			(xy 334.282089 -263.620504) (xy 334.32537 -263.631819) (xy 334.376699 -263.653631) (xy 334.424305 -263.682685)
			(xy 334.467173 -263.71836) (xy 334.50439 -263.759897) (xy 334.535163 -263.80641) (xy 334.558835 -263.856907)
			(xy 334.574903 -263.910314) (xy 334.583023 -263.96549) (xy 334.583532 -263.993376) (xy 334.583023 -264.021262)
			(xy 334.574903 -264.076438) (xy 334.558835 -264.129845) (xy 334.535163 -264.180342) (xy 334.50439 -264.226855)
			(xy 334.467173 -264.268392) (xy 334.424305 -264.304067) (xy 334.411067 -264.312146) (xy 335.602324 -264.312146)
			(xy 335.606395 -264.256524) (xy 335.618521 -264.202087) (xy 335.638444 -264.149996) (xy 335.66574 -264.101361)
			(xy 335.699826 -264.057218) (xy 335.739975 -264.018509) (xy 335.785333 -263.986058) (xy 335.834933 -263.960557)
			(xy 335.887717 -263.94255) (xy 335.94256 -263.93242) (xy 335.998294 -263.930383) (xy 336.053731 -263.936483)
			(xy 336.107688 -263.950589) (xy 336.159017 -263.972401) (xy 336.206623 -264.001455) (xy 336.249491 -264.03713)
			(xy 336.286708 -264.078667) (xy 336.317481 -264.12518) (xy 336.341153 -264.175677) (xy 336.357221 -264.229084)
			(xy 336.365341 -264.28426) (xy 336.36585 -264.312146) (xy 336.365341 -264.340032) (xy 336.357221 -264.395208)
			(xy 336.341153 -264.448615) (xy 336.317481 -264.499112) (xy 336.286708 -264.545625) (xy 336.249491 -264.587162)
			(xy 336.206623 -264.622837) (xy 336.159017 -264.651891) (xy 336.107688 -264.673703) (xy 336.053731 -264.687809)
			(xy 335.998294 -264.693909) (xy 335.94256 -264.691872) (xy 335.887717 -264.681742) (xy 335.834933 -264.663735)
			(xy 335.785333 -264.638234) (xy 335.739975 -264.605783) (xy 335.699826 -264.567074) (xy 335.66574 -264.522931)
			(xy 335.638444 -264.474296) (xy 335.618521 -264.422205) (xy 335.606395 -264.367768) (xy 335.602324 -264.312146)
			(xy 334.411067 -264.312146) (xy 334.376699 -264.333121) (xy 334.32537 -264.354933) (xy 334.271413 -264.369039)
			(xy 334.215976 -264.375139) (xy 334.160242 -264.373102) (xy 334.105399 -264.362972) (xy 334.052615 -264.344965)
			(xy 334.003015 -264.319464) (xy 333.957657 -264.287013) (xy 333.917508 -264.248304) (xy 333.883422 -264.204161)
			(xy 333.856126 -264.155526) (xy 333.836203 -264.103435) (xy 333.824077 -264.048998) (xy 333.820006 -263.993376)
			(xy 332.044548 -263.993376) (xy 331.173328 -264.864596) (xy 331.170622 -264.867447) (xy 331.166029 -264.873826)
			(xy 331.164184 -264.877296) (xy 331.164063 -264.87755) (xy 333.781906 -264.87755) (xy 333.785977 -264.821928)
			(xy 333.798103 -264.767491) (xy 333.818026 -264.7154) (xy 333.845322 -264.666765) (xy 333.879408 -264.622622)
			(xy 333.919557 -264.583913) (xy 333.964915 -264.551462) (xy 334.014515 -264.525961) (xy 334.067299 -264.507954)
			(xy 334.122142 -264.497824) (xy 334.177876 -264.495787) (xy 334.233313 -264.501887) (xy 334.28727 -264.515993)
			(xy 334.338599 -264.537805) (xy 334.386205 -264.566859) (xy 334.429073 -264.602534) (xy 334.46629 -264.644071)
			(xy 334.497063 -264.690584) (xy 334.520735 -264.741081) (xy 334.536803 -264.794488) (xy 334.544923 -264.849664)
			(xy 334.545432 -264.87755) (xy 334.544923 -264.905436) (xy 334.536803 -264.960612) (xy 334.520735 -265.014019)
			(xy 334.497063 -265.064516) (xy 334.46629 -265.111029) (xy 334.429073 -265.152566) (xy 334.386205 -265.188241)
			(xy 334.338599 -265.217295) (xy 334.28727 -265.239107) (xy 334.233313 -265.253213) (xy 334.177876 -265.259313)
			(xy 334.122142 -265.257276) (xy 334.067299 -265.247146) (xy 334.014515 -265.229139) (xy 333.964915 -265.203638)
			(xy 333.919557 -265.171187) (xy 333.879408 -265.132478) (xy 333.845322 -265.088335) (xy 333.818026 -265.0397)
			(xy 333.798103 -264.987609) (xy 333.785977 -264.933172) (xy 333.781906 -264.87755) (xy 331.164063 -264.87755)
			(xy 331.161607 -264.882724) (xy 331.158796 -264.894404) (xy 331.158596 -264.90041) (xy 331.158596 -269.417038)
			(xy 334.700626 -269.417038) (xy 334.701132 -269.388299) (xy 334.709762 -269.331471) (xy 334.726817 -269.276581)
			(xy 334.751912 -269.22487) (xy 334.784479 -269.177507) (xy 334.80375 -269.15618) (xy 334.810354 -269.149322)
			(xy 334.817466 -269.131288) (xy 334.817466 -269.042388) (xy 334.810354 -269.024354) (xy 334.80375 -269.017496)
			(xy 334.784499 -268.996152) (xy 334.75193 -268.948795) (xy 334.726833 -268.897087) (xy 334.709778 -268.8422)
			(xy 334.70115 -268.785376) (xy 334.700626 -268.756638) (xy 334.701091 -268.729385) (xy 334.708843 -268.675432)
			(xy 334.724196 -268.623132) (xy 334.746837 -268.57355) (xy 334.776304 -268.527695) (xy 334.811998 -268.486501)
			(xy 334.853192 -268.450807) (xy 334.899046 -268.421339) (xy 334.948628 -268.398698) (xy 335.000928 -268.383344)
			(xy 335.054881 -268.375591) (xy 335.082134 -268.37513) (xy 335.109505 -268.375569) (xy 335.163686 -268.383392)
			(xy 335.21619 -268.398887) (xy 335.265936 -268.421735) (xy 335.311901 -268.451466) (xy 335.332832 -268.46911)
			(xy 335.333086 -268.469364) (xy 335.340167 -268.474958) (xy 335.357088 -268.481199) (xy 335.366106 -268.481556)
			(xy 335.433162 -268.481556) (xy 335.442178 -268.48119) (xy 335.459096 -268.47495) (xy 335.466182 -268.469364)
			(xy 335.466182 -268.46911) (xy 335.466436 -268.46911) (xy 335.487369 -268.451469) (xy 335.533337 -268.421745)
			(xy 335.583083 -268.398899) (xy 335.635585 -268.383403) (xy 335.689763 -268.375574) (xy 335.744505 -268.375574)
			(xy 335.798683 -268.383403) (xy 335.851185 -268.398899) (xy 335.900931 -268.421745) (xy 335.946899 -268.451469)
			(xy 335.967832 -268.46911) (xy 335.968086 -268.469364) (xy 335.975167 -268.474958) (xy 335.992088 -268.481199)
			(xy 336.001106 -268.481556) (xy 336.068162 -268.481556) (xy 336.077178 -268.48119) (xy 336.094096 -268.47495)
			(xy 336.101182 -268.469364) (xy 336.101182 -268.46911) (xy 336.101436 -268.46911) (xy 336.122369 -268.451469)
			(xy 336.168337 -268.421745) (xy 336.218083 -268.398899) (xy 336.270585 -268.383403) (xy 336.324763 -268.375574)
			(xy 336.379505 -268.375574) (xy 336.433683 -268.383403) (xy 336.486185 -268.398899) (xy 336.535931 -268.421745)
			(xy 336.581899 -268.451469) (xy 336.602832 -268.46911) (xy 336.603086 -268.469364) (xy 336.610167 -268.474958)
			(xy 336.627088 -268.481199) (xy 336.636106 -268.481556) (xy 336.703162 -268.481556) (xy 336.712178 -268.48119)
			(xy 336.729096 -268.47495) (xy 336.736182 -268.469364) (xy 336.736182 -268.46911) (xy 336.736436 -268.46911)
			(xy 336.757369 -268.451469) (xy 336.803337 -268.421745) (xy 336.853083 -268.398899) (xy 336.905585 -268.383403)
			(xy 336.959763 -268.375574) (xy 337.014505 -268.375574) (xy 337.068683 -268.383403) (xy 337.121185 -268.398899)
			(xy 337.170931 -268.421745) (xy 337.216899 -268.451469) (xy 337.237832 -268.46911) (xy 337.238086 -268.469364)
			(xy 337.245167 -268.474958) (xy 337.262088 -268.481199) (xy 337.271106 -268.481556) (xy 337.338162 -268.481556)
			(xy 337.347178 -268.48119) (xy 337.364096 -268.47495) (xy 337.371182 -268.469364) (xy 337.371182 -268.46911)
			(xy 337.371436 -268.46911) (xy 337.392383 -268.451489) (xy 337.438351 -268.421774) (xy 337.488095 -268.398935)
			(xy 337.540593 -268.383439) (xy 337.594766 -268.375606) (xy 337.622134 -268.37513) (xy 337.649389 -268.375523)
			(xy 337.703345 -268.383286) (xy 337.755646 -268.398648) (xy 337.805229 -268.421297) (xy 337.851084 -268.450773)
			(xy 337.892277 -268.486474) (xy 337.927971 -268.527674) (xy 337.957437 -268.573534) (xy 337.980077 -268.623121)
			(xy 337.995429 -268.675426) (xy 338.003182 -268.729382) (xy 338.003642 -268.756638) (xy 338.00313 -268.785377)
			(xy 337.994503 -268.842205) (xy 337.977449 -268.897095) (xy 337.952356 -268.948807) (xy 337.919789 -268.996169)
			(xy 337.900518 -269.017496) (xy 337.893914 -269.024354) (xy 337.886802 -269.042388) (xy 337.886802 -269.131288)
			(xy 337.893914 -269.149322) (xy 337.900518 -269.15618) (xy 337.919799 -269.177498) (xy 337.952366 -269.224862)
			(xy 337.977457 -269.276575) (xy 337.994505 -269.331469) (xy 338.003124 -269.388298) (xy 338.003642 -269.417038)
			(xy 338.003158 -269.444289) (xy 337.995397 -269.498235) (xy 337.980039 -269.550527) (xy 337.957396 -269.600102)
			(xy 337.927928 -269.645951) (xy 337.892237 -269.68714) (xy 337.851048 -269.722831) (xy 337.805199 -269.752297)
			(xy 337.755624 -269.77494) (xy 337.703331 -269.790298) (xy 337.649385 -269.798058) (xy 337.622134 -269.798546)
			(xy 337.594764 -269.798073) (xy 337.540585 -269.790259) (xy 337.488081 -269.774772) (xy 337.438334 -269.751932)
			(xy 337.392367 -269.722207) (xy 337.371436 -269.704566) (xy 337.371182 -269.704312) (xy 337.364104 -269.698713)
			(xy 337.347181 -269.692473) (xy 337.338162 -269.69212) (xy 337.271106 -269.69212) (xy 337.262089 -269.692475)
			(xy 337.245172 -269.698724) (xy 337.238086 -269.704312) (xy 337.237832 -269.704566) (xy 337.216899 -269.722207)
			(xy 337.170931 -269.751931) (xy 337.121185 -269.774777) (xy 337.068683 -269.790273) (xy 337.014505 -269.798102)
			(xy 336.959763 -269.798102) (xy 336.905585 -269.790273) (xy 336.853083 -269.774777) (xy 336.803337 -269.751931)
			(xy 336.757369 -269.722207) (xy 336.736436 -269.704566) (xy 336.736182 -269.704312) (xy 336.729104 -269.698713)
			(xy 336.712181 -269.692473) (xy 336.703162 -269.69212) (xy 336.636106 -269.69212) (xy 336.627089 -269.692475)
			(xy 336.610172 -269.698724) (xy 336.603086 -269.704312) (xy 336.603086 -269.704566) (xy 336.602832 -269.704566)
			(xy 336.581899 -269.722207) (xy 336.535931 -269.751931) (xy 336.486185 -269.774777) (xy 336.433683 -269.790273)
			(xy 336.379505 -269.798102) (xy 336.324763 -269.798102) (xy 336.270585 -269.790273) (xy 336.218083 -269.774777)
			(xy 336.168337 -269.751931) (xy 336.122369 -269.722207) (xy 336.101436 -269.704566) (xy 336.101182 -269.704312)
			(xy 336.094104 -269.698713) (xy 336.077181 -269.692473) (xy 336.068162 -269.69212) (xy 336.001106 -269.69212)
			(xy 335.992089 -269.692475) (xy 335.975172 -269.698724) (xy 335.968086 -269.704312) (xy 335.968086 -269.704566)
			(xy 335.967832 -269.704566) (xy 335.946899 -269.722207) (xy 335.900931 -269.751931) (xy 335.851185 -269.774777)
			(xy 335.798683 -269.790273) (xy 335.744505 -269.798102) (xy 335.689763 -269.798102) (xy 335.635585 -269.790273)
			(xy 335.583083 -269.774777) (xy 335.533337 -269.751931) (xy 335.487369 -269.722207) (xy 335.466436 -269.704566)
			(xy 335.466182 -269.704312) (xy 335.459104 -269.698713) (xy 335.442181 -269.692473) (xy 335.433162 -269.69212)
			(xy 335.366106 -269.69212) (xy 335.357089 -269.692475) (xy 335.340172 -269.698724) (xy 335.333086 -269.704312)
			(xy 335.333086 -269.704566) (xy 335.332832 -269.704566) (xy 335.311894 -269.722198) (xy 335.265924 -269.751912)
			(xy 335.216178 -269.77475) (xy 335.163678 -269.790243) (xy 335.109503 -269.798072) (xy 335.082134 -269.798546)
			(xy 335.054885 -269.79799) (xy 335.000942 -269.790239) (xy 334.948651 -269.77489) (xy 334.899077 -269.752256)
			(xy 334.853228 -269.722797) (xy 334.812038 -269.687113) (xy 334.776346 -269.64593) (xy 334.746878 -269.600087)
			(xy 334.724235 -269.550516) (xy 334.708876 -269.498228) (xy 334.701115 -269.444287) (xy 334.700626 -269.417038)
			(xy 331.158596 -269.417038) (xy 331.158596 -276.47646) (xy 331.158764 -276.482469) (xy 331.16159 -276.494151)
			(xy 331.164184 -276.499574) (xy 331.166021 -276.50305) (xy 331.170609 -276.509434) (xy 331.173328 -276.512274)
			(xy 331.182726 -276.521672) (xy 331.198728 -276.539452) (xy 331.203554 -276.545548) (xy 331.219194 -276.565954)
			(xy 331.24412 -276.610915) (xy 331.261158 -276.659418) (xy 331.269825 -276.71009) (xy 331.270356 -276.735794)
			(xy 331.270356 -277.864824) (xy 335.665826 -277.864824) (xy 335.666352 -277.835907) (xy 335.675078 -277.778736)
			(xy 335.692334 -277.723537) (xy 335.717724 -277.671575) (xy 335.750667 -277.624041) (xy 335.790407 -277.582024)
			(xy 335.812892 -277.563834) (xy 335.821673 -277.556201) (xy 335.831871 -277.53532) (xy 335.83245 -277.523702)
			(xy 335.83245 -277.443946) (xy 335.831945 -277.432309) (xy 335.821734 -277.411399) (xy 335.812892 -277.403814)
			(xy 335.790414 -277.385617) (xy 335.750678 -277.343598) (xy 335.717739 -277.296065) (xy 335.69235 -277.244104)
			(xy 335.675092 -277.188908) (xy 335.666362 -277.13174) (xy 335.665826 -277.102824) (xy 335.666409 -277.073417)
			(xy 335.675439 -277.015299) (xy 335.693274 -276.959253) (xy 335.719492 -276.906605) (xy 335.753473 -276.858599)
			(xy 335.794413 -276.816372) (xy 335.841345 -276.780923) (xy 335.866994 -276.766528) (xy 335.878932 -276.760178)
			(xy 335.893156 -276.737826) (xy 335.898998 -276.624288) (xy 335.88706 -276.600412) (xy 335.876138 -276.593046)
			(xy 335.85438 -276.577735) (xy 335.814901 -276.542071) (xy 335.780757 -276.50127) (xy 335.75261 -276.456123)
			(xy 335.731005 -276.407505) (xy 335.716362 -276.356357) (xy 335.708964 -276.303671) (xy 335.708498 -276.27707)
			(xy 335.708947 -276.249699) (xy 335.716769 -276.195519) (xy 335.732262 -276.143016) (xy 335.755108 -276.09327)
			(xy 335.784835 -276.047303) (xy 335.802478 -276.026372) (xy 335.802732 -276.026118) (xy 335.808321 -276.019033)
			(xy 335.814565 -276.002115) (xy 335.814924 -275.993098) (xy 335.814924 -275.926042) (xy 335.814542 -275.917028)
			(xy 335.808311 -275.900111) (xy 335.802732 -275.893022) (xy 335.802478 -275.893022) (xy 335.802478 -275.892768)
			(xy 335.784854 -275.871824) (xy 335.755141 -275.825854) (xy 335.732302 -275.77611) (xy 335.716807 -275.723612)
			(xy 335.708975 -275.669438) (xy 335.708498 -275.64207) (xy 335.708498 -275.641816) (xy 335.709069 -275.612017)
			(xy 335.718346 -275.553146) (xy 335.736663 -275.496434) (xy 335.763574 -275.443258) (xy 335.798424 -275.394912)
			(xy 335.818988 -275.373338) (xy 335.826354 -275.365972) (xy 335.833974 -275.34743) (xy 335.832958 -275.25472)
			(xy 335.825084 -275.236178) (xy 335.817718 -275.229066) (xy 335.799761 -275.211015) (xy 335.768263 -275.171012)
			(xy 335.742365 -275.127176) (xy 335.722525 -275.080286) (xy 335.709097 -275.031173) (xy 335.70232 -274.980711)
			(xy 335.701894 -274.955254) (xy 335.702335 -274.928002) (xy 335.710098 -274.874052) (xy 335.725459 -274.821756)
			(xy 335.748106 -274.772179) (xy 335.777577 -274.726329) (xy 335.813273 -274.685139) (xy 335.854467 -274.649448)
			(xy 335.900321 -274.619983) (xy 335.949901 -274.597342) (xy 336.002199 -274.581988) (xy 336.056149 -274.574232)
			(xy 336.083402 -274.573746) (xy 336.11232 -274.574246) (xy 336.169493 -274.582976) (xy 336.224693 -274.600237)
			(xy 336.276655 -274.625632) (xy 336.324188 -274.658579) (xy 336.366203 -274.698324) (xy 336.384392 -274.720812)
			(xy 336.39201 -274.729607) (xy 336.412903 -274.739797) (xy 336.424524 -274.74037) (xy 336.50428 -274.74037)
			(xy 336.51591 -274.739816) (xy 336.536821 -274.729639) (xy 336.544412 -274.720812) (xy 336.561165 -274.700029)
			(xy 336.599519 -274.662899) (xy 336.642673 -274.631477) (xy 336.689787 -274.606378) (xy 336.739939 -274.588092)
			(xy 336.79215 -274.576975) (xy 336.845402 -274.573245) (xy 336.898654 -274.576975) (xy 336.950865 -274.588092)
			(xy 337.001017 -274.606378) (xy 337.048131 -274.631477) (xy 337.091285 -274.662899) (xy 337.129639 -274.700029)
			(xy 337.146392 -274.720812) (xy 337.15401 -274.729607) (xy 337.174903 -274.739797) (xy 337.186524 -274.74037)
			(xy 337.26628 -274.74037) (xy 337.27791 -274.739816) (xy 337.298821 -274.729639) (xy 337.306412 -274.720812)
			(xy 337.324599 -274.698325) (xy 337.366619 -274.65859) (xy 337.414155 -274.625651) (xy 337.466117 -274.600263)
			(xy 337.521315 -274.583007) (xy 337.578486 -274.57428) (xy 337.607402 -274.573746) (xy 337.634651 -274.574276)
			(xy 337.688595 -274.582031) (xy 337.740886 -274.597384) (xy 337.79046 -274.620022) (xy 337.836308 -274.649485)
			(xy 337.877497 -274.685171) (xy 337.913189 -274.726356) (xy 337.942656 -274.772201) (xy 337.9653 -274.821773)
			(xy 337.980659 -274.874062) (xy 337.988421 -274.928005) (xy 337.98891 -274.955254) (xy 337.98891 -274.955508)
			(xy 337.988352 -274.985307) (xy 337.979071 -275.044178) (xy 337.960751 -275.100891) (xy 337.933837 -275.154067)
			(xy 337.898985 -275.202413) (xy 337.87842 -275.223986) (xy 337.871054 -275.231352) (xy 337.863434 -275.249894)
			(xy 337.86445 -275.342604) (xy 337.872324 -275.361146) (xy 337.87969 -275.368258) (xy 337.89766 -275.386296)
			(xy 337.929156 -275.426302) (xy 337.955053 -275.470141) (xy 337.97489 -275.517034) (xy 337.988315 -275.566148)
			(xy 337.99509 -275.616612) (xy 337.995514 -275.64207) (xy 337.995007 -275.670988) (xy 337.98628 -275.728161)
			(xy 337.969022 -275.783361) (xy 337.943629 -275.835324) (xy 337.910681 -275.882857) (xy 337.870936 -275.924872)
			(xy 337.848448 -275.94306) (xy 337.83966 -275.950685) (xy 337.829468 -275.971573) (xy 337.82889 -275.983192)
			(xy 337.82889 -276.062948) (xy 337.829419 -276.074581) (xy 337.839615 -276.09549) (xy 337.848448 -276.10308)
			(xy 337.870932 -276.12127) (xy 337.910665 -276.163292) (xy 337.943602 -276.210827) (xy 337.96899 -276.262788)
			(xy 337.986247 -276.317985) (xy 337.994978 -276.375154) (xy 337.995514 -276.40407) (xy 337.995017 -276.431322)
			(xy 337.987264 -276.485271) (xy 337.971912 -276.537568) (xy 337.949274 -276.587148) (xy 337.919809 -276.633001)
			(xy 337.884119 -276.674194) (xy 337.84293 -276.709888) (xy 337.797079 -276.739356) (xy 337.747502 -276.762)
			(xy 337.695206 -276.777356) (xy 337.641258 -276.785114) (xy 337.614006 -276.785578) (xy 337.585089 -276.785064)
			(xy 337.527917 -276.776335) (xy 337.472718 -276.759077) (xy 337.420756 -276.733684) (xy 337.373222 -276.70074)
			(xy 337.331206 -276.660998) (xy 337.313016 -276.638512) (xy 337.30539 -276.629724) (xy 337.284504 -276.619529)
			(xy 337.272884 -276.618954) (xy 337.193128 -276.618954) (xy 337.181497 -276.619505) (xy 337.160586 -276.629683)
			(xy 337.152996 -276.638512) (xy 337.142965 -276.651117) (xy 337.121089 -276.674769) (xy 337.109308 -276.685756)
			(xy 337.100418 -276.693884) (xy 337.091782 -276.715982) (xy 337.100418 -276.808692) (xy 337.102114 -276.820317)
			(xy 337.114422 -276.840299) (xy 337.12404 -276.847046) (xy 337.124294 -276.8473) (xy 337.147602 -276.862308)
			(xy 337.190041 -276.897972) (xy 337.226868 -276.939406) (xy 337.257308 -276.985735) (xy 337.28072 -277.035983)
			(xy 337.296609 -277.089091) (xy 337.304642 -277.143941) (xy 337.305142 -277.171658) (xy 337.304656 -277.198909)
			(xy 337.2969 -277.252857) (xy 337.281545 -277.305152) (xy 337.258903 -277.354729) (xy 337.229437 -277.400579)
			(xy 337.193746 -277.44177) (xy 337.152555 -277.477461) (xy 337.106705 -277.506927) (xy 337.057128 -277.529569)
			(xy 337.004833 -277.544924) (xy 336.950885 -277.55268) (xy 336.896383 -277.55268) (xy 336.842435 -277.544924)
			(xy 336.79014 -277.529569) (xy 336.740563 -277.506927) (xy 336.694713 -277.477461) (xy 336.653522 -277.44177)
			(xy 336.617831 -277.400579) (xy 336.588365 -277.354729) (xy 336.565723 -277.305152) (xy 336.550368 -277.252857)
			(xy 336.542612 -277.198909) (xy 336.542126 -277.171658) (xy 336.542599 -277.14524) (xy 336.549883 -277.09291)
			(xy 336.564319 -277.042086) (xy 336.585632 -276.99374) (xy 336.613413 -276.948798) (xy 336.647131 -276.908121)
			(xy 336.666332 -276.889972) (xy 336.675222 -276.881844) (xy 336.683858 -276.859746) (xy 336.675222 -276.767036)
			(xy 336.673535 -276.755408) (xy 336.661222 -276.735426) (xy 336.6516 -276.728682) (xy 336.651346 -276.728428)
			(xy 336.62973 -276.71459) (xy 336.590072 -276.682011) (xy 336.555155 -276.644394) (xy 336.525613 -276.602425)
			(xy 336.513424 -276.579838) (xy 336.507836 -276.56917) (xy 336.488786 -276.5552) (xy 336.396584 -276.539706)
			(xy 336.38488 -276.538458) (xy 336.362394 -276.545319) (xy 336.353404 -276.552914) (xy 336.35315 -276.553168)
			(xy 336.334296 -276.57061) (xy 336.292756 -276.600817) (xy 336.270346 -276.613366) (xy 336.258408 -276.619716)
			(xy 336.244184 -276.642068) (xy 336.238342 -276.755606) (xy 336.25028 -276.779482) (xy 336.261202 -276.786848)
			(xy 336.282944 -276.802182) (xy 336.322426 -276.83784) (xy 336.356574 -276.878636) (xy 336.384724 -276.923779)
			(xy 336.406331 -276.972394) (xy 336.420976 -277.02354) (xy 336.428376 -277.076224) (xy 336.428842 -277.102824)
			(xy 336.428291 -277.13174) (xy 336.419572 -277.188911) (xy 336.402322 -277.24411) (xy 336.376936 -277.296072)
			(xy 336.343997 -277.343607) (xy 336.30426 -277.385624) (xy 336.281776 -277.403814) (xy 336.272968 -277.411421)
			(xy 336.262786 -277.432322) (xy 336.262218 -277.443946) (xy 336.262218 -277.523702) (xy 336.262764 -277.535333)
			(xy 336.272947 -277.556243) (xy 336.281776 -277.563834) (xy 336.304271 -277.582012) (xy 336.344006 -277.624034)
			(xy 336.376945 -277.671571) (xy 336.402331 -277.723535) (xy 336.419585 -277.778735) (xy 336.42831 -277.835907)
			(xy 336.428842 -277.864824) (xy 336.428356 -277.892075) (xy 336.4206 -277.946023) (xy 336.405245 -277.998318)
			(xy 336.382603 -278.047895) (xy 336.353137 -278.093745) (xy 336.317446 -278.134936) (xy 336.276255 -278.170627)
			(xy 336.230405 -278.200093) (xy 336.180828 -278.222735) (xy 336.128533 -278.23809) (xy 336.074585 -278.245846)
			(xy 336.020083 -278.245846) (xy 335.966135 -278.23809) (xy 335.91384 -278.222735) (xy 335.864263 -278.200093)
			(xy 335.818413 -278.170627) (xy 335.777222 -278.134936) (xy 335.741531 -278.093745) (xy 335.712065 -278.047895)
			(xy 335.689423 -277.998318) (xy 335.674068 -277.946023) (xy 335.666312 -277.892075) (xy 335.665826 -277.864824)
			(xy 331.270356 -277.864824) (xy 331.270356 -282.904438) (xy 334.103218 -282.904438) (xy 334.103704 -282.876864)
			(xy 334.111651 -282.822292) (xy 334.127372 -282.769432) (xy 334.150538 -282.719386) (xy 334.180667 -282.673196)
			(xy 334.217132 -282.631824) (xy 334.237838 -282.613608) (xy 334.245916 -282.606056) (xy 334.255267 -282.586042)
			(xy 334.255872 -282.575) (xy 334.255872 -282.497276) (xy 334.255271 -282.486231) (xy 334.24593 -282.466209)
			(xy 334.237838 -282.458668) (xy 334.217116 -282.440469) (xy 334.180645 -282.399098) (xy 334.150513 -282.352906)
			(xy 334.127349 -282.302856) (xy 334.111635 -282.249991) (xy 334.1037 -282.195414) (xy 334.103218 -282.167838)
			(xy 334.103704 -282.140264) (xy 334.111651 -282.085692) (xy 334.127372 -282.032832) (xy 334.150538 -281.982786)
			(xy 334.180667 -281.936596) (xy 334.217132 -281.895224) (xy 334.237838 -281.877008) (xy 334.245916 -281.869456)
			(xy 334.255267 -281.849442) (xy 334.255872 -281.8384) (xy 334.255872 -281.760676) (xy 334.255271 -281.749631)
			(xy 334.24593 -281.729609) (xy 334.237838 -281.722068) (xy 334.217116 -281.703869) (xy 334.180645 -281.662498)
			(xy 334.150513 -281.616306) (xy 334.127349 -281.566256) (xy 334.111635 -281.513391) (xy 334.1037 -281.458814)
			(xy 334.103218 -281.431238) (xy 334.103691 -281.403985) (xy 334.111443 -281.350033) (xy 334.126796 -281.297734)
			(xy 334.149436 -281.248152) (xy 334.178902 -281.202297) (xy 334.214595 -281.161104) (xy 334.255788 -281.125409)
			(xy 334.301641 -281.095941) (xy 334.351222 -281.0733) (xy 334.403521 -281.057946) (xy 334.457473 -281.050192)
			(xy 334.484726 -281.04973) (xy 334.512583 -281.050207) (xy 334.567702 -281.058335) (xy 334.621054 -281.074386)
			(xy 334.671509 -281.098018) (xy 334.717994 -281.128731) (xy 334.759523 -281.165872) (xy 334.795215 -281.208653)
			(xy 334.824311 -281.256166) (xy 334.846196 -281.307402) (xy 334.853788 -281.33421) (xy 334.856074 -281.3431)
			(xy 334.866742 -281.35834) (xy 334.938624 -281.406092) (xy 334.956658 -281.410156) (xy 334.965802 -281.408886)
			(xy 334.978819 -281.407219) (xy 335.005003 -281.405438) (xy 335.018126 -281.40533) (xy 335.031249 -281.405426)
			(xy 335.057435 -281.407203) (xy 335.07045 -281.408886) (xy 335.079594 -281.410156) (xy 335.097628 -281.406092)
			(xy 335.16951 -281.35834) (xy 335.180178 -281.3431) (xy 335.182464 -281.33421) (xy 335.189975 -281.307375)
			(xy 335.211845 -281.25612) (xy 335.240938 -281.208592) (xy 335.276635 -281.165801) (xy 335.318177 -281.128657)
			(xy 335.36468 -281.097952) (xy 335.415154 -281.074337) (xy 335.468527 -281.058315) (xy 335.523663 -281.050228)
			(xy 335.551526 -281.04973) (xy 335.578781 -281.050131) (xy 335.632736 -281.057892) (xy 335.685038 -281.073254)
			(xy 335.734621 -281.095902) (xy 335.780476 -281.125376) (xy 335.821669 -281.161076) (xy 335.857362 -281.202276)
			(xy 335.886829 -281.248136) (xy 335.909469 -281.297722) (xy 335.924821 -281.350026) (xy 335.932574 -281.403983)
			(xy 335.933034 -281.431238) (xy 335.932564 -281.458537) (xy 335.924788 -281.512579) (xy 335.909386 -281.564959)
			(xy 335.886672 -281.614609) (xy 335.857111 -281.660512) (xy 335.839562 -281.681428) (xy 335.833212 -281.688794)
			(xy 335.826862 -281.706574) (xy 335.830164 -281.795728) (xy 335.838038 -281.813508) (xy 335.844896 -281.820112)
			(xy 335.866027 -281.841742) (xy 335.901827 -281.89047) (xy 335.929491 -281.944237) (xy 335.948326 -282.001695)
			(xy 335.957859 -282.061405) (xy 335.958434 -282.091638) (xy 335.957939 -282.119276) (xy 335.949947 -282.173971)
			(xy 335.934149 -282.226942) (xy 335.910877 -282.277081) (xy 335.880617 -282.323339) (xy 335.862676 -282.344368)
			(xy 335.854294 -282.353766) (xy 335.848452 -282.37815) (xy 335.872582 -282.47213) (xy 335.876286 -282.484074)
			(xy 335.893061 -282.502583) (xy 335.904586 -282.507436) (xy 335.931994 -282.517774) (xy 335.983509 -282.545656)
			(xy 336.030154 -282.581087) (xy 336.070833 -282.623236) (xy 336.104587 -282.671109) (xy 336.130623 -282.72358)
			(xy 336.148329 -282.779417) (xy 336.157288 -282.837304) (xy 336.157824 -282.866592) (xy 336.15729 -282.893854)
			(xy 336.487447 -282.893854) (xy 336.487447 -282.839346) (xy 336.495205 -282.785392) (xy 336.510562 -282.733092)
			(xy 336.533206 -282.68351) (xy 336.562676 -282.637655) (xy 336.598372 -282.596461) (xy 336.639568 -282.560767)
			(xy 336.685424 -282.531299) (xy 336.735007 -282.508657) (xy 336.787308 -282.493302) (xy 336.841262 -282.485546)
			(xy 336.868516 -282.485084) (xy 336.895888 -282.48552) (xy 336.950069 -282.493342) (xy 337.002573 -282.508837)
			(xy 337.052319 -282.531686) (xy 337.098284 -282.561419) (xy 337.119214 -282.579064) (xy 337.119468 -282.579318)
			(xy 337.126558 -282.584899) (xy 337.143472 -282.591149) (xy 337.152488 -282.59151) (xy 337.219544 -282.59151)
			(xy 337.228558 -282.591124) (xy 337.245475 -282.584896) (xy 337.252564 -282.579318) (xy 337.252564 -282.579064)
			(xy 337.252818 -282.579064) (xy 337.273766 -282.561444) (xy 337.319735 -282.531731) (xy 337.369478 -282.508892)
			(xy 337.421975 -282.493396) (xy 337.476148 -282.485562) (xy 337.503516 -282.485084) (xy 337.530766 -282.485587)
			(xy 337.584711 -282.493345) (xy 337.637003 -282.508701) (xy 337.686577 -282.531343) (xy 337.732424 -282.560809)
			(xy 337.773612 -282.5965) (xy 337.809301 -282.637689) (xy 337.838765 -282.683537) (xy 337.861404 -282.733112)
			(xy 337.876758 -282.785405) (xy 337.884514 -282.83935) (xy 337.884514 -282.89385) (xy 337.876758 -282.947795)
			(xy 337.861404 -283.000088) (xy 337.838765 -283.049663) (xy 337.809301 -283.095511) (xy 337.773612 -283.1367)
			(xy 337.732424 -283.172391) (xy 337.686577 -283.201857) (xy 337.637003 -283.224499) (xy 337.584711 -283.239855)
			(xy 337.530766 -283.247613) (xy 337.503516 -283.2481) (xy 337.476146 -283.247625) (xy 337.421967 -283.239809)
			(xy 337.369464 -283.224322) (xy 337.319717 -283.201482) (xy 337.27375 -283.17176) (xy 337.252818 -283.15412)
			(xy 337.252564 -283.153866) (xy 337.245466 -283.148296) (xy 337.228558 -283.142041) (xy 337.219544 -283.141674)
			(xy 337.152488 -283.141674) (xy 337.143471 -283.142031) (xy 337.126555 -283.148279) (xy 337.119468 -283.153866)
			(xy 337.119468 -283.15412) (xy 337.119214 -283.15412) (xy 337.09829 -283.171769) (xy 337.052315 -283.201479)
			(xy 337.002565 -283.224312) (xy 336.950063 -283.239801) (xy 336.895886 -283.247627) (xy 336.868516 -283.2481)
			(xy 336.841262 -283.247654) (xy 336.787308 -283.239898) (xy 336.735007 -283.224543) (xy 336.685424 -283.201901)
			(xy 336.639568 -283.172433) (xy 336.598372 -283.136739) (xy 336.562676 -283.095545) (xy 336.533206 -283.04969)
			(xy 336.510562 -283.000108) (xy 336.495205 -282.947808) (xy 336.487447 -282.893854) (xy 336.15729 -282.893854)
			(xy 336.157239 -282.89643) (xy 336.14793 -282.955376) (xy 336.139282 -282.98394) (xy 336.13598 -282.994354)
			(xy 336.138266 -283.015944) (xy 336.188558 -283.100526) (xy 336.20583 -283.112972) (xy 336.216752 -283.115004)
			(xy 336.242567 -283.120354) (xy 336.292483 -283.137321) (xy 336.339587 -283.161) (xy 336.382982 -283.190939)
			(xy 336.421841 -283.226569) (xy 336.455423 -283.267211) (xy 336.483088 -283.31209) (xy 336.50431 -283.36035)
			(xy 336.518685 -283.411074) (xy 336.525937 -283.463294) (xy 336.526378 -283.489654) (xy 336.52577 -283.519776)
			(xy 336.516297 -283.57927) (xy 336.497594 -283.636537) (xy 336.470127 -283.690155) (xy 336.434577 -283.738792)
			(xy 336.413602 -283.760418) (xy 336.406762 -283.767818) (xy 336.399042 -283.786417) (xy 336.398616 -283.796486)
			(xy 336.398616 -283.868622) (xy 336.399026 -283.878693) (xy 336.406757 -283.897291) (xy 336.413602 -283.90469)
			(xy 336.434603 -283.926296) (xy 336.470168 -283.97493) (xy 336.497645 -284.028551) (xy 336.516348 -284.085826)
			(xy 336.525813 -284.145328) (xy 336.526378 -284.175454) (xy 336.525892 -284.202705) (xy 336.518136 -284.256653)
			(xy 336.502781 -284.308948) (xy 336.480139 -284.358525) (xy 336.450673 -284.404375) (xy 336.414982 -284.445566)
			(xy 336.373791 -284.481257) (xy 336.327941 -284.510723) (xy 336.278364 -284.533365) (xy 336.226069 -284.54872)
			(xy 336.172121 -284.556476) (xy 336.117619 -284.556476) (xy 336.063671 -284.54872) (xy 336.011376 -284.533365)
			(xy 335.961799 -284.510723) (xy 335.915949 -284.481257) (xy 335.874758 -284.445566) (xy 335.839067 -284.404375)
			(xy 335.809601 -284.358525) (xy 335.786959 -284.308948) (xy 335.771604 -284.256653) (xy 335.763848 -284.202705)
			(xy 335.763362 -284.175454) (xy 335.763964 -284.145332) (xy 335.773437 -284.085837) (xy 335.79214 -284.028569)
			(xy 335.819609 -283.974951) (xy 335.855162 -283.926316) (xy 335.876138 -283.90469) (xy 335.88298 -283.897292)
			(xy 335.890698 -283.878691) (xy 335.891124 -283.868622) (xy 335.891124 -283.796486) (xy 335.890726 -283.786413)
			(xy 335.882988 -283.767815) (xy 335.876138 -283.760418) (xy 335.855148 -283.738802) (xy 335.819579 -283.690172)
			(xy 335.7921 -283.636553) (xy 335.773395 -283.57928) (xy 335.763928 -283.519779) (xy 335.763362 -283.489654)
			(xy 335.763935 -283.459815) (xy 335.773252 -283.400869) (xy 335.781904 -283.372306) (xy 335.785206 -283.361892)
			(xy 335.78292 -283.340302) (xy 335.732628 -283.25572) (xy 335.715356 -283.243274) (xy 335.704434 -283.241242)
			(xy 335.676582 -283.235401) (xy 335.622919 -283.216462) (xy 335.572662 -283.189766) (xy 335.526925 -283.155903)
			(xy 335.486724 -283.115625) (xy 335.452948 -283.069825) (xy 335.426347 -283.019518) (xy 335.40751 -282.965818)
			(xy 335.401666 -282.937966) (xy 335.399126 -282.92552) (xy 335.383886 -282.906216) (xy 335.282794 -282.862528)
			(xy 335.258156 -282.864306) (xy 335.247488 -282.871164) (xy 335.224497 -282.885167) (xy 335.175431 -282.907306)
			(xy 335.123735 -282.922312) (xy 335.070441 -282.929886) (xy 335.043526 -282.930346) (xy 335.025506 -282.930131)
			(xy 334.989632 -282.926693) (xy 334.971898 -282.923488) (xy 334.962246 -282.92171) (xy 334.943196 -282.925266)
			(xy 334.868266 -282.973272) (xy 334.856836 -282.98902) (xy 334.85455 -282.998418) (xy 334.847165 -283.025466)
			(xy 334.825537 -283.077195) (xy 334.796572 -283.125203) (xy 334.760896 -283.168456) (xy 334.719275 -283.206023)
			(xy 334.672605 -283.237097) (xy 334.621891 -283.261008) (xy 334.568224 -283.277242) (xy 334.51276 -283.28545)
			(xy 334.484726 -283.285946) (xy 334.457477 -283.285398) (xy 334.403534 -283.277646) (xy 334.351242 -283.262296)
			(xy 334.301668 -283.23966) (xy 334.255819 -283.2102) (xy 334.21463 -283.174516) (xy 334.178938 -283.133332)
			(xy 334.14947 -283.087488) (xy 334.126827 -283.037918) (xy 334.111468 -282.985629) (xy 334.103707 -282.931687)
			(xy 334.103218 -282.904438) (xy 331.270356 -282.904438) (xy 331.270356 -283.289248) (xy 331.271372 -283.298646)
			(xy 331.271372 -283.299154) (xy 331.273072 -283.306316) (xy 331.279897 -283.31935) (xy 331.284834 -283.324808)
			(xy 331.774292 -283.814266) (xy 331.781129 -283.821668) (xy 331.78884 -283.840266) (xy 331.789278 -283.850334)
			(xy 331.789278 -286.42564) (xy 331.789647 -286.434746) (xy 331.796019 -286.451808) (xy 331.801724 -286.458914)
			(xy 331.807312 -286.465518) (xy 331.823314 -286.474408) (xy 331.832712 -286.475678) (xy 331.914605 -286.488012)
			(xy 332.07718 -286.519682) (xy 332.238008 -286.559279) (xy 332.396702 -286.606709) (xy 332.552882 -286.661856)
			(xy 332.706173 -286.72459) (xy 332.856206 -286.794759) (xy 333.00262 -286.872195) (xy 333.145065 -286.956712)
			(xy 333.283198 -287.048106) (xy 333.416686 -287.146158) (xy 333.545211 -287.250633) (xy 333.668462 -287.361279)
			(xy 333.786144 -287.477832) (xy 333.897974 -287.60001) (xy 334.003684 -287.727521) (xy 334.103019 -287.860058)
			(xy 334.195741 -287.997303) (xy 334.281627 -288.138925) (xy 334.360472 -288.284586) (xy 334.432085 -288.433935)
			(xy 334.496294 -288.586614) (xy 334.552946 -288.742255) (xy 334.601904 -288.900484) (xy 334.64305 -289.060923)
			(xy 334.676287 -289.223184) (xy 334.701533 -289.38688) (xy 334.718729 -289.551615) (xy 334.727832 -289.716996)
			(xy 334.728822 -289.882623) (xy 334.725772 -289.965384) (xy 334.721872 -290.044945) (xy 334.707513 -290.203608)
			(xy 334.685694 -290.361418) (xy 334.656463 -290.518025) (xy 334.619887 -290.673081) (xy 334.576045 -290.82624)
			(xy 334.525035 -290.977165) (xy 334.46697 -291.125517) (xy 334.40198 -291.27097) (xy 334.330209 -291.413198)
			(xy 334.291432 -291.48278) (xy 334.287114 -291.490654) (xy 334.287368 -291.517578) (xy 334.292194 -291.525706)
			(xy 334.339184 -291.60597) (xy 334.343984 -291.613106) (xy 334.35734 -291.623922) (xy 334.373519 -291.629722)
			(xy 334.38211 -291.6301) (xy 341.615268 -291.6301) (xy 341.621277 -291.629931) (xy 341.632957 -291.627103)
			(xy 341.638382 -291.624512) (xy 341.641858 -291.622675) (xy 341.648241 -291.618085) (xy 341.651082 -291.615368)
			(xy 341.77732 -291.48913) (xy 341.780025 -291.486278) (xy 341.784617 -291.479899) (xy 341.786464 -291.47643)
			(xy 341.789046 -291.471003) (xy 341.791866 -291.459323) (xy 341.792052 -291.453316) (xy 341.792052 -287.835594)
			(xy 341.791626 -287.825525) (xy 341.783905 -287.806927) (xy 341.777066 -287.799526) (xy 340.991698 -287.013904)
			(xy 340.971419 -286.992999) (xy 340.935946 -286.946807) (xy 340.906811 -286.896376) (xy 340.884513 -286.842572)
			(xy 340.869434 -286.786316) (xy 340.861832 -286.728573) (xy 340.861396 -286.699452) (xy 340.861875 -286.670329)
			(xy 340.86948 -286.61258) (xy 340.884556 -286.556318) (xy 340.906843 -286.502504) (xy 340.93596 -286.452057)
			(xy 340.971411 -286.40584) (xy 341.012588 -286.364644) (xy 341.058789 -286.329173) (xy 341.109222 -286.300032)
			(xy 341.163027 -286.277721) (xy 341.219282 -286.26262) (xy 341.277027 -286.254988) (xy 341.30615 -286.254444)
			(xy 341.33528 -286.254911) (xy 341.393038 -286.262542) (xy 341.449305 -286.277655) (xy 341.503114 -286.299989)
			(xy 341.553544 -286.329163) (xy 341.59973 -286.364675) (xy 341.620602 -286.385) (xy 341.644478 -286.408876)
			(xy 341.651921 -286.415572) (xy 341.670421 -286.423177) (xy 341.690422 -286.423169) (xy 341.69985 -286.419798)
			(xy 341.714074 -286.413956) (xy 341.731092 -286.388556) (xy 341.731092 -285.949898) (xy 341.730668 -285.939828)
			(xy 341.722952 -285.921225) (xy 341.716106 -285.91383) (xy 340.475824 -284.673548) (xy 340.453885 -284.650855)
			(xy 340.415479 -284.600763) (xy 340.383927 -284.546094) (xy 340.359767 -284.48778) (xy 340.343411 -284.426816)
			(xy 340.335138 -284.36424) (xy 340.3346 -284.33268) (xy 340.3346 -283.115766) (xy 340.335147 -283.084207)
			(xy 340.343433 -283.021635) (xy 340.359794 -282.960675) (xy 340.383952 -282.902362) (xy 340.415495 -282.847691)
			(xy 340.453887 -282.797592) (xy 340.475824 -282.774898) (xy 340.764114 -282.486862) (xy 340.772566 -282.477348)
			(xy 340.77974 -282.452964) (xy 340.77783 -282.44038) (xy 340.76005 -282.356814) (xy 340.757989 -282.348614)
			(xy 340.749288 -282.334126) (xy 340.736349 -282.323256) (xy 340.728554 -282.319984) (xy 340.7283 -282.319984)
			(xy 340.701562 -282.309254) (xy 340.651404 -282.280912) (xy 340.606077 -282.24535) (xy 340.566614 -282.203377)
			(xy 340.53391 -282.155947) (xy 340.508709 -282.10414) (xy 340.491585 -282.049131) (xy 340.482927 -281.992174)
			(xy 340.482428 -281.963368) (xy 340.482894 -281.936118) (xy 340.490654 -281.882172) (xy 340.506014 -281.82988)
			(xy 340.528658 -281.780306) (xy 340.558128 -281.73446) (xy 340.593822 -281.693274) (xy 340.635014 -281.657587)
			(xy 340.680866 -281.628126) (xy 340.730444 -281.60549) (xy 340.782739 -281.59014) (xy 340.836685 -281.582389)
			(xy 340.863936 -281.58186) (xy 340.89274 -281.582388) (xy 340.949693 -281.591052) (xy 341.004697 -281.608177)
			(xy 341.056503 -281.633375) (xy 341.103932 -281.666073) (xy 341.145909 -281.705529) (xy 341.181478 -281.750845)
			(xy 341.209832 -281.800992) (xy 341.220552 -281.827732) (xy 341.220552 -281.827986) (xy 341.225758 -281.839612)
			(xy 341.245087 -281.856154) (xy 341.257382 -281.859482) (xy 341.340694 -281.877262) (xy 341.349059 -281.87878)
			(xy 341.365932 -281.876782) (xy 341.381204 -281.869336) (xy 341.38743 -281.863546) (xy 341.511636 -281.73934)
			(xy 341.518416 -281.731916) (xy 341.526019 -281.71332) (xy 341.526368 -281.703272) (xy 341.526368 -281.482546)
			(xy 341.525874 -281.472733) (xy 341.518434 -281.454568) (xy 341.51189 -281.44724) (xy 341.455502 -281.389328)
			(xy 341.437468 -281.381454) (xy 341.427562 -281.3812) (xy 341.400761 -281.380073) (xy 341.347852 -281.371232)
			(xy 341.296704 -281.355064) (xy 341.248325 -281.331889) (xy 341.203672 -281.302164) (xy 341.163623 -281.266476)
			(xy 341.12897 -281.225529) (xy 341.100396 -281.18013) (xy 341.078465 -281.131175) (xy 341.063609 -281.079631)
			(xy 341.056122 -281.026514) (xy 341.055706 -280.999692) (xy 341.05617 -280.97244) (xy 341.063928 -280.918491)
			(xy 341.079285 -280.866195) (xy 341.101928 -280.816616) (xy 341.131396 -280.770765) (xy 341.16709 -280.729575)
			(xy 341.208283 -280.693883) (xy 341.254136 -280.664417) (xy 341.303715 -280.641777) (xy 341.356012 -280.626423)
			(xy 341.409962 -280.618668) (xy 341.437214 -280.618184) (xy 341.467201 -280.618743) (xy 341.526436 -280.628132)
			(xy 341.583472 -280.646674) (xy 341.636902 -280.673915) (xy 341.661496 -280.691082) (xy 341.666322 -280.694638)
			(xy 341.67191 -280.696924) (xy 341.681359 -280.700331) (xy 341.701423 -280.700374) (xy 341.719977 -280.692739)
			(xy 341.7342 -280.678586) (xy 341.738458 -280.669492) (xy 341.752682 -280.634694) (xy 341.765246 -280.605633)
			(xy 341.796848 -280.550769) (xy 341.835336 -280.500497) (xy 341.85733 -280.477722) (xy 342.066372 -280.26868)
			(xy 342.089066 -280.246743) (xy 342.13916 -280.208343) (xy 342.19383 -280.176797) (xy 342.252143 -280.152641)
			(xy 342.313107 -280.13629) (xy 342.375681 -280.12802) (xy 342.40724 -280.127456) (xy 344.810588 -280.127456)
			(xy 344.842145 -280.128006) (xy 344.904715 -280.136298) (xy 344.965672 -280.152663) (xy 345.023981 -280.176824)
			(xy 345.078649 -280.208369) (xy 345.128746 -280.246761) (xy 345.151456 -280.26868) (xy 346.103448 -281.220926)
			(xy 346.110878 -281.227725) (xy 346.129492 -281.235375) (xy 346.149617 -281.235314) (xy 346.159074 -281.231848)
			(xy 346.245688 -281.195526) (xy 346.254814 -281.19127) (xy 346.268986 -281.176988) (xy 346.276555 -281.158346)
			(xy 346.27693 -281.148282) (xy 346.27693 -281.144218) (xy 346.276976 -281.133528) (xy 346.278122 -281.11218)
			(xy 346.279216 -281.101546) (xy 346.279766 -281.092189) (xy 346.274933 -281.074096) (xy 346.269818 -281.06624)
			(xy 346.229432 -281.010614) (xy 346.223615 -281.003314) (xy 346.207988 -280.993135) (xy 346.198952 -280.990802)
			(xy 346.198698 -280.990802) (xy 346.170404 -280.98442) (xy 346.116022 -280.964252) (xy 346.06532 -280.936085)
			(xy 346.019465 -280.90057) (xy 345.979514 -280.858523) (xy 345.946386 -280.810914) (xy 345.920846 -280.758839)
			(xy 345.903482 -280.703499) (xy 345.894693 -280.646168) (xy 345.894152 -280.617168) (xy 345.894638 -280.589917)
			(xy 345.902394 -280.535969) (xy 345.917749 -280.483674) (xy 345.940391 -280.434097) (xy 345.969857 -280.388247)
			(xy 346.005548 -280.347056) (xy 346.046739 -280.311365) (xy 346.092589 -280.281899) (xy 346.142166 -280.259257)
			(xy 346.194461 -280.243902) (xy 346.248409 -280.236146) (xy 346.302911 -280.236146) (xy 346.356859 -280.243902)
			(xy 346.409154 -280.259257) (xy 346.458731 -280.281899) (xy 346.504581 -280.311365) (xy 346.545772 -280.347056)
			(xy 346.581463 -280.388247) (xy 346.610929 -280.434097) (xy 346.633571 -280.483674) (xy 346.648926 -280.535969)
			(xy 346.656682 -280.589917) (xy 346.657168 -280.617168) (xy 346.657123 -280.627858) (xy 346.655977 -280.649206)
			(xy 346.654882 -280.65984) (xy 346.654329 -280.669197) (xy 346.659159 -280.687294) (xy 346.66428 -280.695146)
			(xy 346.704412 -280.750518) (xy 346.710318 -280.758023) (xy 346.72637 -280.768346) (xy 346.735654 -280.770584)
			(xy 346.736162 -280.770838) (xy 346.747268 -280.772461) (xy 346.769024 -280.767064) (xy 346.778072 -280.760424)
			(xy 346.839032 -280.71064) (xy 346.847428 -280.703023) (xy 346.857176 -280.682588) (xy 346.857828 -280.67127)
			(xy 346.857828 -280.308558) (xy 346.857398 -280.298491) (xy 346.849676 -280.279895) (xy 346.842842 -280.27249)
			(xy 346.22994 -279.659588) (xy 346.209156 -279.637975) (xy 346.173908 -279.589473) (xy 346.146678 -279.536054)
			(xy 346.128136 -279.479036) (xy 346.118739 -279.419819) (xy 346.11818 -279.38984) (xy 346.11818 -279.02408)
			(xy 346.117753 -279.014012) (xy 346.110031 -278.995415) (xy 346.103194 -278.988012) (xy 345.855036 -278.739854)
			(xy 345.847637 -278.733012) (xy 345.829038 -278.725292) (xy 345.818968 -278.724868) (xy 345.502484 -278.724868)
			(xy 345.492414 -278.725293) (xy 345.473811 -278.733008) (xy 345.466416 -278.739854) (xy 344.399108 -279.807162)
			(xy 344.377532 -279.827897) (xy 344.329115 -279.86306) (xy 344.275797 -279.89022) (xy 344.218887 -279.908711)
			(xy 344.159787 -279.918077) (xy 344.129868 -279.918668) (xy 341.87892 -279.918668) (xy 341.849003 -279.918063)
			(xy 341.789908 -279.90868) (xy 341.733002 -279.890188) (xy 341.67968 -279.86304) (xy 341.63125 -279.827901)
			(xy 341.60968 -279.807162) (xy 340.542372 -278.739854) (xy 340.534974 -278.733006) (xy 340.516376 -278.725274)
			(xy 340.506304 -278.724868) (xy 340.06663 -278.724868) (xy 340.056598 -278.725308) (xy 340.038025 -278.732883)
			(xy 340.030562 -278.7396) (xy 339.976206 -278.793956) (xy 339.969368 -278.801357) (xy 339.961653 -278.819955)
			(xy 339.96122 -278.830024) (xy 339.96122 -279.414732) (xy 339.961736 -279.426179) (xy 339.971641 -279.446818)
			(xy 339.98027 -279.454356) (xy 340.050882 -279.511252) (xy 340.073234 -279.516332) (xy 340.08441 -279.514046)
			(xy 340.104294 -279.510004) (xy 340.144639 -279.505679) (xy 340.164928 -279.50541) (xy 340.165436 -279.50541)
			(xy 340.192685 -279.505899) (xy 340.246628 -279.51366) (xy 340.298917 -279.529018) (xy 340.348489 -279.551661)
			(xy 340.394333 -279.581129) (xy 340.435518 -279.616821) (xy 340.471204 -279.65801) (xy 340.500665 -279.703859)
			(xy 340.523301 -279.753433) (xy 340.538652 -279.805725) (xy 340.546405 -279.859669) (xy 340.546944 -279.886918)
			(xy 340.546404 -279.915783) (xy 340.537687 -279.972852) (xy 340.520469 -280.027956) (xy 340.495145 -280.079835)
			(xy 340.462291 -280.127306) (xy 340.422659 -280.169284) (xy 340.377154 -280.204811) (xy 340.326815 -280.233074)
			(xy 340.272791 -280.253429) (xy 340.216317 -280.26541) (xy 340.187534 -280.267664) (xy 340.18728 -280.267664)
			(xy 340.176007 -280.269018) (xy 340.156221 -280.280093) (xy 340.14918 -280.289) (xy 340.096348 -280.363168)
			(xy 340.092538 -280.385774) (xy 340.095586 -280.39695) (xy 340.102356 -280.422451) (xy 340.109625 -280.474709)
			(xy 340.110064 -280.50109) (xy 340.109292 -280.535173) (xy 340.097161 -280.602251) (xy 340.085934 -280.63444)
			(xy 340.081616 -280.645616) (xy 340.08441 -280.669492) (xy 340.13521 -280.747978) (xy 340.142143 -280.757606)
			(xy 340.162547 -280.769657) (xy 340.174326 -280.771092) (xy 340.202942 -280.773516) (xy 340.259024 -280.785876)
			(xy 340.312619 -280.806503) (xy 340.362517 -280.83493) (xy 340.40759 -280.870517) (xy 340.446818 -280.912458)
			(xy 340.479316 -280.959805) (xy 340.50435 -281.011489) (xy 340.521353 -281.066342) (xy 340.529941 -281.123124)
			(xy 340.530434 -281.151838) (xy 340.529948 -281.179089) (xy 340.522192 -281.233037) (xy 340.506837 -281.285332)
			(xy 340.484195 -281.334909) (xy 340.454729 -281.380759) (xy 340.419038 -281.42195) (xy 340.377847 -281.457641)
			(xy 340.331997 -281.487107) (xy 340.28242 -281.509749) (xy 340.230125 -281.525104) (xy 340.176177 -281.53286)
			(xy 340.121675 -281.53286) (xy 340.067727 -281.525104) (xy 340.015432 -281.509749) (xy 339.965855 -281.487107)
			(xy 339.920005 -281.457641) (xy 339.878814 -281.42195) (xy 339.843123 -281.380759) (xy 339.813657 -281.334909)
			(xy 339.791015 -281.285332) (xy 339.77566 -281.233037) (xy 339.767904 -281.179089) (xy 339.767418 -281.151838)
			(xy 339.768196 -281.117757) (xy 339.780338 -281.050683) (xy 339.791548 -281.018488) (xy 339.795866 -281.007312)
			(xy 339.793072 -280.983436) (xy 339.742272 -280.90495) (xy 339.73534 -280.89532) (xy 339.714935 -280.88327)
			(xy 339.703156 -280.881836) (xy 339.671795 -280.8791) (xy 339.61052 -280.864684) (xy 339.581236 -280.853134)
			(xy 339.571103 -280.849367) (xy 339.549512 -280.849884) (xy 339.53958 -280.85415) (xy 339.471508 -280.886408)
			(xy 339.462022 -280.891442) (xy 339.448078 -280.90775) (xy 339.444584 -280.917904) (xy 339.436443 -280.943892)
			(xy 339.413814 -280.993427) (xy 339.384368 -281.039238) (xy 339.348705 -281.080395) (xy 339.307549 -281.11606)
			(xy 339.261739 -281.145507) (xy 339.212205 -281.168138) (xy 339.159955 -281.183492) (xy 339.106053 -281.191257)
			(xy 339.078824 -281.191716) (xy 339.055469 -281.191348) (xy 339.00911 -281.185616) (xy 338.986368 -281.180286)
			(xy 338.976721 -281.178304) (xy 338.957235 -281.181032) (xy 338.948522 -281.18562) (xy 338.878926 -281.225498)
			(xy 338.867242 -281.240738) (xy 338.864448 -281.25039) (xy 338.856394 -281.276514) (xy 338.833847 -281.326315)
			(xy 338.80442 -281.372386) (xy 338.768717 -281.413784) (xy 338.727469 -281.449661) (xy 338.681522 -281.47928)
			(xy 338.631816 -281.502036) (xy 338.57937 -281.517463) (xy 338.52526 -281.525243) (xy 338.497926 -281.525726)
			(xy 338.470671 -281.525265) (xy 338.416717 -281.517511) (xy 338.364415 -281.502157) (xy 338.31483 -281.479517)
			(xy 338.268972 -281.45005) (xy 338.227775 -281.414356) (xy 338.192077 -281.373163) (xy 338.162604 -281.327309)
			(xy 338.139958 -281.277727) (xy 338.124598 -281.225426) (xy 338.116838 -281.171473) (xy 338.116418 -281.144218)
			(xy 338.116464 -281.133528) (xy 338.11761 -281.11218) (xy 338.118704 -281.101546) (xy 338.119255 -281.092189)
			(xy 338.114428 -281.074091) (xy 338.109306 -281.06624) (xy 338.06892 -281.010614) (xy 338.063102 -281.003316)
			(xy 338.047474 -280.99314) (xy 338.03844 -280.990802) (xy 338.038186 -280.990802) (xy 338.009892 -280.984419)
			(xy 337.955513 -280.96425) (xy 337.904812 -280.936083) (xy 337.858958 -280.900567) (xy 337.819008 -280.85852)
			(xy 337.785882 -280.810911) (xy 337.760343 -280.758837) (xy 337.742979 -280.703498) (xy 337.734191 -280.646168)
			(xy 337.73364 -280.617168) (xy 337.734126 -280.589917) (xy 337.741882 -280.535969) (xy 337.757237 -280.483674)
			(xy 337.779879 -280.434097) (xy 337.809345 -280.388247) (xy 337.845036 -280.347056) (xy 337.886227 -280.311365)
			(xy 337.932077 -280.281899) (xy 337.981654 -280.259257) (xy 338.033949 -280.243902) (xy 338.087897 -280.236146)
			(xy 338.142399 -280.236146) (xy 338.196347 -280.243902) (xy 338.248642 -280.259257) (xy 338.298219 -280.281899)
			(xy 338.344069 -280.311365) (xy 338.38526 -280.347056) (xy 338.420951 -280.388247) (xy 338.450417 -280.434097)
			(xy 338.473059 -280.483674) (xy 338.488414 -280.535969) (xy 338.49617 -280.589917) (xy 338.496656 -280.617168)
			(xy 338.496611 -280.627858) (xy 338.495465 -280.649206) (xy 338.49437 -280.65984) (xy 338.493817 -280.669197)
			(xy 338.498646 -280.687294) (xy 338.503768 -280.695146) (xy 338.5439 -280.750518) (xy 338.549805 -280.758025)
			(xy 338.565857 -280.768351) (xy 338.575142 -280.770584) (xy 338.57565 -280.770838) (xy 338.586756 -280.772463)
			(xy 338.608517 -280.767071) (xy 338.61756 -280.760424) (xy 338.67852 -280.71064) (xy 338.686917 -280.703024)
			(xy 338.696668 -280.682589) (xy 338.697316 -280.67127) (xy 338.697316 -280.370026) (xy 338.69688 -280.359961)
			(xy 338.689148 -280.341375) (xy 338.68233 -280.333958) (xy 338.407756 -280.05913) (xy 338.400356 -280.052287)
			(xy 338.381758 -280.044564) (xy 338.371688 -280.044144) (xy 337.930998 -280.044144) (xy 337.901082 -280.043537)
			(xy 337.841989 -280.034151) (xy 337.785086 -280.015655) (xy 337.731768 -279.988504) (xy 337.683341 -279.953363)
			(xy 337.661758 -279.932638) (xy 337.358228 -279.629108) (xy 337.337449 -279.607493) (xy 337.302213 -279.558988)
			(xy 337.274995 -279.505569) (xy 337.256466 -279.448551) (xy 337.247081 -279.389337) (xy 337.246468 -279.35936)
			(xy 337.246468 -278.863552) (xy 337.247022 -278.83357) (xy 337.256399 -278.774345) (xy 337.274929 -278.717317)
			(xy 337.302156 -278.663891) (xy 337.337409 -278.615386) (xy 337.358228 -278.593804) (xy 339.176614 -276.775418)
			(xy 339.183457 -276.768019) (xy 339.191175 -276.74942) (xy 339.1916 -276.73935) (xy 339.1916 -268.59738)
			(xy 339.192152 -268.567398) (xy 339.201526 -268.508171) (xy 339.220054 -268.451141) (xy 339.24728 -268.397714)
			(xy 339.282534 -268.349207) (xy 339.30336 -268.327632) (xy 341.216996 -266.413996) (xy 341.238611 -266.393219)
			(xy 341.287118 -266.357986) (xy 341.340537 -266.330771) (xy 341.397555 -266.312244) (xy 341.456768 -266.30286)
			(xy 341.486744 -266.302236) (xy 343.5858 -266.302236) (xy 343.595869 -266.301811) (xy 343.614467 -266.29409)
			(xy 343.621868 -266.28725) (xy 346.049346 -263.859772) (xy 346.070961 -263.838993) (xy 346.119467 -263.803756)
			(xy 346.172885 -263.776536) (xy 346.229903 -263.758002) (xy 346.289117 -263.748612) (xy 346.319094 -263.748012)
			(xy 347.03131 -263.748012) (xy 347.058559 -263.748499) (xy 347.112503 -263.756256) (xy 347.164794 -263.771611)
			(xy 347.214367 -263.794252) (xy 347.260214 -263.823717) (xy 347.301401 -263.859406) (xy 347.337089 -263.900594)
			(xy 347.366553 -263.946442) (xy 347.389192 -263.996016) (xy 347.404546 -264.048307) (xy 347.412302 -264.102251)
			(xy 347.412302 -264.156749) (xy 347.404546 -264.210693) (xy 347.389192 -264.262984) (xy 347.366553 -264.312558)
			(xy 347.337089 -264.358406) (xy 347.301401 -264.399594) (xy 347.260214 -264.435283) (xy 347.214367 -264.464748)
			(xy 347.164794 -264.487389) (xy 347.112503 -264.502744) (xy 347.058559 -264.510501) (xy 347.03131 -264.511028)
			(xy 346.498164 -264.511028) (xy 346.488097 -264.511458) (xy 346.469505 -264.519185) (xy 346.462096 -264.526014)
			(xy 344.034618 -266.953492) (xy 344.013003 -266.97427) (xy 343.964497 -267.009507) (xy 343.911078 -267.036724)
			(xy 343.854061 -267.055254) (xy 343.794847 -267.06464) (xy 343.76487 -267.065252) (xy 341.665814 -267.065252)
			(xy 341.655752 -267.065692) (xy 341.637175 -267.073434) (xy 341.629746 -267.080238) (xy 339.969602 -268.740382)
			(xy 339.962768 -268.747785) (xy 339.955064 -268.766383) (xy 339.954616 -268.77645) (xy 339.954616 -276.051264)
			(xy 341.2617 -276.051264) (xy 341.262145 -276.023893) (xy 341.269968 -275.969713) (xy 341.285462 -275.91721)
			(xy 341.308308 -275.867463) (xy 341.338037 -275.821497) (xy 341.35568 -275.800566) (xy 341.355934 -275.800312)
			(xy 341.361525 -275.793229) (xy 341.367768 -275.776309) (xy 341.368126 -275.767292) (xy 341.368126 -275.700236)
			(xy 341.367746 -275.691222) (xy 341.361514 -275.674305) (xy 341.355934 -275.667216) (xy 341.35568 -275.667216)
			(xy 341.35568 -275.666962) (xy 341.338006 -275.646057) (xy 341.308286 -275.600083) (xy 341.285446 -275.550332)
			(xy 341.269954 -275.497826) (xy 341.26213 -275.443645) (xy 341.262134 -275.388901) (xy 341.269966 -275.334721)
			(xy 341.285465 -275.282217) (xy 341.308312 -275.232469) (xy 341.338039 -275.1865) (xy 341.35568 -275.165566)
			(xy 341.355934 -275.165312) (xy 341.361525 -275.158229) (xy 341.367768 -275.141309) (xy 341.368126 -275.132292)
			(xy 341.368126 -275.065236) (xy 341.367746 -275.056222) (xy 341.361514 -275.039305) (xy 341.355934 -275.032216)
			(xy 341.35568 -275.032216) (xy 341.35568 -275.031962) (xy 341.338053 -275.01102) (xy 341.30834 -274.96505)
			(xy 341.285502 -274.915305) (xy 341.270008 -274.862806) (xy 341.262176 -274.808632) (xy 341.2617 -274.781264)
			(xy 341.262144 -274.754011) (xy 341.269906 -274.700062) (xy 341.285266 -274.647766) (xy 341.307912 -274.598188)
			(xy 341.337383 -274.552337) (xy 341.373079 -274.511147) (xy 341.414273 -274.475456) (xy 341.460127 -274.445991)
			(xy 341.509707 -274.423351) (xy 341.562005 -274.407997) (xy 341.615955 -274.400241) (xy 341.643208 -274.399756)
			(xy 341.670579 -274.400204) (xy 341.724759 -274.408024) (xy 341.777263 -274.423516) (xy 341.82701 -274.446363)
			(xy 341.872975 -274.476092) (xy 341.893906 -274.493736) (xy 341.89416 -274.49399) (xy 341.901255 -274.499565)
			(xy 341.918165 -274.505819) (xy 341.92718 -274.506182) (xy 341.994236 -274.506182) (xy 342.003255 -274.505846)
			(xy 342.020172 -274.499584) (xy 342.027256 -274.49399) (xy 342.027256 -274.493736) (xy 342.02751 -274.493736)
			(xy 342.048432 -274.476084) (xy 342.094407 -274.446373) (xy 342.144157 -274.423539) (xy 342.19666 -274.408051)
			(xy 342.250838 -274.400227) (xy 342.278208 -274.399756) (xy 342.305458 -274.40027) (xy 342.359403 -274.408027)
			(xy 342.411695 -274.423381) (xy 342.46127 -274.446021) (xy 342.507118 -274.475484) (xy 342.548307 -274.511173)
			(xy 342.583999 -274.552359) (xy 342.613466 -274.598206) (xy 342.636109 -274.647779) (xy 342.651467 -274.70007)
			(xy 342.659228 -274.754014) (xy 342.659716 -274.781264) (xy 342.659249 -274.808634) (xy 342.651435 -274.862814)
			(xy 342.635947 -274.915318) (xy 342.613105 -274.965065) (xy 342.583379 -275.011031) (xy 342.565736 -275.031962)
			(xy 342.565482 -275.032216) (xy 342.559881 -275.039292) (xy 342.553643 -275.056217) (xy 342.55329 -275.065236)
			(xy 342.55329 -275.132292) (xy 342.553653 -275.141308) (xy 342.559897 -275.158225) (xy 342.565482 -275.165312)
			(xy 342.565736 -275.165312) (xy 342.565736 -275.165566) (xy 342.583343 -275.186527) (xy 342.613072 -275.232489)
			(xy 342.635922 -275.28223) (xy 342.651422 -275.334728) (xy 342.659255 -275.388904) (xy 342.659259 -275.443642)
			(xy 342.651434 -275.497819) (xy 342.635941 -275.550319) (xy 342.613098 -275.600064) (xy 342.583376 -275.64603)
			(xy 342.565736 -275.666962) (xy 342.565482 -275.667216) (xy 342.559881 -275.674292) (xy 342.553643 -275.691217)
			(xy 342.55329 -275.700236) (xy 342.55329 -275.767292) (xy 342.553653 -275.776308) (xy 342.559897 -275.793225)
			(xy 342.565482 -275.800312) (xy 342.565736 -275.800312) (xy 342.565736 -275.800566) (xy 342.583343 -275.821527)
			(xy 342.613072 -275.867489) (xy 342.635922 -275.91723) (xy 342.651422 -275.969728) (xy 342.659255 -276.023904)
			(xy 342.659259 -276.078642) (xy 342.651434 -276.132819) (xy 342.635941 -276.185319) (xy 342.613098 -276.235064)
			(xy 342.583376 -276.28103) (xy 342.565736 -276.301962) (xy 342.565482 -276.302216) (xy 342.559881 -276.309292)
			(xy 342.553643 -276.326217) (xy 342.55329 -276.335236) (xy 342.55329 -276.402292) (xy 342.553653 -276.411308)
			(xy 342.559897 -276.428225) (xy 342.565482 -276.435312) (xy 342.565736 -276.435312) (xy 342.565736 -276.43582)
			(xy 342.581886 -276.454875) (xy 342.609553 -276.496465) (xy 342.631554 -276.54131) (xy 342.639904 -276.564852)
			(xy 342.643714 -276.576282) (xy 342.660224 -276.593046) (xy 342.748108 -276.622764) (xy 342.759411 -276.62603)
			(xy 342.782715 -276.622965) (xy 342.792812 -276.616922) (xy 342.793066 -276.616668) (xy 342.816823 -276.601327)
			(xy 342.867881 -276.577017) (xy 342.921967 -276.560507) (xy 342.977897 -276.552158) (xy 343.006172 -276.551644)
			(xy 343.03342 -276.552204) (xy 343.087363 -276.559956) (xy 343.139653 -276.575305) (xy 343.189227 -276.597939)
			(xy 343.235075 -276.627398) (xy 343.276265 -276.663082) (xy 343.311956 -276.704264) (xy 343.341424 -276.750106)
			(xy 343.364069 -276.799675) (xy 343.379428 -276.851963) (xy 343.38719 -276.905904) (xy 343.38768 -276.933152)
			(xy 343.387254 -276.959467) (xy 343.380011 -277.011598) (xy 343.365685 -277.062242) (xy 343.344544 -277.110441)
			(xy 343.316991 -277.155283) (xy 343.283545 -277.195921) (xy 343.26449 -277.214076) (xy 343.257095 -277.221603)
			(xy 343.248567 -277.240879) (xy 343.24798 -277.251414) (xy 343.24798 -277.32609) (xy 343.248507 -277.33664)
			(xy 343.257044 -277.355935) (xy 343.26449 -277.363428) (xy 343.28355 -277.381579) (xy 343.317007 -277.422209)
			(xy 343.344566 -277.467051) (xy 343.365704 -277.515252) (xy 343.38002 -277.565901) (xy 343.387243 -277.618036)
			(xy 343.38768 -277.644352) (xy 343.3872 -277.671605) (xy 343.379449 -277.725557) (xy 343.364097 -277.777856)
			(xy 343.341458 -277.827438) (xy 343.311993 -277.873293) (xy 343.276301 -277.914486) (xy 343.235109 -277.950181)
			(xy 343.189255 -277.979649) (xy 343.139675 -278.00229) (xy 343.087376 -278.017645) (xy 343.033425 -278.025399)
			(xy 343.006172 -278.02586) (xy 342.979701 -278.025468) (xy 342.927265 -278.01817) (xy 342.876343 -278.00369)
			(xy 342.827912 -277.982306) (xy 342.782904 -277.95443) (xy 342.742184 -277.920597) (xy 342.706535 -277.881457)
			(xy 342.676641 -277.837764) (xy 342.653077 -277.790356) (xy 342.636297 -277.740144) (xy 342.631014 -277.714202)
			(xy 342.628728 -277.701756) (xy 342.613488 -277.682452) (xy 342.513666 -277.638002) (xy 342.488774 -277.63978)
			(xy 342.478106 -277.646384) (xy 342.455508 -277.659731) (xy 342.40744 -277.680798) (xy 342.356939 -277.695082)
			(xy 342.304957 -277.702314) (xy 342.278716 -277.702772) (xy 342.278208 -277.702772) (xy 342.250954 -277.702337)
			(xy 342.197 -277.69458) (xy 342.144699 -277.679223) (xy 342.095117 -277.656579) (xy 342.049262 -277.627109)
			(xy 342.008068 -277.591412) (xy 341.972374 -277.550216) (xy 341.942907 -277.504359) (xy 341.920267 -277.454774)
			(xy 341.904914 -277.402473) (xy 341.897161 -277.348518) (xy 341.8967 -277.321264) (xy 341.897145 -277.293893)
			(xy 341.904968 -277.239713) (xy 341.920462 -277.18721) (xy 341.943308 -277.137463) (xy 341.973037 -277.091497)
			(xy 341.99068 -277.070566) (xy 341.990934 -277.070312) (xy 341.996525 -277.063229) (xy 342.002768 -277.046309)
			(xy 342.003126 -277.037292) (xy 342.003126 -276.970236) (xy 342.002746 -276.961222) (xy 341.996514 -276.944305)
			(xy 341.990934 -276.937216) (xy 341.99068 -276.937216) (xy 341.99068 -276.936962) (xy 341.973053 -276.91602)
			(xy 341.94334 -276.87005) (xy 341.920502 -276.820305) (xy 341.905008 -276.767806) (xy 341.897176 -276.713632)
			(xy 341.8967 -276.686264) (xy 341.89728 -276.656788) (xy 341.906339 -276.598537) (xy 341.924252 -276.542372)
			(xy 341.950593 -276.489632) (xy 341.984733 -276.441573) (xy 342.004904 -276.420072) (xy 342.011444 -276.412742)
			(xy 342.018886 -276.394578) (xy 342.019382 -276.384766) (xy 342.019382 -276.331426) (xy 342.012016 -276.324568)
			(xy 342.004674 -276.318043) (xy 341.986519 -276.310593) (xy 341.97671 -276.31009) (xy 341.944706 -276.31009)
			(xy 341.934893 -276.310591) (xy 341.916729 -276.318026) (xy 341.9094 -276.324568) (xy 341.887903 -276.344744)
			(xy 341.839843 -276.378888) (xy 341.787102 -276.405234) (xy 341.730938 -276.423154) (xy 341.672685 -276.432223)
			(xy 341.643208 -276.432772) (xy 341.615954 -276.432337) (xy 341.562 -276.42458) (xy 341.509699 -276.409223)
			(xy 341.460117 -276.386579) (xy 341.414262 -276.357109) (xy 341.373068 -276.321412) (xy 341.337374 -276.280216)
			(xy 341.307907 -276.234359) (xy 341.285267 -276.184774) (xy 341.269914 -276.132473) (xy 341.262161 -276.078518)
			(xy 341.2617 -276.051264) (xy 339.954616 -276.051264) (xy 339.954616 -276.91842) (xy 339.954064 -276.948402)
			(xy 339.944691 -277.00763) (xy 339.926163 -277.06466) (xy 339.898938 -277.118088) (xy 339.863686 -277.166596)
			(xy 339.842856 -277.188168) (xy 338.02447 -279.006554) (xy 338.017624 -279.013952) (xy 338.009898 -279.032551)
			(xy 338.009484 -279.042622) (xy 338.009484 -279.18029) (xy 338.009929 -279.19032) (xy 338.017511 -279.208887)
			(xy 338.024216 -279.216358) (xy 338.074508 -279.26665) (xy 338.081904 -279.273501) (xy 338.100503 -279.28124)
			(xy 338.110576 -279.281636) (xy 338.551266 -279.281636) (xy 338.581184 -279.28224) (xy 338.640279 -279.291621)
			(xy 338.697187 -279.310112) (xy 338.75051 -279.337259) (xy 338.798942 -279.372397) (xy 338.820506 -279.393142)
			(xy 339.04301 -279.615646) (xy 339.05034 -279.622466) (xy 339.068784 -279.630219) (xy 339.088791 -279.630304)
			(xy 339.1073 -279.622708) (xy 339.114638 -279.6159) (xy 339.183726 -279.546812) (xy 339.190582 -279.539418)
			(xy 339.198333 -279.520819) (xy 339.198712 -279.510744) (xy 339.198712 -278.650446) (xy 339.199322 -278.620531)
			(xy 339.208715 -278.561442) (xy 339.227215 -278.504543) (xy 339.254369 -278.451228) (xy 339.289511 -278.402805)
			(xy 339.310218 -278.381206) (xy 339.617812 -278.073612) (xy 339.639425 -278.052829) (xy 339.687929 -278.017584)
			(xy 339.741347 -277.990356) (xy 339.798366 -277.971816) (xy 339.857582 -277.962419) (xy 339.88756 -277.961852)
			(xy 340.685374 -277.961852) (xy 340.715355 -277.962408) (xy 340.774579 -277.971788) (xy 340.831605 -277.99032)
			(xy 340.885028 -278.017549) (xy 340.933532 -278.052803) (xy 340.955122 -278.073612) (xy 342.02243 -279.141174)
			(xy 342.029829 -279.148019) (xy 342.048427 -279.155746) (xy 342.058498 -279.15616) (xy 343.95029 -279.15616)
			(xy 343.96036 -279.155737) (xy 343.978963 -279.148021) (xy 343.986358 -279.141174) (xy 345.053666 -278.073612)
			(xy 345.07528 -278.052832) (xy 345.123786 -278.017594) (xy 345.177204 -277.990374) (xy 345.234222 -277.971841)
			(xy 345.293437 -277.962453) (xy 345.323414 -277.961852) (xy 345.998038 -277.961852) (xy 346.02802 -277.962405)
			(xy 346.087247 -277.97178) (xy 346.144276 -277.990309) (xy 346.197704 -278.017534) (xy 346.246211 -278.052785)
			(xy 346.267786 -278.073612) (xy 346.719652 -278.525478) (xy 349.772732 -278.525478) (xy 349.772732 -263.787636)
			(xy 349.773218 -263.760403) (xy 349.780969 -263.706491) (xy 349.796314 -263.654231) (xy 349.81894 -263.604687)
			(xy 349.848387 -263.558867) (xy 349.884054 -263.517704) (xy 349.925217 -263.482037) (xy 349.971037 -263.45259)
			(xy 350.020581 -263.429964) (xy 350.072841 -263.414619) (xy 350.126753 -263.406868) (xy 350.181219 -263.406868)
			(xy 350.235131 -263.414619) (xy 350.287391 -263.429964) (xy 350.336935 -263.45259) (xy 350.382755 -263.482037)
			(xy 350.423918 -263.517704) (xy 350.459585 -263.558867) (xy 350.489032 -263.604687) (xy 350.511658 -263.654231)
			(xy 350.527003 -263.706491) (xy 350.534754 -263.760403) (xy 350.53524 -263.787636) (xy 350.53524 -263.82091)
			(xy 351.643948 -263.82091) (xy 351.648019 -263.765288) (xy 351.660145 -263.710851) (xy 351.680068 -263.65876)
			(xy 351.707364 -263.610125) (xy 351.74145 -263.565982) (xy 351.781599 -263.527273) (xy 351.826957 -263.494822)
			(xy 351.876557 -263.469321) (xy 351.929341 -263.451314) (xy 351.984184 -263.441184) (xy 352.039918 -263.439147)
			(xy 352.095355 -263.445247) (xy 352.149312 -263.459353) (xy 352.200641 -263.481165) (xy 352.248247 -263.510219)
			(xy 352.291115 -263.545894) (xy 352.328332 -263.587431) (xy 352.359105 -263.633944) (xy 352.382777 -263.684441)
			(xy 352.398845 -263.737848) (xy 352.406965 -263.793024) (xy 352.407474 -263.82091) (xy 352.406965 -263.848796)
			(xy 352.398845 -263.903972) (xy 352.382777 -263.957379) (xy 352.359105 -264.007876) (xy 352.328332 -264.054389)
			(xy 352.291115 -264.095926) (xy 352.281574 -264.103866) (xy 355.18039 -264.103866) (xy 355.184461 -264.048244)
			(xy 355.196587 -263.993807) (xy 355.21651 -263.941716) (xy 355.243806 -263.893081) (xy 355.277892 -263.848938)
			(xy 355.318041 -263.810229) (xy 355.363399 -263.777778) (xy 355.412999 -263.752277) (xy 355.465783 -263.73427)
			(xy 355.520626 -263.72414) (xy 355.57636 -263.722103) (xy 355.631797 -263.728203) (xy 355.685754 -263.742309)
			(xy 355.737083 -263.764121) (xy 355.784689 -263.793175) (xy 355.827557 -263.82885) (xy 355.864774 -263.870387)
			(xy 355.895547 -263.9169) (xy 355.919219 -263.967397) (xy 355.935287 -264.020804) (xy 355.943407 -264.07598)
			(xy 355.943916 -264.103866) (xy 355.943407 -264.131752) (xy 355.935287 -264.186928) (xy 355.919219 -264.240335)
			(xy 355.895547 -264.290832) (xy 355.864774 -264.337345) (xy 355.837512 -264.367772) (xy 386.190488 -264.367772)
			(xy 386.194559 -264.31215) (xy 386.206685 -264.257713) (xy 386.226608 -264.205622) (xy 386.253904 -264.156987)
			(xy 386.28799 -264.112844) (xy 386.328139 -264.074135) (xy 386.373497 -264.041684) (xy 386.423097 -264.016183)
			(xy 386.475881 -263.998176) (xy 386.530724 -263.988046) (xy 386.586458 -263.986009) (xy 386.641895 -263.992109)
			(xy 386.695852 -264.006215) (xy 386.747181 -264.028027) (xy 386.794787 -264.057081) (xy 386.837655 -264.092756)
			(xy 386.874872 -264.134293) (xy 386.905645 -264.180806) (xy 386.929317 -264.231303) (xy 386.945385 -264.28471)
			(xy 386.953505 -264.339886) (xy 386.954014 -264.367772) (xy 386.953505 -264.395658) (xy 386.945385 -264.450834)
			(xy 386.929317 -264.504241) (xy 386.905645 -264.554738) (xy 386.874872 -264.601251) (xy 386.853299 -264.625328)
			(xy 388.763 -264.625328) (xy 388.767071 -264.569706) (xy 388.779197 -264.515269) (xy 388.79912 -264.463178)
			(xy 388.826416 -264.414543) (xy 388.860502 -264.3704) (xy 388.900651 -264.331691) (xy 388.946009 -264.29924)
			(xy 388.995609 -264.273739) (xy 389.048393 -264.255732) (xy 389.103236 -264.245602) (xy 389.15897 -264.243565)
			(xy 389.214407 -264.249665) (xy 389.268364 -264.263771) (xy 389.319693 -264.285583) (xy 389.367299 -264.314637)
			(xy 389.410167 -264.350312) (xy 389.447384 -264.391849) (xy 389.478157 -264.438362) (xy 389.501829 -264.488859)
			(xy 389.517897 -264.542266) (xy 389.526017 -264.597442) (xy 389.526526 -264.625328) (xy 389.526017 -264.653214)
			(xy 389.517897 -264.70839) (xy 389.501829 -264.761797) (xy 389.478157 -264.812294) (xy 389.447384 -264.858807)
			(xy 389.410167 -264.900344) (xy 389.367299 -264.936019) (xy 389.319693 -264.965073) (xy 389.268364 -264.986885)
			(xy 389.214407 -265.000991) (xy 389.15897 -265.007091) (xy 389.103236 -265.005054) (xy 389.048393 -264.994924)
			(xy 388.995609 -264.976917) (xy 388.946009 -264.951416) (xy 388.900651 -264.918965) (xy 388.860502 -264.880256)
			(xy 388.826416 -264.836113) (xy 388.79912 -264.787478) (xy 388.779197 -264.735387) (xy 388.767071 -264.68095)
			(xy 388.763 -264.625328) (xy 386.853299 -264.625328) (xy 386.837655 -264.642788) (xy 386.794787 -264.678463)
			(xy 386.747181 -264.707517) (xy 386.695852 -264.729329) (xy 386.641895 -264.743435) (xy 386.586458 -264.749535)
			(xy 386.530724 -264.747498) (xy 386.475881 -264.737368) (xy 386.423097 -264.719361) (xy 386.373497 -264.69386)
			(xy 386.328139 -264.661409) (xy 386.28799 -264.6227) (xy 386.253904 -264.578557) (xy 386.226608 -264.529922)
			(xy 386.206685 -264.477831) (xy 386.194559 -264.423394) (xy 386.190488 -264.367772) (xy 355.837512 -264.367772)
			(xy 355.827557 -264.378882) (xy 355.784689 -264.414557) (xy 355.737083 -264.443611) (xy 355.685754 -264.465423)
			(xy 355.631797 -264.479529) (xy 355.57636 -264.485629) (xy 355.520626 -264.483592) (xy 355.465783 -264.473462)
			(xy 355.412999 -264.455455) (xy 355.363399 -264.429954) (xy 355.318041 -264.397503) (xy 355.277892 -264.358794)
			(xy 355.243806 -264.314651) (xy 355.21651 -264.266016) (xy 355.196587 -264.213925) (xy 355.184461 -264.159488)
			(xy 355.18039 -264.103866) (xy 352.281574 -264.103866) (xy 352.248247 -264.131601) (xy 352.200641 -264.160655)
			(xy 352.149312 -264.182467) (xy 352.095355 -264.196573) (xy 352.039918 -264.202673) (xy 351.984184 -264.200636)
			(xy 351.929341 -264.190506) (xy 351.876557 -264.172499) (xy 351.826957 -264.146998) (xy 351.781599 -264.114547)
			(xy 351.74145 -264.075838) (xy 351.707364 -264.031695) (xy 351.680068 -263.98306) (xy 351.660145 -263.930969)
			(xy 351.648019 -263.876532) (xy 351.643948 -263.82091) (xy 350.53524 -263.82091) (xy 350.53524 -264.93597)
			(xy 352.61753 -264.93597) (xy 352.621601 -264.880348) (xy 352.633727 -264.825911) (xy 352.65365 -264.77382)
			(xy 352.680946 -264.725185) (xy 352.715032 -264.681042) (xy 352.755181 -264.642333) (xy 352.800539 -264.609882)
			(xy 352.850139 -264.584381) (xy 352.902923 -264.566374) (xy 352.957766 -264.556244) (xy 353.0135 -264.554207)
			(xy 353.068937 -264.560307) (xy 353.122894 -264.574413) (xy 353.174223 -264.596225) (xy 353.221829 -264.625279)
			(xy 353.264697 -264.660954) (xy 353.301914 -264.702491) (xy 353.332687 -264.749004) (xy 353.356359 -264.799501)
			(xy 353.372427 -264.852908) (xy 353.380547 -264.908084) (xy 353.381056 -264.93597) (xy 353.380547 -264.963856)
			(xy 353.372427 -265.019032) (xy 353.356359 -265.072439) (xy 353.332687 -265.122936) (xy 353.301914 -265.169449)
			(xy 353.264697 -265.210986) (xy 353.221829 -265.246661) (xy 353.174223 -265.275715) (xy 353.122894 -265.297527)
			(xy 353.068937 -265.311633) (xy 353.0135 -265.317733) (xy 352.957766 -265.315696) (xy 352.902923 -265.305566)
			(xy 352.850139 -265.287559) (xy 352.800539 -265.262058) (xy 352.755181 -265.229607) (xy 352.715032 -265.190898)
			(xy 352.680946 -265.146755) (xy 352.65365 -265.09812) (xy 352.633727 -265.046029) (xy 352.621601 -264.991592)
			(xy 352.61753 -264.93597) (xy 350.53524 -264.93597) (xy 350.53524 -265.834114) (xy 351.44659 -265.834114)
			(xy 351.450661 -265.778492) (xy 351.462787 -265.724055) (xy 351.48271 -265.671964) (xy 351.510006 -265.623329)
			(xy 351.544092 -265.579186) (xy 351.584241 -265.540477) (xy 351.629599 -265.508026) (xy 351.679199 -265.482525)
			(xy 351.731983 -265.464518) (xy 351.786826 -265.454388) (xy 351.84256 -265.452351) (xy 351.897997 -265.458451)
			(xy 351.951954 -265.472557) (xy 352.003283 -265.494369) (xy 352.050889 -265.523423) (xy 352.093757 -265.559098)
			(xy 352.130974 -265.600635) (xy 352.161747 -265.647148) (xy 352.185419 -265.697645) (xy 352.197514 -265.737848)
			(xy 388.73252 -265.737848) (xy 388.736591 -265.682226) (xy 388.748717 -265.627789) (xy 388.76864 -265.575698)
			(xy 388.795936 -265.527063) (xy 388.830022 -265.48292) (xy 388.870171 -265.444211) (xy 388.915529 -265.41176)
			(xy 388.965129 -265.386259) (xy 389.017913 -265.368252) (xy 389.072756 -265.358122) (xy 389.12849 -265.356085)
			(xy 389.183927 -265.362185) (xy 389.237884 -265.376291) (xy 389.289213 -265.398103) (xy 389.336819 -265.427157)
			(xy 389.379687 -265.462832) (xy 389.416904 -265.504369) (xy 389.447677 -265.550882) (xy 389.471349 -265.601379)
			(xy 389.487417 -265.654786) (xy 389.495537 -265.709962) (xy 389.496046 -265.737848) (xy 389.495537 -265.765734)
			(xy 389.487417 -265.82091) (xy 389.471349 -265.874317) (xy 389.447677 -265.924814) (xy 389.416904 -265.971327)
			(xy 389.379687 -266.012864) (xy 389.336819 -266.048539) (xy 389.289213 -266.077593) (xy 389.237884 -266.099405)
			(xy 389.183927 -266.113511) (xy 389.12849 -266.119611) (xy 389.072756 -266.117574) (xy 389.017913 -266.107444)
			(xy 388.965129 -266.089437) (xy 388.915529 -266.063936) (xy 388.870171 -266.031485) (xy 388.830022 -265.992776)
			(xy 388.795936 -265.948633) (xy 388.76864 -265.899998) (xy 388.748717 -265.847907) (xy 388.736591 -265.79347)
			(xy 388.73252 -265.737848) (xy 352.197514 -265.737848) (xy 352.201487 -265.751052) (xy 352.209607 -265.806228)
			(xy 352.210116 -265.834114) (xy 352.209607 -265.862) (xy 352.201487 -265.917176) (xy 352.185419 -265.970583)
			(xy 352.161747 -266.02108) (xy 352.130974 -266.067593) (xy 352.093757 -266.10913) (xy 352.050889 -266.144805)
			(xy 352.003283 -266.173859) (xy 351.951954 -266.195671) (xy 351.897997 -266.209777) (xy 351.84256 -266.215877)
			(xy 351.786826 -266.21384) (xy 351.731983 -266.20371) (xy 351.679199 -266.185703) (xy 351.629599 -266.160202)
			(xy 351.584241 -266.127751) (xy 351.544092 -266.089042) (xy 351.510006 -266.044899) (xy 351.48271 -265.996264)
			(xy 351.462787 -265.944173) (xy 351.450661 -265.889736) (xy 351.44659 -265.834114) (xy 350.53524 -265.834114)
			(xy 350.53524 -266.963398) (xy 386.956044 -266.963398) (xy 386.960115 -266.907776) (xy 386.972241 -266.853339)
			(xy 386.992164 -266.801248) (xy 387.01946 -266.752613) (xy 387.053546 -266.70847) (xy 387.093695 -266.669761)
			(xy 387.139053 -266.63731) (xy 387.188653 -266.611809) (xy 387.241437 -266.593802) (xy 387.29628 -266.583672)
			(xy 387.352014 -266.581635) (xy 387.407451 -266.587735) (xy 387.461408 -266.601841) (xy 387.512737 -266.623653)
			(xy 387.560343 -266.652707) (xy 387.603211 -266.688382) (xy 387.640428 -266.729919) (xy 387.671201 -266.776432)
			(xy 387.694873 -266.826929) (xy 387.710941 -266.880336) (xy 387.716137 -266.915646) (xy 388.736076 -266.915646)
			(xy 388.740147 -266.860024) (xy 388.752273 -266.805587) (xy 388.772196 -266.753496) (xy 388.799492 -266.704861)
			(xy 388.833578 -266.660718) (xy 388.873727 -266.622009) (xy 388.919085 -266.589558) (xy 388.968685 -266.564057)
			(xy 389.021469 -266.54605) (xy 389.076312 -266.53592) (xy 389.132046 -266.533883) (xy 389.187483 -266.539983)
			(xy 389.24144 -266.554089) (xy 389.292769 -266.575901) (xy 389.340375 -266.604955) (xy 389.383243 -266.64063)
			(xy 389.42046 -266.682167) (xy 389.451233 -266.72868) (xy 389.474905 -266.779177) (xy 389.490973 -266.832584)
			(xy 389.499093 -266.88776) (xy 389.499602 -266.915646) (xy 389.499093 -266.943532) (xy 389.490973 -266.998708)
			(xy 389.474905 -267.052115) (xy 389.451233 -267.102612) (xy 389.42046 -267.149125) (xy 389.383243 -267.190662)
			(xy 389.340375 -267.226337) (xy 389.292769 -267.255391) (xy 389.24144 -267.277203) (xy 389.187483 -267.291309)
			(xy 389.132046 -267.297409) (xy 389.076312 -267.295372) (xy 389.021469 -267.285242) (xy 388.968685 -267.267235)
			(xy 388.919085 -267.241734) (xy 388.873727 -267.209283) (xy 388.833578 -267.170574) (xy 388.799492 -267.126431)
			(xy 388.772196 -267.077796) (xy 388.752273 -267.025705) (xy 388.740147 -266.971268) (xy 388.736076 -266.915646)
			(xy 387.716137 -266.915646) (xy 387.719061 -266.935512) (xy 387.71957 -266.963398) (xy 387.719061 -266.991284)
			(xy 387.710941 -267.04646) (xy 387.694873 -267.099867) (xy 387.671201 -267.150364) (xy 387.640428 -267.196877)
			(xy 387.603211 -267.238414) (xy 387.560343 -267.274089) (xy 387.512737 -267.303143) (xy 387.461408 -267.324955)
			(xy 387.407451 -267.339061) (xy 387.352014 -267.345161) (xy 387.29628 -267.343124) (xy 387.241437 -267.332994)
			(xy 387.188653 -267.314987) (xy 387.139053 -267.289486) (xy 387.093695 -267.257035) (xy 387.053546 -267.218326)
			(xy 387.01946 -267.174183) (xy 386.992164 -267.125548) (xy 386.972241 -267.073457) (xy 386.960115 -267.01902)
			(xy 386.956044 -266.963398) (xy 350.53524 -266.963398) (xy 350.53524 -267.578078) (xy 385.153152 -267.578078)
			(xy 385.157223 -267.522456) (xy 385.169349 -267.468019) (xy 385.189272 -267.415928) (xy 385.216568 -267.367293)
			(xy 385.250654 -267.32315) (xy 385.290803 -267.284441) (xy 385.336161 -267.25199) (xy 385.385761 -267.226489)
			(xy 385.438545 -267.208482) (xy 385.493388 -267.198352) (xy 385.549122 -267.196315) (xy 385.604559 -267.202415)
			(xy 385.658516 -267.216521) (xy 385.709845 -267.238333) (xy 385.757451 -267.267387) (xy 385.800319 -267.303062)
			(xy 385.837536 -267.344599) (xy 385.868309 -267.391112) (xy 385.891981 -267.441609) (xy 385.908049 -267.495016)
			(xy 385.916169 -267.550192) (xy 385.916678 -267.578078) (xy 385.916169 -267.605964) (xy 385.908049 -267.66114)
			(xy 385.891981 -267.714547) (xy 385.868309 -267.765044) (xy 385.837536 -267.811557) (xy 385.800319 -267.853094)
			(xy 385.757451 -267.888769) (xy 385.709845 -267.917823) (xy 385.658516 -267.939635) (xy 385.604559 -267.953741)
			(xy 385.549122 -267.959841) (xy 385.493388 -267.957804) (xy 385.438545 -267.947674) (xy 385.385761 -267.929667)
			(xy 385.336161 -267.904166) (xy 385.290803 -267.871715) (xy 385.250654 -267.833006) (xy 385.216568 -267.788863)
			(xy 385.189272 -267.740228) (xy 385.169349 -267.688137) (xy 385.157223 -267.6337) (xy 385.153152 -267.578078)
			(xy 350.53524 -267.578078) (xy 350.53524 -269.417038) (xy 357.085646 -269.417038) (xy 357.086146 -269.388298)
			(xy 357.094777 -269.331471) (xy 357.111833 -269.27658) (xy 357.13693 -269.224869) (xy 357.169498 -269.177507)
			(xy 357.18877 -269.15618) (xy 357.195374 -269.149322) (xy 357.202486 -269.131288) (xy 357.202486 -269.042388)
			(xy 357.195374 -269.024354) (xy 357.18877 -269.017496) (xy 357.169523 -268.996149) (xy 357.136952 -268.948793)
			(xy 357.111854 -268.897086) (xy 357.094798 -268.8422) (xy 357.08617 -268.785376) (xy 357.085646 -268.756638)
			(xy 357.086213 -268.72939) (xy 357.093964 -268.675447) (xy 357.109312 -268.623157) (xy 357.131945 -268.573583)
			(xy 357.161403 -268.527735) (xy 357.197086 -268.486545) (xy 357.238267 -268.450853) (xy 357.284109 -268.421385)
			(xy 357.333678 -268.398741) (xy 357.385965 -268.383381) (xy 357.439906 -268.375619) (xy 357.467154 -268.37513)
			(xy 357.494524 -268.375616) (xy 357.548702 -268.383428) (xy 357.601205 -268.398912) (xy 357.650953 -268.421749)
			(xy 357.69692 -268.45147) (xy 357.717852 -268.46911) (xy 357.718106 -268.469364) (xy 357.725181 -268.474967)
			(xy 357.742107 -268.481202) (xy 357.751126 -268.481556) (xy 357.818182 -268.481556) (xy 357.827199 -268.4812)
			(xy 357.844117 -268.474953) (xy 357.851202 -268.469364) (xy 357.851202 -268.46911) (xy 357.851456 -268.46911)
			(xy 357.872389 -268.451469) (xy 357.918357 -268.421745) (xy 357.968103 -268.398899) (xy 358.020605 -268.383403)
			(xy 358.074783 -268.375574) (xy 358.129525 -268.375574) (xy 358.183703 -268.383403) (xy 358.236205 -268.398899)
			(xy 358.285951 -268.421745) (xy 358.331919 -268.451469) (xy 358.352852 -268.46911) (xy 358.353106 -268.469364)
			(xy 358.360181 -268.474967) (xy 358.377107 -268.481202) (xy 358.386126 -268.481556) (xy 358.453182 -268.481556)
			(xy 358.462199 -268.4812) (xy 358.479117 -268.474953) (xy 358.486202 -268.469364) (xy 358.486202 -268.46911)
			(xy 358.486456 -268.46911) (xy 358.507389 -268.451469) (xy 358.553357 -268.421745) (xy 358.603103 -268.398899)
			(xy 358.655605 -268.383403) (xy 358.709783 -268.375574) (xy 358.764525 -268.375574) (xy 358.818703 -268.383403)
			(xy 358.871205 -268.398899) (xy 358.920951 -268.421745) (xy 358.966919 -268.451469) (xy 358.987852 -268.46911)
			(xy 358.988106 -268.469364) (xy 358.995181 -268.474967) (xy 359.012107 -268.481202) (xy 359.021126 -268.481556)
			(xy 359.088182 -268.481556) (xy 359.097199 -268.4812) (xy 359.114117 -268.474953) (xy 359.121202 -268.469364)
			(xy 359.121202 -268.46911) (xy 359.121456 -268.46911) (xy 359.142389 -268.451469) (xy 359.188357 -268.421745)
			(xy 359.238103 -268.398899) (xy 359.290605 -268.383403) (xy 359.344783 -268.375574) (xy 359.399525 -268.375574)
			(xy 359.453703 -268.383403) (xy 359.506205 -268.398899) (xy 359.555951 -268.421745) (xy 359.601919 -268.451469)
			(xy 359.622852 -268.46911) (xy 359.623106 -268.469364) (xy 359.630181 -268.474967) (xy 359.647107 -268.481202)
			(xy 359.656126 -268.481556) (xy 359.723182 -268.481556) (xy 359.732199 -268.4812) (xy 359.749117 -268.474953)
			(xy 359.756202 -268.469364) (xy 359.756202 -268.46911) (xy 359.756456 -268.46911) (xy 359.777395 -268.45148)
			(xy 359.823366 -268.421766) (xy 359.873112 -268.398928) (xy 359.925611 -268.383435) (xy 359.979785 -268.375605)
			(xy 360.007154 -268.37513) (xy 360.034407 -268.375598) (xy 360.08836 -268.38335) (xy 360.14066 -268.398702)
			(xy 360.190243 -268.421342) (xy 360.236098 -268.450809) (xy 360.277292 -268.486502) (xy 360.312987 -268.527696)
			(xy 360.342454 -268.57355) (xy 360.365095 -268.623132) (xy 360.380448 -268.675432) (xy 360.388201 -268.729385)
			(xy 360.388662 -268.756638) (xy 360.388145 -268.785377) (xy 360.379518 -268.842204) (xy 360.362466 -268.897094)
			(xy 360.337373 -268.948806) (xy 360.304808 -268.996169) (xy 360.285538 -269.017496) (xy 360.278934 -269.024354)
			(xy 360.271822 -269.042388) (xy 360.271822 -269.131288) (xy 360.278934 -269.149322) (xy 360.285538 -269.15618)
			(xy 360.304823 -269.177495) (xy 360.337388 -269.22486) (xy 360.362478 -269.276574) (xy 360.379525 -269.331468)
			(xy 360.388144 -269.388298) (xy 360.388662 -269.417038) (xy 360.38828 -269.444294) (xy 360.380517 -269.49825)
			(xy 360.365154 -269.550552) (xy 360.342504 -269.600136) (xy 360.313027 -269.645991) (xy 360.277325 -269.687184)
			(xy 360.236124 -269.722878) (xy 360.190262 -269.752344) (xy 360.140674 -269.774983) (xy 360.088368 -269.790335)
			(xy 360.03441 -269.798086) (xy 360.007154 -269.798546) (xy 359.979784 -269.798061) (xy 359.925605 -269.79025)
			(xy 359.873102 -269.774766) (xy 359.823355 -269.751928) (xy 359.777388 -269.722206) (xy 359.756456 -269.704566)
			(xy 359.756202 -269.704312) (xy 359.749118 -269.698721) (xy 359.732199 -269.692477) (xy 359.723182 -269.69212)
			(xy 359.656126 -269.69212) (xy 359.64711 -269.692485) (xy 359.630193 -269.698727) (xy 359.623106 -269.704312)
			(xy 359.622852 -269.704566) (xy 359.601919 -269.722207) (xy 359.555951 -269.751931) (xy 359.506205 -269.774777)
			(xy 359.453703 -269.790273) (xy 359.399525 -269.798102) (xy 359.344783 -269.798102) (xy 359.290605 -269.790273)
			(xy 359.238103 -269.774777) (xy 359.188357 -269.751931) (xy 359.142389 -269.722207) (xy 359.121456 -269.704566)
			(xy 359.121202 -269.704312) (xy 359.114118 -269.698721) (xy 359.097199 -269.692477) (xy 359.088182 -269.69212)
			(xy 359.021126 -269.69212) (xy 359.01211 -269.692485) (xy 358.995193 -269.698727) (xy 358.988106 -269.704312)
			(xy 358.988106 -269.704566) (xy 358.987852 -269.704566) (xy 358.966919 -269.722207) (xy 358.920951 -269.751931)
			(xy 358.871205 -269.774777) (xy 358.818703 -269.790273) (xy 358.764525 -269.798102) (xy 358.709783 -269.798102)
			(xy 358.655605 -269.790273) (xy 358.603103 -269.774777) (xy 358.553357 -269.751931) (xy 358.507389 -269.722207)
			(xy 358.486456 -269.704566) (xy 358.486202 -269.704312) (xy 358.479118 -269.698721) (xy 358.462199 -269.692477)
			(xy 358.453182 -269.69212) (xy 358.386126 -269.69212) (xy 358.37711 -269.692485) (xy 358.360193 -269.698727)
			(xy 358.353106 -269.704312) (xy 358.353106 -269.704566) (xy 358.352852 -269.704566) (xy 358.331919 -269.722207)
			(xy 358.285951 -269.751931) (xy 358.236205 -269.774777) (xy 358.183703 -269.790273) (xy 358.129525 -269.798102)
			(xy 358.074783 -269.798102) (xy 358.020605 -269.790273) (xy 357.968103 -269.774777) (xy 357.918357 -269.751931)
			(xy 357.872389 -269.722207) (xy 357.851456 -269.704566) (xy 357.851202 -269.704312) (xy 357.844118 -269.698721)
			(xy 357.827199 -269.692477) (xy 357.818182 -269.69212) (xy 357.751126 -269.69212) (xy 357.74211 -269.692485)
			(xy 357.725193 -269.698727) (xy 357.718106 -269.704312) (xy 357.718106 -269.704566) (xy 357.717852 -269.704566)
			(xy 357.696907 -269.722189) (xy 357.650938 -269.751904) (xy 357.601194 -269.774744) (xy 357.548696 -269.790239)
			(xy 357.494522 -269.79807) (xy 357.467154 -269.798546) (xy 357.439903 -269.798065) (xy 357.385957 -269.790303)
			(xy 357.333665 -269.774944) (xy 357.28409 -269.752301) (xy 357.238242 -269.722833) (xy 357.197053 -269.687141)
			(xy 357.161362 -269.645952) (xy 357.131896 -269.600103) (xy 357.109253 -269.550528) (xy 357.093895 -269.498235)
			(xy 357.086134 -269.444289) (xy 357.085646 -269.417038) (xy 350.53524 -269.417038) (xy 350.53524 -270.89989)
			(xy 375.182393 -270.89989) (xy 375.186382 -270.75135) (xy 375.198339 -270.603237) (xy 375.218229 -270.45598)
			(xy 375.245994 -270.310004) (xy 375.281555 -270.165727) (xy 375.324809 -270.023568) (xy 375.375631 -269.883935)
			(xy 375.433875 -269.747232) (xy 375.499373 -269.613852) (xy 375.571936 -269.48418) (xy 375.651354 -269.35859)
			(xy 375.737399 -269.237443) (xy 375.829823 -269.12109) (xy 375.928359 -269.009866) (xy 376.032723 -268.904091)
			(xy 376.142615 -268.804071) (xy 376.257716 -268.710093) (xy 376.377696 -268.622429) (xy 376.502209 -268.541332)
			(xy 376.630895 -268.467035) (xy 376.763384 -268.399753) (xy 376.899293 -268.339679) (xy 377.038231 -268.286987)
			(xy 377.179797 -268.241828) (xy 377.323583 -268.204333) (xy 377.469174 -268.174611) (xy 377.61615 -268.152746)
			(xy 377.764089 -268.138802) (xy 377.912562 -268.132818) (xy 378.061143 -268.134813) (xy 378.209402 -268.144781)
			(xy 378.356913 -268.162692) (xy 378.503249 -268.188495) (xy 378.64799 -268.222115) (xy 378.790717 -268.263457)
			(xy 378.93102 -268.3124) (xy 378.996004 -268.339062) (xy 388.744204 -268.339062) (xy 388.748275 -268.28344)
			(xy 388.760401 -268.229003) (xy 388.780324 -268.176912) (xy 388.80762 -268.128277) (xy 388.841706 -268.084134)
			(xy 388.881855 -268.045425) (xy 388.927213 -268.012974) (xy 388.976813 -267.987473) (xy 389.029597 -267.969466)
			(xy 389.08444 -267.959336) (xy 389.140174 -267.957299) (xy 389.195611 -267.963399) (xy 389.249568 -267.977505)
			(xy 389.300897 -267.999317) (xy 389.348503 -268.028371) (xy 389.391371 -268.064046) (xy 389.428588 -268.105583)
			(xy 389.459361 -268.152096) (xy 389.483033 -268.202593) (xy 389.499101 -268.256) (xy 389.507221 -268.311176)
			(xy 389.50773 -268.339062) (xy 389.507221 -268.366948) (xy 389.499101 -268.422124) (xy 389.483033 -268.475531)
			(xy 389.459361 -268.526028) (xy 389.428588 -268.572541) (xy 389.391371 -268.614078) (xy 389.348503 -268.649753)
			(xy 389.300897 -268.678807) (xy 389.249568 -268.700619) (xy 389.195611 -268.714725) (xy 389.140174 -268.720825)
			(xy 389.08444 -268.718788) (xy 389.029597 -268.708658) (xy 388.976813 -268.690651) (xy 388.927213 -268.66515)
			(xy 388.881855 -268.632699) (xy 388.841706 -268.59399) (xy 388.80762 -268.549847) (xy 388.780324 -268.501212)
			(xy 388.760401 -268.449121) (xy 388.748275 -268.394684) (xy 388.744204 -268.339062) (xy 378.996004 -268.339062)
			(xy 379.068493 -268.368803) (xy 379.20274 -268.432504) (xy 379.333375 -268.50332) (xy 379.46002 -268.581045)
			(xy 379.58231 -268.665456) (xy 379.699893 -268.756309) (xy 379.81243 -268.853343) (xy 379.919597 -268.956278)
			(xy 380.021084 -269.064817) (xy 380.116598 -269.178646) (xy 380.205865 -269.297439) (xy 380.288626 -269.420851)
			(xy 380.364644 -269.548529) (xy 380.433699 -269.680102) (xy 380.495592 -269.815193) (xy 380.546165 -269.943326)
			(xy 388.630666 -269.943326) (xy 388.634737 -269.887704) (xy 388.646863 -269.833267) (xy 388.666786 -269.781176)
			(xy 388.694082 -269.732541) (xy 388.728168 -269.688398) (xy 388.768317 -269.649689) (xy 388.813675 -269.617238)
			(xy 388.863275 -269.591737) (xy 388.916059 -269.57373) (xy 388.970902 -269.5636) (xy 389.026636 -269.561563)
			(xy 389.082073 -269.567663) (xy 389.13603 -269.581769) (xy 389.187359 -269.603581) (xy 389.234965 -269.632635)
			(xy 389.277833 -269.66831) (xy 389.31505 -269.709847) (xy 389.345823 -269.75636) (xy 389.369495 -269.806857)
			(xy 389.385563 -269.860264) (xy 389.393683 -269.91544) (xy 389.394192 -269.943326) (xy 389.393683 -269.971212)
			(xy 389.385563 -270.026388) (xy 389.369495 -270.079795) (xy 389.345823 -270.130292) (xy 389.31505 -270.176805)
			(xy 389.277833 -270.218342) (xy 389.234965 -270.254017) (xy 389.187359 -270.283071) (xy 389.13603 -270.304883)
			(xy 389.082073 -270.318989) (xy 389.026636 -270.325089) (xy 388.970902 -270.323052) (xy 388.916059 -270.312922)
			(xy 388.863275 -270.294915) (xy 388.813675 -270.269414) (xy 388.768317 -270.236963) (xy 388.728168 -270.198254)
			(xy 388.694082 -270.154111) (xy 388.666786 -270.105476) (xy 388.646863 -270.053385) (xy 388.634737 -269.998948)
			(xy 388.630666 -269.943326) (xy 380.546165 -269.943326) (xy 380.550145 -269.95341) (xy 380.5972 -270.094357)
			(xy 380.636622 -270.237627) (xy 380.668296 -270.382806) (xy 380.692132 -270.529475) (xy 380.708061 -270.677213)
			(xy 380.716037 -270.825593) (xy 380.716536 -270.89989) (xy 380.716037 -270.974187) (xy 380.708061 -271.122567)
			(xy 380.692132 -271.270305) (xy 380.668296 -271.416974) (xy 380.636622 -271.562153) (xy 380.5972 -271.705423)
			(xy 380.550145 -271.84637) (xy 380.495592 -271.984587) (xy 380.433699 -272.119678) (xy 380.364644 -272.251251)
			(xy 380.288626 -272.378929) (xy 380.205865 -272.502341) (xy 380.116598 -272.621134) (xy 380.113519 -272.624804)
			(xy 386.269242 -272.624804) (xy 386.273202 -272.57575) (xy 386.284979 -272.527966) (xy 386.30427 -272.48269)
			(xy 386.330573 -272.441094) (xy 386.363208 -272.404257) (xy 386.401329 -272.373132) (xy 386.44395 -272.348525)
			(xy 386.489966 -272.331073) (xy 386.538185 -272.321229) (xy 386.58736 -272.319248) (xy 386.636215 -272.32518)
			(xy 386.683486 -272.338872) (xy 386.727948 -272.35997) (xy 386.768451 -272.387926) (xy 386.803944 -272.422018)
			(xy 386.833509 -272.461362) (xy 386.85638 -272.504939) (xy 386.871964 -272.55162) (xy 386.879859 -272.600197)
			(xy 386.880354 -272.624804) (xy 388.169162 -272.624804) (xy 388.173122 -272.57575) (xy 388.184899 -272.527966)
			(xy 388.20419 -272.48269) (xy 388.230493 -272.441094) (xy 388.263128 -272.404257) (xy 388.301249 -272.373132)
			(xy 388.34387 -272.348525) (xy 388.389886 -272.331073) (xy 388.438105 -272.321229) (xy 388.48728 -272.319248)
			(xy 388.536135 -272.32518) (xy 388.583406 -272.338872) (xy 388.627868 -272.35997) (xy 388.668371 -272.387926)
			(xy 388.703864 -272.422018) (xy 388.733429 -272.461362) (xy 388.7563 -272.504939) (xy 388.771884 -272.55162)
			(xy 388.779779 -272.600197) (xy 388.780274 -272.624804) (xy 388.779779 -272.649411) (xy 388.771884 -272.697988)
			(xy 388.7563 -272.744669) (xy 388.733429 -272.788246) (xy 388.703864 -272.82759) (xy 388.668371 -272.861682)
			(xy 388.627868 -272.889638) (xy 388.583406 -272.910736) (xy 388.536135 -272.924428) (xy 388.48728 -272.93036)
			(xy 388.438105 -272.928379) (xy 388.389886 -272.918535) (xy 388.34387 -272.901083) (xy 388.301249 -272.876476)
			(xy 388.263128 -272.845351) (xy 388.230493 -272.808514) (xy 388.20419 -272.766918) (xy 388.184899 -272.721642)
			(xy 388.173122 -272.673858) (xy 388.169162 -272.624804) (xy 386.880354 -272.624804) (xy 386.879859 -272.649411)
			(xy 386.871964 -272.697988) (xy 386.85638 -272.744669) (xy 386.833509 -272.788246) (xy 386.803944 -272.82759)
			(xy 386.768451 -272.861682) (xy 386.727948 -272.889638) (xy 386.683486 -272.910736) (xy 386.636215 -272.924428)
			(xy 386.58736 -272.93036) (xy 386.538185 -272.928379) (xy 386.489966 -272.918535) (xy 386.44395 -272.901083)
			(xy 386.401329 -272.876476) (xy 386.363208 -272.845351) (xy 386.330573 -272.808514) (xy 386.30427 -272.766918)
			(xy 386.284979 -272.721642) (xy 386.273202 -272.673858) (xy 386.269242 -272.624804) (xy 380.113519 -272.624804)
			(xy 380.021084 -272.734963) (xy 379.919597 -272.843502) (xy 379.81243 -272.946437) (xy 379.699893 -273.043471)
			(xy 379.58231 -273.134324) (xy 379.46002 -273.218735) (xy 379.333375 -273.29646) (xy 379.20274 -273.367276)
			(xy 379.068493 -273.430977) (xy 378.93102 -273.48738) (xy 378.790717 -273.536323) (xy 378.658005 -273.574764)
			(xy 388.169162 -273.574764) (xy 388.173122 -273.52571) (xy 388.184899 -273.477926) (xy 388.20419 -273.43265)
			(xy 388.230493 -273.391054) (xy 388.263128 -273.354217) (xy 388.301249 -273.323092) (xy 388.34387 -273.298485)
			(xy 388.389886 -273.281033) (xy 388.438105 -273.271189) (xy 388.48728 -273.269208) (xy 388.536135 -273.27514)
			(xy 388.583406 -273.288832) (xy 388.627868 -273.30993) (xy 388.668371 -273.337886) (xy 388.703864 -273.371978)
			(xy 388.733429 -273.411322) (xy 388.7563 -273.454899) (xy 388.771884 -273.50158) (xy 388.779779 -273.550157)
			(xy 388.780274 -273.574764) (xy 390.069082 -273.574764) (xy 390.073042 -273.52571) (xy 390.084819 -273.477926)
			(xy 390.10411 -273.43265) (xy 390.130413 -273.391054) (xy 390.163048 -273.354217) (xy 390.201169 -273.323092)
			(xy 390.24379 -273.298485) (xy 390.289806 -273.281033) (xy 390.338025 -273.271189) (xy 390.3872 -273.269208)
			(xy 390.436055 -273.27514) (xy 390.483326 -273.288832) (xy 390.527788 -273.30993) (xy 390.568291 -273.337886)
			(xy 390.603784 -273.371978) (xy 390.633349 -273.411322) (xy 390.65622 -273.454899) (xy 390.671804 -273.50158)
			(xy 390.679699 -273.550157) (xy 390.680194 -273.574764) (xy 390.679699 -273.599371) (xy 390.671804 -273.647948)
			(xy 390.65622 -273.694629) (xy 390.633349 -273.738206) (xy 390.603784 -273.77755) (xy 390.568291 -273.811642)
			(xy 390.527788 -273.839598) (xy 390.483326 -273.860696) (xy 390.436055 -273.874388) (xy 390.3872 -273.88032)
			(xy 390.338025 -273.878339) (xy 390.289806 -273.868495) (xy 390.24379 -273.851043) (xy 390.201169 -273.826436)
			(xy 390.163048 -273.795311) (xy 390.130413 -273.758474) (xy 390.10411 -273.716878) (xy 390.084819 -273.671602)
			(xy 390.073042 -273.623818) (xy 390.069082 -273.574764) (xy 388.780274 -273.574764) (xy 388.779779 -273.599371)
			(xy 388.771884 -273.647948) (xy 388.7563 -273.694629) (xy 388.733429 -273.738206) (xy 388.703864 -273.77755)
			(xy 388.668371 -273.811642) (xy 388.627868 -273.839598) (xy 388.583406 -273.860696) (xy 388.536135 -273.874388)
			(xy 388.48728 -273.88032) (xy 388.438105 -273.878339) (xy 388.389886 -273.868495) (xy 388.34387 -273.851043)
			(xy 388.301249 -273.826436) (xy 388.263128 -273.795311) (xy 388.230493 -273.758474) (xy 388.20419 -273.716878)
			(xy 388.184899 -273.671602) (xy 388.173122 -273.623818) (xy 388.169162 -273.574764) (xy 378.658005 -273.574764)
			(xy 378.64799 -273.577665) (xy 378.503249 -273.611285) (xy 378.356913 -273.637088) (xy 378.209402 -273.654999)
			(xy 378.061143 -273.664967) (xy 377.912562 -273.666962) (xy 377.764089 -273.660978) (xy 377.61615 -273.647034)
			(xy 377.469174 -273.625169) (xy 377.323583 -273.595447) (xy 377.179797 -273.557952) (xy 377.038231 -273.512793)
			(xy 376.899293 -273.460101) (xy 376.763384 -273.400027) (xy 376.630895 -273.332745) (xy 376.502209 -273.258448)
			(xy 376.377696 -273.177351) (xy 376.257716 -273.089687) (xy 376.142615 -272.995709) (xy 376.032723 -272.895689)
			(xy 375.928359 -272.789914) (xy 375.829823 -272.67869) (xy 375.737399 -272.562337) (xy 375.651354 -272.44119)
			(xy 375.571936 -272.3156) (xy 375.499373 -272.185928) (xy 375.433875 -272.052548) (xy 375.375631 -271.915845)
			(xy 375.324809 -271.776212) (xy 375.281555 -271.634053) (xy 375.245994 -271.489776) (xy 375.218229 -271.3438)
			(xy 375.198339 -271.196543) (xy 375.186382 -271.04843) (xy 375.182393 -270.89989) (xy 350.53524 -270.89989)
			(xy 350.53524 -276.027896) (xy 352.727006 -276.027896) (xy 352.727468 -276.000526) (xy 352.735287 -275.946346)
			(xy 352.750777 -275.893843) (xy 352.773619 -275.844096) (xy 352.803344 -275.79813) (xy 352.820986 -275.777198)
			(xy 352.82124 -275.776944) (xy 352.826819 -275.769853) (xy 352.833069 -275.752939) (xy 352.833432 -275.743924)
			(xy 352.833432 -275.676868) (xy 352.833083 -275.66785) (xy 352.826829 -275.650934) (xy 352.82124 -275.643848)
			(xy 352.820986 -275.643848) (xy 352.820986 -275.643594) (xy 352.803343 -275.622664) (xy 352.773622 -275.576694)
			(xy 352.750779 -275.526948) (xy 352.735285 -275.474445) (xy 352.727457 -275.420267) (xy 352.727458 -275.365527)
			(xy 352.735286 -275.311349) (xy 352.750781 -275.258847) (xy 352.773624 -275.2091) (xy 352.803347 -275.163132)
			(xy 352.820986 -275.142198) (xy 352.82124 -275.141944) (xy 352.826819 -275.134853) (xy 352.833069 -275.117939)
			(xy 352.833432 -275.108924) (xy 352.833432 -275.041868) (xy 352.833083 -275.03285) (xy 352.826829 -275.015934)
			(xy 352.82124 -275.008848) (xy 352.820986 -275.008848) (xy 352.820986 -275.008594) (xy 352.803328 -274.987677)
			(xy 352.77362 -274.9417) (xy 352.750788 -274.891948) (xy 352.735301 -274.839444) (xy 352.727477 -274.785266)
			(xy 352.727006 -274.757896) (xy 352.727452 -274.730642) (xy 352.73521 -274.67669) (xy 352.750567 -274.624391)
			(xy 352.773211 -274.57481) (xy 352.80268 -274.528956) (xy 352.838376 -274.487763) (xy 352.879571 -274.45207)
			(xy 352.925426 -274.422602) (xy 352.975008 -274.39996) (xy 353.027308 -274.384606) (xy 353.08126 -274.37685)
			(xy 353.108514 -274.376388) (xy 353.135884 -274.376849) (xy 353.190064 -274.384668) (xy 353.242567 -274.400159)
			(xy 353.292313 -274.423002) (xy 353.33828 -274.452727) (xy 353.359212 -274.470368) (xy 353.359466 -274.470622)
			(xy 353.366556 -274.476203) (xy 353.38347 -274.482452) (xy 353.392486 -274.482814) (xy 353.459542 -274.482814)
			(xy 353.468556 -274.482426) (xy 353.485473 -274.4762) (xy 353.492562 -274.470622) (xy 353.492562 -274.470368)
			(xy 353.492816 -274.470368) (xy 353.513765 -274.45275) (xy 353.559734 -274.423036) (xy 353.609477 -274.400196)
			(xy 353.661974 -274.3847) (xy 353.716146 -274.376866) (xy 353.743514 -274.376388) (xy 353.770765 -274.376865)
			(xy 353.824713 -274.384623) (xy 353.877008 -274.39998) (xy 353.926585 -274.422622) (xy 353.972435 -274.45209)
			(xy 354.013625 -274.487782) (xy 354.045854 -274.524978) (xy 387.219202 -274.524978) (xy 387.223162 -274.475924)
			(xy 387.234939 -274.42814) (xy 387.25423 -274.382864) (xy 387.280533 -274.341268) (xy 387.313168 -274.304431)
			(xy 387.351289 -274.273306) (xy 387.39391 -274.248699) (xy 387.439926 -274.231247) (xy 387.488145 -274.221403)
			(xy 387.53732 -274.219422) (xy 387.586175 -274.225354) (xy 387.633446 -274.239046) (xy 387.677908 -274.260144)
			(xy 387.718411 -274.2881) (xy 387.753904 -274.322192) (xy 387.783469 -274.361536) (xy 387.80634 -274.405113)
			(xy 387.821924 -274.451794) (xy 387.829819 -274.500371) (xy 387.830314 -274.524978) (xy 389.119122 -274.524978)
			(xy 389.123082 -274.475924) (xy 389.134859 -274.42814) (xy 389.15415 -274.382864) (xy 389.180453 -274.341268)
			(xy 389.213088 -274.304431) (xy 389.251209 -274.273306) (xy 389.29383 -274.248699) (xy 389.339846 -274.231247)
			(xy 389.388065 -274.221403) (xy 389.43724 -274.219422) (xy 389.486095 -274.225354) (xy 389.533366 -274.239046)
			(xy 389.577828 -274.260144) (xy 389.618331 -274.2881) (xy 389.653824 -274.322192) (xy 389.683389 -274.361536)
			(xy 389.70626 -274.405113) (xy 389.721844 -274.451794) (xy 389.729739 -274.500371) (xy 389.730234 -274.524978)
			(xy 389.729739 -274.549585) (xy 389.721844 -274.598162) (xy 389.70626 -274.644843) (xy 389.683389 -274.68842)
			(xy 389.653824 -274.727764) (xy 389.618331 -274.761856) (xy 389.577828 -274.789812) (xy 389.533366 -274.81091)
			(xy 389.486095 -274.824602) (xy 389.43724 -274.830534) (xy 389.388065 -274.828553) (xy 389.339846 -274.818709)
			(xy 389.29383 -274.801257) (xy 389.251209 -274.77665) (xy 389.213088 -274.745525) (xy 389.180453 -274.708688)
			(xy 389.15415 -274.667092) (xy 389.134859 -274.621816) (xy 389.123082 -274.574032) (xy 389.119122 -274.524978)
			(xy 387.830314 -274.524978) (xy 387.829819 -274.549585) (xy 387.821924 -274.598162) (xy 387.80634 -274.644843)
			(xy 387.783469 -274.68842) (xy 387.753904 -274.727764) (xy 387.718411 -274.761856) (xy 387.677908 -274.789812)
			(xy 387.633446 -274.81091) (xy 387.586175 -274.824602) (xy 387.53732 -274.830534) (xy 387.488145 -274.828553)
			(xy 387.439926 -274.818709) (xy 387.39391 -274.801257) (xy 387.351289 -274.77665) (xy 387.313168 -274.745525)
			(xy 387.280533 -274.708688) (xy 387.25423 -274.667092) (xy 387.234939 -274.621816) (xy 387.223162 -274.574032)
			(xy 387.219202 -274.524978) (xy 354.045854 -274.524978) (xy 354.049316 -274.528973) (xy 354.078783 -274.574824)
			(xy 354.101424 -274.624401) (xy 354.116779 -274.676697) (xy 354.124536 -274.730645) (xy 354.125022 -274.757896)
			(xy 354.124573 -274.785267) (xy 354.116754 -274.839448) (xy 354.101262 -274.891952) (xy 354.078416 -274.941698)
			(xy 354.048686 -274.987664) (xy 354.031042 -275.008594) (xy 354.030788 -275.008848) (xy 354.025216 -275.015944)
			(xy 354.018961 -275.032854) (xy 354.018596 -275.041868) (xy 354.018596 -275.108924) (xy 354.018943 -275.117942)
			(xy 354.025198 -275.134859) (xy 354.030788 -275.141944) (xy 354.031042 -275.141944) (xy 354.031042 -275.142198)
			(xy 354.04868 -275.163133) (xy 354.078407 -275.2091) (xy 354.101255 -275.258846) (xy 354.116753 -275.311347)
			(xy 354.124582 -275.365526) (xy 354.124583 -275.420268) (xy 354.116754 -275.474447) (xy 354.101257 -275.526949)
			(xy 354.07841 -275.576695) (xy 354.048684 -275.622662) (xy 354.031042 -275.643594) (xy 354.030788 -275.643848)
			(xy 354.025216 -275.650944) (xy 354.018961 -275.667854) (xy 354.018596 -275.676868) (xy 354.018596 -275.743924)
			(xy 354.018943 -275.752942) (xy 354.025198 -275.769859) (xy 354.030788 -275.776944) (xy 354.031042 -275.776944)
			(xy 354.031042 -275.777198) (xy 354.04868 -275.798133) (xy 354.078407 -275.8441) (xy 354.101255 -275.893846)
			(xy 354.116753 -275.946347) (xy 354.124582 -276.000526) (xy 354.124583 -276.046184) (xy 356.66045 -276.046184)
			(xy 356.660895 -276.018813) (xy 356.668716 -275.964632) (xy 356.684209 -275.912129) (xy 356.707056 -275.862382)
			(xy 356.736786 -275.816417) (xy 356.75443 -275.795486) (xy 356.754684 -275.795232) (xy 356.760262 -275.788139)
			(xy 356.766514 -275.771227) (xy 356.766876 -275.762212) (xy 356.766876 -275.695156) (xy 356.766497 -275.686141)
			(xy 356.760265 -275.669224) (xy 356.754684 -275.662136) (xy 356.75443 -275.662136) (xy 356.75443 -275.661882)
			(xy 356.736821 -275.640926) (xy 356.707103 -275.59496) (xy 356.684261 -275.545219) (xy 356.668763 -275.492723)
			(xy 356.660928 -275.438552) (xy 356.66045 -275.411184) (xy 356.660963 -275.383934) (xy 356.66872 -275.32999)
			(xy 356.684075 -275.277698) (xy 356.706715 -275.228124) (xy 356.736179 -275.182275) (xy 356.771868 -275.141086)
			(xy 356.813054 -275.105395) (xy 356.858901 -275.075928) (xy 356.908474 -275.053285) (xy 356.960764 -275.037926)
			(xy 357.014708 -275.030165) (xy 357.041958 -275.029676) (xy 357.069328 -275.030148) (xy 357.123508 -275.037962)
			(xy 357.176012 -275.053448) (xy 357.225759 -275.076289) (xy 357.271725 -275.106014) (xy 357.292656 -275.123656)
			(xy 357.29291 -275.12391) (xy 357.299989 -275.129508) (xy 357.316912 -275.135748) (xy 357.32593 -275.136102)
			(xy 357.392986 -275.136102) (xy 357.402002 -275.135738) (xy 357.418919 -275.129495) (xy 357.426006 -275.12391)
			(xy 357.426006 -275.123656) (xy 357.42626 -275.123656) (xy 357.447193 -275.106015) (xy 357.493161 -275.076291)
			(xy 357.542907 -275.053445) (xy 357.595409 -275.037949) (xy 357.649587 -275.03012) (xy 357.704329 -275.03012)
			(xy 357.758507 -275.037949) (xy 357.811009 -275.053445) (xy 357.860755 -275.076291) (xy 357.906723 -275.106015)
			(xy 357.927656 -275.123656) (xy 357.92791 -275.12391) (xy 357.934989 -275.129508) (xy 357.951912 -275.135748)
			(xy 357.96093 -275.136102) (xy 358.027986 -275.136102) (xy 358.037002 -275.135738) (xy 358.053919 -275.129495)
			(xy 358.061006 -275.12391) (xy 358.061006 -275.123656) (xy 358.06126 -275.123656) (xy 358.082193 -275.106015)
			(xy 358.128161 -275.076291) (xy 358.177907 -275.053445) (xy 358.230409 -275.037949) (xy 358.284587 -275.03012)
			(xy 358.339329 -275.03012) (xy 358.393507 -275.037949) (xy 358.446009 -275.053445) (xy 358.495755 -275.076291)
			(xy 358.541723 -275.106015) (xy 358.562656 -275.123656) (xy 358.56291 -275.12391) (xy 358.569989 -275.129508)
			(xy 358.586912 -275.135748) (xy 358.59593 -275.136102) (xy 358.662986 -275.136102) (xy 358.672002 -275.135738)
			(xy 358.688919 -275.129495) (xy 358.696006 -275.12391) (xy 358.696006 -275.123656) (xy 358.69626 -275.123656)
			(xy 358.717193 -275.106015) (xy 358.763161 -275.076291) (xy 358.812907 -275.053445) (xy 358.865409 -275.037949)
			(xy 358.919587 -275.03012) (xy 358.974329 -275.03012) (xy 359.028507 -275.037949) (xy 359.081009 -275.053445)
			(xy 359.130755 -275.076291) (xy 359.176723 -275.106015) (xy 359.197656 -275.123656) (xy 359.19791 -275.12391)
			(xy 359.204989 -275.129508) (xy 359.221912 -275.135748) (xy 359.23093 -275.136102) (xy 359.297986 -275.136102)
			(xy 359.307002 -275.135738) (xy 359.323919 -275.129495) (xy 359.331006 -275.12391) (xy 359.331006 -275.123656)
			(xy 359.33126 -275.123656) (xy 359.35219 -275.106015) (xy 359.398164 -275.076305) (xy 359.447912 -275.05347)
			(xy 359.500413 -275.037979) (xy 359.554589 -275.03015) (xy 359.581958 -275.029676) (xy 359.609209 -275.030194)
			(xy 359.663157 -275.037945) (xy 359.715453 -275.053295) (xy 359.765032 -275.075932) (xy 359.810885 -275.105394)
			(xy 359.852077 -275.141082) (xy 359.887772 -275.182269) (xy 359.917241 -275.228117) (xy 359.939885 -275.277693)
			(xy 359.955242 -275.329986) (xy 359.963002 -275.383933) (xy 359.963466 -275.411184) (xy 359.962999 -275.438554)
			(xy 359.95775 -275.474938) (xy 387.219202 -275.474938) (xy 387.223162 -275.425884) (xy 387.234939 -275.3781)
			(xy 387.25423 -275.332824) (xy 387.280533 -275.291228) (xy 387.313168 -275.254391) (xy 387.351289 -275.223266)
			(xy 387.39391 -275.198659) (xy 387.439926 -275.181207) (xy 387.488145 -275.171363) (xy 387.53732 -275.169382)
			(xy 387.586175 -275.175314) (xy 387.633446 -275.189006) (xy 387.677908 -275.210104) (xy 387.718411 -275.23806)
			(xy 387.753904 -275.272152) (xy 387.783469 -275.311496) (xy 387.80634 -275.355073) (xy 387.821924 -275.401754)
			(xy 387.829819 -275.450331) (xy 387.830314 -275.474938) (xy 389.119122 -275.474938) (xy 389.123082 -275.425884)
			(xy 389.134859 -275.3781) (xy 389.15415 -275.332824) (xy 389.180453 -275.291228) (xy 389.213088 -275.254391)
			(xy 389.251209 -275.223266) (xy 389.29383 -275.198659) (xy 389.339846 -275.181207) (xy 389.388065 -275.171363)
			(xy 389.43724 -275.169382) (xy 389.486095 -275.175314) (xy 389.533366 -275.189006) (xy 389.577828 -275.210104)
			(xy 389.618331 -275.23806) (xy 389.653824 -275.272152) (xy 389.683389 -275.311496) (xy 389.70626 -275.355073)
			(xy 389.721844 -275.401754) (xy 389.729739 -275.450331) (xy 389.730234 -275.474938) (xy 391.019042 -275.474938)
			(xy 391.023002 -275.425884) (xy 391.034779 -275.3781) (xy 391.05407 -275.332824) (xy 391.080373 -275.291228)
			(xy 391.113008 -275.254391) (xy 391.151129 -275.223266) (xy 391.19375 -275.198659) (xy 391.239766 -275.181207)
			(xy 391.287985 -275.171363) (xy 391.33716 -275.169382) (xy 391.386015 -275.175314) (xy 391.433286 -275.189006)
			(xy 391.477748 -275.210104) (xy 391.518251 -275.23806) (xy 391.553744 -275.272152) (xy 391.583309 -275.311496)
			(xy 391.60618 -275.355073) (xy 391.621764 -275.401754) (xy 391.629659 -275.450331) (xy 391.630154 -275.474938)
			(xy 391.629659 -275.499545) (xy 391.621764 -275.548122) (xy 391.60618 -275.594803) (xy 391.583309 -275.63838)
			(xy 391.553744 -275.677724) (xy 391.518251 -275.711816) (xy 391.477748 -275.739772) (xy 391.433286 -275.76087)
			(xy 391.386015 -275.774562) (xy 391.33716 -275.780494) (xy 391.287985 -275.778513) (xy 391.239766 -275.768669)
			(xy 391.19375 -275.751217) (xy 391.151129 -275.72661) (xy 391.113008 -275.695485) (xy 391.080373 -275.658648)
			(xy 391.05407 -275.617052) (xy 391.034779 -275.571776) (xy 391.023002 -275.523992) (xy 391.019042 -275.474938)
			(xy 389.730234 -275.474938) (xy 389.729739 -275.499545) (xy 389.721844 -275.548122) (xy 389.70626 -275.594803)
			(xy 389.683389 -275.63838) (xy 389.653824 -275.677724) (xy 389.618331 -275.711816) (xy 389.577828 -275.739772)
			(xy 389.533366 -275.76087) (xy 389.486095 -275.774562) (xy 389.43724 -275.780494) (xy 389.388065 -275.778513)
			(xy 389.339846 -275.768669) (xy 389.29383 -275.751217) (xy 389.251209 -275.72661) (xy 389.213088 -275.695485)
			(xy 389.180453 -275.658648) (xy 389.15415 -275.617052) (xy 389.134859 -275.571776) (xy 389.123082 -275.523992)
			(xy 389.119122 -275.474938) (xy 387.830314 -275.474938) (xy 387.829819 -275.499545) (xy 387.821924 -275.548122)
			(xy 387.80634 -275.594803) (xy 387.783469 -275.63838) (xy 387.753904 -275.677724) (xy 387.718411 -275.711816)
			(xy 387.677908 -275.739772) (xy 387.633446 -275.76087) (xy 387.586175 -275.774562) (xy 387.53732 -275.780494)
			(xy 387.488145 -275.778513) (xy 387.439926 -275.768669) (xy 387.39391 -275.751217) (xy 387.351289 -275.72661)
			(xy 387.313168 -275.695485) (xy 387.280533 -275.658648) (xy 387.25423 -275.617052) (xy 387.234939 -275.571776)
			(xy 387.223162 -275.523992) (xy 387.219202 -275.474938) (xy 359.95775 -275.474938) (xy 359.955183 -275.492734)
			(xy 359.939694 -275.545237) (xy 359.916852 -275.594984) (xy 359.887128 -275.640951) (xy 359.869486 -275.661882)
			(xy 359.869232 -275.662136) (xy 359.863658 -275.669231) (xy 359.857406 -275.686142) (xy 359.85704 -275.695156)
			(xy 359.85704 -275.762212) (xy 359.857382 -275.771231) (xy 359.863639 -275.788148) (xy 359.869232 -275.795232)
			(xy 359.869486 -275.795232) (xy 359.869486 -275.795486) (xy 359.88713 -275.816414) (xy 359.916841 -275.862388)
			(xy 359.939677 -275.912136) (xy 359.955167 -275.964638) (xy 359.962993 -276.018815) (xy 359.963466 -276.046184)
			(xy 359.96303 -276.073438) (xy 359.955274 -276.127392) (xy 359.939918 -276.179693) (xy 359.917274 -276.229276)
			(xy 359.887804 -276.275131) (xy 359.852107 -276.316325) (xy 359.810911 -276.352019) (xy 359.765053 -276.381486)
			(xy 359.715469 -276.404127) (xy 359.663167 -276.419479) (xy 359.625455 -276.424898) (xy 384.369068 -276.424898)
			(xy 384.373028 -276.375844) (xy 384.384805 -276.32806) (xy 384.404096 -276.282784) (xy 384.430399 -276.241188)
			(xy 384.463034 -276.204351) (xy 384.501155 -276.173226) (xy 384.543776 -276.148619) (xy 384.589792 -276.131167)
			(xy 384.638011 -276.121323) (xy 384.687186 -276.119342) (xy 384.736041 -276.125274) (xy 384.783312 -276.138966)
			(xy 384.827774 -276.160064) (xy 384.868277 -276.18802) (xy 384.90377 -276.222112) (xy 384.933335 -276.261456)
			(xy 384.956206 -276.305033) (xy 384.97179 -276.351714) (xy 384.979685 -276.400291) (xy 384.98018 -276.424898)
			(xy 385.319028 -276.424898) (xy 385.322988 -276.375844) (xy 385.334765 -276.32806) (xy 385.354056 -276.282784)
			(xy 385.380359 -276.241188) (xy 385.412994 -276.204351) (xy 385.451115 -276.173226) (xy 385.493736 -276.148619)
			(xy 385.539752 -276.131167) (xy 385.587971 -276.121323) (xy 385.637146 -276.119342) (xy 385.686001 -276.125274)
			(xy 385.733272 -276.138966) (xy 385.777734 -276.160064) (xy 385.818237 -276.18802) (xy 385.85373 -276.222112)
			(xy 385.883295 -276.261456) (xy 385.906166 -276.305033) (xy 385.92175 -276.351714) (xy 385.929645 -276.400291)
			(xy 385.93014 -276.424898) (xy 385.929645 -276.449505) (xy 385.92175 -276.498082) (xy 385.906166 -276.544763)
			(xy 385.883295 -276.58834) (xy 385.85373 -276.627684) (xy 385.818237 -276.661776) (xy 385.777734 -276.689732)
			(xy 385.733272 -276.71083) (xy 385.686001 -276.724522) (xy 385.637146 -276.730454) (xy 385.587971 -276.728473)
			(xy 385.539752 -276.718629) (xy 385.493736 -276.701177) (xy 385.451115 -276.67657) (xy 385.412994 -276.645445)
			(xy 385.380359 -276.608608) (xy 385.354056 -276.567012) (xy 385.334765 -276.521736) (xy 385.322988 -276.473952)
			(xy 385.319028 -276.424898) (xy 384.98018 -276.424898) (xy 384.979685 -276.449505) (xy 384.97179 -276.498082)
			(xy 384.956206 -276.544763) (xy 384.933335 -276.58834) (xy 384.90377 -276.627684) (xy 384.868277 -276.661776)
			(xy 384.827774 -276.689732) (xy 384.783312 -276.71083) (xy 384.736041 -276.724522) (xy 384.687186 -276.730454)
			(xy 384.638011 -276.728473) (xy 384.589792 -276.718629) (xy 384.543776 -276.701177) (xy 384.501155 -276.67657)
			(xy 384.463034 -276.645445) (xy 384.430399 -276.608608) (xy 384.404096 -276.567012) (xy 384.384805 -276.521736)
			(xy 384.373028 -276.473952) (xy 384.369068 -276.424898) (xy 359.625455 -276.424898) (xy 359.609212 -276.427232)
			(xy 359.581958 -276.427692) (xy 359.554589 -276.427194) (xy 359.500411 -276.419384) (xy 359.447908 -276.403903)
			(xy 359.398161 -276.381068) (xy 359.352193 -276.35135) (xy 359.33126 -276.333712) (xy 359.331006 -276.333458)
			(xy 359.323926 -276.327863) (xy 359.307004 -276.321622) (xy 359.297986 -276.321266) (xy 359.23093 -276.321266)
			(xy 359.221915 -276.321645) (xy 359.204999 -276.327878) (xy 359.19791 -276.333458) (xy 359.197656 -276.333712)
			(xy 359.176723 -276.351353) (xy 359.130755 -276.381077) (xy 359.081009 -276.403923) (xy 359.028507 -276.419419)
			(xy 358.974329 -276.427248) (xy 358.919587 -276.427248) (xy 358.865409 -276.419419) (xy 358.812907 -276.403923)
			(xy 358.763161 -276.381077) (xy 358.717193 -276.351353) (xy 358.69626 -276.333712) (xy 358.696006 -276.333458)
			(xy 358.688926 -276.327863) (xy 358.672004 -276.321622) (xy 358.662986 -276.321266) (xy 358.59593 -276.321266)
			(xy 358.586915 -276.321645) (xy 358.569999 -276.327878) (xy 358.56291 -276.333458) (xy 358.56291 -276.333712)
			(xy 358.562656 -276.333712) (xy 358.541723 -276.351353) (xy 358.495755 -276.381077) (xy 358.446009 -276.403923)
			(xy 358.393507 -276.419419) (xy 358.339329 -276.427248) (xy 358.284587 -276.427248) (xy 358.230409 -276.419419)
			(xy 358.177907 -276.403923) (xy 358.128161 -276.381077) (xy 358.082193 -276.351353) (xy 358.06126 -276.333712)
			(xy 358.061006 -276.333458) (xy 358.053926 -276.327863) (xy 358.037004 -276.321622) (xy 358.027986 -276.321266)
			(xy 357.96093 -276.321266) (xy 357.951915 -276.321645) (xy 357.934999 -276.327878) (xy 357.92791 -276.333458)
			(xy 357.92791 -276.333712) (xy 357.927656 -276.333712) (xy 357.906723 -276.351353) (xy 357.860755 -276.381077)
			(xy 357.811009 -276.403923) (xy 357.758507 -276.419419) (xy 357.704329 -276.427248) (xy 357.649587 -276.427248)
			(xy 357.595409 -276.419419) (xy 357.542907 -276.403923) (xy 357.493161 -276.381077) (xy 357.447193 -276.351353)
			(xy 357.42626 -276.333712) (xy 357.426006 -276.333458) (xy 357.418926 -276.327863) (xy 357.402004 -276.321622)
			(xy 357.392986 -276.321266) (xy 357.32593 -276.321266) (xy 357.316915 -276.321645) (xy 357.299999 -276.327878)
			(xy 357.29291 -276.333458) (xy 357.29291 -276.333712) (xy 357.292656 -276.333712) (xy 357.271715 -276.35134)
			(xy 357.225745 -276.381053) (xy 357.175999 -276.403891) (xy 357.123501 -276.419385) (xy 357.069327 -276.427216)
			(xy 357.041958 -276.427692) (xy 357.014705 -276.427261) (xy 356.960754 -276.419499) (xy 356.908458 -276.404137)
			(xy 356.858879 -276.38149) (xy 356.813028 -276.352018) (xy 356.771838 -276.316321) (xy 356.736147 -276.275125)
			(xy 356.706682 -276.22927) (xy 356.684042 -276.179688) (xy 356.668689 -276.127389) (xy 356.660935 -276.073437)
			(xy 356.66045 -276.046184) (xy 354.124583 -276.046184) (xy 354.124583 -276.055268) (xy 354.116754 -276.109447)
			(xy 354.101257 -276.161949) (xy 354.07841 -276.211695) (xy 354.048684 -276.257662) (xy 354.031042 -276.278594)
			(xy 354.030788 -276.278848) (xy 354.025216 -276.285944) (xy 354.018961 -276.302854) (xy 354.018596 -276.311868)
			(xy 354.018596 -276.378924) (xy 354.018943 -276.387942) (xy 354.025198 -276.404859) (xy 354.030788 -276.411944)
			(xy 354.031042 -276.411944) (xy 354.031042 -276.412198) (xy 354.048701 -276.433114) (xy 354.078408 -276.479092)
			(xy 354.10124 -276.528844) (xy 354.116727 -276.581348) (xy 354.124551 -276.635526) (xy 354.125022 -276.662896)
			(xy 354.124536 -276.690147) (xy 354.11678 -276.744095) (xy 354.101425 -276.79639) (xy 354.078783 -276.845967)
			(xy 354.049317 -276.891817) (xy 354.013626 -276.933008) (xy 353.972435 -276.968699) (xy 353.926585 -276.998165)
			(xy 353.877008 -277.020807) (xy 353.824713 -277.036162) (xy 353.770765 -277.043918) (xy 353.716263 -277.043918)
			(xy 353.662315 -277.036162) (xy 353.61002 -277.020807) (xy 353.560443 -276.998165) (xy 353.514593 -276.968699)
			(xy 353.473402 -276.933008) (xy 353.437711 -276.891817) (xy 353.408245 -276.845967) (xy 353.385603 -276.79639)
			(xy 353.370248 -276.744095) (xy 353.362492 -276.690147) (xy 353.362006 -276.662896) (xy 353.362542 -276.633418)
			(xy 353.371612 -276.575165) (xy 353.389535 -276.519) (xy 353.415885 -276.466261) (xy 353.450035 -276.418203)
			(xy 353.47021 -276.396704) (xy 353.476737 -276.389364) (xy 353.484187 -276.371208) (xy 353.484688 -276.361398)
			(xy 353.484688 -276.308058) (xy 353.477322 -276.3012) (xy 353.469975 -276.294682) (xy 353.451824 -276.287227)
			(xy 353.442016 -276.286722) (xy 353.410012 -276.286722) (xy 353.400199 -276.287218) (xy 353.382034 -276.294656)
			(xy 353.374706 -276.3012) (xy 353.353196 -276.321362) (xy 353.30514 -276.35551) (xy 353.252404 -276.38186)
			(xy 353.196241 -276.399783) (xy 353.13799 -276.408854) (xy 353.108514 -276.409404) (xy 353.081261 -276.408932)
			(xy 353.027311 -276.401176) (xy 352.975013 -276.385822) (xy 352.925432 -276.363181) (xy 352.879579 -276.333714)
			(xy 352.838386 -276.298021) (xy 352.802692 -276.256829) (xy 352.773224 -276.210977) (xy 352.750581 -276.161397)
			(xy 352.735226 -276.109099) (xy 352.727469 -276.055149) (xy 352.727006 -276.027896) (xy 350.53524 -276.027896)
			(xy 350.53524 -277.634192) (xy 352.285046 -277.634192) (xy 352.285601 -277.605067) (xy 352.294469 -277.547495)
			(xy 352.311982 -277.49194) (xy 352.337734 -277.43969) (xy 352.371127 -277.391961) (xy 352.411385 -277.349861)
			(xy 352.434144 -277.331678) (xy 352.443288 -277.324566) (xy 352.453702 -277.304246) (xy 352.455988 -277.213568)
			(xy 352.455627 -277.202192) (xy 352.446251 -277.181483) (xy 352.437954 -277.17369) (xy 352.417226 -277.155498)
			(xy 352.380759 -277.114124) (xy 352.35063 -277.06793) (xy 352.327467 -277.017878) (xy 352.311754 -276.965013)
			(xy 352.303818 -276.910436) (xy 352.303334 -276.88286) (xy 352.30382 -276.855609) (xy 352.311576 -276.801661)
			(xy 352.326931 -276.749366) (xy 352.349573 -276.699789) (xy 352.379039 -276.653939) (xy 352.41473 -276.612748)
			(xy 352.455921 -276.577057) (xy 352.501771 -276.547591) (xy 352.551348 -276.524949) (xy 352.603643 -276.509594)
			(xy 352.657591 -276.501838) (xy 352.712093 -276.501838) (xy 352.766041 -276.509594) (xy 352.818336 -276.524949)
			(xy 352.867913 -276.547591) (xy 352.913763 -276.577057) (xy 352.954954 -276.612748) (xy 352.990645 -276.653939)
			(xy 353.020111 -276.699789) (xy 353.042753 -276.749366) (xy 353.058108 -276.801661) (xy 353.065864 -276.855609)
			(xy 353.06635 -276.88286) (xy 353.065762 -276.911984) (xy 353.056902 -276.969554) (xy 353.039395 -277.025109)
			(xy 353.013649 -277.077359) (xy 352.980262 -277.125088) (xy 352.940009 -277.16719) (xy 352.917252 -277.185374)
			(xy 352.908108 -277.192486) (xy 352.897694 -277.212806) (xy 352.895408 -277.303484) (xy 352.895798 -277.314857)
			(xy 352.905153 -277.335566) (xy 352.913442 -277.343362) (xy 352.934146 -277.36158) (xy 352.970615 -277.402949)
			(xy 353.000747 -277.449137) (xy 353.023914 -277.499184) (xy 353.039632 -277.552045) (xy 353.040313 -277.556722)
			(xy 353.207826 -277.556722) (xy 353.211897 -277.5011) (xy 353.224023 -277.446663) (xy 353.243946 -277.394572)
			(xy 353.271242 -277.345937) (xy 353.305328 -277.301794) (xy 353.345477 -277.263085) (xy 353.390835 -277.230634)
			(xy 353.440435 -277.205133) (xy 353.493219 -277.187126) (xy 353.548062 -277.176996) (xy 353.603796 -277.174959)
			(xy 353.659233 -277.181059) (xy 353.71319 -277.195165) (xy 353.764519 -277.216977) (xy 353.812125 -277.246031)
			(xy 353.854993 -277.281706) (xy 353.89221 -277.323243) (xy 353.922983 -277.369756) (xy 353.946655 -277.420253)
			(xy 353.962723 -277.47366) (xy 353.970843 -277.528836) (xy 353.971352 -277.556722) (xy 353.970843 -277.584608)
			(xy 353.962723 -277.639784) (xy 353.961349 -277.644352) (xy 359.283762 -277.644352) (xy 359.284178 -277.618036)
			(xy 359.29142 -277.565904) (xy 359.305748 -277.51526) (xy 359.32689 -277.467061) (xy 359.354446 -277.422219)
			(xy 359.387895 -277.381582) (xy 359.406952 -277.363428) (xy 359.414336 -277.355891) (xy 359.422872 -277.336623)
			(xy 359.423462 -277.32609) (xy 359.423462 -277.251414) (xy 359.42295 -277.240862) (xy 359.414404 -277.221566)
			(xy 359.406952 -277.214076) (xy 359.387883 -277.195935) (xy 359.354429 -277.155301) (xy 359.326873 -277.110457)
			(xy 359.305737 -277.062254) (xy 359.291422 -277.011604) (xy 359.2842 -276.959469) (xy 359.283762 -276.933152)
			(xy 359.284248 -276.905901) (xy 359.292004 -276.851953) (xy 359.307359 -276.799658) (xy 359.330001 -276.750081)
			(xy 359.359467 -276.704231) (xy 359.395158 -276.66304) (xy 359.436349 -276.627349) (xy 359.482199 -276.597883)
			(xy 359.531776 -276.575241) (xy 359.584071 -276.559886) (xy 359.638019 -276.55213) (xy 359.692521 -276.55213)
			(xy 359.746469 -276.559886) (xy 359.798764 -276.575241) (xy 359.848341 -276.597883) (xy 359.894191 -276.627349)
			(xy 359.935382 -276.66304) (xy 359.971073 -276.704231) (xy 360.000539 -276.750081) (xy 360.023181 -276.799658)
			(xy 360.038536 -276.851953) (xy 360.046292 -276.905901) (xy 360.046778 -276.933152) (xy 360.046352 -276.959467)
			(xy 360.03911 -277.011598) (xy 360.024783 -277.062242) (xy 360.003643 -277.110441) (xy 359.976089 -277.155283)
			(xy 359.942643 -277.195921) (xy 359.923588 -277.214076) (xy 359.916193 -277.221603) (xy 359.907665 -277.240879)
			(xy 359.907078 -277.251414) (xy 359.907078 -277.32609) (xy 359.907605 -277.33664) (xy 359.916142 -277.355935)
			(xy 359.923588 -277.363428) (xy 359.93559 -277.374858) (xy 386.269242 -277.374858) (xy 386.273202 -277.325804)
			(xy 386.284979 -277.27802) (xy 386.30427 -277.232744) (xy 386.330573 -277.191148) (xy 386.363208 -277.154311)
			(xy 386.401329 -277.123186) (xy 386.44395 -277.098579) (xy 386.489966 -277.081127) (xy 386.538185 -277.071283)
			(xy 386.58736 -277.069302) (xy 386.636215 -277.075234) (xy 386.683486 -277.088926) (xy 386.727948 -277.110024)
			(xy 386.768451 -277.13798) (xy 386.803944 -277.172072) (xy 386.833509 -277.211416) (xy 386.85638 -277.254993)
			(xy 386.871964 -277.301674) (xy 386.879859 -277.350251) (xy 386.880354 -277.374858) (xy 388.169162 -277.374858)
			(xy 388.173122 -277.325804) (xy 388.184899 -277.27802) (xy 388.20419 -277.232744) (xy 388.230493 -277.191148)
			(xy 388.263128 -277.154311) (xy 388.301249 -277.123186) (xy 388.34387 -277.098579) (xy 388.389886 -277.081127)
			(xy 388.438105 -277.071283) (xy 388.48728 -277.069302) (xy 388.536135 -277.075234) (xy 388.583406 -277.088926)
			(xy 388.627868 -277.110024) (xy 388.668371 -277.13798) (xy 388.703864 -277.172072) (xy 388.733429 -277.211416)
			(xy 388.7563 -277.254993) (xy 388.771884 -277.301674) (xy 388.779779 -277.350251) (xy 388.780274 -277.374858)
			(xy 390.069082 -277.374858) (xy 390.073042 -277.325804) (xy 390.084819 -277.27802) (xy 390.10411 -277.232744)
			(xy 390.130413 -277.191148) (xy 390.163048 -277.154311) (xy 390.201169 -277.123186) (xy 390.24379 -277.098579)
			(xy 390.289806 -277.081127) (xy 390.338025 -277.071283) (xy 390.3872 -277.069302) (xy 390.436055 -277.075234)
			(xy 390.483326 -277.088926) (xy 390.527788 -277.110024) (xy 390.568291 -277.13798) (xy 390.603784 -277.172072)
			(xy 390.633349 -277.211416) (xy 390.65622 -277.254993) (xy 390.671804 -277.301674) (xy 390.679699 -277.350251)
			(xy 390.680194 -277.374858) (xy 390.679699 -277.399465) (xy 390.671804 -277.448042) (xy 390.65622 -277.494723)
			(xy 390.633349 -277.5383) (xy 390.603784 -277.577644) (xy 390.568291 -277.611736) (xy 390.527788 -277.639692)
			(xy 390.483326 -277.66079) (xy 390.436055 -277.674482) (xy 390.3872 -277.680414) (xy 390.338025 -277.678433)
			(xy 390.289806 -277.668589) (xy 390.24379 -277.651137) (xy 390.201169 -277.62653) (xy 390.163048 -277.595405)
			(xy 390.130413 -277.558568) (xy 390.10411 -277.516972) (xy 390.084819 -277.471696) (xy 390.073042 -277.423912)
			(xy 390.069082 -277.374858) (xy 388.780274 -277.374858) (xy 388.779779 -277.399465) (xy 388.771884 -277.448042)
			(xy 388.7563 -277.494723) (xy 388.733429 -277.5383) (xy 388.703864 -277.577644) (xy 388.668371 -277.611736)
			(xy 388.627868 -277.639692) (xy 388.583406 -277.66079) (xy 388.536135 -277.674482) (xy 388.48728 -277.680414)
			(xy 388.438105 -277.678433) (xy 388.389886 -277.668589) (xy 388.34387 -277.651137) (xy 388.301249 -277.62653)
			(xy 388.263128 -277.595405) (xy 388.230493 -277.558568) (xy 388.20419 -277.516972) (xy 388.184899 -277.471696)
			(xy 388.173122 -277.423912) (xy 388.169162 -277.374858) (xy 386.880354 -277.374858) (xy 386.879859 -277.399465)
			(xy 386.871964 -277.448042) (xy 386.85638 -277.494723) (xy 386.833509 -277.5383) (xy 386.803944 -277.577644)
			(xy 386.768451 -277.611736) (xy 386.727948 -277.639692) (xy 386.683486 -277.66079) (xy 386.636215 -277.674482)
			(xy 386.58736 -277.680414) (xy 386.538185 -277.678433) (xy 386.489966 -277.668589) (xy 386.44395 -277.651137)
			(xy 386.401329 -277.62653) (xy 386.363208 -277.595405) (xy 386.330573 -277.558568) (xy 386.30427 -277.516972)
			(xy 386.284979 -277.471696) (xy 386.273202 -277.423912) (xy 386.269242 -277.374858) (xy 359.93559 -277.374858)
			(xy 359.942648 -277.381579) (xy 359.976105 -277.42221) (xy 360.003664 -277.467051) (xy 360.024802 -277.515252)
			(xy 360.039118 -277.565901) (xy 360.046341 -277.618036) (xy 360.046778 -277.644352) (xy 360.046292 -277.671603)
			(xy 360.038536 -277.725551) (xy 360.023181 -277.777846) (xy 360.000539 -277.827423) (xy 359.986134 -277.849838)
			(xy 392.443982 -277.849838) (xy 392.447942 -277.800784) (xy 392.459719 -277.753) (xy 392.47901 -277.707724)
			(xy 392.505313 -277.666128) (xy 392.537948 -277.629291) (xy 392.576069 -277.598166) (xy 392.61869 -277.573559)
			(xy 392.664706 -277.556107) (xy 392.712925 -277.546263) (xy 392.7621 -277.544282) (xy 392.810955 -277.550214)
			(xy 392.858226 -277.563906) (xy 392.902688 -277.585004) (xy 392.943191 -277.61296) (xy 392.978684 -277.647052)
			(xy 393.008249 -277.686396) (xy 393.03112 -277.729973) (xy 393.046704 -277.776654) (xy 393.054599 -277.825231)
			(xy 393.055094 -277.849838) (xy 394.344156 -277.849838) (xy 394.348116 -277.800784) (xy 394.359893 -277.753)
			(xy 394.379184 -277.707724) (xy 394.405487 -277.666128) (xy 394.438122 -277.629291) (xy 394.476243 -277.598166)
			(xy 394.518864 -277.573559) (xy 394.56488 -277.556107) (xy 394.613099 -277.546263) (xy 394.662274 -277.544282)
			(xy 394.711129 -277.550214) (xy 394.7584 -277.563906) (xy 394.802862 -277.585004) (xy 394.843365 -277.61296)
			(xy 394.878858 -277.647052) (xy 394.908423 -277.686396) (xy 394.931294 -277.729973) (xy 394.946878 -277.776654)
			(xy 394.954773 -277.825231) (xy 394.955268 -277.849838) (xy 394.954773 -277.874445) (xy 394.946878 -277.923022)
			(xy 394.931294 -277.969703) (xy 394.908423 -278.01328) (xy 394.878858 -278.052624) (xy 394.843365 -278.086716)
			(xy 394.802862 -278.114672) (xy 394.7584 -278.13577) (xy 394.711129 -278.149462) (xy 394.662274 -278.155394)
			(xy 394.613099 -278.153413) (xy 394.56488 -278.143569) (xy 394.518864 -278.126117) (xy 394.476243 -278.10151)
			(xy 394.438122 -278.070385) (xy 394.405487 -278.033548) (xy 394.379184 -277.991952) (xy 394.359893 -277.946676)
			(xy 394.348116 -277.898892) (xy 394.344156 -277.849838) (xy 393.055094 -277.849838) (xy 393.054599 -277.874445)
			(xy 393.046704 -277.923022) (xy 393.03112 -277.969703) (xy 393.008249 -278.01328) (xy 392.978684 -278.052624)
			(xy 392.943191 -278.086716) (xy 392.902688 -278.114672) (xy 392.858226 -278.13577) (xy 392.810955 -278.149462)
			(xy 392.7621 -278.155394) (xy 392.712925 -278.153413) (xy 392.664706 -278.143569) (xy 392.61869 -278.126117)
			(xy 392.576069 -278.10151) (xy 392.537948 -278.070385) (xy 392.505313 -278.033548) (xy 392.47901 -277.991952)
			(xy 392.459719 -277.946676) (xy 392.447942 -277.898892) (xy 392.443982 -277.849838) (xy 359.986134 -277.849838)
			(xy 359.971073 -277.873273) (xy 359.935382 -277.914464) (xy 359.894191 -277.950155) (xy 359.848341 -277.979621)
			(xy 359.798764 -278.002263) (xy 359.746469 -278.017618) (xy 359.692521 -278.025374) (xy 359.638019 -278.025374)
			(xy 359.584071 -278.017618) (xy 359.531776 -278.002263) (xy 359.482199 -277.979621) (xy 359.436349 -277.950155)
			(xy 359.395158 -277.914464) (xy 359.359467 -277.873273) (xy 359.330001 -277.827423) (xy 359.307359 -277.777846)
			(xy 359.292004 -277.725551) (xy 359.284248 -277.671603) (xy 359.283762 -277.644352) (xy 353.961349 -277.644352)
			(xy 353.946655 -277.693191) (xy 353.922983 -277.743688) (xy 353.89221 -277.790201) (xy 353.854993 -277.831738)
			(xy 353.812125 -277.867413) (xy 353.764519 -277.896467) (xy 353.71319 -277.918279) (xy 353.659233 -277.932385)
			(xy 353.603796 -277.938485) (xy 353.548062 -277.936448) (xy 353.493219 -277.926318) (xy 353.440435 -277.908311)
			(xy 353.390835 -277.88281) (xy 353.345477 -277.850359) (xy 353.305328 -277.81165) (xy 353.271242 -277.767507)
			(xy 353.243946 -277.718872) (xy 353.224023 -277.666781) (xy 353.211897 -277.612344) (xy 353.207826 -277.556722)
			(xy 353.040313 -277.556722) (xy 353.047575 -277.606618) (xy 353.048062 -277.634192) (xy 353.047576 -277.661443)
			(xy 353.03982 -277.715391) (xy 353.024465 -277.767686) (xy 353.001823 -277.817263) (xy 352.972357 -277.863113)
			(xy 352.936666 -277.904304) (xy 352.895475 -277.939995) (xy 352.849625 -277.969461) (xy 352.800048 -277.992103)
			(xy 352.747753 -278.007458) (xy 352.693805 -278.015214) (xy 352.639303 -278.015214) (xy 352.585355 -278.007458)
			(xy 352.53306 -277.992103) (xy 352.483483 -277.969461) (xy 352.437633 -277.939995) (xy 352.396442 -277.904304)
			(xy 352.360751 -277.863113) (xy 352.331285 -277.817263) (xy 352.308643 -277.767686) (xy 352.293288 -277.715391)
			(xy 352.285532 -277.661443) (xy 352.285046 -277.634192) (xy 350.53524 -277.634192) (xy 350.53524 -278.3459)
			(xy 350.535655 -278.355971) (xy 350.543382 -278.374569) (xy 350.550226 -278.381968) (xy 351.434908 -279.26665)
			(xy 351.442317 -279.273479) (xy 351.460909 -279.281207) (xy 351.470976 -279.281636) (xy 355.210364 -279.281636)
			(xy 355.240283 -279.282229) (xy 355.299383 -279.291594) (xy 355.356293 -279.310084) (xy 355.409611 -279.337244)
			(xy 355.458028 -279.372407) (xy 355.479604 -279.393142) (xy 355.701854 -279.615646) (xy 355.709288 -279.622362)
			(xy 355.727788 -279.629998) (xy 355.747802 -279.629998) (xy 355.766302 -279.622362) (xy 355.773736 -279.615646)
			(xy 355.842824 -279.546812) (xy 355.849542 -279.53935) (xy 355.857118 -279.520776) (xy 355.857556 -279.510744)
			(xy 355.857556 -278.650954) (xy 355.858118 -278.620975) (xy 355.867516 -278.561759) (xy 355.886057 -278.504741)
			(xy 355.913286 -278.451322) (xy 355.948533 -278.402819) (xy 355.969316 -278.381206) (xy 356.27691 -278.073612)
			(xy 356.298486 -278.052787) (xy 356.346994 -278.017536) (xy 356.40042 -277.99031) (xy 356.45745 -277.971781)
			(xy 356.516676 -277.962405) (xy 356.546658 -277.961852) (xy 357.344472 -277.961852) (xy 357.374449 -277.962462)
			(xy 357.433663 -277.971848) (xy 357.490681 -277.990378) (xy 357.5441 -278.017597) (xy 357.592605 -278.052833)
			(xy 357.61422 -278.073612) (xy 358.681528 -279.141174) (xy 358.688927 -279.148015) (xy 358.707527 -279.155735)
			(xy 358.717596 -279.15616) (xy 360.609388 -279.15616) (xy 360.619458 -279.155739) (xy 360.638056 -279.148017)
			(xy 360.645456 -279.141174) (xy 361.712764 -278.073612) (xy 361.73436 -278.052809) (xy 361.782863 -278.017555)
			(xy 361.836284 -277.990325) (xy 361.893309 -277.971791) (xy 361.952531 -277.962409) (xy 361.982512 -277.961852)
			(xy 362.657136 -277.961852) (xy 362.687114 -277.962422) (xy 362.74633 -277.971818) (xy 362.803349 -277.990357)
			(xy 362.856767 -278.017585) (xy 362.905271 -278.05283) (xy 362.926884 -278.073612) (xy 363.17809 -278.324818)
			(xy 386.269242 -278.324818) (xy 386.273202 -278.275764) (xy 386.284979 -278.22798) (xy 386.30427 -278.182704)
			(xy 386.330573 -278.141108) (xy 386.363208 -278.104271) (xy 386.401329 -278.073146) (xy 386.44395 -278.048539)
			(xy 386.489966 -278.031087) (xy 386.538185 -278.021243) (xy 386.58736 -278.019262) (xy 386.636215 -278.025194)
			(xy 386.683486 -278.038886) (xy 386.727948 -278.059984) (xy 386.768451 -278.08794) (xy 386.803944 -278.122032)
			(xy 386.833509 -278.161376) (xy 386.85638 -278.204953) (xy 386.871964 -278.251634) (xy 386.879859 -278.300211)
			(xy 386.880354 -278.324818) (xy 388.169162 -278.324818) (xy 388.173122 -278.275764) (xy 388.184899 -278.22798)
			(xy 388.20419 -278.182704) (xy 388.230493 -278.141108) (xy 388.263128 -278.104271) (xy 388.301249 -278.073146)
			(xy 388.34387 -278.048539) (xy 388.389886 -278.031087) (xy 388.438105 -278.021243) (xy 388.48728 -278.019262)
			(xy 388.536135 -278.025194) (xy 388.583406 -278.038886) (xy 388.627868 -278.059984) (xy 388.668371 -278.08794)
			(xy 388.703864 -278.122032) (xy 388.733429 -278.161376) (xy 388.7563 -278.204953) (xy 388.771884 -278.251634)
			(xy 388.779779 -278.300211) (xy 388.780274 -278.324818) (xy 390.069082 -278.324818) (xy 390.073042 -278.275764)
			(xy 390.084819 -278.22798) (xy 390.10411 -278.182704) (xy 390.130413 -278.141108) (xy 390.163048 -278.104271)
			(xy 390.201169 -278.073146) (xy 390.24379 -278.048539) (xy 390.289806 -278.031087) (xy 390.338025 -278.021243)
			(xy 390.3872 -278.019262) (xy 390.436055 -278.025194) (xy 390.483326 -278.038886) (xy 390.527788 -278.059984)
			(xy 390.568291 -278.08794) (xy 390.603784 -278.122032) (xy 390.633349 -278.161376) (xy 390.65622 -278.204953)
			(xy 390.671804 -278.251634) (xy 390.679699 -278.300211) (xy 390.680194 -278.324818) (xy 390.679699 -278.349425)
			(xy 390.671804 -278.398002) (xy 390.65622 -278.444683) (xy 390.633349 -278.48826) (xy 390.603784 -278.527604)
			(xy 390.568291 -278.561696) (xy 390.527788 -278.589652) (xy 390.483326 -278.61075) (xy 390.436055 -278.624442)
			(xy 390.3872 -278.630374) (xy 390.338025 -278.628393) (xy 390.289806 -278.618549) (xy 390.24379 -278.601097)
			(xy 390.201169 -278.57649) (xy 390.163048 -278.545365) (xy 390.130413 -278.508528) (xy 390.10411 -278.466932)
			(xy 390.084819 -278.421656) (xy 390.073042 -278.373872) (xy 390.069082 -278.324818) (xy 388.780274 -278.324818)
			(xy 388.779779 -278.349425) (xy 388.771884 -278.398002) (xy 388.7563 -278.444683) (xy 388.733429 -278.48826)
			(xy 388.703864 -278.527604) (xy 388.668371 -278.561696) (xy 388.627868 -278.589652) (xy 388.583406 -278.61075)
			(xy 388.536135 -278.624442) (xy 388.48728 -278.630374) (xy 388.438105 -278.628393) (xy 388.389886 -278.618549)
			(xy 388.34387 -278.601097) (xy 388.301249 -278.57649) (xy 388.263128 -278.545365) (xy 388.230493 -278.508528)
			(xy 388.20419 -278.466932) (xy 388.184899 -278.421656) (xy 388.173122 -278.373872) (xy 388.169162 -278.324818)
			(xy 386.880354 -278.324818) (xy 386.879859 -278.349425) (xy 386.871964 -278.398002) (xy 386.85638 -278.444683)
			(xy 386.833509 -278.48826) (xy 386.803944 -278.527604) (xy 386.768451 -278.561696) (xy 386.727948 -278.589652)
			(xy 386.683486 -278.61075) (xy 386.636215 -278.624442) (xy 386.58736 -278.630374) (xy 386.538185 -278.628393)
			(xy 386.489966 -278.618549) (xy 386.44395 -278.601097) (xy 386.401329 -278.57649) (xy 386.363208 -278.545365)
			(xy 386.330573 -278.508528) (xy 386.30427 -278.466932) (xy 386.284979 -278.421656) (xy 386.273202 -278.373872)
			(xy 386.269242 -278.324818) (xy 363.17809 -278.324818) (xy 363.428534 -278.575262) (xy 363.44926 -278.596844)
			(xy 363.484401 -278.645271) (xy 363.511552 -278.69859) (xy 363.530048 -278.755493) (xy 363.537085 -278.799798)
			(xy 392.443982 -278.799798) (xy 392.447942 -278.750744) (xy 392.459719 -278.70296) (xy 392.47901 -278.657684)
			(xy 392.505313 -278.616088) (xy 392.537948 -278.579251) (xy 392.576069 -278.548126) (xy 392.61869 -278.523519)
			(xy 392.664706 -278.506067) (xy 392.712925 -278.496223) (xy 392.7621 -278.494242) (xy 392.810955 -278.500174)
			(xy 392.858226 -278.513866) (xy 392.902688 -278.534964) (xy 392.943191 -278.56292) (xy 392.978684 -278.597012)
			(xy 393.008249 -278.636356) (xy 393.03112 -278.679933) (xy 393.046704 -278.726614) (xy 393.054599 -278.775191)
			(xy 393.055094 -278.799798) (xy 394.344156 -278.799798) (xy 394.348116 -278.750744) (xy 394.359893 -278.70296)
			(xy 394.379184 -278.657684) (xy 394.405487 -278.616088) (xy 394.438122 -278.579251) (xy 394.476243 -278.548126)
			(xy 394.518864 -278.523519) (xy 394.56488 -278.506067) (xy 394.613099 -278.496223) (xy 394.662274 -278.494242)
			(xy 394.711129 -278.500174) (xy 394.7584 -278.513866) (xy 394.802862 -278.534964) (xy 394.843365 -278.56292)
			(xy 394.878858 -278.597012) (xy 394.908423 -278.636356) (xy 394.931294 -278.679933) (xy 394.946878 -278.726614)
			(xy 394.954773 -278.775191) (xy 394.955268 -278.799798) (xy 394.954773 -278.824405) (xy 394.946878 -278.872982)
			(xy 394.931294 -278.919663) (xy 394.908423 -278.96324) (xy 394.878858 -279.002584) (xy 394.843365 -279.036676)
			(xy 394.802862 -279.064632) (xy 394.7584 -279.08573) (xy 394.711129 -279.099422) (xy 394.662274 -279.105354)
			(xy 394.613099 -279.103373) (xy 394.56488 -279.093529) (xy 394.518864 -279.076077) (xy 394.476243 -279.05147)
			(xy 394.438122 -279.020345) (xy 394.405487 -278.983508) (xy 394.379184 -278.941912) (xy 394.359893 -278.896636)
			(xy 394.348116 -278.848852) (xy 394.344156 -278.799798) (xy 393.055094 -278.799798) (xy 393.054599 -278.824405)
			(xy 393.046704 -278.872982) (xy 393.03112 -278.919663) (xy 393.008249 -278.96324) (xy 392.978684 -279.002584)
			(xy 392.943191 -279.036676) (xy 392.902688 -279.064632) (xy 392.858226 -279.08573) (xy 392.810955 -279.099422)
			(xy 392.7621 -279.105354) (xy 392.712925 -279.103373) (xy 392.664706 -279.093529) (xy 392.61869 -279.076077)
			(xy 392.576069 -279.05147) (xy 392.537948 -279.020345) (xy 392.505313 -278.983508) (xy 392.47901 -278.941912)
			(xy 392.459719 -278.896636) (xy 392.447942 -278.848852) (xy 392.443982 -278.799798) (xy 363.537085 -278.799798)
			(xy 363.539434 -278.814586) (xy 363.54004 -278.844502) (xy 363.54004 -279.21077) (xy 363.540471 -279.220839)
			(xy 363.548187 -279.239437) (xy 363.555026 -279.246838) (xy 363.582978 -279.274778) (xy 384.369068 -279.274778)
			(xy 384.373028 -279.225724) (xy 384.384805 -279.17794) (xy 384.404096 -279.132664) (xy 384.430399 -279.091068)
			(xy 384.463034 -279.054231) (xy 384.501155 -279.023106) (xy 384.543776 -278.998499) (xy 384.589792 -278.981047)
			(xy 384.638011 -278.971203) (xy 384.687186 -278.969222) (xy 384.736041 -278.975154) (xy 384.783312 -278.988846)
			(xy 384.827774 -279.009944) (xy 384.868277 -279.0379) (xy 384.90377 -279.071992) (xy 384.933335 -279.111336)
			(xy 384.956206 -279.154913) (xy 384.97179 -279.201594) (xy 384.979685 -279.250171) (xy 384.98018 -279.274778)
			(xy 385.319028 -279.274778) (xy 385.322988 -279.225724) (xy 385.334765 -279.17794) (xy 385.354056 -279.132664)
			(xy 385.380359 -279.091068) (xy 385.412994 -279.054231) (xy 385.451115 -279.023106) (xy 385.493736 -278.998499)
			(xy 385.539752 -278.981047) (xy 385.587971 -278.971203) (xy 385.637146 -278.969222) (xy 385.686001 -278.975154)
			(xy 385.733272 -278.988846) (xy 385.777734 -279.009944) (xy 385.818237 -279.0379) (xy 385.85373 -279.071992)
			(xy 385.883295 -279.111336) (xy 385.906166 -279.154913) (xy 385.92175 -279.201594) (xy 385.929645 -279.250171)
			(xy 385.93014 -279.274778) (xy 387.219202 -279.274778) (xy 387.223162 -279.225724) (xy 387.234939 -279.17794)
			(xy 387.25423 -279.132664) (xy 387.280533 -279.091068) (xy 387.313168 -279.054231) (xy 387.351289 -279.023106)
			(xy 387.39391 -278.998499) (xy 387.439926 -278.981047) (xy 387.488145 -278.971203) (xy 387.53732 -278.969222)
			(xy 387.586175 -278.975154) (xy 387.633446 -278.988846) (xy 387.677908 -279.009944) (xy 387.718411 -279.0379)
			(xy 387.753904 -279.071992) (xy 387.783469 -279.111336) (xy 387.80634 -279.154913) (xy 387.821924 -279.201594)
			(xy 387.829819 -279.250171) (xy 387.830314 -279.274778) (xy 389.119122 -279.274778) (xy 389.123082 -279.225724)
			(xy 389.134859 -279.17794) (xy 389.15415 -279.132664) (xy 389.180453 -279.091068) (xy 389.213088 -279.054231)
			(xy 389.251209 -279.023106) (xy 389.29383 -278.998499) (xy 389.339846 -278.981047) (xy 389.388065 -278.971203)
			(xy 389.43724 -278.969222) (xy 389.486095 -278.975154) (xy 389.533366 -278.988846) (xy 389.577828 -279.009944)
			(xy 389.618331 -279.0379) (xy 389.653824 -279.071992) (xy 389.683389 -279.111336) (xy 389.70626 -279.154913)
			(xy 389.721844 -279.201594) (xy 389.729739 -279.250171) (xy 389.730234 -279.274778) (xy 389.729739 -279.299385)
			(xy 389.721844 -279.347962) (xy 389.70626 -279.394643) (xy 389.683389 -279.43822) (xy 389.653824 -279.477564)
			(xy 389.618331 -279.511656) (xy 389.577828 -279.539612) (xy 389.533366 -279.56071) (xy 389.486095 -279.574402)
			(xy 389.43724 -279.580334) (xy 389.388065 -279.578353) (xy 389.339846 -279.568509) (xy 389.29383 -279.551057)
			(xy 389.251209 -279.52645) (xy 389.213088 -279.495325) (xy 389.180453 -279.458488) (xy 389.15415 -279.416892)
			(xy 389.134859 -279.371616) (xy 389.123082 -279.323832) (xy 389.119122 -279.274778) (xy 387.830314 -279.274778)
			(xy 387.829819 -279.299385) (xy 387.821924 -279.347962) (xy 387.80634 -279.394643) (xy 387.783469 -279.43822)
			(xy 387.753904 -279.477564) (xy 387.718411 -279.511656) (xy 387.677908 -279.539612) (xy 387.633446 -279.56071)
			(xy 387.586175 -279.574402) (xy 387.53732 -279.580334) (xy 387.488145 -279.578353) (xy 387.439926 -279.568509)
			(xy 387.39391 -279.551057) (xy 387.351289 -279.52645) (xy 387.313168 -279.495325) (xy 387.280533 -279.458488)
			(xy 387.25423 -279.416892) (xy 387.234939 -279.371616) (xy 387.223162 -279.323832) (xy 387.219202 -279.274778)
			(xy 385.93014 -279.274778) (xy 385.929645 -279.299385) (xy 385.92175 -279.347962) (xy 385.906166 -279.394643)
			(xy 385.883295 -279.43822) (xy 385.85373 -279.477564) (xy 385.818237 -279.511656) (xy 385.777734 -279.539612)
			(xy 385.733272 -279.56071) (xy 385.686001 -279.574402) (xy 385.637146 -279.580334) (xy 385.587971 -279.578353)
			(xy 385.539752 -279.568509) (xy 385.493736 -279.551057) (xy 385.451115 -279.52645) (xy 385.412994 -279.495325)
			(xy 385.380359 -279.458488) (xy 385.354056 -279.416892) (xy 385.334765 -279.371616) (xy 385.322988 -279.323832)
			(xy 385.319028 -279.274778) (xy 384.98018 -279.274778) (xy 384.979685 -279.299385) (xy 384.97179 -279.347962)
			(xy 384.956206 -279.394643) (xy 384.933335 -279.43822) (xy 384.90377 -279.477564) (xy 384.868277 -279.511656)
			(xy 384.827774 -279.539612) (xy 384.783312 -279.56071) (xy 384.736041 -279.574402) (xy 384.687186 -279.580334)
			(xy 384.638011 -279.578353) (xy 384.589792 -279.568509) (xy 384.543776 -279.551057) (xy 384.501155 -279.52645)
			(xy 384.463034 -279.495325) (xy 384.430399 -279.458488) (xy 384.404096 -279.416892) (xy 384.384805 -279.371616)
			(xy 384.373028 -279.323832) (xy 384.369068 -279.274778) (xy 363.582978 -279.274778) (xy 364.168182 -279.85974)
			(xy 364.188719 -279.881042) (xy 364.223578 -279.928855) (xy 364.250626 -279.981481) (xy 364.269215 -280.037655)
			(xy 364.274608 -280.06675) (xy 364.274608 -280.067004) (xy 364.277053 -280.078022) (xy 364.289992 -280.096481)
			(xy 364.2995 -280.102564) (xy 364.377986 -280.147522) (xy 364.400592 -280.149046) (xy 364.41126 -280.144982)
			(xy 364.438989 -280.134929) (xy 364.496656 -280.122559) (xy 364.526068 -280.120344) (xy 364.526322 -280.120344)
			(xy 364.537598 -280.118999) (xy 364.557384 -280.10792) (xy 364.564422 -280.099008) (xy 364.617254 -280.02484)
			(xy 364.621064 -280.002234) (xy 364.618016 -279.991058) (xy 364.611252 -279.965556) (xy 364.603985 -279.913298)
			(xy 364.603538 -279.886918) (xy 364.604024 -279.859667) (xy 364.61178 -279.805719) (xy 364.627135 -279.753424)
			(xy 364.649777 -279.703847) (xy 364.679243 -279.657997) (xy 364.714934 -279.616806) (xy 364.756125 -279.581115)
			(xy 364.801975 -279.551649) (xy 364.851552 -279.529007) (xy 364.903847 -279.513652) (xy 364.957795 -279.505896)
			(xy 365.012297 -279.505896) (xy 365.066245 -279.513652) (xy 365.11854 -279.529007) (xy 365.168117 -279.551649)
			(xy 365.213967 -279.581115) (xy 365.255158 -279.616806) (xy 365.290849 -279.657997) (xy 365.320315 -279.703847)
			(xy 365.342957 -279.753424) (xy 365.358312 -279.805719) (xy 365.366068 -279.859667) (xy 365.366554 -279.886918)
			(xy 365.366066 -279.915793) (xy 365.357382 -279.972885) (xy 365.340186 -280.028014) (xy 365.314871 -280.079918)
			(xy 365.282016 -280.12741) (xy 365.242373 -280.169402) (xy 365.19685 -280.204934) (xy 365.146488 -280.233193)
			(xy 365.092439 -280.253532) (xy 365.035941 -280.265485) (xy 365.007144 -280.267664) (xy 365.00689 -280.267664)
			(xy 364.995623 -280.269049) (xy 364.975836 -280.280103) (xy 364.96879 -280.289) (xy 364.915958 -280.363168)
			(xy 364.912148 -280.385774) (xy 364.915196 -280.39695) (xy 364.921961 -280.422452) (xy 364.929228 -280.47471)
			(xy 364.929674 -280.50109) (xy 364.928906 -280.535173) (xy 364.916774 -280.602251) (xy 364.905544 -280.63444)
			(xy 364.901226 -280.64587) (xy 364.903766 -280.669492) (xy 364.96117 -280.758138) (xy 364.981998 -280.77033)
			(xy 364.993936 -280.771092) (xy 365.022544 -280.773549) (xy 365.078611 -280.785929) (xy 365.13219 -280.806569)
			(xy 365.182073 -280.835001) (xy 365.227134 -280.870586) (xy 365.266356 -280.912519) (xy 365.298854 -280.959855)
			(xy 365.323894 -281.011524) (xy 365.325503 -281.01671) (xy 366.057178 -281.01671) (xy 366.061249 -280.961088)
			(xy 366.073375 -280.906651) (xy 366.093298 -280.85456) (xy 366.120594 -280.805925) (xy 366.15468 -280.761782)
			(xy 366.194829 -280.723073) (xy 366.240187 -280.690622) (xy 366.289787 -280.665121) (xy 366.342571 -280.647114)
			(xy 366.397414 -280.636984) (xy 366.453148 -280.634947) (xy 366.508585 -280.641047) (xy 366.562542 -280.655153)
			(xy 366.613871 -280.676965) (xy 366.640332 -280.693114) (xy 379.638052 -280.693114) (xy 379.638619 -280.663733)
			(xy 379.647646 -280.605668) (xy 379.665474 -280.549675) (xy 379.691681 -280.49708) (xy 379.725646 -280.449128)
			(xy 379.766565 -280.406954) (xy 379.78969 -280.388822) (xy 379.798622 -280.38135) (xy 379.809075 -280.360569)
			(xy 379.809756 -280.348944) (xy 379.811026 -280.256996) (xy 379.80112 -280.235914) (xy 379.791976 -280.228548)
			(xy 379.770116 -280.210356) (xy 379.731578 -280.168534) (xy 379.699673 -280.121455) (xy 379.675108 -280.070163)
			(xy 379.658427 -280.015793) (xy 379.65 -279.95955) (xy 379.649482 -279.931114) (xy 379.649968 -279.903863)
			(xy 379.657724 -279.849915) (xy 379.673079 -279.79762) (xy 379.695721 -279.748043) (xy 379.725187 -279.702193)
			(xy 379.760878 -279.661002) (xy 379.802069 -279.625311) (xy 379.847919 -279.595845) (xy 379.897496 -279.573203)
			(xy 379.949791 -279.557848) (xy 380.003739 -279.550092) (xy 380.058241 -279.550092) (xy 380.112189 -279.557848)
			(xy 380.164484 -279.573203) (xy 380.214061 -279.595845) (xy 380.259911 -279.625311) (xy 380.301102 -279.661002)
			(xy 380.336793 -279.702193) (xy 380.366259 -279.748043) (xy 380.366926 -279.749504) (xy 393.394196 -279.749504)
			(xy 393.398156 -279.70045) (xy 393.409933 -279.652666) (xy 393.429224 -279.60739) (xy 393.455527 -279.565794)
			(xy 393.488162 -279.528957) (xy 393.526283 -279.497832) (xy 393.568904 -279.473225) (xy 393.61492 -279.455773)
			(xy 393.663139 -279.445929) (xy 393.712314 -279.443948) (xy 393.761169 -279.44988) (xy 393.80844 -279.463572)
			(xy 393.852902 -279.48467) (xy 393.893405 -279.512626) (xy 393.928898 -279.546718) (xy 393.958463 -279.586062)
			(xy 393.981334 -279.629639) (xy 393.996918 -279.67632) (xy 394.004813 -279.724897) (xy 394.005308 -279.749504)
			(xy 395.294116 -279.749504) (xy 395.298076 -279.70045) (xy 395.309853 -279.652666) (xy 395.329144 -279.60739)
			(xy 395.355447 -279.565794) (xy 395.388082 -279.528957) (xy 395.426203 -279.497832) (xy 395.468824 -279.473225)
			(xy 395.51484 -279.455773) (xy 395.563059 -279.445929) (xy 395.612234 -279.443948) (xy 395.661089 -279.44988)
			(xy 395.70836 -279.463572) (xy 395.752822 -279.48467) (xy 395.793325 -279.512626) (xy 395.828818 -279.546718)
			(xy 395.858383 -279.586062) (xy 395.881254 -279.629639) (xy 395.896838 -279.67632) (xy 395.904733 -279.724897)
			(xy 395.905228 -279.749504) (xy 395.904733 -279.774111) (xy 395.896838 -279.822688) (xy 395.881254 -279.869369)
			(xy 395.858383 -279.912946) (xy 395.828818 -279.95229) (xy 395.793325 -279.986382) (xy 395.752822 -280.014338)
			(xy 395.70836 -280.035436) (xy 395.661089 -280.049128) (xy 395.612234 -280.05506) (xy 395.563059 -280.053079)
			(xy 395.51484 -280.043235) (xy 395.468824 -280.025783) (xy 395.426203 -280.001176) (xy 395.388082 -279.970051)
			(xy 395.355447 -279.933214) (xy 395.329144 -279.891618) (xy 395.309853 -279.846342) (xy 395.298076 -279.798558)
			(xy 395.294116 -279.749504) (xy 394.005308 -279.749504) (xy 394.004813 -279.774111) (xy 393.996918 -279.822688)
			(xy 393.981334 -279.869369) (xy 393.958463 -279.912946) (xy 393.928898 -279.95229) (xy 393.893405 -279.986382)
			(xy 393.852902 -280.014338) (xy 393.80844 -280.035436) (xy 393.761169 -280.049128) (xy 393.712314 -280.05506)
			(xy 393.663139 -280.053079) (xy 393.61492 -280.043235) (xy 393.568904 -280.025783) (xy 393.526283 -280.001176)
			(xy 393.488162 -279.970051) (xy 393.455527 -279.933214) (xy 393.429224 -279.891618) (xy 393.409933 -279.846342)
			(xy 393.398156 -279.798558) (xy 393.394196 -279.749504) (xy 380.366926 -279.749504) (xy 380.388901 -279.79762)
			(xy 380.404256 -279.849915) (xy 380.412012 -279.903863) (xy 380.412498 -279.931114) (xy 380.411971 -279.960497)
			(xy 380.402938 -280.018564) (xy 380.385103 -280.074559) (xy 380.358889 -280.127154) (xy 380.324916 -280.175105)
			(xy 380.283989 -280.217276) (xy 380.274469 -280.224738) (xy 387.219202 -280.224738) (xy 387.223162 -280.175684)
			(xy 387.234939 -280.1279) (xy 387.25423 -280.082624) (xy 387.280533 -280.041028) (xy 387.313168 -280.004191)
			(xy 387.351289 -279.973066) (xy 387.39391 -279.948459) (xy 387.439926 -279.931007) (xy 387.488145 -279.921163)
			(xy 387.53732 -279.919182) (xy 387.586175 -279.925114) (xy 387.633446 -279.938806) (xy 387.677908 -279.959904)
			(xy 387.718411 -279.98786) (xy 387.753904 -280.021952) (xy 387.783469 -280.061296) (xy 387.80634 -280.104873)
			(xy 387.821924 -280.151554) (xy 387.829819 -280.200131) (xy 387.830314 -280.224738) (xy 389.119122 -280.224738)
			(xy 389.123082 -280.175684) (xy 389.134859 -280.1279) (xy 389.15415 -280.082624) (xy 389.180453 -280.041028)
			(xy 389.213088 -280.004191) (xy 389.251209 -279.973066) (xy 389.29383 -279.948459) (xy 389.339846 -279.931007)
			(xy 389.388065 -279.921163) (xy 389.43724 -279.919182) (xy 389.486095 -279.925114) (xy 389.533366 -279.938806)
			(xy 389.577828 -279.959904) (xy 389.618331 -279.98786) (xy 389.653824 -280.021952) (xy 389.683389 -280.061296)
			(xy 389.70626 -280.104873) (xy 389.721844 -280.151554) (xy 389.729739 -280.200131) (xy 389.730234 -280.224738)
			(xy 391.019042 -280.224738) (xy 391.023002 -280.175684) (xy 391.034779 -280.1279) (xy 391.05407 -280.082624)
			(xy 391.080373 -280.041028) (xy 391.113008 -280.004191) (xy 391.151129 -279.973066) (xy 391.19375 -279.948459)
			(xy 391.239766 -279.931007) (xy 391.287985 -279.921163) (xy 391.33716 -279.919182) (xy 391.386015 -279.925114)
			(xy 391.433286 -279.938806) (xy 391.477748 -279.959904) (xy 391.518251 -279.98786) (xy 391.553744 -280.021952)
			(xy 391.583309 -280.061296) (xy 391.60618 -280.104873) (xy 391.621764 -280.151554) (xy 391.629659 -280.200131)
			(xy 391.630154 -280.224738) (xy 391.629659 -280.249345) (xy 391.621764 -280.297922) (xy 391.60618 -280.344603)
			(xy 391.583309 -280.38818) (xy 391.553744 -280.427524) (xy 391.518251 -280.461616) (xy 391.477748 -280.489572)
			(xy 391.433286 -280.51067) (xy 391.386015 -280.524362) (xy 391.33716 -280.530294) (xy 391.287985 -280.528313)
			(xy 391.239766 -280.518469) (xy 391.19375 -280.501017) (xy 391.151129 -280.47641) (xy 391.113008 -280.445285)
			(xy 391.080373 -280.408448) (xy 391.05407 -280.366852) (xy 391.034779 -280.321576) (xy 391.023002 -280.273792)
			(xy 391.019042 -280.224738) (xy 389.730234 -280.224738) (xy 389.729739 -280.249345) (xy 389.721844 -280.297922)
			(xy 389.70626 -280.344603) (xy 389.683389 -280.38818) (xy 389.653824 -280.427524) (xy 389.618331 -280.461616)
			(xy 389.577828 -280.489572) (xy 389.533366 -280.51067) (xy 389.486095 -280.524362) (xy 389.43724 -280.530294)
			(xy 389.388065 -280.528313) (xy 389.339846 -280.518469) (xy 389.29383 -280.501017) (xy 389.251209 -280.47641)
			(xy 389.213088 -280.445285) (xy 389.180453 -280.408448) (xy 389.15415 -280.366852) (xy 389.134859 -280.321576)
			(xy 389.123082 -280.273792) (xy 389.119122 -280.224738) (xy 387.830314 -280.224738) (xy 387.829819 -280.249345)
			(xy 387.821924 -280.297922) (xy 387.80634 -280.344603) (xy 387.783469 -280.38818) (xy 387.753904 -280.427524)
			(xy 387.718411 -280.461616) (xy 387.677908 -280.489572) (xy 387.633446 -280.51067) (xy 387.586175 -280.524362)
			(xy 387.53732 -280.530294) (xy 387.488145 -280.528313) (xy 387.439926 -280.518469) (xy 387.39391 -280.501017)
			(xy 387.351289 -280.47641) (xy 387.313168 -280.445285) (xy 387.280533 -280.408448) (xy 387.25423 -280.366852)
			(xy 387.234939 -280.321576) (xy 387.223162 -280.273792) (xy 387.219202 -280.224738) (xy 380.274469 -280.224738)
			(xy 380.26086 -280.235406) (xy 380.251924 -280.242875) (xy 380.241471 -280.263657) (xy 380.240794 -280.275284)
			(xy 380.239524 -280.367232) (xy 380.24943 -280.388314) (xy 380.258574 -280.39568) (xy 380.280389 -280.413924)
			(xy 380.318933 -280.455734) (xy 380.350844 -280.502801) (xy 380.375417 -280.554084) (xy 380.392107 -280.608445)
			(xy 380.400545 -280.664681) (xy 380.401068 -280.693114) (xy 381.034542 -280.693114) (xy 381.038613 -280.637492)
			(xy 381.050739 -280.583055) (xy 381.070662 -280.530964) (xy 381.097958 -280.482329) (xy 381.132044 -280.438186)
			(xy 381.172193 -280.399477) (xy 381.217551 -280.367026) (xy 381.267151 -280.341525) (xy 381.319935 -280.323518)
			(xy 381.374778 -280.313388) (xy 381.430512 -280.311351) (xy 381.485949 -280.317451) (xy 381.539906 -280.331557)
			(xy 381.591235 -280.353369) (xy 381.638841 -280.382423) (xy 381.681709 -280.418098) (xy 381.718926 -280.459635)
			(xy 381.749699 -280.506148) (xy 381.773371 -280.556645) (xy 381.789439 -280.610052) (xy 381.797559 -280.665228)
			(xy 381.798068 -280.693114) (xy 381.797947 -280.699718) (xy 393.394196 -280.699718) (xy 393.398156 -280.650664)
			(xy 393.409933 -280.60288) (xy 393.429224 -280.557604) (xy 393.455527 -280.516008) (xy 393.488162 -280.479171)
			(xy 393.526283 -280.448046) (xy 393.568904 -280.423439) (xy 393.61492 -280.405987) (xy 393.663139 -280.396143)
			(xy 393.712314 -280.394162) (xy 393.761169 -280.400094) (xy 393.80844 -280.413786) (xy 393.852902 -280.434884)
			(xy 393.893405 -280.46284) (xy 393.928898 -280.496932) (xy 393.958463 -280.536276) (xy 393.981334 -280.579853)
			(xy 393.996918 -280.626534) (xy 394.004813 -280.675111) (xy 394.005308 -280.699718) (xy 395.294116 -280.699718)
			(xy 395.298076 -280.650664) (xy 395.309853 -280.60288) (xy 395.329144 -280.557604) (xy 395.355447 -280.516008)
			(xy 395.388082 -280.479171) (xy 395.426203 -280.448046) (xy 395.468824 -280.423439) (xy 395.51484 -280.405987)
			(xy 395.563059 -280.396143) (xy 395.612234 -280.394162) (xy 395.661089 -280.400094) (xy 395.70836 -280.413786)
			(xy 395.752822 -280.434884) (xy 395.793325 -280.46284) (xy 395.828818 -280.496932) (xy 395.858383 -280.536276)
			(xy 395.881254 -280.579853) (xy 395.896838 -280.626534) (xy 395.904733 -280.675111) (xy 395.905228 -280.699718)
			(xy 395.904733 -280.724325) (xy 395.896838 -280.772902) (xy 395.881254 -280.819583) (xy 395.858383 -280.86316)
			(xy 395.828818 -280.902504) (xy 395.793325 -280.936596) (xy 395.752822 -280.964552) (xy 395.70836 -280.98565)
			(xy 395.661089 -280.999342) (xy 395.612234 -281.005274) (xy 395.563059 -281.003293) (xy 395.51484 -280.993449)
			(xy 395.468824 -280.975997) (xy 395.426203 -280.95139) (xy 395.388082 -280.920265) (xy 395.355447 -280.883428)
			(xy 395.329144 -280.841832) (xy 395.309853 -280.796556) (xy 395.298076 -280.748772) (xy 395.294116 -280.699718)
			(xy 394.005308 -280.699718) (xy 394.004813 -280.724325) (xy 393.996918 -280.772902) (xy 393.981334 -280.819583)
			(xy 393.958463 -280.86316) (xy 393.928898 -280.902504) (xy 393.893405 -280.936596) (xy 393.852902 -280.964552)
			(xy 393.80844 -280.98565) (xy 393.761169 -280.999342) (xy 393.712314 -281.005274) (xy 393.663139 -281.003293)
			(xy 393.61492 -280.993449) (xy 393.568904 -280.975997) (xy 393.526283 -280.95139) (xy 393.488162 -280.920265)
			(xy 393.455527 -280.883428) (xy 393.429224 -280.841832) (xy 393.409933 -280.796556) (xy 393.398156 -280.748772)
			(xy 393.394196 -280.699718) (xy 381.797947 -280.699718) (xy 381.797559 -280.721) (xy 381.789439 -280.776176)
			(xy 381.773371 -280.829583) (xy 381.749699 -280.88008) (xy 381.718926 -280.926593) (xy 381.681709 -280.96813)
			(xy 381.638841 -281.003805) (xy 381.591235 -281.032859) (xy 381.539906 -281.054671) (xy 381.485949 -281.068777)
			(xy 381.430512 -281.074877) (xy 381.374778 -281.07284) (xy 381.319935 -281.06271) (xy 381.267151 -281.044703)
			(xy 381.217551 -281.019202) (xy 381.172193 -280.986751) (xy 381.132044 -280.948042) (xy 381.097958 -280.903899)
			(xy 381.070662 -280.855264) (xy 381.050739 -280.803173) (xy 381.038613 -280.748736) (xy 381.034542 -280.693114)
			(xy 380.401068 -280.693114) (xy 380.400582 -280.720365) (xy 380.392826 -280.774313) (xy 380.377471 -280.826608)
			(xy 380.354829 -280.876185) (xy 380.325363 -280.922035) (xy 380.289672 -280.963226) (xy 380.248481 -280.998917)
			(xy 380.202631 -281.028383) (xy 380.153054 -281.051025) (xy 380.100759 -281.06638) (xy 380.046811 -281.074136)
			(xy 379.992309 -281.074136) (xy 379.938361 -281.06638) (xy 379.886066 -281.051025) (xy 379.836489 -281.028383)
			(xy 379.790639 -280.998917) (xy 379.749448 -280.963226) (xy 379.713757 -280.922035) (xy 379.684291 -280.876185)
			(xy 379.661649 -280.826608) (xy 379.646294 -280.774313) (xy 379.638538 -280.720365) (xy 379.638052 -280.693114)
			(xy 366.640332 -280.693114) (xy 366.661477 -280.706019) (xy 366.704345 -280.741694) (xy 366.741562 -280.783231)
			(xy 366.772335 -280.829744) (xy 366.796007 -280.880241) (xy 366.812075 -280.933648) (xy 366.820195 -280.988824)
			(xy 366.820704 -281.01671) (xy 366.820195 -281.044596) (xy 366.812075 -281.099772) (xy 366.796007 -281.153179)
			(xy 366.7858 -281.174952) (xy 384.369068 -281.174952) (xy 384.373028 -281.125898) (xy 384.384805 -281.078114)
			(xy 384.404096 -281.032838) (xy 384.430399 -280.991242) (xy 384.463034 -280.954405) (xy 384.501155 -280.92328)
			(xy 384.543776 -280.898673) (xy 384.589792 -280.881221) (xy 384.638011 -280.871377) (xy 384.687186 -280.869396)
			(xy 384.736041 -280.875328) (xy 384.783312 -280.88902) (xy 384.827774 -280.910118) (xy 384.868277 -280.938074)
			(xy 384.90377 -280.972166) (xy 384.933335 -281.01151) (xy 384.956206 -281.055087) (xy 384.97179 -281.101768)
			(xy 384.979685 -281.150345) (xy 384.98018 -281.174952) (xy 385.319028 -281.174952) (xy 385.322988 -281.125898)
			(xy 385.334765 -281.078114) (xy 385.354056 -281.032838) (xy 385.380359 -280.991242) (xy 385.412994 -280.954405)
			(xy 385.451115 -280.92328) (xy 385.493736 -280.898673) (xy 385.539752 -280.881221) (xy 385.587971 -280.871377)
			(xy 385.637146 -280.869396) (xy 385.686001 -280.875328) (xy 385.733272 -280.88902) (xy 385.777734 -280.910118)
			(xy 385.818237 -280.938074) (xy 385.85373 -280.972166) (xy 385.883295 -281.01151) (xy 385.906166 -281.055087)
			(xy 385.92175 -281.101768) (xy 385.929645 -281.150345) (xy 385.93014 -281.174952) (xy 385.929645 -281.199559)
			(xy 385.92175 -281.248136) (xy 385.906166 -281.294817) (xy 385.883295 -281.338394) (xy 385.85373 -281.377738)
			(xy 385.818237 -281.41183) (xy 385.777734 -281.439786) (xy 385.733272 -281.460884) (xy 385.686001 -281.474576)
			(xy 385.637146 -281.480508) (xy 385.587971 -281.478527) (xy 385.539752 -281.468683) (xy 385.493736 -281.451231)
			(xy 385.451115 -281.426624) (xy 385.412994 -281.395499) (xy 385.380359 -281.358662) (xy 385.354056 -281.317066)
			(xy 385.334765 -281.27179) (xy 385.322988 -281.224006) (xy 385.319028 -281.174952) (xy 384.98018 -281.174952)
			(xy 384.979685 -281.199559) (xy 384.97179 -281.248136) (xy 384.956206 -281.294817) (xy 384.933335 -281.338394)
			(xy 384.90377 -281.377738) (xy 384.868277 -281.41183) (xy 384.827774 -281.439786) (xy 384.783312 -281.460884)
			(xy 384.736041 -281.474576) (xy 384.687186 -281.480508) (xy 384.638011 -281.478527) (xy 384.589792 -281.468683)
			(xy 384.543776 -281.451231) (xy 384.501155 -281.426624) (xy 384.463034 -281.395499) (xy 384.430399 -281.358662)
			(xy 384.404096 -281.317066) (xy 384.384805 -281.27179) (xy 384.373028 -281.224006) (xy 384.369068 -281.174952)
			(xy 366.7858 -281.174952) (xy 366.772335 -281.203676) (xy 366.741562 -281.250189) (xy 366.704345 -281.291726)
			(xy 366.661477 -281.327401) (xy 366.613871 -281.356455) (xy 366.562542 -281.378267) (xy 366.508585 -281.392373)
			(xy 366.453148 -281.398473) (xy 366.397414 -281.396436) (xy 366.342571 -281.386306) (xy 366.289787 -281.368299)
			(xy 366.240187 -281.342798) (xy 366.194829 -281.310347) (xy 366.15468 -281.271638) (xy 366.120594 -281.227495)
			(xy 366.093298 -281.17886) (xy 366.073375 -281.126769) (xy 366.061249 -281.072332) (xy 366.057178 -281.01671)
			(xy 365.325503 -281.01671) (xy 365.340911 -281.066362) (xy 365.349521 -281.123129) (xy 365.350044 -281.151838)
			(xy 365.349558 -281.179089) (xy 365.341802 -281.233037) (xy 365.326447 -281.285332) (xy 365.303805 -281.334909)
			(xy 365.274339 -281.380759) (xy 365.238648 -281.42195) (xy 365.197457 -281.457641) (xy 365.151607 -281.487107)
			(xy 365.10203 -281.509749) (xy 365.049735 -281.525104) (xy 364.995787 -281.53286) (xy 364.941285 -281.53286)
			(xy 364.887337 -281.525104) (xy 364.835042 -281.509749) (xy 364.785465 -281.487107) (xy 364.739615 -281.457641)
			(xy 364.698424 -281.42195) (xy 364.662733 -281.380759) (xy 364.633267 -281.334909) (xy 364.610625 -281.285332)
			(xy 364.59527 -281.233037) (xy 364.587514 -281.179089) (xy 364.587028 -281.151838) (xy 364.587777 -281.117754)
			(xy 364.599921 -281.050676) (xy 364.611158 -281.018488) (xy 364.615476 -281.007058) (xy 364.612936 -280.983436)
			(xy 364.555532 -280.89479) (xy 364.534704 -280.882598) (xy 364.522766 -280.881836) (xy 364.491397 -280.879158)
			(xy 364.430117 -280.864728) (xy 364.400846 -280.853134) (xy 364.39094 -280.848816) (xy 364.36935 -280.849324)
			(xy 364.281212 -280.891234) (xy 364.267242 -280.90749) (xy 364.264194 -280.918158) (xy 364.256019 -280.944123)
			(xy 364.233368 -280.99362) (xy 364.203909 -281.039393) (xy 364.168239 -281.080512) (xy 364.127085 -281.11614)
			(xy 364.081282 -281.145553) (xy 364.031762 -281.168154) (xy 363.979531 -281.183484) (xy 363.925651 -281.191229)
			(xy 363.898434 -281.191716) (xy 363.875078 -281.191348) (xy 363.828719 -281.185619) (xy 363.805978 -281.180286)
			(xy 363.79658 -281.177746) (xy 363.777022 -281.18054) (xy 363.69879 -281.225498) (xy 363.686598 -281.240992)
			(xy 363.684058 -281.25039) (xy 363.676029 -281.27652) (xy 363.653459 -281.326308) (xy 363.624017 -281.372368)
			(xy 363.588307 -281.413756) (xy 363.547057 -281.449628) (xy 363.501113 -281.479248) (xy 363.451413 -281.502011)
			(xy 363.398974 -281.517452) (xy 363.344868 -281.525255) (xy 363.317536 -281.525726) (xy 363.290285 -281.525211)
			(xy 363.236337 -281.51746) (xy 363.184041 -281.502109) (xy 363.134462 -281.479472) (xy 363.08861 -281.45001)
			(xy 363.047417 -281.414321) (xy 363.011723 -281.373134) (xy 362.982254 -281.327285) (xy 362.95961 -281.27771)
			(xy 362.944252 -281.225416) (xy 362.936493 -281.171469) (xy 362.936028 -281.144218) (xy 362.936085 -281.133592)
			(xy 362.937228 -281.112371) (xy 362.938314 -281.1018) (xy 362.93933 -281.092402) (xy 362.934504 -281.074114)
			(xy 362.88853 -281.010614) (xy 362.882703 -281.003326) (xy 362.867077 -280.99316) (xy 362.85805 -280.990802)
			(xy 362.857796 -280.990802) (xy 362.829495 -280.984439) (xy 362.775108 -280.964278) (xy 362.724399 -280.936114)
			(xy 362.67854 -280.900598) (xy 362.638586 -280.858548) (xy 362.605459 -280.810934) (xy 362.579922 -280.758853)
			(xy 362.562566 -280.703507) (xy 362.553789 -280.64617) (xy 362.55325 -280.617168) (xy 362.553736 -280.589917)
			(xy 362.561492 -280.535969) (xy 362.576847 -280.483674) (xy 362.599489 -280.434097) (xy 362.628955 -280.388247)
			(xy 362.664646 -280.347056) (xy 362.705837 -280.311365) (xy 362.751687 -280.281899) (xy 362.801264 -280.259257)
			(xy 362.853559 -280.243902) (xy 362.907507 -280.236146) (xy 362.962009 -280.236146) (xy 363.015957 -280.243902)
			(xy 363.068252 -280.259257) (xy 363.117829 -280.281899) (xy 363.163679 -280.311365) (xy 363.20487 -280.347056)
			(xy 363.240561 -280.388247) (xy 363.270027 -280.434097) (xy 363.292669 -280.483674) (xy 363.308024 -280.535969)
			(xy 363.31578 -280.589917) (xy 363.316266 -280.617168) (xy 363.316208 -280.627794) (xy 363.315065 -280.649015)
			(xy 363.31398 -280.659586) (xy 363.312964 -280.668984) (xy 363.31779 -280.687272) (xy 363.363764 -280.750772)
			(xy 363.369595 -280.758056) (xy 363.385218 -280.768224) (xy 363.394244 -280.770584) (xy 363.39526 -280.770584)
			(xy 363.406336 -280.772252) (xy 363.428079 -280.766969) (xy 363.43717 -280.760424) (xy 363.498384 -280.71064)
			(xy 363.506794 -280.703028) (xy 363.516566 -280.682595) (xy 363.51718 -280.67127) (xy 363.51718 -280.308558)
			(xy 363.516782 -280.298486) (xy 363.509043 -280.279888) (xy 363.502194 -280.27249) (xy 362.889038 -279.659588)
			(xy 362.868331 -279.637989) (xy 362.833188 -279.589566) (xy 362.806034 -279.536252) (xy 362.787534 -279.479352)
			(xy 362.778142 -279.420263) (xy 362.777532 -279.390348) (xy 362.777532 -279.02408) (xy 362.777135 -279.014007)
			(xy 362.769397 -278.995408) (xy 362.762546 -278.988012) (xy 362.514134 -278.739854) (xy 362.506683 -278.733088)
			(xy 362.488118 -278.725371) (xy 362.478066 -278.724868) (xy 362.161582 -278.724868) (xy 362.151509 -278.725266)
			(xy 362.132911 -278.733004) (xy 362.125514 -278.739854) (xy 361.058206 -279.807162) (xy 361.036642 -279.827908)
			(xy 360.98821 -279.863046) (xy 360.934887 -279.890192) (xy 360.877979 -279.908683) (xy 360.818884 -279.918064)
			(xy 360.788966 -279.918668) (xy 358.538018 -279.918668) (xy 358.508099 -279.918086) (xy 358.448998 -279.908718)
			(xy 358.392089 -279.890225) (xy 358.33877 -279.863063) (xy 358.290354 -279.827898) (xy 358.268778 -279.807162)
			(xy 357.20147 -278.739854) (xy 357.19408 -278.733002) (xy 357.175473 -278.725291) (xy 357.165402 -278.724868)
			(xy 356.725728 -278.724868) (xy 356.715658 -278.72529) (xy 356.697059 -278.733011) (xy 356.68966 -278.739854)
			(xy 356.635558 -278.793956) (xy 356.628797 -278.801411) (xy 356.621077 -278.819973) (xy 356.620572 -278.830024)
			(xy 356.620572 -279.414732) (xy 356.621195 -279.426149) (xy 356.631104 -279.446726) (xy 356.639622 -279.454356)
			(xy 356.70998 -279.511252) (xy 356.732332 -279.516332) (xy 356.743508 -279.514046) (xy 356.763393 -279.510013)
			(xy 356.803738 -279.505691) (xy 356.824026 -279.50541) (xy 356.824534 -279.50541) (xy 356.851787 -279.505846)
			(xy 356.905737 -279.513608) (xy 356.958034 -279.528968) (xy 357.007613 -279.551615) (xy 357.053464 -279.581086)
			(xy 357.094654 -279.616783) (xy 357.130345 -279.657978) (xy 357.15981 -279.703833) (xy 357.18245 -279.753415)
			(xy 357.197803 -279.805714) (xy 357.205557 -279.859665) (xy 357.206042 -279.886918) (xy 357.205565 -279.915793)
			(xy 357.196881 -279.972886) (xy 357.179684 -280.028016) (xy 357.154368 -280.079921) (xy 357.121512 -280.127413)
			(xy 357.081868 -280.169406) (xy 357.036343 -280.204938) (xy 356.985979 -280.233196) (xy 356.931929 -280.253534)
			(xy 356.87543 -280.265486) (xy 356.846632 -280.267664) (xy 356.846378 -280.267664) (xy 356.83511 -280.269043)
			(xy 356.815323 -280.280101) (xy 356.808278 -280.289) (xy 356.755446 -280.363168) (xy 356.751636 -280.385774)
			(xy 356.754684 -280.39695) (xy 356.761449 -280.422452) (xy 356.768716 -280.47471) (xy 356.769162 -280.50109)
			(xy 356.768395 -280.535173) (xy 356.756263 -280.602251) (xy 356.745032 -280.63444) (xy 356.740714 -280.64587)
			(xy 356.743254 -280.669492) (xy 356.800658 -280.758138) (xy 356.821486 -280.77033) (xy 356.833424 -280.771092)
			(xy 356.862031 -280.773559) (xy 356.918098 -280.785938) (xy 356.971677 -280.806576) (xy 357.02156 -280.835007)
			(xy 357.066621 -280.87059) (xy 357.105843 -280.912522) (xy 357.138341 -280.959857) (xy 357.157646 -280.999692)
			(xy 357.896666 -280.999692) (xy 357.900737 -280.94407) (xy 357.912863 -280.889633) (xy 357.932786 -280.837542)
			(xy 357.960082 -280.788907) (xy 357.994168 -280.744764) (xy 358.034317 -280.706055) (xy 358.079675 -280.673604)
			(xy 358.129275 -280.648103) (xy 358.182059 -280.630096) (xy 358.236902 -280.619966) (xy 358.292636 -280.617929)
			(xy 358.348073 -280.624029) (xy 358.40203 -280.638135) (xy 358.453359 -280.659947) (xy 358.500965 -280.689001)
			(xy 358.543833 -280.724676) (xy 358.58105 -280.766213) (xy 358.611823 -280.812726) (xy 358.635495 -280.863223)
			(xy 358.651563 -280.91663) (xy 358.659683 -280.971806) (xy 358.660192 -280.999692) (xy 358.659683 -281.027578)
			(xy 358.651563 -281.082754) (xy 358.635495 -281.136161) (xy 358.611823 -281.186658) (xy 358.58105 -281.233171)
			(xy 358.543833 -281.274708) (xy 358.500965 -281.310383) (xy 358.453359 -281.339437) (xy 358.40203 -281.361249)
			(xy 358.348073 -281.375355) (xy 358.292636 -281.381455) (xy 358.236902 -281.379418) (xy 358.182059 -281.369288)
			(xy 358.129275 -281.351281) (xy 358.079675 -281.32578) (xy 358.034317 -281.293329) (xy 357.994168 -281.25462)
			(xy 357.960082 -281.210477) (xy 357.932786 -281.161842) (xy 357.912863 -281.109751) (xy 357.900737 -281.055314)
			(xy 357.896666 -280.999692) (xy 357.157646 -280.999692) (xy 357.163381 -281.011526) (xy 357.180399 -281.066362)
			(xy 357.189009 -281.12313) (xy 357.189532 -281.151838) (xy 357.189046 -281.179089) (xy 357.18129 -281.233037)
			(xy 357.165935 -281.285332) (xy 357.143293 -281.334909) (xy 357.113827 -281.380759) (xy 357.078136 -281.42195)
			(xy 357.036945 -281.457641) (xy 356.991095 -281.487107) (xy 356.941518 -281.509749) (xy 356.889223 -281.525104)
			(xy 356.835275 -281.53286) (xy 356.780773 -281.53286) (xy 356.726825 -281.525104) (xy 356.67453 -281.509749)
			(xy 356.624953 -281.487107) (xy 356.579103 -281.457641) (xy 356.537912 -281.42195) (xy 356.502221 -281.380759)
			(xy 356.472755 -281.334909) (xy 356.450113 -281.285332) (xy 356.434758 -281.233037) (xy 356.427002 -281.179089)
			(xy 356.426516 -281.151838) (xy 356.427266 -281.117754) (xy 356.43941 -281.050676) (xy 356.450646 -281.018488)
			(xy 356.454964 -281.007058) (xy 356.452424 -280.983436) (xy 356.39502 -280.89479) (xy 356.374192 -280.882598)
			(xy 356.362254 -280.881836) (xy 356.330884 -280.879161) (xy 356.269605 -280.864729) (xy 356.240334 -280.853134)
			(xy 356.230428 -280.848816) (xy 356.208838 -280.849324) (xy 356.1207 -280.891234) (xy 356.10673 -280.90749)
			(xy 356.103682 -280.918158) (xy 356.095518 -280.944127) (xy 356.072866 -280.993625) (xy 356.043405 -281.039398)
			(xy 356.007734 -281.080517) (xy 355.966578 -281.116145) (xy 355.920774 -281.145558) (xy 355.871253 -281.168158)
			(xy 355.819021 -281.183486) (xy 355.765139 -281.19123) (xy 355.737922 -281.191716) (xy 355.714566 -281.191351)
			(xy 355.668207 -281.18562) (xy 355.645466 -281.180286) (xy 355.636068 -281.177746) (xy 355.61651 -281.18054)
			(xy 355.538278 -281.225498) (xy 355.526086 -281.240992) (xy 355.523546 -281.25039) (xy 355.515528 -281.276524)
			(xy 355.492957 -281.326313) (xy 355.463514 -281.372372) (xy 355.427802 -281.413761) (xy 355.386551 -281.449632)
			(xy 355.340605 -281.479252) (xy 355.290904 -281.502015) (xy 355.238463 -281.517455) (xy 355.184357 -281.525256)
			(xy 355.157024 -281.525726) (xy 355.129773 -281.525222) (xy 355.075824 -281.517469) (xy 355.023528 -281.502117)
			(xy 354.973949 -281.479479) (xy 354.928097 -281.450015) (xy 354.886904 -281.414325) (xy 354.85121 -281.373137)
			(xy 354.821741 -281.327288) (xy 354.799098 -281.277711) (xy 354.78374 -281.225417) (xy 354.775981 -281.171469)
			(xy 354.775516 -281.144218) (xy 354.775573 -281.133592) (xy 354.776716 -281.112371) (xy 354.777802 -281.1018)
			(xy 354.778818 -281.092402) (xy 354.773992 -281.074114) (xy 354.728018 -281.010614) (xy 354.722196 -281.003322)
			(xy 354.706566 -280.993159) (xy 354.697538 -280.990802) (xy 354.697284 -280.990802) (xy 354.668981 -280.984448)
			(xy 354.614594 -280.964285) (xy 354.563886 -280.93612) (xy 354.518026 -280.900602) (xy 354.478073 -280.858552)
			(xy 354.444946 -280.810936) (xy 354.41941 -280.758855) (xy 354.402054 -280.703508) (xy 354.393277 -280.646171)
			(xy 354.392738 -280.617168) (xy 354.393224 -280.589917) (xy 354.40098 -280.535969) (xy 354.416335 -280.483674)
			(xy 354.438977 -280.434097) (xy 354.468443 -280.388247) (xy 354.504134 -280.347056) (xy 354.545325 -280.311365)
			(xy 354.591175 -280.281899) (xy 354.640752 -280.259257) (xy 354.693047 -280.243902) (xy 354.746995 -280.236146)
			(xy 354.801497 -280.236146) (xy 354.855445 -280.243902) (xy 354.90774 -280.259257) (xy 354.957317 -280.281899)
			(xy 355.003167 -280.311365) (xy 355.044358 -280.347056) (xy 355.080049 -280.388247) (xy 355.109515 -280.434097)
			(xy 355.132157 -280.483674) (xy 355.147512 -280.535969) (xy 355.155268 -280.589917) (xy 355.155754 -280.617168)
			(xy 355.155696 -280.627794) (xy 355.154553 -280.649015) (xy 355.153468 -280.659586) (xy 355.152452 -280.668984)
			(xy 355.157278 -280.687272) (xy 355.203252 -280.750772) (xy 355.209088 -280.758052) (xy 355.224707 -280.768222)
			(xy 355.233732 -280.770584) (xy 355.234748 -280.770584) (xy 355.245825 -280.772245) (xy 355.267567 -280.766967)
			(xy 355.276658 -280.760424) (xy 355.337872 -280.71064) (xy 355.34628 -280.703026) (xy 355.356054 -280.682595)
			(xy 355.356668 -280.67127) (xy 355.356668 -280.370026) (xy 355.356237 -280.359957) (xy 355.348521 -280.341359)
			(xy 355.341682 -280.333958) (xy 355.066854 -280.05913) (xy 355.059426 -280.052325) (xy 355.040848 -280.044584)
			(xy 355.030786 -280.044144) (xy 351.291398 -280.044144) (xy 351.261478 -280.043581) (xy 351.202376 -280.034209)
			(xy 351.145466 -280.015713) (xy 351.092148 -279.988546) (xy 351.043733 -279.953377) (xy 351.022158 -279.932638)
			(xy 349.884238 -278.794718) (xy 349.863498 -278.773149) (xy 349.828359 -278.724718) (xy 349.801212 -278.671396)
			(xy 349.782719 -278.61449) (xy 349.773337 -278.555395) (xy 349.772732 -278.525478) (xy 346.719652 -278.525478)
			(xy 346.769436 -278.575262) (xy 346.790213 -278.596878) (xy 346.825448 -278.645384) (xy 346.852665 -278.698803)
			(xy 346.871196 -278.75582) (xy 346.880584 -278.815034) (xy 346.881196 -278.84501) (xy 346.881196 -279.21077)
			(xy 346.881632 -279.220835) (xy 346.889364 -279.239421) (xy 346.896182 -279.246838) (xy 347.509084 -279.85974)
			(xy 347.529596 -279.881064) (xy 347.564445 -279.928877) (xy 347.591496 -279.981497) (xy 347.610102 -280.03766)
			(xy 347.61551 -280.06675) (xy 347.61551 -280.067004) (xy 347.61802 -280.077994) (xy 347.630938 -280.096437)
			(xy 347.640402 -280.102564) (xy 347.718888 -280.147522) (xy 347.741494 -280.149046) (xy 347.752162 -280.144982)
			(xy 347.779831 -280.134949) (xy 347.837369 -280.12258) (xy 347.866716 -280.120344) (xy 347.867224 -280.120344)
			(xy 347.878497 -280.118989) (xy 347.898283 -280.107914) (xy 347.905324 -280.099008) (xy 347.958156 -280.02484)
			(xy 347.961966 -280.002234) (xy 347.958918 -279.991058) (xy 347.952147 -279.965557) (xy 347.944878 -279.913299)
			(xy 347.94444 -279.886918) (xy 347.944926 -279.859667) (xy 347.952682 -279.805719) (xy 347.968037 -279.753424)
			(xy 347.990679 -279.703847) (xy 348.020145 -279.657997) (xy 348.055836 -279.616806) (xy 348.097027 -279.581115)
			(xy 348.142877 -279.551649) (xy 348.192454 -279.529007) (xy 348.244749 -279.513652) (xy 348.298697 -279.505896)
			(xy 348.353199 -279.505896) (xy 348.407147 -279.513652) (xy 348.459442 -279.529007) (xy 348.509019 -279.551649)
			(xy 348.554869 -279.581115) (xy 348.59606 -279.616806) (xy 348.631751 -279.657997) (xy 348.661217 -279.703847)
			(xy 348.683859 -279.753424) (xy 348.699214 -279.805719) (xy 348.70697 -279.859667) (xy 348.707456 -279.886918)
			(xy 348.706916 -279.915784) (xy 348.698199 -279.972853) (xy 348.680982 -280.027957) (xy 348.655657 -280.079838)
			(xy 348.622804 -280.12731) (xy 348.583172 -280.169289) (xy 348.537667 -280.204816) (xy 348.487328 -280.233081)
			(xy 348.433304 -280.253438) (xy 348.37683 -280.265421) (xy 348.348046 -280.267664) (xy 348.347792 -280.267664)
			(xy 348.336518 -280.269016) (xy 348.316728 -280.280088) (xy 348.309692 -280.289) (xy 348.25686 -280.363168)
			(xy 348.25305 -280.385774) (xy 348.256098 -280.39695) (xy 348.262868 -280.422451) (xy 348.270136 -280.474709)
			(xy 348.270576 -280.50109) (xy 348.269804 -280.535173) (xy 348.257674 -280.602251) (xy 348.246446 -280.63444)
			(xy 348.242128 -280.645616) (xy 348.244922 -280.669492) (xy 348.295722 -280.747978) (xy 348.302656 -280.757605)
			(xy 348.323061 -280.76965) (xy 348.334838 -280.771092) (xy 348.363453 -280.773517) (xy 348.419534 -280.785878)
			(xy 348.473128 -280.806506) (xy 348.523024 -280.834934) (xy 348.568095 -280.870521) (xy 348.607322 -280.912461)
			(xy 348.639819 -280.959808) (xy 348.664852 -281.011492) (xy 348.681854 -281.066344) (xy 348.690442 -281.123125)
			(xy 348.690946 -281.151838) (xy 348.69046 -281.179089) (xy 348.682704 -281.233037) (xy 348.667349 -281.285332)
			(xy 348.644707 -281.334909) (xy 348.615241 -281.380759) (xy 348.57955 -281.42195) (xy 348.538359 -281.457641)
			(xy 348.492509 -281.487107) (xy 348.442932 -281.509749) (xy 348.390637 -281.525104) (xy 348.336689 -281.53286)
			(xy 348.282187 -281.53286) (xy 348.228239 -281.525104) (xy 348.175944 -281.509749) (xy 348.126367 -281.487107)
			(xy 348.080517 -281.457641) (xy 348.039326 -281.42195) (xy 348.003635 -281.380759) (xy 347.974169 -281.334909)
			(xy 347.951527 -281.285332) (xy 347.936172 -281.233037) (xy 347.928416 -281.179089) (xy 347.92793 -281.151838)
			(xy 347.928708 -281.117757) (xy 347.94085 -281.050683) (xy 347.95206 -281.018488) (xy 347.956378 -281.007312)
			(xy 347.953584 -280.983436) (xy 347.902784 -280.90495) (xy 347.895853 -280.895318) (xy 347.875449 -280.883263)
			(xy 347.863668 -280.881836) (xy 347.832309 -280.879093) (xy 347.77104 -280.864664) (xy 347.741748 -280.853134)
			(xy 347.731615 -280.849364) (xy 347.710022 -280.849877) (xy 347.700092 -280.85415) (xy 347.63202 -280.886408)
			(xy 347.622532 -280.89144) (xy 347.608585 -280.907747) (xy 347.605096 -280.917904) (xy 347.596954 -280.943889)
			(xy 347.574322 -280.993417) (xy 347.544875 -281.039222) (xy 347.50921 -281.08037) (xy 347.468053 -281.116026)
			(xy 347.422242 -281.145463) (xy 347.372709 -281.168083) (xy 347.320462 -281.183426) (xy 347.266563 -281.191178)
			(xy 347.239336 -281.191716) (xy 347.21598 -281.191349) (xy 347.169622 -281.185618) (xy 347.14688 -281.180286)
			(xy 347.137236 -281.178321) (xy 347.117768 -281.181079) (xy 347.109034 -281.18562) (xy 347.039438 -281.225498)
			(xy 347.027754 -281.240738) (xy 347.02496 -281.25039) (xy 347.016906 -281.276515) (xy 346.994359 -281.326316)
			(xy 346.964933 -281.372389) (xy 346.92923 -281.413788) (xy 346.887982 -281.449665) (xy 346.842035 -281.479286)
			(xy 346.792329 -281.502044) (xy 346.739883 -281.517472) (xy 346.685772 -281.525254) (xy 346.658438 -281.525726)
			(xy 346.654374 -281.525726) (xy 346.644333 -281.526178) (xy 346.62575 -281.533782) (xy 346.611479 -281.547906)
			(xy 346.60713 -281.556968) (xy 346.570808 -281.643582) (xy 346.567254 -281.653029) (xy 346.567138 -281.673195)
			(xy 346.574846 -281.69183) (xy 346.58173 -281.699208) (xy 346.598748 -281.716226) (xy 346.606145 -281.723073)
			(xy 346.624745 -281.730802) (xy 346.634816 -281.731212) (xy 348.198186 -281.731212) (xy 348.229743 -281.731762)
			(xy 348.292312 -281.740054) (xy 348.353268 -281.756421) (xy 348.411576 -281.780584) (xy 348.466241 -281.812131)
			(xy 348.516335 -281.850526) (xy 348.539054 -281.872436) (xy 348.567502 -281.900884) (xy 348.574868 -281.907724)
			(xy 348.593401 -281.915466) (xy 348.613485 -281.915466) (xy 348.632018 -281.907724) (xy 348.639384 -281.900884)
			(xy 348.64421 -281.896058) (xy 348.651322 -281.883612) (xy 348.652846 -281.8765) (xy 348.65985 -281.848931)
			(xy 348.680911 -281.796094) (xy 348.709575 -281.746966) (xy 348.745211 -281.702633) (xy 348.787028 -281.664077)
			(xy 348.834103 -281.632151) (xy 348.885392 -281.607561) (xy 348.939762 -281.590851) (xy 348.996008 -281.582391)
			(xy 349.024448 -281.58186) (xy 349.052009 -281.582342) (xy 349.106557 -281.590273) (xy 349.159394 -281.605977)
			(xy 349.209418 -281.629127) (xy 349.255588 -281.659239) (xy 349.296939 -281.695687) (xy 349.332611 -281.737709)
			(xy 349.361858 -281.784431) (xy 349.373444 -281.809444) (xy 349.373444 -281.809698) (xy 349.379076 -281.820799)
			(xy 349.398649 -281.836132) (xy 349.410782 -281.838908) (xy 349.493078 -281.854402) (xy 349.505384 -281.856099)
			(xy 349.529092 -281.84878) (xy 349.53829 -281.840432) (xy 349.809054 -281.569668) (xy 349.815551 -281.562532)
			(xy 349.823136 -281.544803) (xy 349.823657 -281.525527) (xy 349.820738 -281.516328) (xy 349.784416 -281.415998)
			(xy 349.760794 -281.397964) (xy 349.746062 -281.396694) (xy 349.717947 -281.393661) (xy 349.662988 -281.380358)
			(xy 349.610594 -281.359089) (xy 349.561913 -281.330319) (xy 349.518012 -281.294679) (xy 349.479853 -281.25295)
			(xy 349.44827 -281.206045) (xy 349.423957 -281.154992) (xy 349.407446 -281.10091) (xy 349.399098 -281.044983)
			(xy 349.39859 -281.01671) (xy 349.399053 -280.989457) (xy 349.406808 -280.935505) (xy 349.422164 -280.883205)
			(xy 349.444805 -280.833624) (xy 349.474273 -280.787769) (xy 349.509967 -280.746575) (xy 349.55116 -280.71088)
			(xy 349.597013 -280.681411) (xy 349.646594 -280.658768) (xy 349.698893 -280.643411) (xy 349.752845 -280.635654)
			(xy 349.780098 -280.635202) (xy 349.80948 -280.635746) (xy 349.867548 -280.644771) (xy 349.923541 -280.662607)
			(xy 349.97613 -280.688832) (xy 350.024067 -280.722821) (xy 350.045528 -280.742898) (xy 350.053033 -280.749643)
			(xy 350.071763 -280.757108) (xy 350.08185 -280.757376) (xy 350.113346 -280.756614) (xy 350.123572 -280.755992)
			(xy 350.142304 -280.747735) (xy 350.149668 -280.740612) (xy 350.15932 -280.730706) (xy 350.54159 -280.348436)
			(xy 350.564282 -280.326493) (xy 350.614372 -280.28808) (xy 350.66904 -280.256521) (xy 350.727353 -280.232353)
			(xy 350.788319 -280.215988) (xy 350.850897 -280.207707) (xy 350.882458 -280.207212) (xy 352.688906 -280.207212)
			(xy 352.720465 -280.207757) (xy 352.783039 -280.21604) (xy 352.844002 -280.232398) (xy 352.902316 -280.256554)
			(xy 352.956989 -280.288096) (xy 353.007091 -280.326488) (xy 353.029774 -280.348436) (xy 354.391722 -281.710638)
			(xy 354.399119 -281.717488) (xy 354.417718 -281.725224) (xy 354.42779 -281.725624) (xy 356.638606 -281.725624)
			(xy 356.670165 -281.726169) (xy 356.732739 -281.734452) (xy 356.793701 -281.750811) (xy 356.852015 -281.774967)
			(xy 356.906688 -281.80651) (xy 356.956789 -281.844902) (xy 356.979474 -281.866848) (xy 356.99319 -281.880818)
			(xy 356.99955 -281.886727) (xy 357.015176 -281.894263) (xy 357.032419 -281.896178) (xy 357.040942 -281.894534)
			(xy 357.125016 -281.874722) (xy 357.133326 -281.872466) (xy 357.147863 -281.863259) (xy 357.15851 -281.849741)
			(xy 357.161592 -281.841702) (xy 357.161592 -281.841448) (xy 357.17046 -281.816572) (xy 357.194087 -281.769342)
			(xy 357.224 -281.725819) (xy 357.259627 -281.686837) (xy 357.30029 -281.653139) (xy 357.34521 -281.625369)
			(xy 357.393529 -281.604058) (xy 357.444326 -281.589613) (xy 357.496629 -281.582309) (xy 357.523034 -281.58186)
			(xy 357.550284 -281.582348) (xy 357.60423 -281.590108) (xy 357.656523 -281.605466) (xy 357.706098 -281.628109)
			(xy 357.751946 -281.657575) (xy 357.793135 -281.693266) (xy 357.828826 -281.734455) (xy 357.858292 -281.780304)
			(xy 357.880935 -281.829879) (xy 357.896292 -281.882172) (xy 357.904052 -281.936118) (xy 357.904542 -281.963368)
			(xy 357.904095 -281.989775) (xy 357.896812 -282.042085) (xy 357.882379 -282.092889) (xy 357.861074 -282.141215)
			(xy 357.833304 -282.186139) (xy 357.7996 -282.226801) (xy 357.760608 -282.262423) (xy 357.717072 -282.292323)
			(xy 357.669828 -282.31593) (xy 357.644954 -282.32481) (xy 357.6447 -282.32481) (xy 357.63669 -282.327935)
			(xy 357.623216 -282.338598) (xy 357.614011 -282.353108) (xy 357.61168 -282.361386) (xy 357.591868 -282.445714)
			(xy 357.590267 -282.454197) (xy 357.592204 -282.471342) (xy 357.599725 -282.486869) (xy 357.605584 -282.493212)
			(xy 357.818436 -282.70581) (xy 357.840375 -282.728504) (xy 357.87878 -282.778596) (xy 357.910333 -282.833265)
			(xy 357.934495 -282.891578) (xy 357.937946 -282.904438) (xy 358.922828 -282.904438) (xy 358.92331 -282.876864)
			(xy 358.931258 -282.822291) (xy 358.946979 -282.769431) (xy 358.970146 -282.719385) (xy 359.000276 -282.673195)
			(xy 359.036742 -282.631824) (xy 359.057448 -282.613608) (xy 359.065528 -282.606057) (xy 359.074877 -282.586042)
			(xy 359.075482 -282.575) (xy 359.075482 -282.497276) (xy 359.074877 -282.486231) (xy 359.065539 -282.466209)
			(xy 359.057448 -282.458668) (xy 359.036728 -282.440466) (xy 359.000256 -282.399097) (xy 358.970124 -282.352905)
			(xy 358.946959 -282.302855) (xy 358.931246 -282.24999) (xy 358.92331 -282.195413) (xy 358.922828 -282.167838)
			(xy 358.92331 -282.140264) (xy 358.931258 -282.085691) (xy 358.946979 -282.032831) (xy 358.970146 -281.982785)
			(xy 359.000276 -281.936595) (xy 359.036742 -281.895224) (xy 359.057448 -281.877008) (xy 359.065528 -281.869457)
			(xy 359.074877 -281.849442) (xy 359.075482 -281.8384) (xy 359.075482 -281.760676) (xy 359.074877 -281.749631)
			(xy 359.065539 -281.729609) (xy 359.057448 -281.722068) (xy 359.036728 -281.703866) (xy 359.000256 -281.662497)
			(xy 358.970124 -281.616305) (xy 358.946959 -281.566255) (xy 358.931246 -281.51339) (xy 358.92331 -281.458813)
			(xy 358.922828 -281.431238) (xy 358.923291 -281.403984) (xy 358.931043 -281.350032) (xy 358.946397 -281.297732)
			(xy 358.969037 -281.248149) (xy 358.998505 -281.202294) (xy 359.034199 -281.1611) (xy 359.075393 -281.125406)
			(xy 359.121247 -281.095938) (xy 359.17083 -281.073297) (xy 359.22313 -281.057944) (xy 359.277082 -281.050191)
			(xy 359.304336 -281.04973) (xy 359.332193 -281.050198) (xy 359.387312 -281.058328) (xy 359.440665 -281.07438)
			(xy 359.491119 -281.098013) (xy 359.537604 -281.128727) (xy 359.579133 -281.165869) (xy 359.614825 -281.208651)
			(xy 359.643922 -281.256165) (xy 359.665806 -281.307402) (xy 359.673398 -281.33421) (xy 359.675684 -281.3431)
			(xy 359.686352 -281.35834) (xy 359.758234 -281.406092) (xy 359.776268 -281.410156) (xy 359.785412 -281.408886)
			(xy 359.798429 -281.407218) (xy 359.824613 -281.405437) (xy 359.837736 -281.40533) (xy 359.850859 -281.405425)
			(xy 359.877045 -281.407203) (xy 359.89006 -281.408886) (xy 359.899204 -281.410156) (xy 359.917238 -281.406092)
			(xy 359.98912 -281.35834) (xy 359.999788 -281.3431) (xy 360.002074 -281.33421) (xy 360.009666 -281.3074)
			(xy 360.031529 -281.256151) (xy 360.060614 -281.208626) (xy 360.096301 -281.165836) (xy 360.137832 -281.128692)
			(xy 360.184324 -281.097983) (xy 360.234788 -281.074362) (xy 360.28815 -281.058332) (xy 360.343277 -281.050234)
			(xy 360.371136 -281.04973) (xy 360.398392 -281.050122) (xy 360.452347 -281.057884) (xy 360.504649 -281.073247)
			(xy 360.554231 -281.095896) (xy 360.600086 -281.125372) (xy 360.64128 -281.161073) (xy 360.676973 -281.202273)
			(xy 360.706439 -281.248134) (xy 360.729079 -281.297721) (xy 360.744431 -281.350025) (xy 360.752184 -281.403982)
			(xy 360.752644 -281.431238) (xy 360.752172 -281.458537) (xy 360.744396 -281.512578) (xy 360.728994 -281.564959)
			(xy 360.706281 -281.614608) (xy 360.676721 -281.660512) (xy 360.659172 -281.681428) (xy 360.652822 -281.688794)
			(xy 360.646472 -281.706574) (xy 360.649774 -281.795728) (xy 360.657648 -281.813508) (xy 360.664506 -281.820112)
			(xy 360.685621 -281.841757) (xy 360.721427 -281.89048) (xy 360.749095 -281.944242) (xy 360.755366 -281.963368)
			(xy 365.301528 -281.963368) (xy 365.305599 -281.907746) (xy 365.317725 -281.853309) (xy 365.337648 -281.801218)
			(xy 365.364944 -281.752583) (xy 365.39903 -281.70844) (xy 365.439179 -281.669731) (xy 365.484537 -281.63728)
			(xy 365.534137 -281.611779) (xy 365.586921 -281.593772) (xy 365.641764 -281.583642) (xy 365.697498 -281.581605)
			(xy 365.752935 -281.587705) (xy 365.806892 -281.601811) (xy 365.858221 -281.623623) (xy 365.905827 -281.652677)
			(xy 365.948695 -281.688352) (xy 365.985912 -281.729889) (xy 366.016685 -281.776402) (xy 366.040357 -281.826899)
			(xy 366.041066 -281.829256) (xy 374.111518 -281.829256) (xy 374.115589 -281.773634) (xy 374.127715 -281.719197)
			(xy 374.147638 -281.667106) (xy 374.174934 -281.618471) (xy 374.20902 -281.574328) (xy 374.249169 -281.535619)
			(xy 374.294527 -281.503168) (xy 374.344127 -281.477667) (xy 374.396911 -281.45966) (xy 374.451754 -281.44953)
			(xy 374.507488 -281.447493) (xy 374.562925 -281.453593) (xy 374.616882 -281.467699) (xy 374.668211 -281.489511)
			(xy 374.715817 -281.518565) (xy 374.758685 -281.55424) (xy 374.795902 -281.595777) (xy 374.826675 -281.64229)
			(xy 374.850347 -281.692787) (xy 374.866415 -281.746194) (xy 374.874535 -281.80137) (xy 374.875044 -281.829256)
			(xy 375.596656 -281.829256) (xy 375.600727 -281.773634) (xy 375.612853 -281.719197) (xy 375.632776 -281.667106)
			(xy 375.660072 -281.618471) (xy 375.694158 -281.574328) (xy 375.734307 -281.535619) (xy 375.779665 -281.503168)
			(xy 375.829265 -281.477667) (xy 375.882049 -281.45966) (xy 375.936892 -281.44953) (xy 375.992626 -281.447493)
			(xy 376.048063 -281.453593) (xy 376.10202 -281.467699) (xy 376.153349 -281.489511) (xy 376.200955 -281.518565)
			(xy 376.243823 -281.55424) (xy 376.28104 -281.595777) (xy 376.311813 -281.64229) (xy 376.335485 -281.692787)
			(xy 376.351553 -281.746194) (xy 376.359673 -281.80137) (xy 376.360182 -281.829256) (xy 376.359673 -281.857142)
			(xy 376.351553 -281.912318) (xy 376.335485 -281.965725) (xy 376.311813 -282.016222) (xy 376.28104 -282.062735)
			(xy 376.243823 -282.104272) (xy 376.219021 -282.124912) (xy 386.269242 -282.124912) (xy 386.273202 -282.075858)
			(xy 386.284979 -282.028074) (xy 386.30427 -281.982798) (xy 386.330573 -281.941202) (xy 386.363208 -281.904365)
			(xy 386.401329 -281.87324) (xy 386.44395 -281.848633) (xy 386.489966 -281.831181) (xy 386.538185 -281.821337)
			(xy 386.58736 -281.819356) (xy 386.636215 -281.825288) (xy 386.683486 -281.83898) (xy 386.727948 -281.860078)
			(xy 386.768451 -281.888034) (xy 386.803944 -281.922126) (xy 386.833509 -281.96147) (xy 386.85638 -282.005047)
			(xy 386.871964 -282.051728) (xy 386.879859 -282.100305) (xy 386.880354 -282.124912) (xy 387.219202 -282.124912)
			(xy 387.223162 -282.075858) (xy 387.234939 -282.028074) (xy 387.25423 -281.982798) (xy 387.280533 -281.941202)
			(xy 387.313168 -281.904365) (xy 387.351289 -281.87324) (xy 387.39391 -281.848633) (xy 387.439926 -281.831181)
			(xy 387.488145 -281.821337) (xy 387.53732 -281.819356) (xy 387.586175 -281.825288) (xy 387.633446 -281.83898)
			(xy 387.677908 -281.860078) (xy 387.718411 -281.888034) (xy 387.753904 -281.922126) (xy 387.783469 -281.96147)
			(xy 387.80634 -282.005047) (xy 387.821924 -282.051728) (xy 387.829819 -282.100305) (xy 387.830314 -282.124912)
			(xy 389.119122 -282.124912) (xy 389.123082 -282.075858) (xy 389.134859 -282.028074) (xy 389.15415 -281.982798)
			(xy 389.180453 -281.941202) (xy 389.213088 -281.904365) (xy 389.251209 -281.87324) (xy 389.29383 -281.848633)
			(xy 389.339846 -281.831181) (xy 389.388065 -281.821337) (xy 389.43724 -281.819356) (xy 389.486095 -281.825288)
			(xy 389.533366 -281.83898) (xy 389.577828 -281.860078) (xy 389.618331 -281.888034) (xy 389.653824 -281.922126)
			(xy 389.683389 -281.96147) (xy 389.70626 -282.005047) (xy 389.721844 -282.051728) (xy 389.729739 -282.100305)
			(xy 389.730234 -282.124912) (xy 390.069082 -282.124912) (xy 390.073042 -282.075858) (xy 390.084819 -282.028074)
			(xy 390.10411 -281.982798) (xy 390.130413 -281.941202) (xy 390.163048 -281.904365) (xy 390.201169 -281.87324)
			(xy 390.24379 -281.848633) (xy 390.289806 -281.831181) (xy 390.338025 -281.821337) (xy 390.3872 -281.819356)
			(xy 390.436055 -281.825288) (xy 390.483326 -281.83898) (xy 390.527788 -281.860078) (xy 390.568291 -281.888034)
			(xy 390.603784 -281.922126) (xy 390.633349 -281.96147) (xy 390.65622 -282.005047) (xy 390.671804 -282.051728)
			(xy 390.679699 -282.100305) (xy 390.680194 -282.124912) (xy 390.679699 -282.149519) (xy 390.671804 -282.198096)
			(xy 390.65622 -282.244777) (xy 390.633349 -282.288354) (xy 390.603784 -282.327698) (xy 390.568291 -282.36179)
			(xy 390.527788 -282.389746) (xy 390.483326 -282.410844) (xy 390.436055 -282.424536) (xy 390.3872 -282.430468)
			(xy 390.338025 -282.428487) (xy 390.289806 -282.418643) (xy 390.24379 -282.401191) (xy 390.201169 -282.376584)
			(xy 390.163048 -282.345459) (xy 390.130413 -282.308622) (xy 390.10411 -282.267026) (xy 390.084819 -282.22175)
			(xy 390.073042 -282.173966) (xy 390.069082 -282.124912) (xy 389.730234 -282.124912) (xy 389.729739 -282.149519)
			(xy 389.721844 -282.198096) (xy 389.70626 -282.244777) (xy 389.683389 -282.288354) (xy 389.653824 -282.327698)
			(xy 389.618331 -282.36179) (xy 389.577828 -282.389746) (xy 389.533366 -282.410844) (xy 389.486095 -282.424536)
			(xy 389.43724 -282.430468) (xy 389.388065 -282.428487) (xy 389.339846 -282.418643) (xy 389.29383 -282.401191)
			(xy 389.251209 -282.376584) (xy 389.213088 -282.345459) (xy 389.180453 -282.308622) (xy 389.15415 -282.267026)
			(xy 389.134859 -282.22175) (xy 389.123082 -282.173966) (xy 389.119122 -282.124912) (xy 387.830314 -282.124912)
			(xy 387.829819 -282.149519) (xy 387.821924 -282.198096) (xy 387.80634 -282.244777) (xy 387.783469 -282.288354)
			(xy 387.753904 -282.327698) (xy 387.718411 -282.36179) (xy 387.677908 -282.389746) (xy 387.633446 -282.410844)
			(xy 387.586175 -282.424536) (xy 387.53732 -282.430468) (xy 387.488145 -282.428487) (xy 387.439926 -282.418643)
			(xy 387.39391 -282.401191) (xy 387.351289 -282.376584) (xy 387.313168 -282.345459) (xy 387.280533 -282.308622)
			(xy 387.25423 -282.267026) (xy 387.234939 -282.22175) (xy 387.223162 -282.173966) (xy 387.219202 -282.124912)
			(xy 386.880354 -282.124912) (xy 386.879859 -282.149519) (xy 386.871964 -282.198096) (xy 386.85638 -282.244777)
			(xy 386.833509 -282.288354) (xy 386.803944 -282.327698) (xy 386.768451 -282.36179) (xy 386.727948 -282.389746)
			(xy 386.683486 -282.410844) (xy 386.636215 -282.424536) (xy 386.58736 -282.430468) (xy 386.538185 -282.428487)
			(xy 386.489966 -282.418643) (xy 386.44395 -282.401191) (xy 386.401329 -282.376584) (xy 386.363208 -282.345459)
			(xy 386.330573 -282.308622) (xy 386.30427 -282.267026) (xy 386.284979 -282.22175) (xy 386.273202 -282.173966)
			(xy 386.269242 -282.124912) (xy 376.219021 -282.124912) (xy 376.200955 -282.139947) (xy 376.153349 -282.169001)
			(xy 376.10202 -282.190813) (xy 376.048063 -282.204919) (xy 375.992626 -282.211019) (xy 375.936892 -282.208982)
			(xy 375.882049 -282.198852) (xy 375.829265 -282.180845) (xy 375.779665 -282.155344) (xy 375.734307 -282.122893)
			(xy 375.694158 -282.084184) (xy 375.660072 -282.040041) (xy 375.632776 -281.991406) (xy 375.612853 -281.939315)
			(xy 375.600727 -281.884878) (xy 375.596656 -281.829256) (xy 374.875044 -281.829256) (xy 374.874535 -281.857142)
			(xy 374.866415 -281.912318) (xy 374.850347 -281.965725) (xy 374.826675 -282.016222) (xy 374.795902 -282.062735)
			(xy 374.758685 -282.104272) (xy 374.715817 -282.139947) (xy 374.668211 -282.169001) (xy 374.616882 -282.190813)
			(xy 374.562925 -282.204919) (xy 374.507488 -282.211019) (xy 374.451754 -282.208982) (xy 374.396911 -282.198852)
			(xy 374.344127 -282.180845) (xy 374.294527 -282.155344) (xy 374.249169 -282.122893) (xy 374.20902 -282.084184)
			(xy 374.174934 -282.040041) (xy 374.147638 -281.991406) (xy 374.127715 -281.939315) (xy 374.115589 -281.884878)
			(xy 374.111518 -281.829256) (xy 366.041066 -281.829256) (xy 366.056425 -281.880306) (xy 366.064545 -281.935482)
			(xy 366.065054 -281.963368) (xy 366.064545 -281.991254) (xy 366.056425 -282.04643) (xy 366.040357 -282.099837)
			(xy 366.016685 -282.150334) (xy 365.985912 -282.196847) (xy 365.948695 -282.238384) (xy 365.905827 -282.274059)
			(xy 365.858221 -282.303113) (xy 365.806892 -282.324925) (xy 365.752935 -282.339031) (xy 365.697498 -282.345131)
			(xy 365.641764 -282.343094) (xy 365.586921 -282.332964) (xy 365.534137 -282.314957) (xy 365.484537 -282.289456)
			(xy 365.439179 -282.257005) (xy 365.39903 -282.218296) (xy 365.364944 -282.174153) (xy 365.337648 -282.125518)
			(xy 365.317725 -282.073427) (xy 365.305599 -282.01899) (xy 365.301528 -281.963368) (xy 360.755366 -281.963368)
			(xy 360.767934 -282.001698) (xy 360.777469 -282.061406) (xy 360.778044 -282.091638) (xy 360.777546 -282.119276)
			(xy 360.769554 -282.173971) (xy 360.753757 -282.226942) (xy 360.730486 -282.27708) (xy 360.700226 -282.323338)
			(xy 360.682286 -282.344368) (xy 360.673904 -282.353766) (xy 360.668062 -282.37815) (xy 360.692192 -282.47213)
			(xy 360.695891 -282.484077) (xy 360.712669 -282.502585) (xy 360.724196 -282.507436) (xy 360.751606 -282.517769)
			(xy 360.803121 -282.545652) (xy 360.849766 -282.581084) (xy 360.890444 -282.623233) (xy 360.924198 -282.671107)
			(xy 360.950234 -282.723579) (xy 360.967939 -282.779416) (xy 360.976898 -282.837304) (xy 360.977434 -282.866592)
			(xy 360.976899 -282.893855) (xy 361.307047 -282.893855) (xy 361.307047 -282.839345) (xy 361.314805 -282.785391)
			(xy 361.330163 -282.73309) (xy 361.352808 -282.683507) (xy 361.382279 -282.637652) (xy 361.417976 -282.596458)
			(xy 361.459173 -282.560763) (xy 361.50503 -282.531295) (xy 361.554614 -282.508654) (xy 361.606917 -282.4933)
			(xy 361.660871 -282.485546) (xy 361.688126 -282.485084) (xy 361.715498 -282.485514) (xy 361.769679 -282.493338)
			(xy 361.822183 -282.508834) (xy 361.87193 -282.531684) (xy 361.917894 -282.561418) (xy 361.938824 -282.579064)
			(xy 361.939078 -282.579318) (xy 361.946165 -282.584904) (xy 361.963082 -282.59115) (xy 361.972098 -282.59151)
			(xy 362.039154 -282.59151) (xy 362.048168 -282.591129) (xy 362.065085 -282.584898) (xy 362.072174 -282.579318)
			(xy 362.072174 -282.579064) (xy 362.072428 -282.579064) (xy 362.093372 -282.56144) (xy 362.139342 -282.531727)
			(xy 362.189087 -282.508889) (xy 362.241584 -282.493394) (xy 362.295758 -282.485561) (xy 362.323126 -282.485084)
			(xy 362.350375 -282.485588) (xy 362.404319 -282.493347) (xy 362.45661 -282.508704) (xy 362.506183 -282.531346)
			(xy 362.552029 -282.560812) (xy 362.593215 -282.596503) (xy 362.628903 -282.637692) (xy 362.658366 -282.68354)
			(xy 362.681005 -282.733115) (xy 362.696359 -282.785406) (xy 362.704114 -282.839351) (xy 362.704114 -282.893849)
			(xy 362.696359 -282.947794) (xy 362.681005 -283.000085) (xy 362.658366 -283.04966) (xy 362.628903 -283.095508)
			(xy 362.593215 -283.136697) (xy 362.552029 -283.172388) (xy 362.506183 -283.201854) (xy 362.45661 -283.224496)
			(xy 362.404319 -283.239853) (xy 362.350375 -283.247612) (xy 362.323126 -283.2481) (xy 362.295756 -283.247619)
			(xy 362.241578 -283.239805) (xy 362.189075 -283.224319) (xy 362.139328 -283.201481) (xy 362.09336 -283.17176)
			(xy 362.072428 -283.15412) (xy 362.072174 -283.153866) (xy 362.065073 -283.1483) (xy 362.048167 -283.142042)
			(xy 362.039154 -283.141674) (xy 361.972098 -283.141674) (xy 361.963082 -283.142036) (xy 361.946165 -283.148281)
			(xy 361.939078 -283.153866) (xy 361.939078 -283.15412) (xy 361.938824 -283.15412) (xy 361.917896 -283.171764)
			(xy 361.871922 -283.201475) (xy 361.822173 -283.224309) (xy 361.769672 -283.239799) (xy 361.715495 -283.247626)
			(xy 361.688126 -283.2481) (xy 361.660871 -283.247654) (xy 361.606917 -283.2399) (xy 361.554614 -283.224546)
			(xy 361.50503 -283.201905) (xy 361.459173 -283.172437) (xy 361.417976 -283.136742) (xy 361.382279 -283.095548)
			(xy 361.352808 -283.049693) (xy 361.330163 -283.00011) (xy 361.314805 -282.947809) (xy 361.307047 -282.893855)
			(xy 360.976899 -282.893855) (xy 360.976849 -282.89643) (xy 360.96754 -282.955376) (xy 360.958892 -282.98394)
			(xy 360.95559 -282.994354) (xy 360.957876 -283.015944) (xy 361.008168 -283.100526) (xy 361.02544 -283.112972)
			(xy 361.036362 -283.115004) (xy 361.062178 -283.120347) (xy 361.112094 -283.137315) (xy 361.159199 -283.160995)
			(xy 361.202593 -283.190935) (xy 361.241451 -283.226566) (xy 361.275033 -283.267209) (xy 361.302699 -283.312088)
			(xy 361.323921 -283.360349) (xy 361.338295 -283.411073) (xy 361.345547 -283.463293) (xy 361.345988 -283.489654)
			(xy 361.345406 -283.519777) (xy 361.33593 -283.579274) (xy 361.317223 -283.636542) (xy 361.289749 -283.69016)
			(xy 361.254191 -283.738794) (xy 361.233212 -283.760418) (xy 361.226373 -283.767819) (xy 361.218652 -283.786417)
			(xy 361.218226 -283.796486) (xy 361.218226 -283.868622) (xy 361.218633 -283.878693) (xy 361.226366 -283.897291)
			(xy 361.233212 -283.90469) (xy 361.254215 -283.926294) (xy 361.28978 -283.974929) (xy 361.317255 -284.02855)
			(xy 361.331634 -284.072584) (xy 366.233202 -284.072584) (xy 366.233658 -284.045213) (xy 366.241478 -283.991034)
			(xy 366.25697 -283.938531) (xy 366.279814 -283.888784) (xy 366.30954 -283.842817) (xy 366.327182 -283.821886)
			(xy 366.327436 -283.821632) (xy 366.333019 -283.814543) (xy 366.339267 -283.797628) (xy 366.339628 -283.788612)
			(xy 366.339628 -283.721556) (xy 366.339238 -283.712543) (xy 366.333013 -283.695626) (xy 366.327436 -283.688536)
			(xy 366.327182 -283.688536) (xy 366.327182 -283.688282) (xy 366.309565 -283.667332) (xy 366.279851 -283.621364)
			(xy 366.257011 -283.571621) (xy 366.241514 -283.519124) (xy 366.23368 -283.464952) (xy 366.233202 -283.437584)
			(xy 366.233688 -283.410333) (xy 366.241444 -283.356385) (xy 366.256799 -283.30409) (xy 366.279441 -283.254513)
			(xy 366.308907 -283.208663) (xy 366.344598 -283.167472) (xy 366.385789 -283.131781) (xy 366.431639 -283.102315)
			(xy 366.481216 -283.079673) (xy 366.533511 -283.064318) (xy 366.587459 -283.056562) (xy 366.641961 -283.056562)
			(xy 366.695909 -283.064318) (xy 366.748204 -283.079673) (xy 366.797781 -283.102315) (xy 366.843631 -283.131781)
			(xy 366.884822 -283.167472) (xy 366.920513 -283.208663) (xy 366.949979 -283.254513) (xy 366.972621 -283.30409)
			(xy 366.987976 -283.356385) (xy 366.995732 -283.410333) (xy 366.996218 -283.437584) (xy 366.995763 -283.464955)
			(xy 366.987945 -283.519135) (xy 366.972455 -283.571639) (xy 366.94961 -283.621386) (xy 366.919882 -283.667352)
			(xy 366.902238 -283.688282) (xy 366.901984 -283.688536) (xy 366.896416 -283.695635) (xy 366.890159 -283.712542)
			(xy 366.889792 -283.721556) (xy 366.889792 -283.788612) (xy 366.890145 -283.797629) (xy 366.896396 -283.814546)
			(xy 366.901984 -283.821632) (xy 366.902238 -283.821632) (xy 366.902238 -283.821886) (xy 366.91989 -283.842807)
			(xy 366.949599 -283.888784) (xy 366.972432 -283.938534) (xy 366.98792 -283.991037) (xy 366.995746 -284.045214)
			(xy 366.996218 -284.072584) (xy 366.995732 -284.099835) (xy 366.990228 -284.138116) (xy 373.346978 -284.138116)
			(xy 373.351049 -284.082494) (xy 373.363175 -284.028057) (xy 373.383098 -283.975966) (xy 373.410394 -283.927331)
			(xy 373.44448 -283.883188) (xy 373.484629 -283.844479) (xy 373.529987 -283.812028) (xy 373.579587 -283.786527)
			(xy 373.632371 -283.76852) (xy 373.687214 -283.75839) (xy 373.742948 -283.756353) (xy 373.798385 -283.762453)
			(xy 373.852342 -283.776559) (xy 373.903671 -283.798371) (xy 373.951277 -283.827425) (xy 373.994145 -283.8631)
			(xy 374.021396 -283.893514) (xy 379.638052 -283.893514) (xy 379.638619 -283.864133) (xy 379.647646 -283.806068)
			(xy 379.665474 -283.750075) (xy 379.691681 -283.69748) (xy 379.725646 -283.649528) (xy 379.766565 -283.607354)
			(xy 379.78969 -283.589222) (xy 379.798622 -283.58175) (xy 379.809075 -283.560969) (xy 379.809756 -283.549344)
			(xy 379.811026 -283.457396) (xy 379.80112 -283.436314) (xy 379.791976 -283.428948) (xy 379.770116 -283.410756)
			(xy 379.731578 -283.368934) (xy 379.699673 -283.321855) (xy 379.675108 -283.270563) (xy 379.658427 -283.216193)
			(xy 379.65 -283.15995) (xy 379.649482 -283.131514) (xy 379.649968 -283.104263) (xy 379.657724 -283.050315)
			(xy 379.673079 -282.99802) (xy 379.695721 -282.948443) (xy 379.725187 -282.902593) (xy 379.760878 -282.861402)
			(xy 379.802069 -282.825711) (xy 379.847919 -282.796245) (xy 379.897496 -282.773603) (xy 379.949791 -282.758248)
			(xy 380.003739 -282.750492) (xy 380.058241 -282.750492) (xy 380.112189 -282.758248) (xy 380.164484 -282.773603)
			(xy 380.214061 -282.796245) (xy 380.259911 -282.825711) (xy 380.301102 -282.861402) (xy 380.336793 -282.902593)
			(xy 380.366259 -282.948443) (xy 380.388901 -282.99802) (xy 380.404256 -283.050315) (xy 380.407787 -283.074872)
			(xy 384.369068 -283.074872) (xy 384.373028 -283.025818) (xy 384.384805 -282.978034) (xy 384.404096 -282.932758)
			(xy 384.430399 -282.891162) (xy 384.463034 -282.854325) (xy 384.501155 -282.8232) (xy 384.543776 -282.798593)
			(xy 384.589792 -282.781141) (xy 384.638011 -282.771297) (xy 384.687186 -282.769316) (xy 384.736041 -282.775248)
			(xy 384.783312 -282.78894) (xy 384.827774 -282.810038) (xy 384.868277 -282.837994) (xy 384.90377 -282.872086)
			(xy 384.933335 -282.91143) (xy 384.956206 -282.955007) (xy 384.97179 -283.001688) (xy 384.979685 -283.050265)
			(xy 384.98018 -283.074872) (xy 385.319028 -283.074872) (xy 385.322988 -283.025818) (xy 385.334765 -282.978034)
			(xy 385.354056 -282.932758) (xy 385.380359 -282.891162) (xy 385.412994 -282.854325) (xy 385.451115 -282.8232)
			(xy 385.493736 -282.798593) (xy 385.539752 -282.781141) (xy 385.587971 -282.771297) (xy 385.637146 -282.769316)
			(xy 385.686001 -282.775248) (xy 385.733272 -282.78894) (xy 385.777734 -282.810038) (xy 385.818237 -282.837994)
			(xy 385.85373 -282.872086) (xy 385.883295 -282.91143) (xy 385.906166 -282.955007) (xy 385.92175 -283.001688)
			(xy 385.929645 -283.050265) (xy 385.93014 -283.074872) (xy 391.019042 -283.074872) (xy 391.023002 -283.025818)
			(xy 391.034779 -282.978034) (xy 391.05407 -282.932758) (xy 391.080373 -282.891162) (xy 391.113008 -282.854325)
			(xy 391.151129 -282.8232) (xy 391.19375 -282.798593) (xy 391.239766 -282.781141) (xy 391.287985 -282.771297)
			(xy 391.33716 -282.769316) (xy 391.386015 -282.775248) (xy 391.433286 -282.78894) (xy 391.477748 -282.810038)
			(xy 391.518251 -282.837994) (xy 391.553744 -282.872086) (xy 391.583309 -282.91143) (xy 391.60618 -282.955007)
			(xy 391.621764 -283.001688) (xy 391.629659 -283.050265) (xy 391.630154 -283.074872) (xy 391.969002 -283.074872)
			(xy 391.972962 -283.025818) (xy 391.984739 -282.978034) (xy 392.00403 -282.932758) (xy 392.030333 -282.891162)
			(xy 392.062968 -282.854325) (xy 392.101089 -282.8232) (xy 392.14371 -282.798593) (xy 392.189726 -282.781141)
			(xy 392.237945 -282.771297) (xy 392.28712 -282.769316) (xy 392.335975 -282.775248) (xy 392.383246 -282.78894)
			(xy 392.427708 -282.810038) (xy 392.468211 -282.837994) (xy 392.503704 -282.872086) (xy 392.533269 -282.91143)
			(xy 392.55614 -282.955007) (xy 392.571724 -283.001688) (xy 392.579619 -283.050265) (xy 392.580114 -283.074872)
			(xy 394.819136 -283.074872) (xy 394.823096 -283.025818) (xy 394.834873 -282.978034) (xy 394.854164 -282.932758)
			(xy 394.880467 -282.891162) (xy 394.913102 -282.854325) (xy 394.951223 -282.8232) (xy 394.993844 -282.798593)
			(xy 395.03986 -282.781141) (xy 395.088079 -282.771297) (xy 395.137254 -282.769316) (xy 395.186109 -282.775248)
			(xy 395.23338 -282.78894) (xy 395.277842 -282.810038) (xy 395.318345 -282.837994) (xy 395.353838 -282.872086)
			(xy 395.383403 -282.91143) (xy 395.406274 -282.955007) (xy 395.421858 -283.001688) (xy 395.429753 -283.050265)
			(xy 395.430248 -283.074872) (xy 395.429753 -283.099479) (xy 395.421858 -283.148056) (xy 395.406274 -283.194737)
			(xy 395.383403 -283.238314) (xy 395.353838 -283.277658) (xy 395.318345 -283.31175) (xy 395.277842 -283.339706)
			(xy 395.23338 -283.360804) (xy 395.186109 -283.374496) (xy 395.137254 -283.380428) (xy 395.088079 -283.378447)
			(xy 395.03986 -283.368603) (xy 394.993844 -283.351151) (xy 394.951223 -283.326544) (xy 394.913102 -283.295419)
			(xy 394.880467 -283.258582) (xy 394.854164 -283.216986) (xy 394.834873 -283.17171) (xy 394.823096 -283.123926)
			(xy 394.819136 -283.074872) (xy 392.580114 -283.074872) (xy 392.579619 -283.099479) (xy 392.571724 -283.148056)
			(xy 392.55614 -283.194737) (xy 392.533269 -283.238314) (xy 392.503704 -283.277658) (xy 392.468211 -283.31175)
			(xy 392.427708 -283.339706) (xy 392.383246 -283.360804) (xy 392.335975 -283.374496) (xy 392.28712 -283.380428)
			(xy 392.237945 -283.378447) (xy 392.189726 -283.368603) (xy 392.14371 -283.351151) (xy 392.101089 -283.326544)
			(xy 392.062968 -283.295419) (xy 392.030333 -283.258582) (xy 392.00403 -283.216986) (xy 391.984739 -283.17171)
			(xy 391.972962 -283.123926) (xy 391.969002 -283.074872) (xy 391.630154 -283.074872) (xy 391.629659 -283.099479)
			(xy 391.621764 -283.148056) (xy 391.60618 -283.194737) (xy 391.583309 -283.238314) (xy 391.553744 -283.277658)
			(xy 391.518251 -283.31175) (xy 391.477748 -283.339706) (xy 391.433286 -283.360804) (xy 391.386015 -283.374496)
			(xy 391.33716 -283.380428) (xy 391.287985 -283.378447) (xy 391.239766 -283.368603) (xy 391.19375 -283.351151)
			(xy 391.151129 -283.326544) (xy 391.113008 -283.295419) (xy 391.080373 -283.258582) (xy 391.05407 -283.216986)
			(xy 391.034779 -283.17171) (xy 391.023002 -283.123926) (xy 391.019042 -283.074872) (xy 385.93014 -283.074872)
			(xy 385.929645 -283.099479) (xy 385.92175 -283.148056) (xy 385.906166 -283.194737) (xy 385.883295 -283.238314)
			(xy 385.85373 -283.277658) (xy 385.818237 -283.31175) (xy 385.777734 -283.339706) (xy 385.733272 -283.360804)
			(xy 385.686001 -283.374496) (xy 385.637146 -283.380428) (xy 385.587971 -283.378447) (xy 385.539752 -283.368603)
			(xy 385.493736 -283.351151) (xy 385.451115 -283.326544) (xy 385.412994 -283.295419) (xy 385.380359 -283.258582)
			(xy 385.354056 -283.216986) (xy 385.334765 -283.17171) (xy 385.322988 -283.123926) (xy 385.319028 -283.074872)
			(xy 384.98018 -283.074872) (xy 384.979685 -283.099479) (xy 384.97179 -283.148056) (xy 384.956206 -283.194737)
			(xy 384.933335 -283.238314) (xy 384.90377 -283.277658) (xy 384.868277 -283.31175) (xy 384.827774 -283.339706)
			(xy 384.783312 -283.360804) (xy 384.736041 -283.374496) (xy 384.687186 -283.380428) (xy 384.638011 -283.378447)
			(xy 384.589792 -283.368603) (xy 384.543776 -283.351151) (xy 384.501155 -283.326544) (xy 384.463034 -283.295419)
			(xy 384.430399 -283.258582) (xy 384.404096 -283.216986) (xy 384.384805 -283.17171) (xy 384.373028 -283.123926)
			(xy 384.369068 -283.074872) (xy 380.407787 -283.074872) (xy 380.412012 -283.104263) (xy 380.412498 -283.131514)
			(xy 380.411971 -283.160897) (xy 380.402938 -283.218964) (xy 380.385103 -283.274959) (xy 380.358889 -283.327554)
			(xy 380.324916 -283.375505) (xy 380.283989 -283.417676) (xy 380.26086 -283.435806) (xy 380.251924 -283.443275)
			(xy 380.241471 -283.464057) (xy 380.240794 -283.475684) (xy 380.239524 -283.567632) (xy 380.24943 -283.588714)
			(xy 380.258574 -283.59608) (xy 380.280389 -283.614324) (xy 380.318933 -283.656134) (xy 380.350844 -283.703201)
			(xy 380.375417 -283.754484) (xy 380.392107 -283.808845) (xy 380.400545 -283.865081) (xy 380.401068 -283.893514)
			(xy 381.034542 -283.893514) (xy 381.038613 -283.837892) (xy 381.050739 -283.783455) (xy 381.070662 -283.731364)
			(xy 381.097958 -283.682729) (xy 381.132044 -283.638586) (xy 381.172193 -283.599877) (xy 381.217551 -283.567426)
			(xy 381.267151 -283.541925) (xy 381.319935 -283.523918) (xy 381.374778 -283.513788) (xy 381.430512 -283.511751)
			(xy 381.485949 -283.517851) (xy 381.539906 -283.531957) (xy 381.591235 -283.553769) (xy 381.638841 -283.582823)
			(xy 381.681709 -283.618498) (xy 381.718926 -283.660035) (xy 381.749699 -283.706548) (xy 381.773371 -283.757045)
			(xy 381.789439 -283.810452) (xy 381.797559 -283.865628) (xy 381.798068 -283.893514) (xy 381.797559 -283.9214)
			(xy 381.789439 -283.976576) (xy 381.774921 -284.024832) (xy 386.269242 -284.024832) (xy 386.273202 -283.975778)
			(xy 386.284979 -283.927994) (xy 386.30427 -283.882718) (xy 386.330573 -283.841122) (xy 386.363208 -283.804285)
			(xy 386.401329 -283.77316) (xy 386.44395 -283.748553) (xy 386.489966 -283.731101) (xy 386.538185 -283.721257)
			(xy 386.58736 -283.719276) (xy 386.636215 -283.725208) (xy 386.683486 -283.7389) (xy 386.727948 -283.759998)
			(xy 386.768451 -283.787954) (xy 386.803944 -283.822046) (xy 386.833509 -283.86139) (xy 386.85638 -283.904967)
			(xy 386.871964 -283.951648) (xy 386.879859 -284.000225) (xy 386.880354 -284.024832) (xy 387.219202 -284.024832)
			(xy 387.223162 -283.975778) (xy 387.234939 -283.927994) (xy 387.25423 -283.882718) (xy 387.280533 -283.841122)
			(xy 387.313168 -283.804285) (xy 387.351289 -283.77316) (xy 387.39391 -283.748553) (xy 387.439926 -283.731101)
			(xy 387.488145 -283.721257) (xy 387.53732 -283.719276) (xy 387.586175 -283.725208) (xy 387.633446 -283.7389)
			(xy 387.677908 -283.759998) (xy 387.718411 -283.787954) (xy 387.753904 -283.822046) (xy 387.783469 -283.86139)
			(xy 387.80634 -283.904967) (xy 387.821924 -283.951648) (xy 387.829819 -284.000225) (xy 387.830314 -284.024832)
			(xy 389.119122 -284.024832) (xy 389.123082 -283.975778) (xy 389.134859 -283.927994) (xy 389.15415 -283.882718)
			(xy 389.180453 -283.841122) (xy 389.213088 -283.804285) (xy 389.251209 -283.77316) (xy 389.29383 -283.748553)
			(xy 389.339846 -283.731101) (xy 389.388065 -283.721257) (xy 389.43724 -283.719276) (xy 389.486095 -283.725208)
			(xy 389.533366 -283.7389) (xy 389.577828 -283.759998) (xy 389.618331 -283.787954) (xy 389.653824 -283.822046)
			(xy 389.683389 -283.86139) (xy 389.70626 -283.904967) (xy 389.721844 -283.951648) (xy 389.729739 -284.000225)
			(xy 389.730234 -284.024832) (xy 390.069082 -284.024832) (xy 390.073042 -283.975778) (xy 390.084819 -283.927994)
			(xy 390.10411 -283.882718) (xy 390.130413 -283.841122) (xy 390.163048 -283.804285) (xy 390.201169 -283.77316)
			(xy 390.24379 -283.748553) (xy 390.289806 -283.731101) (xy 390.338025 -283.721257) (xy 390.3872 -283.719276)
			(xy 390.436055 -283.725208) (xy 390.483326 -283.7389) (xy 390.527788 -283.759998) (xy 390.568291 -283.787954)
			(xy 390.603784 -283.822046) (xy 390.633349 -283.86139) (xy 390.65622 -283.904967) (xy 390.671804 -283.951648)
			(xy 390.679699 -284.000225) (xy 390.680194 -284.024832) (xy 390.679699 -284.049439) (xy 390.671804 -284.098016)
			(xy 390.65622 -284.144697) (xy 390.633349 -284.188274) (xy 390.603784 -284.227618) (xy 390.568291 -284.26171)
			(xy 390.527788 -284.289666) (xy 390.483326 -284.310764) (xy 390.436055 -284.324456) (xy 390.3872 -284.330388)
			(xy 390.338025 -284.328407) (xy 390.289806 -284.318563) (xy 390.24379 -284.301111) (xy 390.201169 -284.276504)
			(xy 390.163048 -284.245379) (xy 390.130413 -284.208542) (xy 390.10411 -284.166946) (xy 390.084819 -284.12167)
			(xy 390.073042 -284.073886) (xy 390.069082 -284.024832) (xy 389.730234 -284.024832) (xy 389.729739 -284.049439)
			(xy 389.721844 -284.098016) (xy 389.70626 -284.144697) (xy 389.683389 -284.188274) (xy 389.653824 -284.227618)
			(xy 389.618331 -284.26171) (xy 389.577828 -284.289666) (xy 389.533366 -284.310764) (xy 389.486095 -284.324456)
			(xy 389.43724 -284.330388) (xy 389.388065 -284.328407) (xy 389.339846 -284.318563) (xy 389.29383 -284.301111)
			(xy 389.251209 -284.276504) (xy 389.213088 -284.245379) (xy 389.180453 -284.208542) (xy 389.15415 -284.166946)
			(xy 389.134859 -284.12167) (xy 389.123082 -284.073886) (xy 389.119122 -284.024832) (xy 387.830314 -284.024832)
			(xy 387.829819 -284.049439) (xy 387.821924 -284.098016) (xy 387.80634 -284.144697) (xy 387.783469 -284.188274)
			(xy 387.753904 -284.227618) (xy 387.718411 -284.26171) (xy 387.677908 -284.289666) (xy 387.633446 -284.310764)
			(xy 387.586175 -284.324456) (xy 387.53732 -284.330388) (xy 387.488145 -284.328407) (xy 387.439926 -284.318563)
			(xy 387.39391 -284.301111) (xy 387.351289 -284.276504) (xy 387.313168 -284.245379) (xy 387.280533 -284.208542)
			(xy 387.25423 -284.166946) (xy 387.234939 -284.12167) (xy 387.223162 -284.073886) (xy 387.219202 -284.024832)
			(xy 386.880354 -284.024832) (xy 386.879859 -284.049439) (xy 386.871964 -284.098016) (xy 386.85638 -284.144697)
			(xy 386.833509 -284.188274) (xy 386.803944 -284.227618) (xy 386.768451 -284.26171) (xy 386.727948 -284.289666)
			(xy 386.683486 -284.310764) (xy 386.636215 -284.324456) (xy 386.58736 -284.330388) (xy 386.538185 -284.328407)
			(xy 386.489966 -284.318563) (xy 386.44395 -284.301111) (xy 386.401329 -284.276504) (xy 386.363208 -284.245379)
			(xy 386.330573 -284.208542) (xy 386.30427 -284.166946) (xy 386.284979 -284.12167) (xy 386.273202 -284.073886)
			(xy 386.269242 -284.024832) (xy 381.774921 -284.024832) (xy 381.773371 -284.029983) (xy 381.749699 -284.08048)
			(xy 381.718926 -284.126993) (xy 381.681709 -284.16853) (xy 381.638841 -284.204205) (xy 381.591235 -284.233259)
			(xy 381.539906 -284.255071) (xy 381.485949 -284.269177) (xy 381.430512 -284.275277) (xy 381.374778 -284.27324)
			(xy 381.319935 -284.26311) (xy 381.267151 -284.245103) (xy 381.217551 -284.219602) (xy 381.172193 -284.187151)
			(xy 381.132044 -284.148442) (xy 381.097958 -284.104299) (xy 381.070662 -284.055664) (xy 381.050739 -284.003573)
			(xy 381.038613 -283.949136) (xy 381.034542 -283.893514) (xy 380.401068 -283.893514) (xy 380.400582 -283.920765)
			(xy 380.392826 -283.974713) (xy 380.377471 -284.027008) (xy 380.354829 -284.076585) (xy 380.325363 -284.122435)
			(xy 380.289672 -284.163626) (xy 380.248481 -284.199317) (xy 380.202631 -284.228783) (xy 380.153054 -284.251425)
			(xy 380.100759 -284.26678) (xy 380.046811 -284.274536) (xy 379.992309 -284.274536) (xy 379.938361 -284.26678)
			(xy 379.886066 -284.251425) (xy 379.836489 -284.228783) (xy 379.790639 -284.199317) (xy 379.749448 -284.163626)
			(xy 379.713757 -284.122435) (xy 379.684291 -284.076585) (xy 379.661649 -284.027008) (xy 379.646294 -283.974713)
			(xy 379.638538 -283.920765) (xy 379.638052 -283.893514) (xy 374.021396 -283.893514) (xy 374.031362 -283.904637)
			(xy 374.062135 -283.95115) (xy 374.085807 -284.001647) (xy 374.101875 -284.055054) (xy 374.109995 -284.11023)
			(xy 374.110504 -284.138116) (xy 374.109995 -284.166002) (xy 374.101875 -284.221178) (xy 374.085807 -284.274585)
			(xy 374.062135 -284.325082) (xy 374.031362 -284.371595) (xy 373.994145 -284.413132) (xy 373.951277 -284.448807)
			(xy 373.903671 -284.477861) (xy 373.852342 -284.499673) (xy 373.798385 -284.513779) (xy 373.742948 -284.519879)
			(xy 373.687214 -284.517842) (xy 373.632371 -284.507712) (xy 373.579587 -284.489705) (xy 373.529987 -284.464204)
			(xy 373.484629 -284.431753) (xy 373.44448 -284.393044) (xy 373.410394 -284.348901) (xy 373.383098 -284.300266)
			(xy 373.363175 -284.248175) (xy 373.351049 -284.193738) (xy 373.346978 -284.138116) (xy 366.990228 -284.138116)
			(xy 366.987976 -284.153783) (xy 366.972621 -284.206078) (xy 366.949979 -284.255655) (xy 366.920513 -284.301505)
			(xy 366.884822 -284.342696) (xy 366.843631 -284.378387) (xy 366.797781 -284.407853) (xy 366.748204 -284.430495)
			(xy 366.695909 -284.44585) (xy 366.641961 -284.453606) (xy 366.587459 -284.453606) (xy 366.533511 -284.44585)
			(xy 366.481216 -284.430495) (xy 366.431639 -284.407853) (xy 366.385789 -284.378387) (xy 366.344598 -284.342696)
			(xy 366.308907 -284.301505) (xy 366.279441 -284.255655) (xy 366.256799 -284.206078) (xy 366.241444 -284.153783)
			(xy 366.233688 -284.099835) (xy 366.233202 -284.072584) (xy 361.331634 -284.072584) (xy 361.335958 -284.085825)
			(xy 361.345423 -284.145328) (xy 361.345988 -284.175454) (xy 361.345502 -284.202705) (xy 361.337746 -284.256653)
			(xy 361.322391 -284.308948) (xy 361.299749 -284.358525) (xy 361.270283 -284.404375) (xy 361.234592 -284.445566)
			(xy 361.193401 -284.481257) (xy 361.147551 -284.510723) (xy 361.097974 -284.533365) (xy 361.045679 -284.54872)
			(xy 360.991731 -284.556476) (xy 360.937229 -284.556476) (xy 360.883281 -284.54872) (xy 360.830986 -284.533365)
			(xy 360.781409 -284.510723) (xy 360.735559 -284.481257) (xy 360.694368 -284.445566) (xy 360.658677 -284.404375)
			(xy 360.629211 -284.358525) (xy 360.606569 -284.308948) (xy 360.591214 -284.256653) (xy 360.583458 -284.202705)
			(xy 360.582972 -284.175454) (xy 360.583571 -284.145332) (xy 360.593044 -284.085836) (xy 360.611748 -284.028568)
			(xy 360.639218 -283.974951) (xy 360.674771 -283.926316) (xy 360.695748 -283.90469) (xy 360.702578 -283.897281)
			(xy 360.710305 -283.878689) (xy 360.710734 -283.868622) (xy 360.710734 -283.796486) (xy 360.710334 -283.786414)
			(xy 360.702597 -283.767815) (xy 360.695748 -283.760418) (xy 360.67476 -283.7388) (xy 360.63919 -283.690171)
			(xy 360.611711 -283.636552) (xy 360.593005 -283.57928) (xy 360.583538 -283.519779) (xy 360.582972 -283.489654)
			(xy 360.583545 -283.459815) (xy 360.592862 -283.400869) (xy 360.601514 -283.372306) (xy 360.604816 -283.361892)
			(xy 360.60253 -283.340302) (xy 360.552238 -283.25572) (xy 360.534966 -283.243274) (xy 360.524044 -283.241242)
			(xy 360.496194 -283.235394) (xy 360.44253 -283.216457) (xy 360.392273 -283.189761) (xy 360.346537 -283.1559)
			(xy 360.306335 -283.115623) (xy 360.272559 -283.069824) (xy 360.245957 -283.019517) (xy 360.22712 -282.965818)
			(xy 360.221276 -282.937966) (xy 360.218736 -282.92552) (xy 360.203496 -282.906216) (xy 360.102404 -282.862528)
			(xy 360.077766 -282.864306) (xy 360.067098 -282.871164) (xy 360.044129 -282.885204) (xy 359.995055 -282.907334)
			(xy 359.943352 -282.92233) (xy 359.890053 -282.929892) (xy 359.863136 -282.930346) (xy 359.845117 -282.930129)
			(xy 359.809242 -282.926692) (xy 359.791508 -282.923488) (xy 359.781856 -282.92171) (xy 359.762806 -282.925266)
			(xy 359.687876 -282.973272) (xy 359.676446 -282.98902) (xy 359.67416 -282.998418) (xy 359.666766 -283.025464)
			(xy 359.645138 -283.077192) (xy 359.616175 -283.125199) (xy 359.5805 -283.168452) (xy 359.53888 -283.20602)
			(xy 359.492211 -283.237094) (xy 359.441498 -283.261006) (xy 359.387833 -283.27724) (xy 359.33237 -283.285449)
			(xy 359.304336 -283.285946) (xy 359.277087 -283.285388) (xy 359.223144 -283.277638) (xy 359.170853 -283.262289)
			(xy 359.121279 -283.239655) (xy 359.07543 -283.210196) (xy 359.03424 -283.174512) (xy 358.998548 -283.133329)
			(xy 358.969081 -283.087486) (xy 358.946437 -283.037916) (xy 358.931078 -282.985628) (xy 358.923317 -282.931687)
			(xy 358.922828 -282.904438) (xy 357.937946 -282.904438) (xy 357.950854 -282.952542) (xy 357.959131 -283.015118)
			(xy 357.95966 -283.046678) (xy 357.95966 -283.131006) (xy 357.960187 -283.141539) (xy 357.968655 -283.160828)
			(xy 357.98416 -283.175089) (xy 357.99395 -283.179012) (xy 358.100122 -283.215588) (xy 358.131364 -283.20619)
			(xy 358.14127 -283.19349) (xy 358.160199 -283.170142) (xy 358.203905 -283.128884) (xy 358.253333 -283.094688)
			(xy 358.307352 -283.068336) (xy 358.364727 -283.050431) (xy 358.424146 -283.041382) (xy 358.454198 -283.040836)
			(xy 358.482538 -283.041342) (xy 358.538642 -283.049408) (xy 358.593027 -283.065376) (xy 358.644586 -283.088921)
			(xy 358.692269 -283.119564) (xy 358.735106 -283.156681) (xy 358.772225 -283.199516) (xy 358.80287 -283.247198)
			(xy 358.826418 -283.298756) (xy 358.842389 -283.35314) (xy 358.850457 -283.409244) (xy 358.850946 -283.437584)
			(xy 358.850518 -283.464182) (xy 358.843407 -283.5169) (xy 358.82931 -283.568193) (xy 358.80848 -283.617141)
			(xy 358.781292 -283.662863) (xy 358.765094 -283.683964) (xy 358.753156 -283.699204) (xy 358.753664 -283.708094)
			(xy 358.745282 -283.708094) (xy 358.73055 -283.722318) (xy 358.723946 -283.728414) (xy 358.723184 -283.780992)
			(xy 358.72345 -283.790622) (xy 358.730229 -283.80864) (xy 358.736392 -283.816044) (xy 358.754984 -283.837199)
			(xy 358.786371 -283.88396) (xy 358.810524 -283.934837) (xy 358.826916 -283.988717) (xy 358.835189 -284.044425)
			(xy 358.835706 -284.072584) (xy 358.83522 -284.099835) (xy 358.827464 -284.153783) (xy 358.812109 -284.206078)
			(xy 358.789467 -284.255655) (xy 358.760001 -284.301505) (xy 358.72431 -284.342696) (xy 358.683119 -284.378387)
			(xy 358.637269 -284.407853) (xy 358.587692 -284.430495) (xy 358.535397 -284.44585) (xy 358.481449 -284.453606)
			(xy 358.426947 -284.453606) (xy 358.372999 -284.44585) (xy 358.320704 -284.430495) (xy 358.271127 -284.407853)
			(xy 358.225277 -284.378387) (xy 358.184086 -284.342696) (xy 358.148395 -284.301505) (xy 358.118929 -284.255655)
			(xy 358.096287 -284.206078) (xy 358.080932 -284.153783) (xy 358.073176 -284.099835) (xy 358.07269 -284.072584)
			(xy 358.073122 -284.046444) (xy 358.08027 -283.994656) (xy 358.09443 -283.944331) (xy 358.115336 -283.896413)
			(xy 358.142595 -283.851803) (xy 358.158796 -283.831284) (xy 358.158796 -283.83103) (xy 358.164096 -283.8239)
			(xy 358.169954 -283.807143) (xy 358.170226 -283.798264) (xy 358.168956 -283.723334) (xy 358.162606 -283.706824)
			(xy 358.15651 -283.699966) (xy 358.137117 -283.677136) (xy 358.10472 -283.626753) (xy 358.091994 -283.599636)
			(xy 358.080697 -283.573118) (xy 358.065018 -283.517653) (xy 358.060752 -283.489146) (xy 358.059172 -283.480108)
			(xy 358.050539 -283.463932) (xy 358.036771 -283.451823) (xy 358.019626 -283.445325) (xy 358.01046 -283.44495)
			(xy 357.989378 -283.44495) (xy 357.95966 -283.474668) (xy 357.95966 -284.620462) (xy 357.960096 -284.630526)
			(xy 357.967833 -284.649108) (xy 357.974646 -284.65653) (xy 358.33558 -285.01721) (xy 358.347614 -285.029656)
			(xy 374.111518 -285.029656) (xy 374.115589 -284.974034) (xy 374.127715 -284.919597) (xy 374.147638 -284.867506)
			(xy 374.174934 -284.818871) (xy 374.20902 -284.774728) (xy 374.249169 -284.736019) (xy 374.294527 -284.703568)
			(xy 374.344127 -284.678067) (xy 374.396911 -284.66006) (xy 374.451754 -284.64993) (xy 374.507488 -284.647893)
			(xy 374.562925 -284.653993) (xy 374.616882 -284.668099) (xy 374.668211 -284.689911) (xy 374.715817 -284.718965)
			(xy 374.758685 -284.75464) (xy 374.795902 -284.796177) (xy 374.826675 -284.84269) (xy 374.850347 -284.893187)
			(xy 374.866415 -284.946594) (xy 374.874535 -285.00177) (xy 374.875044 -285.029656) (xy 375.596656 -285.029656)
			(xy 375.600727 -284.974034) (xy 375.612853 -284.919597) (xy 375.632776 -284.867506) (xy 375.660072 -284.818871)
			(xy 375.694158 -284.774728) (xy 375.734307 -284.736019) (xy 375.779665 -284.703568) (xy 375.829265 -284.678067)
			(xy 375.882049 -284.66006) (xy 375.936892 -284.64993) (xy 375.992626 -284.647893) (xy 376.048063 -284.653993)
			(xy 376.10202 -284.668099) (xy 376.153349 -284.689911) (xy 376.200955 -284.718965) (xy 376.243823 -284.75464)
			(xy 376.28104 -284.796177) (xy 376.311813 -284.84269) (xy 376.335485 -284.893187) (xy 376.351553 -284.946594)
			(xy 376.355703 -284.974792) (xy 384.369068 -284.974792) (xy 384.373028 -284.925738) (xy 384.384805 -284.877954)
			(xy 384.404096 -284.832678) (xy 384.430399 -284.791082) (xy 384.463034 -284.754245) (xy 384.501155 -284.72312)
			(xy 384.543776 -284.698513) (xy 384.589792 -284.681061) (xy 384.638011 -284.671217) (xy 384.687186 -284.669236)
			(xy 384.736041 -284.675168) (xy 384.783312 -284.68886) (xy 384.827774 -284.709958) (xy 384.868277 -284.737914)
			(xy 384.90377 -284.772006) (xy 384.933335 -284.81135) (xy 384.956206 -284.854927) (xy 384.97179 -284.901608)
			(xy 384.979685 -284.950185) (xy 384.98018 -284.974792) (xy 385.319028 -284.974792) (xy 385.322988 -284.925738)
			(xy 385.334765 -284.877954) (xy 385.354056 -284.832678) (xy 385.380359 -284.791082) (xy 385.412994 -284.754245)
			(xy 385.451115 -284.72312) (xy 385.493736 -284.698513) (xy 385.539752 -284.681061) (xy 385.587971 -284.671217)
			(xy 385.637146 -284.669236) (xy 385.686001 -284.675168) (xy 385.733272 -284.68886) (xy 385.777734 -284.709958)
			(xy 385.818237 -284.737914) (xy 385.85373 -284.772006) (xy 385.883295 -284.81135) (xy 385.906166 -284.854927)
			(xy 385.92175 -284.901608) (xy 385.929645 -284.950185) (xy 385.93014 -284.974792) (xy 389.119122 -284.974792)
			(xy 389.123082 -284.925738) (xy 389.134859 -284.877954) (xy 389.15415 -284.832678) (xy 389.180453 -284.791082)
			(xy 389.213088 -284.754245) (xy 389.251209 -284.72312) (xy 389.29383 -284.698513) (xy 389.339846 -284.681061)
			(xy 389.388065 -284.671217) (xy 389.43724 -284.669236) (xy 389.486095 -284.675168) (xy 389.533366 -284.68886)
			(xy 389.577828 -284.709958) (xy 389.618331 -284.737914) (xy 389.653824 -284.772006) (xy 389.683389 -284.81135)
			(xy 389.70626 -284.854927) (xy 389.721844 -284.901608) (xy 389.729739 -284.950185) (xy 389.730234 -284.974792)
			(xy 389.729739 -284.999399) (xy 389.721844 -285.047976) (xy 389.70626 -285.094657) (xy 389.683389 -285.138234)
			(xy 389.653824 -285.177578) (xy 389.618331 -285.21167) (xy 389.577828 -285.239626) (xy 389.533366 -285.260724)
			(xy 389.486095 -285.274416) (xy 389.43724 -285.280348) (xy 389.388065 -285.278367) (xy 389.339846 -285.268523)
			(xy 389.29383 -285.251071) (xy 389.251209 -285.226464) (xy 389.213088 -285.195339) (xy 389.180453 -285.158502)
			(xy 389.15415 -285.116906) (xy 389.134859 -285.07163) (xy 389.123082 -285.023846) (xy 389.119122 -284.974792)
			(xy 385.93014 -284.974792) (xy 385.929645 -284.999399) (xy 385.92175 -285.047976) (xy 385.906166 -285.094657)
			(xy 385.883295 -285.138234) (xy 385.85373 -285.177578) (xy 385.818237 -285.21167) (xy 385.777734 -285.239626)
			(xy 385.733272 -285.260724) (xy 385.686001 -285.274416) (xy 385.637146 -285.280348) (xy 385.587971 -285.278367)
			(xy 385.539752 -285.268523) (xy 385.493736 -285.251071) (xy 385.451115 -285.226464) (xy 385.412994 -285.195339)
			(xy 385.380359 -285.158502) (xy 385.354056 -285.116906) (xy 385.334765 -285.07163) (xy 385.322988 -285.023846)
			(xy 385.319028 -284.974792) (xy 384.98018 -284.974792) (xy 384.979685 -284.999399) (xy 384.97179 -285.047976)
			(xy 384.956206 -285.094657) (xy 384.933335 -285.138234) (xy 384.90377 -285.177578) (xy 384.868277 -285.21167)
			(xy 384.827774 -285.239626) (xy 384.783312 -285.260724) (xy 384.736041 -285.274416) (xy 384.687186 -285.280348)
			(xy 384.638011 -285.278367) (xy 384.589792 -285.268523) (xy 384.543776 -285.251071) (xy 384.501155 -285.226464)
			(xy 384.463034 -285.195339) (xy 384.430399 -285.158502) (xy 384.404096 -285.116906) (xy 384.384805 -285.07163)
			(xy 384.373028 -285.023846) (xy 384.369068 -284.974792) (xy 376.355703 -284.974792) (xy 376.359673 -285.00177)
			(xy 376.360182 -285.029656) (xy 376.359673 -285.057542) (xy 376.351553 -285.112718) (xy 376.335485 -285.166125)
			(xy 376.311813 -285.216622) (xy 376.28104 -285.263135) (xy 376.243823 -285.304672) (xy 376.200955 -285.340347)
			(xy 376.153349 -285.369401) (xy 376.10202 -285.391213) (xy 376.048063 -285.405319) (xy 375.992626 -285.411419)
			(xy 375.936892 -285.409382) (xy 375.882049 -285.399252) (xy 375.829265 -285.381245) (xy 375.779665 -285.355744)
			(xy 375.734307 -285.323293) (xy 375.694158 -285.284584) (xy 375.660072 -285.240441) (xy 375.632776 -285.191806)
			(xy 375.612853 -285.139715) (xy 375.600727 -285.085278) (xy 375.596656 -285.029656) (xy 374.875044 -285.029656)
			(xy 374.874535 -285.057542) (xy 374.866415 -285.112718) (xy 374.850347 -285.166125) (xy 374.826675 -285.216622)
			(xy 374.795902 -285.263135) (xy 374.758685 -285.304672) (xy 374.715817 -285.340347) (xy 374.668211 -285.369401)
			(xy 374.616882 -285.391213) (xy 374.562925 -285.405319) (xy 374.507488 -285.411419) (xy 374.451754 -285.409382)
			(xy 374.396911 -285.399252) (xy 374.344127 -285.381245) (xy 374.294527 -285.355744) (xy 374.249169 -285.323293)
			(xy 374.20902 -285.284584) (xy 374.174934 -285.240441) (xy 374.147638 -285.191806) (xy 374.127715 -285.139715)
			(xy 374.115589 -285.085278) (xy 374.111518 -285.029656) (xy 358.347614 -285.029656) (xy 358.357521 -285.039903)
			(xy 358.395931 -285.089993) (xy 358.427487 -285.144662) (xy 358.451652 -285.202975) (xy 358.468013 -285.26394)
			(xy 358.476292 -285.326517) (xy 358.476804 -285.358078) (xy 358.476804 -286.45739) (xy 358.477227 -286.467437)
			(xy 358.484932 -286.485994) (xy 358.499166 -286.500175) (xy 358.5083 -286.50438) (xy 358.51769 -286.507716)
			(xy 358.537597 -286.507699) (xy 358.556003 -286.500116) (xy 358.563418 -286.493458) (xy 358.632506 -286.424624)
			(xy 358.653424 -286.404352) (xy 358.699612 -286.368857) (xy 358.750036 -286.339693) (xy 358.803835 -286.317356)
			(xy 358.860087 -286.30223) (xy 358.917833 -286.294573) (xy 358.946958 -286.294068) (xy 358.976068 -286.294541)
			(xy 359.033791 -286.302133) (xy 359.09003 -286.317192) (xy 359.143823 -286.339461) (xy 359.194251 -286.368559)
			(xy 359.24045 -286.403989) (xy 359.28163 -286.445144) (xy 359.317088 -286.491321) (xy 359.346218 -286.541731)
			(xy 359.36852 -286.59551) (xy 359.383614 -286.65174) (xy 359.391241 -286.709458) (xy 359.391712 -286.738568)
			(xy 359.391712 -286.739076) (xy 359.391251 -286.768194) (xy 359.383638 -286.82593) (xy 359.368553 -286.882179)
			(xy 359.346253 -286.935976) (xy 359.31712 -286.986402) (xy 359.281654 -287.032592) (xy 359.26141 -287.053528)
			(xy 359.189274 -287.125664) (xy 359.18243 -287.133063) (xy 359.174707 -287.151662) (xy 359.174288 -287.161732)
			(xy 359.174288 -291.80663) (xy 359.17383 -291.83575) (xy 359.166224 -291.89349) (xy 359.151145 -291.949744)
			(xy 359.128852 -292.003547) (xy 359.099726 -292.05398) (xy 359.064265 -292.10018) (xy 359.043986 -292.121082)
			(xy 358.93883 -292.226238) (xy 358.932055 -292.233663) (xy 358.924471 -292.25226) (xy 358.924098 -292.262306)
			(xy 358.924098 -292.37178) (xy 358.914076 -292.365855) (xy 358.89101 -292.362879) (xy 358.868975 -292.37032)
			(xy 358.860344 -292.37813) (xy 358.79659 -292.44163) (xy 358.775687 -292.461911) (xy 358.729496 -292.497388)
			(xy 358.679066 -292.526526) (xy 358.625261 -292.548827) (xy 358.569004 -292.563906) (xy 358.511259 -292.571507)
			(xy 358.482138 -292.571932) (xy 350.811592 -292.571932) (xy 350.78419 -292.571527) (xy 350.729804 -292.564774)
			(xy 350.703134 -292.55847) (xy 350.701864 -292.558216) (xy 342.63711 -292.558216) (xy 342.607981 -292.557746)
			(xy 342.550226 -292.55011) (xy 342.493964 -292.534992) (xy 342.440159 -292.512653) (xy 342.389735 -292.483475)
			(xy 342.343555 -292.447958) (xy 342.322658 -292.42766) (xy 342.300306 -292.405308) (xy 342.292894 -292.398624)
			(xy 342.274461 -292.391027) (xy 342.254523 -292.391027) (xy 342.23609 -292.398624) (xy 342.228678 -292.405308)
			(xy 342.178894 -292.455092) (xy 342.156154 -292.477084) (xy 342.105954 -292.515579) (xy 342.051163 -292.5472)
			(xy 341.992716 -292.571406) (xy 341.931612 -292.587784) (xy 341.868894 -292.596054) (xy 341.837264 -292.59657)
			(xy 341.83701 -292.59657) (xy 341.821262 -292.596316) (xy 334.494378 -292.596316) (xy 334.484413 -292.596795)
			(xy 334.465978 -292.604373) (xy 334.458564 -292.611048) (xy 333.834994 -293.234364) (xy 333.831478 -293.238027)
			(xy 333.825848 -293.246474) (xy 333.823818 -293.251128) (xy 333.820433 -293.260708) (xy 333.820697 -293.281008)
			(xy 333.824326 -293.290498) (xy 333.826337 -293.294786) (xy 333.831705 -293.302585) (xy 333.834994 -293.305992)
			(xy 334.1243 -293.595298) (xy 334.129978 -293.600494) (xy 334.143683 -293.607478) (xy 334.151224 -293.609014)
			(xy 334.151732 -293.609014) (xy 334.15986 -293.609776) (xy 366.97285 -293.609776)
		)
		(stroke
			(width 0)
			(type solid)
		)
		(fill yes)
		(layer "In7.Cu")
		(net "GND")
	)
	(gr_poly
		(pts
			(xy 141.72565 -317.871094) (xy 141.726158 -317.871094) (xy 141.733675 -317.869489) (xy 141.747357 -317.862508)
			(xy 141.753082 -317.857378) (xy 143.673576 -315.936884) (xy 143.680975 -315.93004) (xy 143.699574 -315.92232)
			(xy 143.709644 -315.921898) (xy 147.733766 -315.921898) (xy 147.743831 -315.922333) (xy 147.762418 -315.930064)
			(xy 147.769834 -315.936884) (xy 148.632418 -316.799468) (xy 151.693638 -316.799468) (xy 151.697598 -316.750414)
			(xy 151.709375 -316.70263) (xy 151.728666 -316.657354) (xy 151.754969 -316.615758) (xy 151.787604 -316.578921)
			(xy 151.825725 -316.547796) (xy 151.868346 -316.523189) (xy 151.914362 -316.505737) (xy 151.962581 -316.495893)
			(xy 152.011756 -316.493912) (xy 152.060611 -316.499844) (xy 152.107882 -316.513536) (xy 152.152344 -316.534634)
			(xy 152.192847 -316.56259) (xy 152.22834 -316.596682) (xy 152.257905 -316.636026) (xy 152.280776 -316.679603)
			(xy 152.29636 -316.726284) (xy 152.304255 -316.774861) (xy 152.30475 -316.799468) (xy 152.304745 -316.799722)
			(xy 152.644106 -316.799722) (xy 152.648066 -316.750668) (xy 152.659843 -316.702884) (xy 152.679134 -316.657608)
			(xy 152.705437 -316.616012) (xy 152.738072 -316.579175) (xy 152.776193 -316.54805) (xy 152.818814 -316.523443)
			(xy 152.86483 -316.505991) (xy 152.913049 -316.496147) (xy 152.962224 -316.494166) (xy 153.011079 -316.500098)
			(xy 153.05835 -316.51379) (xy 153.102812 -316.534888) (xy 153.143315 -316.562844) (xy 153.178808 -316.596936)
			(xy 153.208373 -316.63628) (xy 153.231244 -316.679857) (xy 153.246828 -316.726538) (xy 153.254723 -316.775115)
			(xy 153.255218 -316.799722) (xy 153.594066 -316.799722) (xy 153.598026 -316.750668) (xy 153.609803 -316.702884)
			(xy 153.629094 -316.657608) (xy 153.655397 -316.616012) (xy 153.688032 -316.579175) (xy 153.726153 -316.54805)
			(xy 153.768774 -316.523443) (xy 153.81479 -316.505991) (xy 153.863009 -316.496147) (xy 153.912184 -316.494166)
			(xy 153.961039 -316.500098) (xy 154.00831 -316.51379) (xy 154.052772 -316.534888) (xy 154.093275 -316.562844)
			(xy 154.128768 -316.596936) (xy 154.158333 -316.63628) (xy 154.181204 -316.679857) (xy 154.196788 -316.726538)
			(xy 154.204683 -316.775115) (xy 154.205178 -316.799722) (xy 154.54428 -316.799722) (xy 154.54824 -316.750668)
			(xy 154.560017 -316.702884) (xy 154.579308 -316.657608) (xy 154.605611 -316.616012) (xy 154.638246 -316.579175)
			(xy 154.676367 -316.54805) (xy 154.718988 -316.523443) (xy 154.765004 -316.505991) (xy 154.813223 -316.496147)
			(xy 154.862398 -316.494166) (xy 154.911253 -316.500098) (xy 154.958524 -316.51379) (xy 155.002986 -316.534888)
			(xy 155.043489 -316.562844) (xy 155.078982 -316.596936) (xy 155.108547 -316.63628) (xy 155.131418 -316.679857)
			(xy 155.147002 -316.726538) (xy 155.154897 -316.775115) (xy 155.155392 -316.799722) (xy 155.49424 -316.799722)
			(xy 155.4982 -316.750668) (xy 155.509977 -316.702884) (xy 155.529268 -316.657608) (xy 155.555571 -316.616012)
			(xy 155.588206 -316.579175) (xy 155.626327 -316.54805) (xy 155.668948 -316.523443) (xy 155.714964 -316.505991)
			(xy 155.763183 -316.496147) (xy 155.812358 -316.494166) (xy 155.861213 -316.500098) (xy 155.908484 -316.51379)
			(xy 155.952946 -316.534888) (xy 155.993449 -316.562844) (xy 156.028942 -316.596936) (xy 156.058507 -316.63628)
			(xy 156.081378 -316.679857) (xy 156.096962 -316.726538) (xy 156.104857 -316.775115) (xy 156.105352 -316.799722)
			(xy 156.4442 -316.799722) (xy 156.44816 -316.750668) (xy 156.459937 -316.702884) (xy 156.479228 -316.657608)
			(xy 156.505531 -316.616012) (xy 156.538166 -316.579175) (xy 156.576287 -316.54805) (xy 156.618908 -316.523443)
			(xy 156.664924 -316.505991) (xy 156.713143 -316.496147) (xy 156.762318 -316.494166) (xy 156.811173 -316.500098)
			(xy 156.858444 -316.51379) (xy 156.902906 -316.534888) (xy 156.943409 -316.562844) (xy 156.978902 -316.596936)
			(xy 157.008467 -316.63628) (xy 157.031338 -316.679857) (xy 157.046922 -316.726538) (xy 157.054817 -316.775115)
			(xy 157.055312 -316.799722) (xy 157.39416 -316.799722) (xy 157.39812 -316.750668) (xy 157.409897 -316.702884)
			(xy 157.429188 -316.657608) (xy 157.455491 -316.616012) (xy 157.488126 -316.579175) (xy 157.526247 -316.54805)
			(xy 157.568868 -316.523443) (xy 157.614884 -316.505991) (xy 157.663103 -316.496147) (xy 157.712278 -316.494166)
			(xy 157.761133 -316.500098) (xy 157.808404 -316.51379) (xy 157.852866 -316.534888) (xy 157.893369 -316.562844)
			(xy 157.928862 -316.596936) (xy 157.958427 -316.63628) (xy 157.981298 -316.679857) (xy 157.996882 -316.726538)
			(xy 158.004777 -316.775115) (xy 158.005272 -316.799722) (xy 158.34412 -316.799722) (xy 158.34808 -316.750668)
			(xy 158.359857 -316.702884) (xy 158.379148 -316.657608) (xy 158.405451 -316.616012) (xy 158.438086 -316.579175)
			(xy 158.476207 -316.54805) (xy 158.518828 -316.523443) (xy 158.564844 -316.505991) (xy 158.613063 -316.496147)
			(xy 158.662238 -316.494166) (xy 158.711093 -316.500098) (xy 158.758364 -316.51379) (xy 158.802826 -316.534888)
			(xy 158.843329 -316.562844) (xy 158.878822 -316.596936) (xy 158.908387 -316.63628) (xy 158.931258 -316.679857)
			(xy 158.946842 -316.726538) (xy 158.954737 -316.775115) (xy 158.955232 -316.799722) (xy 159.29408 -316.799722)
			(xy 159.29804 -316.750668) (xy 159.309817 -316.702884) (xy 159.329108 -316.657608) (xy 159.355411 -316.616012)
			(xy 159.388046 -316.579175) (xy 159.426167 -316.54805) (xy 159.468788 -316.523443) (xy 159.514804 -316.505991)
			(xy 159.563023 -316.496147) (xy 159.612198 -316.494166) (xy 159.661053 -316.500098) (xy 159.708324 -316.51379)
			(xy 159.752786 -316.534888) (xy 159.793289 -316.562844) (xy 159.828782 -316.596936) (xy 159.858347 -316.63628)
			(xy 159.881218 -316.679857) (xy 159.896802 -316.726538) (xy 159.904697 -316.775115) (xy 159.905192 -316.799722)
			(xy 160.24404 -316.799722) (xy 160.248 -316.750668) (xy 160.259777 -316.702884) (xy 160.279068 -316.657608)
			(xy 160.305371 -316.616012) (xy 160.338006 -316.579175) (xy 160.376127 -316.54805) (xy 160.418748 -316.523443)
			(xy 160.464764 -316.505991) (xy 160.512983 -316.496147) (xy 160.562158 -316.494166) (xy 160.611013 -316.500098)
			(xy 160.658284 -316.51379) (xy 160.702746 -316.534888) (xy 160.743249 -316.562844) (xy 160.778742 -316.596936)
			(xy 160.808307 -316.63628) (xy 160.831178 -316.679857) (xy 160.846762 -316.726538) (xy 160.854657 -316.775115)
			(xy 160.855152 -316.799722) (xy 161.194254 -316.799722) (xy 161.198214 -316.750668) (xy 161.209991 -316.702884)
			(xy 161.229282 -316.657608) (xy 161.255585 -316.616012) (xy 161.28822 -316.579175) (xy 161.326341 -316.54805)
			(xy 161.368962 -316.523443) (xy 161.414978 -316.505991) (xy 161.463197 -316.496147) (xy 161.512372 -316.494166)
			(xy 161.561227 -316.500098) (xy 161.608498 -316.51379) (xy 161.65296 -316.534888) (xy 161.693463 -316.562844)
			(xy 161.728956 -316.596936) (xy 161.758521 -316.63628) (xy 161.781392 -316.679857) (xy 161.796976 -316.726538)
			(xy 161.804871 -316.775115) (xy 161.805366 -316.799722) (xy 162.144214 -316.799722) (xy 162.148174 -316.750668)
			(xy 162.159951 -316.702884) (xy 162.179242 -316.657608) (xy 162.205545 -316.616012) (xy 162.23818 -316.579175)
			(xy 162.276301 -316.54805) (xy 162.318922 -316.523443) (xy 162.364938 -316.505991) (xy 162.413157 -316.496147)
			(xy 162.462332 -316.494166) (xy 162.511187 -316.500098) (xy 162.558458 -316.51379) (xy 162.60292 -316.534888)
			(xy 162.643423 -316.562844) (xy 162.678916 -316.596936) (xy 162.708481 -316.63628) (xy 162.731352 -316.679857)
			(xy 162.746936 -316.726538) (xy 162.754831 -316.775115) (xy 162.755326 -316.799722) (xy 162.754831 -316.824329)
			(xy 162.746936 -316.872906) (xy 162.731352 -316.919587) (xy 162.708481 -316.963164) (xy 162.678916 -317.002508)
			(xy 162.643423 -317.0366) (xy 162.60292 -317.064556) (xy 162.558458 -317.085654) (xy 162.511187 -317.099346)
			(xy 162.462332 -317.105278) (xy 162.413157 -317.103297) (xy 162.364938 -317.093453) (xy 162.318922 -317.076001)
			(xy 162.276301 -317.051394) (xy 162.23818 -317.020269) (xy 162.205545 -316.983432) (xy 162.179242 -316.941836)
			(xy 162.159951 -316.89656) (xy 162.148174 -316.848776) (xy 162.144214 -316.799722) (xy 161.805366 -316.799722)
			(xy 161.804871 -316.824329) (xy 161.796976 -316.872906) (xy 161.781392 -316.919587) (xy 161.758521 -316.963164)
			(xy 161.728956 -317.002508) (xy 161.693463 -317.0366) (xy 161.65296 -317.064556) (xy 161.608498 -317.085654)
			(xy 161.561227 -317.099346) (xy 161.512372 -317.105278) (xy 161.463197 -317.103297) (xy 161.414978 -317.093453)
			(xy 161.368962 -317.076001) (xy 161.326341 -317.051394) (xy 161.28822 -317.020269) (xy 161.255585 -316.983432)
			(xy 161.229282 -316.941836) (xy 161.209991 -316.89656) (xy 161.198214 -316.848776) (xy 161.194254 -316.799722)
			(xy 160.855152 -316.799722) (xy 160.854657 -316.824329) (xy 160.846762 -316.872906) (xy 160.831178 -316.919587)
			(xy 160.808307 -316.963164) (xy 160.778742 -317.002508) (xy 160.743249 -317.0366) (xy 160.702746 -317.064556)
			(xy 160.658284 -317.085654) (xy 160.611013 -317.099346) (xy 160.562158 -317.105278) (xy 160.512983 -317.103297)
			(xy 160.464764 -317.093453) (xy 160.418748 -317.076001) (xy 160.376127 -317.051394) (xy 160.338006 -317.020269)
			(xy 160.305371 -316.983432) (xy 160.279068 -316.941836) (xy 160.259777 -316.89656) (xy 160.248 -316.848776)
			(xy 160.24404 -316.799722) (xy 159.905192 -316.799722) (xy 159.904697 -316.824329) (xy 159.896802 -316.872906)
			(xy 159.881218 -316.919587) (xy 159.858347 -316.963164) (xy 159.828782 -317.002508) (xy 159.793289 -317.0366)
			(xy 159.752786 -317.064556) (xy 159.708324 -317.085654) (xy 159.661053 -317.099346) (xy 159.612198 -317.105278)
			(xy 159.563023 -317.103297) (xy 159.514804 -317.093453) (xy 159.468788 -317.076001) (xy 159.426167 -317.051394)
			(xy 159.388046 -317.020269) (xy 159.355411 -316.983432) (xy 159.329108 -316.941836) (xy 159.309817 -316.89656)
			(xy 159.29804 -316.848776) (xy 159.29408 -316.799722) (xy 158.955232 -316.799722) (xy 158.954737 -316.824329)
			(xy 158.946842 -316.872906) (xy 158.931258 -316.919587) (xy 158.908387 -316.963164) (xy 158.878822 -317.002508)
			(xy 158.843329 -317.0366) (xy 158.802826 -317.064556) (xy 158.758364 -317.085654) (xy 158.711093 -317.099346)
			(xy 158.662238 -317.105278) (xy 158.613063 -317.103297) (xy 158.564844 -317.093453) (xy 158.518828 -317.076001)
			(xy 158.476207 -317.051394) (xy 158.438086 -317.020269) (xy 158.405451 -316.983432) (xy 158.379148 -316.941836)
			(xy 158.359857 -316.89656) (xy 158.34808 -316.848776) (xy 158.34412 -316.799722) (xy 158.005272 -316.799722)
			(xy 158.004777 -316.824329) (xy 157.996882 -316.872906) (xy 157.981298 -316.919587) (xy 157.958427 -316.963164)
			(xy 157.928862 -317.002508) (xy 157.893369 -317.0366) (xy 157.852866 -317.064556) (xy 157.808404 -317.085654)
			(xy 157.761133 -317.099346) (xy 157.712278 -317.105278) (xy 157.663103 -317.103297) (xy 157.614884 -317.093453)
			(xy 157.568868 -317.076001) (xy 157.526247 -317.051394) (xy 157.488126 -317.020269) (xy 157.455491 -316.983432)
			(xy 157.429188 -316.941836) (xy 157.409897 -316.89656) (xy 157.39812 -316.848776) (xy 157.39416 -316.799722)
			(xy 157.055312 -316.799722) (xy 157.054817 -316.824329) (xy 157.046922 -316.872906) (xy 157.031338 -316.919587)
			(xy 157.008467 -316.963164) (xy 156.978902 -317.002508) (xy 156.943409 -317.0366) (xy 156.902906 -317.064556)
			(xy 156.858444 -317.085654) (xy 156.811173 -317.099346) (xy 156.762318 -317.105278) (xy 156.713143 -317.103297)
			(xy 156.664924 -317.093453) (xy 156.618908 -317.076001) (xy 156.576287 -317.051394) (xy 156.538166 -317.020269)
			(xy 156.505531 -316.983432) (xy 156.479228 -316.941836) (xy 156.459937 -316.89656) (xy 156.44816 -316.848776)
			(xy 156.4442 -316.799722) (xy 156.105352 -316.799722) (xy 156.104857 -316.824329) (xy 156.096962 -316.872906)
			(xy 156.081378 -316.919587) (xy 156.058507 -316.963164) (xy 156.028942 -317.002508) (xy 155.993449 -317.0366)
			(xy 155.952946 -317.064556) (xy 155.908484 -317.085654) (xy 155.861213 -317.099346) (xy 155.812358 -317.105278)
			(xy 155.763183 -317.103297) (xy 155.714964 -317.093453) (xy 155.668948 -317.076001) (xy 155.626327 -317.051394)
			(xy 155.588206 -317.020269) (xy 155.555571 -316.983432) (xy 155.529268 -316.941836) (xy 155.509977 -316.89656)
			(xy 155.4982 -316.848776) (xy 155.49424 -316.799722) (xy 155.155392 -316.799722) (xy 155.154897 -316.824329)
			(xy 155.147002 -316.872906) (xy 155.131418 -316.919587) (xy 155.108547 -316.963164) (xy 155.078982 -317.002508)
			(xy 155.043489 -317.0366) (xy 155.002986 -317.064556) (xy 154.958524 -317.085654) (xy 154.911253 -317.099346)
			(xy 154.862398 -317.105278) (xy 154.813223 -317.103297) (xy 154.765004 -317.093453) (xy 154.718988 -317.076001)
			(xy 154.676367 -317.051394) (xy 154.638246 -317.020269) (xy 154.605611 -316.983432) (xy 154.579308 -316.941836)
			(xy 154.560017 -316.89656) (xy 154.54824 -316.848776) (xy 154.54428 -316.799722) (xy 154.205178 -316.799722)
			(xy 154.204683 -316.824329) (xy 154.196788 -316.872906) (xy 154.181204 -316.919587) (xy 154.158333 -316.963164)
			(xy 154.128768 -317.002508) (xy 154.093275 -317.0366) (xy 154.052772 -317.064556) (xy 154.00831 -317.085654)
			(xy 153.961039 -317.099346) (xy 153.912184 -317.105278) (xy 153.863009 -317.103297) (xy 153.81479 -317.093453)
			(xy 153.768774 -317.076001) (xy 153.726153 -317.051394) (xy 153.688032 -317.020269) (xy 153.655397 -316.983432)
			(xy 153.629094 -316.941836) (xy 153.609803 -316.89656) (xy 153.598026 -316.848776) (xy 153.594066 -316.799722)
			(xy 153.255218 -316.799722) (xy 153.254723 -316.824329) (xy 153.246828 -316.872906) (xy 153.231244 -316.919587)
			(xy 153.208373 -316.963164) (xy 153.178808 -317.002508) (xy 153.143315 -317.0366) (xy 153.102812 -317.064556)
			(xy 153.05835 -317.085654) (xy 153.011079 -317.099346) (xy 152.962224 -317.105278) (xy 152.913049 -317.103297)
			(xy 152.86483 -317.093453) (xy 152.818814 -317.076001) (xy 152.776193 -317.051394) (xy 152.738072 -317.020269)
			(xy 152.705437 -316.983432) (xy 152.679134 -316.941836) (xy 152.659843 -316.89656) (xy 152.648066 -316.848776)
			(xy 152.644106 -316.799722) (xy 152.304745 -316.799722) (xy 152.304255 -316.824075) (xy 152.29636 -316.872652)
			(xy 152.280776 -316.919333) (xy 152.257905 -316.96291) (xy 152.22834 -317.002254) (xy 152.192847 -317.036346)
			(xy 152.152344 -317.064302) (xy 152.107882 -317.0854) (xy 152.060611 -317.099092) (xy 152.011756 -317.105024)
			(xy 151.962581 -317.103043) (xy 151.914362 -317.093199) (xy 151.868346 -317.075747) (xy 151.825725 -317.05114)
			(xy 151.787604 -317.020015) (xy 151.754969 -316.983178) (xy 151.728666 -316.941582) (xy 151.709375 -316.896306)
			(xy 151.697598 -316.848522) (xy 151.693638 -316.799468) (xy 148.632418 -316.799468) (xy 149.690328 -317.857378)
			(xy 149.696011 -317.862564) (xy 149.709719 -317.869529) (xy 149.717252 -317.871094) (xy 149.71776 -317.871094)
			(xy 149.725888 -317.871856) (xy 152.54351 -317.871856) (xy 152.553848 -317.871379) (xy 152.572864 -317.863262)
			(xy 152.58034 -317.856108) (xy 152.63114 -317.802768) (xy 152.637891 -317.794993) (xy 152.6451 -317.775726)
			(xy 152.64511 -317.76543) (xy 152.64511 -317.763906) (xy 152.644602 -317.75019) (xy 152.644602 -317.749682)
			(xy 152.645143 -317.72444) (xy 152.65349 -317.674651) (xy 152.669913 -317.626913) (xy 152.693966 -317.582528)
			(xy 152.724993 -317.542704) (xy 152.762149 -317.508526) (xy 152.804421 -317.480927) (xy 152.850657 -317.460658)
			(xy 152.899598 -317.448272) (xy 152.94991 -317.444105) (xy 153.000222 -317.448272) (xy 153.049163 -317.460658)
			(xy 153.095399 -317.480927) (xy 153.137671 -317.508526) (xy 153.174827 -317.542704) (xy 153.205854 -317.582528)
			(xy 153.229907 -317.626913) (xy 153.24633 -317.674651) (xy 153.254677 -317.72444) (xy 153.255218 -317.749682)
			(xy 153.255218 -317.75019) (xy 153.25471 -317.763652) (xy 153.25471 -317.76543) (xy 153.254202 -317.775844)
			(xy 153.261314 -317.795148) (xy 153.31948 -317.856108) (xy 153.326952 -317.863277) (xy 153.345966 -317.871427)
			(xy 153.35631 -317.871856) (xy 153.49347 -317.871856) (xy 153.503803 -317.871368) (xy 153.522802 -317.863236)
			(xy 153.5303 -317.856108) (xy 153.5811 -317.802768) (xy 153.587844 -317.79499) (xy 153.595045 -317.775725)
			(xy 153.59507 -317.76543) (xy 153.59507 -317.763906) (xy 153.594562 -317.75019) (xy 153.594562 -317.749682)
			(xy 153.595103 -317.72444) (xy 153.60345 -317.674651) (xy 153.619873 -317.626913) (xy 153.643926 -317.582528)
			(xy 153.674953 -317.542704) (xy 153.712109 -317.508526) (xy 153.754381 -317.480927) (xy 153.800617 -317.460658)
			(xy 153.849558 -317.448272) (xy 153.89987 -317.444105) (xy 153.950182 -317.448272) (xy 153.999123 -317.460658)
			(xy 154.045359 -317.480927) (xy 154.087631 -317.508526) (xy 154.124787 -317.542704) (xy 154.155814 -317.582528)
			(xy 154.179867 -317.626913) (xy 154.19629 -317.674651) (xy 154.204637 -317.72444) (xy 154.205178 -317.749682)
			(xy 154.205178 -317.75019) (xy 154.20467 -317.763652) (xy 154.20467 -317.76543) (xy 154.204162 -317.775844)
			(xy 154.211274 -317.795148) (xy 154.26944 -317.856108) (xy 154.276916 -317.863267) (xy 154.295929 -317.871395)
			(xy 154.30627 -317.871856) (xy 154.443684 -317.871856) (xy 154.454016 -317.871365) (xy 154.473011 -317.86323)
			(xy 154.480514 -317.856108) (xy 154.531314 -317.802768) (xy 154.538056 -317.79499) (xy 154.545255 -317.775725)
			(xy 154.545284 -317.76543) (xy 154.545284 -317.763906) (xy 154.544776 -317.75019) (xy 154.544776 -317.749682)
			(xy 154.545317 -317.72444) (xy 154.553664 -317.674651) (xy 154.570087 -317.626913) (xy 154.59414 -317.582528)
			(xy 154.625167 -317.542704) (xy 154.662323 -317.508526) (xy 154.704595 -317.480927) (xy 154.750831 -317.460658)
			(xy 154.799772 -317.448272) (xy 154.850084 -317.444105) (xy 154.900396 -317.448272) (xy 154.949337 -317.460658)
			(xy 154.995573 -317.480927) (xy 155.037845 -317.508526) (xy 155.075001 -317.542704) (xy 155.106028 -317.582528)
			(xy 155.130081 -317.626913) (xy 155.146504 -317.674651) (xy 155.154851 -317.72444) (xy 155.155392 -317.749682)
			(xy 155.155392 -317.75019) (xy 155.154884 -317.763652) (xy 155.154884 -317.76543) (xy 155.154376 -317.775844)
			(xy 155.161488 -317.795148) (xy 155.219654 -317.856108) (xy 155.22713 -317.863265) (xy 155.246144 -317.871388)
			(xy 155.256484 -317.871856) (xy 155.393644 -317.871856) (xy 155.403979 -317.871372) (xy 155.422986 -317.863247)
			(xy 155.430474 -317.856108) (xy 155.481274 -317.802768) (xy 155.488021 -317.794992) (xy 155.495225 -317.775726)
			(xy 155.495244 -317.76543) (xy 155.495244 -317.763906) (xy 155.494736 -317.75019) (xy 155.494736 -317.749682)
			(xy 155.495277 -317.72444) (xy 155.503624 -317.674651) (xy 155.520047 -317.626913) (xy 155.5441 -317.582528)
			(xy 155.575127 -317.542704) (xy 155.612283 -317.508526) (xy 155.654555 -317.480927) (xy 155.700791 -317.460658)
			(xy 155.749732 -317.448272) (xy 155.800044 -317.444105) (xy 155.850356 -317.448272) (xy 155.899297 -317.460658)
			(xy 155.945533 -317.480927) (xy 155.987805 -317.508526) (xy 156.024961 -317.542704) (xy 156.055988 -317.582528)
			(xy 156.080041 -317.626913) (xy 156.096464 -317.674651) (xy 156.104811 -317.72444) (xy 156.105352 -317.749682)
			(xy 156.105352 -317.75019) (xy 156.104844 -317.763652) (xy 156.104844 -317.76543) (xy 156.104336 -317.775844)
			(xy 156.111448 -317.795148) (xy 156.169614 -317.856108) (xy 156.177088 -317.863271) (xy 156.196102 -317.871409)
			(xy 156.206444 -317.871856) (xy 156.343604 -317.871856) (xy 156.353934 -317.871361) (xy 156.372924 -317.863221)
			(xy 156.380434 -317.856108) (xy 156.431234 -317.802768) (xy 156.437985 -317.794993) (xy 156.445195 -317.775727)
			(xy 156.445204 -317.76543) (xy 156.445204 -317.763906) (xy 156.444696 -317.75019) (xy 156.444696 -317.749682)
			(xy 156.445237 -317.72444) (xy 156.453584 -317.674651) (xy 156.470007 -317.626913) (xy 156.49406 -317.582528)
			(xy 156.525087 -317.542704) (xy 156.562243 -317.508526) (xy 156.604515 -317.480927) (xy 156.650751 -317.460658)
			(xy 156.699692 -317.448272) (xy 156.750004 -317.444105) (xy 156.800316 -317.448272) (xy 156.849257 -317.460658)
			(xy 156.895493 -317.480927) (xy 156.937765 -317.508526) (xy 156.974921 -317.542704) (xy 157.005948 -317.582528)
			(xy 157.030001 -317.626913) (xy 157.046424 -317.674651) (xy 157.054771 -317.72444) (xy 157.055312 -317.749682)
			(xy 157.055312 -317.75019) (xy 157.054804 -317.763652) (xy 157.054804 -317.76543) (xy 157.054296 -317.775844)
			(xy 157.061408 -317.795148) (xy 157.119574 -317.856108) (xy 157.127051 -317.863262) (xy 157.146065 -317.871377)
			(xy 157.156404 -317.871856) (xy 157.293564 -317.871856) (xy 157.303897 -317.871369) (xy 157.322899 -317.863238)
			(xy 157.330394 -317.856108) (xy 157.381194 -317.802768) (xy 157.387939 -317.794991) (xy 157.39514 -317.775725)
			(xy 157.395164 -317.76543) (xy 157.395164 -317.763906) (xy 157.394656 -317.75019) (xy 157.394656 -317.749682)
			(xy 157.395197 -317.72444) (xy 157.403544 -317.674651) (xy 157.419967 -317.626913) (xy 157.44402 -317.582528)
			(xy 157.475047 -317.542704) (xy 157.512203 -317.508526) (xy 157.554475 -317.480927) (xy 157.600711 -317.460658)
			(xy 157.649652 -317.448272) (xy 157.699964 -317.444105) (xy 157.750276 -317.448272) (xy 157.799217 -317.460658)
			(xy 157.845453 -317.480927) (xy 157.887725 -317.508526) (xy 157.924881 -317.542704) (xy 157.955908 -317.582528)
			(xy 157.979961 -317.626913) (xy 157.996384 -317.674651) (xy 158.004731 -317.72444) (xy 158.005272 -317.749682)
			(xy 158.005272 -317.75019) (xy 158.004764 -317.763652) (xy 158.004764 -317.76543) (xy 158.004256 -317.775844)
			(xy 158.011368 -317.795148) (xy 158.069534 -317.856108) (xy 158.077009 -317.863268) (xy 158.096023 -317.871398)
			(xy 158.106364 -317.871856) (xy 158.243524 -317.871856) (xy 158.253861 -317.871376) (xy 158.272873 -317.863256)
			(xy 158.280354 -317.856108) (xy 158.331154 -317.802768) (xy 158.337903 -317.794993) (xy 158.345111 -317.775726)
			(xy 158.345124 -317.76543) (xy 158.345124 -317.763906) (xy 158.344616 -317.75019) (xy 158.344616 -317.749682)
			(xy 158.345157 -317.72444) (xy 158.353504 -317.674651) (xy 158.369927 -317.626913) (xy 158.39398 -317.582528)
			(xy 158.425007 -317.542704) (xy 158.462163 -317.508526) (xy 158.504435 -317.480927) (xy 158.550671 -317.460658)
			(xy 158.599612 -317.448272) (xy 158.649924 -317.444105) (xy 158.700236 -317.448272) (xy 158.749177 -317.460658)
			(xy 158.795413 -317.480927) (xy 158.837685 -317.508526) (xy 158.874841 -317.542704) (xy 158.905868 -317.582528)
			(xy 158.929921 -317.626913) (xy 158.946344 -317.674651) (xy 158.954691 -317.72444) (xy 158.955232 -317.749682)
			(xy 158.955232 -317.75019) (xy 158.954724 -317.763652) (xy 158.954724 -317.76543) (xy 158.954216 -317.775844)
			(xy 158.961328 -317.795148) (xy 159.019494 -317.856108) (xy 159.026967 -317.863274) (xy 159.045981 -317.87142)
			(xy 159.056324 -317.871856) (xy 159.193484 -317.871856) (xy 159.203816 -317.871365) (xy 159.222811 -317.86323)
			(xy 159.230314 -317.856108) (xy 159.281114 -317.802768) (xy 159.287856 -317.79499) (xy 159.295055 -317.775725)
			(xy 159.295084 -317.76543) (xy 159.295084 -317.763906) (xy 159.294576 -317.75019) (xy 159.294576 -317.749682)
			(xy 159.295117 -317.72444) (xy 159.303464 -317.674651) (xy 159.319887 -317.626913) (xy 159.34394 -317.582528)
			(xy 159.374967 -317.542704) (xy 159.412123 -317.508526) (xy 159.454395 -317.480927) (xy 159.500631 -317.460658)
			(xy 159.549572 -317.448272) (xy 159.599884 -317.444105) (xy 159.650196 -317.448272) (xy 159.699137 -317.460658)
			(xy 159.745373 -317.480927) (xy 159.787645 -317.508526) (xy 159.824801 -317.542704) (xy 159.855828 -317.582528)
			(xy 159.879881 -317.626913) (xy 159.896304 -317.674651) (xy 159.904651 -317.72444) (xy 159.905192 -317.749682)
			(xy 159.905192 -317.75019) (xy 159.904684 -317.763652) (xy 159.904684 -317.76543) (xy 159.904176 -317.775844)
			(xy 159.911288 -317.795148) (xy 159.969454 -317.856108) (xy 159.97693 -317.863265) (xy 159.995944 -317.871388)
			(xy 160.006284 -317.871856) (xy 160.143444 -317.871856) (xy 160.153779 -317.871372) (xy 160.172786 -317.863247)
			(xy 160.180274 -317.856108) (xy 160.231074 -317.802768) (xy 160.237821 -317.794992) (xy 160.245025 -317.775726)
			(xy 160.245044 -317.76543) (xy 160.245044 -317.763906) (xy 160.244536 -317.75019) (xy 160.244536 -317.749682)
			(xy 160.245077 -317.72444) (xy 160.253424 -317.674651) (xy 160.269847 -317.626913) (xy 160.2939 -317.582528)
			(xy 160.324927 -317.542704) (xy 160.362083 -317.508526) (xy 160.404355 -317.480927) (xy 160.450591 -317.460658)
			(xy 160.499532 -317.448272) (xy 160.549844 -317.444105) (xy 160.600156 -317.448272) (xy 160.649097 -317.460658)
			(xy 160.695333 -317.480927) (xy 160.737605 -317.508526) (xy 160.774761 -317.542704) (xy 160.805788 -317.582528)
			(xy 160.829841 -317.626913) (xy 160.846264 -317.674651) (xy 160.854611 -317.72444) (xy 160.855152 -317.749682)
			(xy 160.855152 -317.75019) (xy 160.854644 -317.763652) (xy 160.854644 -317.76543) (xy 160.854136 -317.775844)
			(xy 160.861248 -317.795148) (xy 160.919414 -317.856108) (xy 160.926888 -317.863271) (xy 160.945902 -317.871409)
			(xy 160.956244 -317.871856) (xy 161.093658 -317.871856) (xy 161.103992 -317.87137) (xy 161.122995 -317.863241)
			(xy 161.130488 -317.856108) (xy 161.181288 -317.802768) (xy 161.188033 -317.794991) (xy 161.195236 -317.775725)
			(xy 161.195258 -317.76543) (xy 161.195258 -317.763906) (xy 161.19475 -317.75019) (xy 161.19475 -317.749682)
			(xy 161.195291 -317.72444) (xy 161.203638 -317.674651) (xy 161.220061 -317.626913) (xy 161.244114 -317.582528)
			(xy 161.275141 -317.542704) (xy 161.312297 -317.508526) (xy 161.354569 -317.480927) (xy 161.400805 -317.460658)
			(xy 161.449746 -317.448272) (xy 161.500058 -317.444105) (xy 161.55037 -317.448272) (xy 161.599311 -317.460658)
			(xy 161.645547 -317.480927) (xy 161.687819 -317.508526) (xy 161.724975 -317.542704) (xy 161.756002 -317.582528)
			(xy 161.780055 -317.626913) (xy 161.796478 -317.674651) (xy 161.804825 -317.72444) (xy 161.805366 -317.749682)
			(xy 161.805366 -317.75019) (xy 161.804858 -317.763652) (xy 161.804858 -317.76543) (xy 161.80435 -317.775844)
			(xy 161.811462 -317.795148) (xy 161.869628 -317.856108) (xy 161.877103 -317.863269) (xy 161.896117 -317.871402)
			(xy 161.906458 -317.871856) (xy 162.043618 -317.871856) (xy 162.053955 -317.871377) (xy 162.072969 -317.863259)
			(xy 162.080448 -317.856108) (xy 162.131248 -317.802768) (xy 162.137998 -317.794993) (xy 162.145206 -317.775726)
			(xy 162.145218 -317.76543) (xy 162.145218 -317.763906) (xy 162.14471 -317.75019) (xy 162.14471 -317.749682)
			(xy 162.145251 -317.72444) (xy 162.153598 -317.674651) (xy 162.170021 -317.626913) (xy 162.194074 -317.582528)
			(xy 162.225101 -317.542704) (xy 162.262257 -317.508526) (xy 162.304529 -317.480927) (xy 162.350765 -317.460658)
			(xy 162.399706 -317.448272) (xy 162.450018 -317.444105) (xy 162.50033 -317.448272) (xy 162.549271 -317.460658)
			(xy 162.595507 -317.480927) (xy 162.637779 -317.508526) (xy 162.674935 -317.542704) (xy 162.705962 -317.582528)
			(xy 162.730015 -317.626913) (xy 162.746438 -317.674651) (xy 162.754785 -317.72444) (xy 162.755326 -317.749682)
			(xy 162.755326 -317.75019) (xy 162.754818 -317.763652) (xy 162.754818 -317.76543) (xy 162.75431 -317.775844)
			(xy 162.761422 -317.795148) (xy 162.819588 -317.856108) (xy 162.827061 -317.863275) (xy 162.846074 -317.871423)
			(xy 162.856418 -317.871856) (xy 162.993578 -317.871856) (xy 163.00391 -317.871366) (xy 163.022908 -317.863232)
			(xy 163.030408 -317.856108) (xy 163.081208 -317.802768) (xy 163.087951 -317.79499) (xy 163.095151 -317.775725)
			(xy 163.095178 -317.76543) (xy 163.095178 -317.763906) (xy 163.09467 -317.75019) (xy 163.09467 -317.749682)
			(xy 163.095157 -317.725701) (xy 163.10269 -317.678335) (xy 163.117536 -317.632728) (xy 163.139331 -317.590004)
			(xy 163.167538 -317.551214) (xy 163.201463 -317.51731) (xy 163.240272 -317.489128) (xy 163.28301 -317.467361)
			(xy 163.328626 -317.452544) (xy 163.375997 -317.445041) (xy 163.399978 -317.444628) (xy 163.413 -317.444795)
			(xy 163.438944 -317.447083) (xy 163.451794 -317.4492) (xy 163.456112 -317.449962) (xy 163.456366 -317.449962)
			(xy 163.468812 -317.452248) (xy 163.492434 -317.444882) (xy 163.56965 -317.367412) (xy 163.577016 -317.34379)
			(xy 163.575746 -317.336678) (xy 163.572772 -317.321357) (xy 163.569589 -317.290308) (xy 163.569396 -317.274702)
			(xy 163.569396 -317.27394) (xy 163.569651 -317.258265) (xy 163.572964 -317.22709) (xy 163.576 -317.21171)
			(xy 163.576 -317.210694) (xy 163.577016 -317.205868) (xy 163.56965 -317.182246) (xy 163.501578 -317.11392)
			(xy 163.497066 -317.109627) (xy 163.486399 -317.103206) (xy 163.480496 -317.10122) (xy 163.468558 -317.097664)
			(xy 163.456112 -317.09995) (xy 163.442203 -317.102346) (xy 163.414091 -317.104885) (xy 163.399978 -317.10503)
			(xy 163.375155 -317.104542) (xy 163.326165 -317.096507) (xy 163.279119 -317.080652) (xy 163.235259 -317.057394)
			(xy 163.195739 -317.027347) (xy 163.1616 -316.991303) (xy 163.133743 -316.95021) (xy 163.112901 -316.905152)
			(xy 163.099623 -316.857315) (xy 163.094259 -316.80796) (xy 163.09695 -316.758388) (xy 163.107626 -316.709904)
			(xy 163.126005 -316.663786) (xy 163.151602 -316.621249) (xy 163.183745 -316.583414) (xy 163.221585 -316.551277)
			(xy 163.264126 -316.525685) (xy 163.310246 -316.507313) (xy 163.358732 -316.496644) (xy 163.408304 -316.49396)
			(xy 163.457658 -316.499331) (xy 163.505493 -316.512616) (xy 163.550548 -316.533465) (xy 163.591637 -316.561328)
			(xy 163.627677 -316.595472) (xy 163.657718 -316.634996) (xy 163.680969 -316.67886) (xy 163.696818 -316.725907)
			(xy 163.704846 -316.774899) (xy 163.705286 -316.799722) (xy 163.705076 -316.813777) (xy 163.702402 -316.841761)
			(xy 163.699952 -316.855602) (xy 163.699952 -316.85611) (xy 163.698444 -316.868345) (xy 163.705735 -316.891853)
			(xy 163.713922 -316.901068) (xy 163.773104 -316.960504) (xy 163.777616 -316.964797) (xy 163.788283 -316.971218)
			(xy 163.794186 -316.973204) (xy 163.806124 -316.97676) (xy 163.81857 -316.974474) (xy 163.832479 -316.972078)
			(xy 163.860591 -316.969537) (xy 163.874704 -316.969394) (xy 163.875212 -316.969394) (xy 163.889204 -316.969609)
			(xy 163.917061 -316.972279) (xy 163.930838 -316.974728) (xy 163.934648 -316.975236) (xy 163.934902 -316.975236)
			(xy 163.94303 -316.977014) (xy 163.967414 -316.969648) (xy 164.044884 -316.892432) (xy 164.05225 -316.86881)
			(xy 164.049964 -316.856364) (xy 164.049202 -316.852046) (xy 164.047079 -316.839069) (xy 164.044792 -316.812871)
			(xy 164.04463 -316.799722) (xy 164.045075 -316.775729) (xy 164.052579 -316.728333) (xy 164.067406 -316.682695)
			(xy 164.089191 -316.639938) (xy 164.117397 -316.601117) (xy 164.151329 -316.567186) (xy 164.190152 -316.538982)
			(xy 164.23291 -316.5172) (xy 164.278548 -316.502375) (xy 164.325945 -316.494873) (xy 164.349938 -316.494414)
			(xy 164.381688 -316.495938) (xy 164.381942 -316.495938) (xy 164.392566 -316.496463) (xy 164.41278 -316.489915)
			(xy 164.421058 -316.483238) (xy 164.476684 -316.432946) (xy 164.4777 -316.43193) (xy 164.483972 -316.425477)
			(xy 164.49191 -316.409341) (xy 164.493194 -316.400434) (xy 164.493448 -316.3951) (xy 164.493448 -316.324742)
			(xy 164.493645 -316.308506) (xy 164.496822 -316.276189) (xy 164.499798 -316.260226) (xy 164.499798 -316.25921)
			(xy 164.500052 -316.258702) (xy 164.49294 -316.235842) (xy 164.420042 -316.159642) (xy 164.39769 -316.151514)
			(xy 164.385752 -316.153038) (xy 164.37683 -316.154001) (xy 164.358912 -316.15502) (xy 164.349938 -316.15507)
			(xy 164.324681 -316.15458) (xy 164.274856 -316.146272) (xy 164.227078 -316.129875) (xy 164.182651 -316.105837)
			(xy 164.142787 -316.074814) (xy 164.108573 -316.037652) (xy 164.080943 -315.995366) (xy 164.060651 -315.949108)
			(xy 164.04825 -315.900141) (xy 164.044078 -315.8498) (xy 164.04825 -315.799459) (xy 164.060651 -315.750492)
			(xy 164.080943 -315.704234) (xy 164.108573 -315.661948) (xy 164.142787 -315.624786) (xy 164.182651 -315.593763)
			(xy 164.227078 -315.569725) (xy 164.274856 -315.553328) (xy 164.324681 -315.54502) (xy 164.349938 -315.544454)
			(xy 164.363993 -315.54466) (xy 164.391978 -315.547327) (xy 164.405818 -315.549788) (xy 164.406326 -315.549788)
			(xy 164.418561 -315.551292) (xy 164.442066 -315.544) (xy 164.451284 -315.535818) (xy 164.51961 -315.467492)
			(xy 164.526976 -315.443362) (xy 164.52469 -315.43117) (xy 164.522299 -315.417324) (xy 164.519753 -315.38934)
			(xy 164.51961 -315.37529) (xy 164.51961 -315.374782) (xy 164.519826 -315.358916) (xy 164.523132 -315.327356)
			(xy 164.526214 -315.31179) (xy 164.526214 -315.310774) (xy 164.52723 -315.305948) (xy 164.519864 -315.282326)
			(xy 164.451284 -315.213746) (xy 164.442042 -315.205607) (xy 164.418557 -315.198323) (xy 164.406326 -315.199776)
			(xy 164.406072 -315.199776) (xy 164.39217 -315.202252) (xy 164.364057 -315.204922) (xy 164.349938 -315.20511)
			(xy 164.324678 -315.20462) (xy 164.274846 -315.196311) (xy 164.227062 -315.179912) (xy 164.182629 -315.155871)
			(xy 164.14276 -315.124844) (xy 164.108542 -315.087677) (xy 164.080908 -315.045385) (xy 164.060613 -314.999121)
			(xy 164.04821 -314.950147) (xy 164.044038 -314.8998) (xy 164.04821 -314.849453) (xy 164.060613 -314.800479)
			(xy 164.080908 -314.754215) (xy 164.108542 -314.711923) (xy 164.14276 -314.674756) (xy 164.182629 -314.643729)
			(xy 164.227062 -314.619688) (xy 164.274846 -314.603289) (xy 164.324678 -314.59498) (xy 164.349938 -314.594494)
			(xy 164.359039 -314.594534) (xy 164.377211 -314.595553) (xy 164.38626 -314.596526) (xy 164.398198 -314.59805)
			(xy 164.42055 -314.589922) (xy 164.493448 -314.513722) (xy 164.50056 -314.491116) (xy 164.499798 -314.48629)
			(xy 164.497071 -314.471069) (xy 164.494147 -314.440284) (xy 164.493956 -314.424822) (xy 164.493956 -314.424314)
			(xy 164.494183 -314.408269) (xy 164.497365 -314.376335) (xy 164.500306 -314.36056) (xy 164.500306 -314.359544)
			(xy 164.50056 -314.358782) (xy 164.493448 -314.335922) (xy 164.42055 -314.259722) (xy 164.398198 -314.251594)
			(xy 164.38626 -314.253118) (xy 164.377213 -314.254107) (xy 164.359039 -314.255125) (xy 164.349938 -314.25515)
			(xy 164.324675 -314.25466) (xy 164.274837 -314.246349) (xy 164.227046 -314.229948) (xy 164.182608 -314.205904)
			(xy 164.142733 -314.174873) (xy 164.10851 -314.137702) (xy 164.080873 -314.095404) (xy 164.060575 -314.049134)
			(xy 164.048171 -314.000154) (xy 164.043998 -313.9498) (xy 164.048171 -313.899446) (xy 164.060575 -313.850466)
			(xy 164.080873 -313.804196) (xy 164.10851 -313.761898) (xy 164.142733 -313.724727) (xy 164.182608 -313.693696)
			(xy 164.227046 -313.669652) (xy 164.274837 -313.653251) (xy 164.324675 -313.64494) (xy 164.349938 -313.644534)
			(xy 164.359039 -313.644574) (xy 164.377211 -313.645593) (xy 164.38626 -313.646566) (xy 164.398198 -313.64809)
			(xy 164.42055 -313.639962) (xy 164.493448 -313.563762) (xy 164.50056 -313.541156) (xy 164.499798 -313.53633)
			(xy 164.497069 -313.521109) (xy 164.494142 -313.490324) (xy 164.493956 -313.474862) (xy 164.493956 -313.474354)
			(xy 164.494182 -313.458308) (xy 164.497359 -313.426374) (xy 164.500306 -313.4106) (xy 164.500306 -313.409584)
			(xy 164.50056 -313.408822) (xy 164.493448 -313.385962) (xy 164.42055 -313.309762) (xy 164.398198 -313.301634)
			(xy 164.38626 -313.303158) (xy 164.377213 -313.304147) (xy 164.359039 -313.305164) (xy 164.349938 -313.30519)
			(xy 164.32468 -313.3047) (xy 164.274851 -313.296391) (xy 164.22707 -313.279993) (xy 164.18264 -313.255954)
			(xy 164.142774 -313.224929) (xy 164.108558 -313.187765) (xy 164.080926 -313.145475) (xy 164.060632 -313.099214)
			(xy 164.04823 -313.050244) (xy 164.044058 -312.9999) (xy 164.04823 -312.949556) (xy 164.060632 -312.900586)
			(xy 164.080926 -312.854325) (xy 164.108558 -312.812035) (xy 164.142774 -312.774871) (xy 164.18264 -312.743846)
			(xy 164.22707 -312.719807) (xy 164.274851 -312.703409) (xy 164.32468 -312.6951) (xy 164.349938 -312.694574)
			(xy 164.359039 -312.694614) (xy 164.377211 -312.695633) (xy 164.38626 -312.696606) (xy 164.398198 -312.69813)
			(xy 164.42055 -312.690002) (xy 164.493448 -312.613802) (xy 164.50056 -312.591196) (xy 164.499798 -312.58637)
			(xy 164.497072 -312.571149) (xy 164.49415 -312.540364) (xy 164.493956 -312.524902) (xy 164.493956 -312.524394)
			(xy 164.494184 -312.508349) (xy 164.497368 -312.476416) (xy 164.500306 -312.46064) (xy 164.500306 -312.459624)
			(xy 164.50056 -312.458862) (xy 164.493448 -312.436002) (xy 164.42055 -312.359802) (xy 164.398198 -312.351674)
			(xy 164.38626 -312.353198) (xy 164.377213 -312.354188) (xy 164.359039 -312.355205) (xy 164.349938 -312.35523)
			(xy 164.324676 -312.35474) (xy 164.274841 -312.34643) (xy 164.227054 -312.33003) (xy 164.182619 -312.305987)
			(xy 164.142746 -312.274958) (xy 164.108526 -312.237789) (xy 164.080891 -312.195494) (xy 164.060594 -312.149227)
			(xy 164.04819 -312.10025) (xy 164.044018 -312.0499) (xy 164.04819 -311.99955) (xy 164.060594 -311.950573)
			(xy 164.080891 -311.904306) (xy 164.108526 -311.862011) (xy 164.142747 -311.824842) (xy 164.182619 -311.793813)
			(xy 164.227054 -311.76977) (xy 164.274841 -311.75337) (xy 164.324676 -311.74506) (xy 164.349938 -311.744614)
			(xy 164.358975 -311.744659) (xy 164.377021 -311.745674) (xy 164.386006 -311.746646) (xy 164.397944 -311.74817)
			(xy 164.420296 -311.740042) (xy 164.49294 -311.663842) (xy 164.500052 -311.640982) (xy 164.49929 -311.63641)
			(xy 164.496553 -311.621126) (xy 164.493623 -311.590214) (xy 164.493448 -311.574688) (xy 164.493448 -311.504584)
			(xy 164.493194 -311.49925) (xy 164.491902 -311.490345) (xy 164.483972 -311.474206) (xy 164.4777 -311.467754)
			(xy 164.476684 -311.466738) (xy 164.421058 -311.416446) (xy 164.412837 -311.409659) (xy 164.392581 -311.403079)
			(xy 164.381942 -311.403746) (xy 164.381688 -311.403746) (xy 164.349938 -311.40527) (xy 164.324681 -311.40478)
			(xy 164.274856 -311.396472) (xy 164.227078 -311.380075) (xy 164.182651 -311.356037) (xy 164.142787 -311.325014)
			(xy 164.108573 -311.287852) (xy 164.080943 -311.245566) (xy 164.060651 -311.199308) (xy 164.04825 -311.150341)
			(xy 164.044078 -311.1) (xy 164.04825 -311.049659) (xy 164.060651 -311.000692) (xy 164.080943 -310.954434)
			(xy 164.108573 -310.912148) (xy 164.142787 -310.874986) (xy 164.182651 -310.843963) (xy 164.227078 -310.819925)
			(xy 164.274856 -310.803528) (xy 164.324681 -310.79522) (xy 164.349938 -310.794654) (xy 164.381688 -310.796178)
			(xy 164.381942 -310.796178) (xy 164.392567 -310.796703) (xy 164.412783 -310.79016) (xy 164.421058 -310.783478)
			(xy 164.476684 -310.733186) (xy 164.4777 -310.73217) (xy 164.483977 -310.725719) (xy 164.491928 -310.709584)
			(xy 164.493194 -310.700674) (xy 164.493448 -310.69534) (xy 164.493448 -310.62422) (xy 164.493675 -310.608175)
			(xy 164.496856 -310.576241) (xy 164.499798 -310.560466) (xy 164.499798 -310.55945) (xy 164.500052 -310.558688)
			(xy 164.49294 -310.535828) (xy 164.420042 -310.459628) (xy 164.39769 -310.4515) (xy 164.385752 -310.453024)
			(xy 164.37683 -310.453987) (xy 164.358912 -310.455006) (xy 164.349938 -310.455056) (xy 164.324674 -310.454566)
			(xy 164.274835 -310.446255) (xy 164.227044 -310.429854) (xy 164.182604 -310.405809) (xy 164.142729 -310.374777)
			(xy 164.108505 -310.337605) (xy 164.080868 -310.295307) (xy 164.06057 -310.249036) (xy 164.048165 -310.200055)
			(xy 164.043992 -310.1497) (xy 164.048165 -310.099345) (xy 164.06057 -310.050364) (xy 164.080868 -310.004093)
			(xy 164.108505 -309.961795) (xy 164.142729 -309.924623) (xy 164.182604 -309.893591) (xy 164.227044 -309.869546)
			(xy 164.274835 -309.853145) (xy 164.324674 -309.844834) (xy 164.349938 -309.84444) (xy 164.363993 -309.844646)
			(xy 164.391978 -309.847312) (xy 164.405818 -309.849774) (xy 164.406326 -309.849774) (xy 164.418561 -309.851279)
			(xy 164.442065 -309.843985) (xy 164.451284 -309.835804) (xy 164.510974 -309.776114) (xy 164.519129 -309.766877)
			(xy 164.526439 -309.743386) (xy 164.524944 -309.731156) (xy 164.524944 -309.730902) (xy 164.522467 -309.717)
			(xy 164.519794 -309.688887) (xy 164.51961 -309.674768) (xy 164.520132 -309.649513) (xy 164.528445 -309.599691)
			(xy 164.544846 -309.551917) (xy 164.568887 -309.507494) (xy 164.599911 -309.467634) (xy 164.637073 -309.433424)
			(xy 164.679359 -309.405798) (xy 164.725615 -309.385508) (xy 164.77458 -309.373108) (xy 164.824918 -309.368937)
			(xy 164.875256 -309.373108) (xy 164.924221 -309.385508) (xy 164.970477 -309.405798) (xy 165.012763 -309.433424)
			(xy 165.049925 -309.467634) (xy 165.080949 -309.507494) (xy 165.10499 -309.551917) (xy 165.121391 -309.599691)
			(xy 165.129704 -309.649513) (xy 165.130226 -309.674768) (xy 165.130019 -309.688823) (xy 165.127349 -309.716808)
			(xy 165.124892 -309.730648) (xy 165.124892 -309.731156) (xy 165.123395 -309.743389) (xy 165.130695 -309.766885)
			(xy 165.138862 -309.776114) (xy 165.198552 -309.835804) (xy 165.207789 -309.843962) (xy 165.231281 -309.851283)
			(xy 165.24351 -309.849774) (xy 165.243764 -309.849774) (xy 165.257603 -309.847305) (xy 165.285588 -309.844629)
			(xy 165.299644 -309.84444) (xy 165.300152 -309.84444) (xy 165.333172 -309.846472) (xy 165.335966 -309.846726)
			(xy 165.336474 -309.846726) (xy 165.348158 -309.847996) (xy 165.359334 -309.843932) (xy 165.364756 -309.841769)
			(xy 165.374502 -309.835352) (xy 165.378638 -309.831232) (xy 165.443154 -309.763668) (xy 165.450266 -309.740808)
			(xy 165.448234 -309.729124) (xy 165.444502 -309.703903) (xy 165.443928 -309.652922) (xy 165.451191 -309.602459)
			(xy 165.466117 -309.553709) (xy 165.488353 -309.50783) (xy 165.517371 -309.465911) (xy 165.552483 -309.428945)
			(xy 165.592856 -309.39781) (xy 165.637531 -309.373245) (xy 165.685448 -309.355832) (xy 165.710362 -309.35041)
			(xy 165.720753 -309.348428) (xy 165.741724 -309.345629) (xy 165.752272 -309.344822) (xy 165.753288 -309.344822)
			(xy 165.76167 -309.34406) (xy 165.77564 -309.338218) (xy 165.776656 -309.33771) (xy 165.789864 -309.331868)
			(xy 165.7985 -309.325772) (xy 165.816788 -309.308246) (xy 165.823743 -309.300823) (xy 165.83162 -309.282087)
			(xy 165.832028 -309.271924) (xy 165.832028 -309.127652) (xy 165.831766 -309.119919) (xy 165.827117 -309.105171)
			(xy 165.822884 -309.098696) (xy 165.817296 -309.091838) (xy 165.808152 -309.082694) (xy 165.807644 -309.082186)
			(xy 165.79342 -309.068216) (xy 165.790258 -309.065512) (xy 165.78324 -309.061042) (xy 165.77945 -309.059326)
			(xy 165.771068 -309.05577) (xy 165.761416 -309.055262) (xy 165.761162 -309.055262) (xy 165.734789 -309.053672)
			(xy 165.683013 -309.043161) (xy 165.633566 -309.024552) (xy 165.587707 -308.998319) (xy 165.546601 -308.96513)
			(xy 165.511295 -308.925828) (xy 165.482685 -308.881412) (xy 165.4615 -308.833014) (xy 165.448278 -308.781863)
			(xy 165.443357 -308.72926) (xy 165.44686 -308.676544) (xy 165.4587 -308.625056) (xy 165.478574 -308.576104)
			(xy 165.505977 -308.530935) (xy 165.540213 -308.490696) (xy 165.58041 -308.456412) (xy 165.625547 -308.428954)
			(xy 165.674474 -308.409021) (xy 165.725948 -308.397119) (xy 165.752272 -308.394862) (xy 165.753288 -308.394862)
			(xy 165.76167 -308.3941) (xy 165.77564 -308.388258) (xy 165.776656 -308.38775) (xy 165.789864 -308.381908)
			(xy 165.7985 -308.375812) (xy 165.816788 -308.358286) (xy 165.823734 -308.35086) (xy 165.831588 -308.332123)
			(xy 165.832028 -308.321964) (xy 165.832028 -308.177692) (xy 165.831757 -308.169963) (xy 165.827094 -308.155225)
			(xy 165.822884 -308.148736) (xy 165.817296 -308.141878) (xy 165.808152 -308.132734) (xy 165.807644 -308.132226)
			(xy 165.79342 -308.118256) (xy 165.790259 -308.11555) (xy 165.783243 -308.111077) (xy 165.77945 -308.109366)
			(xy 165.771068 -308.10581) (xy 165.761416 -308.105302) (xy 165.761162 -308.105302) (xy 165.734793 -308.103712)
			(xy 165.683027 -308.093203) (xy 165.633589 -308.074597) (xy 165.587739 -308.048368) (xy 165.54664 -308.015184)
			(xy 165.51134 -307.975889) (xy 165.482736 -307.931481) (xy 165.461556 -307.883091) (xy 165.448337 -307.831949)
			(xy 165.443417 -307.779356) (xy 165.44692 -307.72665) (xy 165.458758 -307.675171) (xy 165.478629 -307.626228)
			(xy 165.506028 -307.581067) (xy 165.540258 -307.540836) (xy 165.580448 -307.506558) (xy 165.625577 -307.479106)
			(xy 165.674496 -307.459176) (xy 165.725961 -307.447278) (xy 165.752272 -307.444902) (xy 165.753288 -307.444902)
			(xy 165.76167 -307.44414) (xy 165.77564 -307.438298) (xy 165.776656 -307.43779) (xy 165.789864 -307.431948)
			(xy 165.7985 -307.425852) (xy 165.816788 -307.408326) (xy 165.82374 -307.400902) (xy 165.831609 -307.382166)
			(xy 165.832028 -307.372004) (xy 165.832028 -307.227732) (xy 165.831763 -307.22) (xy 165.82711 -307.205256)
			(xy 165.822884 -307.198776) (xy 165.817296 -307.191918) (xy 165.808152 -307.182774) (xy 165.807644 -307.182266)
			(xy 165.79342 -307.168296) (xy 165.790257 -307.165592) (xy 165.783239 -307.161124) (xy 165.77945 -307.159406)
			(xy 165.771068 -307.15585) (xy 165.761416 -307.155342) (xy 165.761162 -307.155342) (xy 165.73479 -307.153752)
			(xy 165.683018 -307.143241) (xy 165.633574 -307.124634) (xy 165.587718 -307.098402) (xy 165.546614 -307.065215)
			(xy 165.51131 -307.025915) (xy 165.482702 -306.981502) (xy 165.461518 -306.933106) (xy 165.448298 -306.881958)
			(xy 165.443377 -306.829359) (xy 165.44688 -306.776646) (xy 165.458719 -306.725161) (xy 165.478592 -306.676212)
			(xy 165.505994 -306.631046) (xy 165.540228 -306.590809) (xy 165.580423 -306.556527) (xy 165.625557 -306.529071)
			(xy 165.674481 -306.509139) (xy 165.725953 -306.497239) (xy 165.752272 -306.494942) (xy 165.753288 -306.494942)
			(xy 165.76167 -306.49418) (xy 165.77564 -306.488338) (xy 165.776656 -306.48783) (xy 165.789864 -306.481988)
			(xy 165.7985 -306.475892) (xy 165.816788 -306.458366) (xy 165.823731 -306.450939) (xy 165.831577 -306.432202)
			(xy 165.832028 -306.422044) (xy 165.832028 -306.277772) (xy 165.831754 -306.270044) (xy 165.827086 -306.255309)
			(xy 165.822884 -306.248816) (xy 165.817296 -306.241958) (xy 165.808152 -306.232814) (xy 165.807644 -306.232306)
			(xy 165.79342 -306.218336) (xy 165.790258 -306.215631) (xy 165.783242 -306.211159) (xy 165.77945 -306.209446)
			(xy 165.771068 -306.20589) (xy 165.761416 -306.205382) (xy 165.761162 -306.205382) (xy 165.734787 -306.203792)
			(xy 165.683008 -306.19328) (xy 165.633559 -306.174671) (xy 165.587697 -306.148436) (xy 165.546588 -306.115245)
			(xy 165.511279 -306.075941) (xy 165.482668 -306.031523) (xy 165.461481 -305.983121) (xy 165.448259 -305.931967)
			(xy 165.443337 -305.879362) (xy 165.44684 -305.826643) (xy 165.45868 -305.775151) (xy 165.478555 -305.726196)
			(xy 165.50596 -305.681024) (xy 165.540198 -305.640783) (xy 165.580398 -305.606496) (xy 165.625536 -305.579037)
			(xy 165.674467 -305.559102) (xy 165.725944 -305.547199) (xy 165.752272 -305.544982) (xy 165.753288 -305.544982)
			(xy 165.76167 -305.54422) (xy 165.77564 -305.538378) (xy 165.776656 -305.53787) (xy 165.789864 -305.532028)
			(xy 165.7985 -305.525932) (xy 165.816788 -305.508406) (xy 165.823737 -305.500981) (xy 165.831598 -305.482244)
			(xy 165.832028 -305.472084) (xy 165.832028 -305.327558) (xy 165.831767 -305.319825) (xy 165.82712 -305.305076)
			(xy 165.822884 -305.298602) (xy 165.817296 -305.291744) (xy 165.808152 -305.2826) (xy 165.807644 -305.282092)
			(xy 165.79342 -305.268122) (xy 165.790258 -305.265417) (xy 165.783241 -305.260947) (xy 165.77945 -305.259232)
			(xy 165.771068 -305.255676) (xy 165.761416 -305.255168) (xy 165.761162 -305.255168) (xy 165.735886 -305.253657)
			(xy 165.686201 -305.243914) (xy 165.638581 -305.226711) (xy 165.594139 -305.202451) (xy 165.553914 -305.171701)
			(xy 165.518846 -305.135179) (xy 165.489754 -305.093739) (xy 165.467317 -305.048349) (xy 165.452062 -305.00007)
			(xy 165.444342 -304.95003) (xy 165.443916 -304.924714) (xy 165.444398 -304.898725) (xy 165.452528 -304.847386)
			(xy 165.468589 -304.797951) (xy 165.492186 -304.751638) (xy 165.522739 -304.709586) (xy 165.559494 -304.672832)
			(xy 165.601546 -304.642281) (xy 165.64786 -304.618685) (xy 165.697296 -304.602625) (xy 165.748635 -304.594497)
			(xy 165.774624 -304.594006) (xy 165.774878 -304.594006) (xy 165.802615 -304.594564) (xy 165.857312 -304.603814)
			(xy 165.909694 -304.622074) (xy 165.958289 -304.648831) (xy 165.980364 -304.665634) (xy 165.986714 -304.670714)
			(xy 166.009574 -304.679096) (xy 166.01059 -304.679604) (xy 166.011606 -304.679858) (xy 166.017448 -304.681382)
			(xy 166.029386 -304.682144) (xy 166.092632 -304.679096) (xy 166.101238 -304.677881) (xy 166.116953 -304.670484)
			(xy 166.123366 -304.664618) (xy 166.45255 -304.335434) (xy 166.457176 -304.331052) (xy 166.468094 -304.324489)
			(xy 166.47414 -304.32248) (xy 166.47795 -304.321464) (xy 166.481865 -304.319842) (xy 166.489143 -304.315505)
			(xy 166.492428 -304.312828) (xy 166.511478 -304.293016) (xy 166.517002 -304.285678) (xy 166.522916 -304.268304)
			(xy 166.522347 -304.24996) (xy 166.515366 -304.232986) (xy 166.509446 -304.22596) (xy 166.504874 -304.221388)
			(xy 166.484424 -304.202438) (xy 166.44957 -304.15893) (xy 166.422525 -304.110183) (xy 166.404058 -304.057583)
			(xy 166.394696 -304.002628) (xy 166.39413 -303.974754) (xy 166.39464 -303.948767) (xy 166.40277 -303.897432)
			(xy 166.418831 -303.848002) (xy 166.442427 -303.801692) (xy 166.472977 -303.759644) (xy 166.509728 -303.722893)
			(xy 166.551776 -303.692343) (xy 166.598086 -303.668747) (xy 166.647516 -303.652686) (xy 166.698851 -303.644556)
			(xy 166.750825 -303.644556) (xy 166.80216 -303.652686) (xy 166.85159 -303.668747) (xy 166.8979 -303.692343)
			(xy 166.939948 -303.722893) (xy 166.976699 -303.759644) (xy 167.007249 -303.801692) (xy 167.030845 -303.848002)
			(xy 167.046906 -303.897432) (xy 167.055036 -303.948767) (xy 167.055546 -303.974754) (xy 167.055546 -303.975008)
			(xy 167.055097 -303.999813) (xy 167.047687 -304.048868) (xy 167.033048 -304.09627) (xy 167.011508 -304.140962)
			(xy 166.997888 -304.161698) (xy 166.995348 -304.165254) (xy 166.993824 -304.168048) (xy 166.993824 -304.168556)
			(xy 166.989489 -304.179057) (xy 166.989489 -304.201743) (xy 166.993824 -304.212244) (xy 167.025066 -304.270664)
			(xy 167.025066 -304.271172) (xy 167.034972 -304.289714) (xy 167.039036 -304.297334) (xy 167.041831 -304.301452)
			(xy 167.04874 -304.308613) (xy 167.052752 -304.311558) (xy 167.054784 -304.312828) (xy 167.113204 -304.312828)
			(xy 167.126158 -304.311304) (xy 167.132508 -304.309526) (xy 167.132508 -304.303684) (xy 167.355774 -304.303684)
			(xy 167.362632 -304.294032) (xy 167.379904 -304.261012) (xy 167.406828 -304.210212) (xy 167.410928 -304.198875)
			(xy 167.409221 -304.174862) (xy 167.403526 -304.164238) (xy 167.401494 -304.16119) (xy 167.398446 -304.156618)
			(xy 167.397938 -304.15611) (xy 167.38524 -304.135898) (xy 167.365157 -304.092597) (xy 167.351504 -304.04686)
			(xy 167.344564 -303.999635) (xy 167.34409 -303.97577) (xy 167.34409 -303.975262) (xy 167.34409 -303.974754)
			(xy 167.3446 -303.948767) (xy 167.35273 -303.897432) (xy 167.368791 -303.848002) (xy 167.392387 -303.801692)
			(xy 167.422937 -303.759644) (xy 167.459688 -303.722893) (xy 167.501736 -303.692343) (xy 167.548046 -303.668747)
			(xy 167.597476 -303.652686) (xy 167.648811 -303.644556) (xy 167.700785 -303.644556) (xy 167.75212 -303.652686)
			(xy 167.80155 -303.668747) (xy 167.84786 -303.692343) (xy 167.889908 -303.722893) (xy 167.926659 -303.759644)
			(xy 167.957209 -303.801692) (xy 167.980805 -303.848002) (xy 167.996866 -303.897432) (xy 168.004996 -303.948767)
			(xy 168.005506 -303.974754) (xy 168.005506 -303.975008) (xy 168.005057 -303.999813) (xy 167.997646 -304.048867)
			(xy 167.983006 -304.096269) (xy 167.961464 -304.140959) (xy 167.947848 -304.161698) (xy 167.945308 -304.165254)
			(xy 167.943784 -304.168048) (xy 167.943784 -304.168556) (xy 167.939451 -304.179057) (xy 167.939451 -304.201743)
			(xy 167.943784 -304.212244) (xy 167.975026 -304.270664) (xy 167.975026 -304.271172) (xy 167.984932 -304.289714)
			(xy 167.988996 -304.297334) (xy 167.991793 -304.30145) (xy 167.998707 -304.308604) (xy 168.002712 -304.311558)
			(xy 168.004744 -304.312828) (xy 168.063164 -304.312828) (xy 168.076118 -304.311304) (xy 168.082468 -304.309526)
			(xy 168.082468 -304.303684) (xy 168.305734 -304.303684) (xy 168.312592 -304.294032) (xy 168.329864 -304.261012)
			(xy 168.356788 -304.210212) (xy 168.360885 -304.198874) (xy 168.359179 -304.174862) (xy 168.353486 -304.164238)
			(xy 168.351454 -304.16119) (xy 168.348406 -304.156618) (xy 168.347898 -304.15611) (xy 168.335198 -304.135899)
			(xy 168.315111 -304.092599) (xy 168.301456 -304.046861) (xy 168.294515 -303.999636) (xy 168.29405 -303.97577)
			(xy 168.29405 -303.975262) (xy 168.29405 -303.974754) (xy 168.29456 -303.948767) (xy 168.30269 -303.897432)
			(xy 168.318751 -303.848002) (xy 168.342347 -303.801692) (xy 168.372897 -303.759644) (xy 168.409648 -303.722893)
			(xy 168.451696 -303.692343) (xy 168.498006 -303.668747) (xy 168.547436 -303.652686) (xy 168.598771 -303.644556)
			(xy 168.650745 -303.644556) (xy 168.70208 -303.652686) (xy 168.75151 -303.668747) (xy 168.79782 -303.692343)
			(xy 168.839868 -303.722893) (xy 168.876619 -303.759644) (xy 168.907169 -303.801692) (xy 168.930765 -303.848002)
			(xy 168.946826 -303.897432) (xy 168.954956 -303.948767) (xy 168.955466 -303.974754) (xy 168.955466 -303.975008)
			(xy 168.954994 -303.999812) (xy 168.947585 -304.048863) (xy 168.932948 -304.096263) (xy 168.91141 -304.140951)
			(xy 168.897808 -304.161698) (xy 168.895268 -304.165254) (xy 168.893744 -304.168048) (xy 168.893744 -304.168556)
			(xy 168.889413 -304.179057) (xy 168.889413 -304.201743) (xy 168.893744 -304.212244) (xy 168.924986 -304.270664)
			(xy 168.924986 -304.271172) (xy 168.934892 -304.289714) (xy 168.938956 -304.297334) (xy 168.941751 -304.301451)
			(xy 168.948662 -304.30861) (xy 168.952672 -304.311558) (xy 168.954704 -304.312828) (xy 169.013124 -304.312828)
			(xy 169.026078 -304.311304) (xy 169.032428 -304.309526) (xy 169.032428 -304.303684) (xy 169.255694 -304.303684)
			(xy 169.262552 -304.294032) (xy 169.279824 -304.261012) (xy 169.306748 -304.210212) (xy 169.310847 -304.198874)
			(xy 169.30914 -304.174862) (xy 169.303446 -304.164238) (xy 169.301414 -304.16119) (xy 169.298366 -304.156618)
			(xy 169.297858 -304.15611) (xy 169.285159 -304.135899) (xy 169.265075 -304.092598) (xy 169.251421 -304.04686)
			(xy 169.244481 -303.999635) (xy 169.24401 -303.97577) (xy 169.24401 -303.975262) (xy 169.24401 -303.974754)
			(xy 169.24452 -303.948767) (xy 169.25265 -303.897432) (xy 169.268711 -303.848002) (xy 169.292307 -303.801692)
			(xy 169.322857 -303.759644) (xy 169.359608 -303.722893) (xy 169.401656 -303.692343) (xy 169.447966 -303.668747)
			(xy 169.497396 -303.652686) (xy 169.548731 -303.644556) (xy 169.600705 -303.644556) (xy 169.65204 -303.652686)
			(xy 169.70147 -303.668747) (xy 169.74778 -303.692343) (xy 169.789828 -303.722893) (xy 169.826579 -303.759644)
			(xy 169.857129 -303.801692) (xy 169.880725 -303.848002) (xy 169.896786 -303.897432) (xy 169.904916 -303.948767)
			(xy 169.905426 -303.974754) (xy 169.905426 -303.975008) (xy 169.904977 -303.999813) (xy 169.897567 -304.048868)
			(xy 169.882927 -304.09627) (xy 169.861386 -304.14096) (xy 169.847768 -304.161698) (xy 169.845228 -304.165254)
			(xy 169.843704 -304.168048) (xy 169.843704 -304.168556) (xy 169.83937 -304.179057) (xy 169.83937 -304.201743)
			(xy 169.843704 -304.212244) (xy 169.874946 -304.270664) (xy 169.874946 -304.271172) (xy 169.884852 -304.289714)
			(xy 169.888916 -304.297334) (xy 169.89171 -304.301453) (xy 169.898618 -304.308616) (xy 169.902632 -304.311558)
			(xy 169.904664 -304.312828) (xy 169.963084 -304.312828) (xy 169.976038 -304.311304) (xy 169.982388 -304.309526)
			(xy 169.982388 -304.303684) (xy 170.205654 -304.303684) (xy 170.212512 -304.294032) (xy 170.229784 -304.261012)
			(xy 170.256708 -304.210212) (xy 170.260804 -304.198874) (xy 170.259099 -304.174862) (xy 170.253406 -304.164238)
			(xy 170.251374 -304.16119) (xy 170.248326 -304.156618) (xy 170.247818 -304.15611) (xy 170.235121 -304.135898)
			(xy 170.215039 -304.092597) (xy 170.201387 -304.046859) (xy 170.194448 -303.999635) (xy 170.19397 -303.97577)
			(xy 170.19397 -303.975262) (xy 170.19397 -303.974754) (xy 170.19448 -303.948767) (xy 170.20261 -303.897432)
			(xy 170.218671 -303.848002) (xy 170.242267 -303.801692) (xy 170.272817 -303.759644) (xy 170.309568 -303.722893)
			(xy 170.351616 -303.692343) (xy 170.397926 -303.668747) (xy 170.447356 -303.652686) (xy 170.498691 -303.644556)
			(xy 170.550665 -303.644556) (xy 170.602 -303.652686) (xy 170.65143 -303.668747) (xy 170.69774 -303.692343)
			(xy 170.739788 -303.722893) (xy 170.776539 -303.759644) (xy 170.807089 -303.801692) (xy 170.830685 -303.848002)
			(xy 170.846746 -303.897432) (xy 170.854876 -303.948767) (xy 170.855386 -303.974754) (xy 170.855386 -303.975008)
			(xy 170.854937 -303.999813) (xy 170.847526 -304.048867) (xy 170.832885 -304.096268) (xy 170.811341 -304.140957)
			(xy 170.797728 -304.161698) (xy 170.795188 -304.165254) (xy 170.793664 -304.168048) (xy 170.793664 -304.168556)
			(xy 170.789333 -304.179057) (xy 170.789333 -304.201743) (xy 170.793664 -304.212244) (xy 170.824906 -304.270664)
			(xy 170.824906 -304.271172) (xy 170.834812 -304.289714) (xy 170.838876 -304.297334) (xy 170.841672 -304.30145)
			(xy 170.848585 -304.308607) (xy 170.852592 -304.311558) (xy 170.854624 -304.312828) (xy 170.913044 -304.312828)
			(xy 170.925998 -304.311304) (xy 170.932348 -304.309526) (xy 170.932348 -304.303684) (xy 171.155614 -304.303684)
			(xy 171.162472 -304.294032) (xy 171.179744 -304.261012) (xy 171.206668 -304.210212) (xy 171.210766 -304.198874)
			(xy 171.20906 -304.174862) (xy 171.203366 -304.164238) (xy 171.201334 -304.16119) (xy 171.198286 -304.156618)
			(xy 171.197778 -304.15611) (xy 171.185079 -304.135899) (xy 171.164993 -304.092598) (xy 171.151338 -304.04686)
			(xy 171.144398 -303.999635) (xy 171.14393 -303.97577) (xy 171.14393 -303.975262) (xy 171.14393 -303.974754)
			(xy 171.14444 -303.948767) (xy 171.15257 -303.897432) (xy 171.168631 -303.848002) (xy 171.192227 -303.801692)
			(xy 171.222777 -303.759644) (xy 171.259528 -303.722893) (xy 171.301576 -303.692343) (xy 171.347886 -303.668747)
			(xy 171.397316 -303.652686) (xy 171.448651 -303.644556) (xy 171.500625 -303.644556) (xy 171.55196 -303.652686)
			(xy 171.60139 -303.668747) (xy 171.6477 -303.692343) (xy 171.689748 -303.722893) (xy 171.726499 -303.759644)
			(xy 171.757049 -303.801692) (xy 171.780645 -303.848002) (xy 171.796706 -303.897432) (xy 171.804836 -303.948767)
			(xy 171.805346 -303.974754) (xy 171.805346 -303.975008) (xy 171.804897 -303.999813) (xy 171.797487 -304.048868)
			(xy 171.782848 -304.09627) (xy 171.761308 -304.140962) (xy 171.747688 -304.161698) (xy 171.745148 -304.165254)
			(xy 171.743624 -304.168048) (xy 171.743624 -304.168556) (xy 171.739289 -304.179057) (xy 171.739289 -304.201743)
			(xy 171.743624 -304.212244) (xy 171.774866 -304.270664) (xy 171.774866 -304.271172) (xy 171.784772 -304.289714)
			(xy 171.788836 -304.297334) (xy 171.791631 -304.301452) (xy 171.79854 -304.308613) (xy 171.802552 -304.311558)
			(xy 171.804584 -304.312828) (xy 171.863004 -304.312828) (xy 171.875958 -304.311304) (xy 171.882308 -304.309526)
			(xy 171.882308 -304.303684) (xy 172.105574 -304.303684) (xy 172.112432 -304.294032) (xy 172.129704 -304.261012)
			(xy 172.156628 -304.210212) (xy 172.160728 -304.198875) (xy 172.159021 -304.174862) (xy 172.153326 -304.164238)
			(xy 172.151294 -304.16119) (xy 172.148246 -304.156618) (xy 172.147738 -304.15611) (xy 172.13504 -304.135898)
			(xy 172.114957 -304.092597) (xy 172.101304 -304.04686) (xy 172.094364 -303.999635) (xy 172.09389 -303.97577)
			(xy 172.09389 -303.975262) (xy 172.09389 -303.974754) (xy 172.0944 -303.948767) (xy 172.10253 -303.897432)
			(xy 172.118591 -303.848002) (xy 172.142187 -303.801692) (xy 172.172737 -303.759644) (xy 172.209488 -303.722893)
			(xy 172.251536 -303.692343) (xy 172.297846 -303.668747) (xy 172.347276 -303.652686) (xy 172.398611 -303.644556)
			(xy 172.450585 -303.644556) (xy 172.50192 -303.652686) (xy 172.55135 -303.668747) (xy 172.59766 -303.692343)
			(xy 172.639708 -303.722893) (xy 172.676459 -303.759644) (xy 172.707009 -303.801692) (xy 172.730605 -303.848002)
			(xy 172.746666 -303.897432) (xy 172.754796 -303.948767) (xy 172.755306 -303.974754) (xy 172.755306 -303.975008)
			(xy 172.754857 -303.999813) (xy 172.747446 -304.048867) (xy 172.732806 -304.096269) (xy 172.711264 -304.140959)
			(xy 172.697648 -304.161698) (xy 172.695108 -304.165254) (xy 172.693584 -304.168048) (xy 172.693584 -304.168556)
			(xy 172.689251 -304.179057) (xy 172.689251 -304.201743) (xy 172.693584 -304.212244) (xy 172.724826 -304.270664)
			(xy 172.724826 -304.271172) (xy 172.734732 -304.289714) (xy 172.738796 -304.297334) (xy 172.741593 -304.30145)
			(xy 172.748507 -304.308604) (xy 172.752512 -304.311558) (xy 172.754544 -304.312828) (xy 172.812964 -304.312828)
			(xy 172.825918 -304.311304) (xy 172.832268 -304.309526) (xy 172.832268 -304.303684) (xy 173.055788 -304.303684)
			(xy 173.062646 -304.294032) (xy 173.079918 -304.261012) (xy 173.106842 -304.210212) (xy 173.110941 -304.198875)
			(xy 173.109234 -304.174862) (xy 173.10354 -304.164238) (xy 173.101508 -304.16119) (xy 173.09846 -304.156618)
			(xy 173.097952 -304.15611) (xy 173.085253 -304.135898) (xy 173.06517 -304.092597) (xy 173.051516 -304.04686)
			(xy 173.044576 -303.999635) (xy 173.044104 -303.97577) (xy 173.044104 -303.975262) (xy 173.044104 -303.974754)
			(xy 173.044614 -303.948767) (xy 173.052744 -303.897432) (xy 173.068805 -303.848002) (xy 173.092401 -303.801692)
			(xy 173.122951 -303.759644) (xy 173.159702 -303.722893) (xy 173.20175 -303.692343) (xy 173.24806 -303.668747)
			(xy 173.29749 -303.652686) (xy 173.348825 -303.644556) (xy 173.400799 -303.644556) (xy 173.452134 -303.652686)
			(xy 173.501564 -303.668747) (xy 173.547874 -303.692343) (xy 173.589922 -303.722893) (xy 173.626673 -303.759644)
			(xy 173.657223 -303.801692) (xy 173.680819 -303.848002) (xy 173.69688 -303.897432) (xy 173.70501 -303.948767)
			(xy 173.70552 -303.974754) (xy 173.70552 -303.975008) (xy 173.705071 -303.999813) (xy 173.69766 -304.048868)
			(xy 173.683021 -304.09627) (xy 173.661479 -304.14096) (xy 173.647862 -304.161698) (xy 173.645322 -304.165254)
			(xy 173.643798 -304.168048) (xy 173.643798 -304.168556) (xy 173.639464 -304.179057) (xy 173.639464 -304.201743)
			(xy 173.643798 -304.212244) (xy 173.67504 -304.270664) (xy 173.67504 -304.271172) (xy 173.684946 -304.289714)
			(xy 173.68901 -304.297334) (xy 173.691804 -304.301453) (xy 173.698711 -304.308617) (xy 173.702726 -304.311558)
			(xy 173.704758 -304.312828) (xy 173.763178 -304.312828) (xy 173.776132 -304.311304) (xy 173.782482 -304.309526)
			(xy 173.782482 -304.303684) (xy 174.005748 -304.303684) (xy 174.012606 -304.294032) (xy 174.029878 -304.261012)
			(xy 174.056802 -304.210212) (xy 174.060898 -304.198874) (xy 174.059193 -304.174862) (xy 174.0535 -304.164238)
			(xy 174.051468 -304.16119) (xy 174.04842 -304.156618) (xy 174.047912 -304.15611) (xy 174.035215 -304.135898)
			(xy 174.015133 -304.092596) (xy 174.001482 -304.046859) (xy 173.994542 -303.999635) (xy 173.994064 -303.97577)
			(xy 173.994064 -303.975262) (xy 173.994064 -303.974754) (xy 173.994574 -303.948767) (xy 174.002704 -303.897432)
			(xy 174.018765 -303.848002) (xy 174.042361 -303.801692) (xy 174.072911 -303.759644) (xy 174.109662 -303.722893)
			(xy 174.15171 -303.692343) (xy 174.19802 -303.668747) (xy 174.24745 -303.652686) (xy 174.298785 -303.644556)
			(xy 174.350759 -303.644556) (xy 174.402094 -303.652686) (xy 174.451524 -303.668747) (xy 174.497834 -303.692343)
			(xy 174.539882 -303.722893) (xy 174.576633 -303.759644) (xy 174.607183 -303.801692) (xy 174.630779 -303.848002)
			(xy 174.64684 -303.897432) (xy 174.65497 -303.948767) (xy 174.65548 -303.974754) (xy 174.65548 -303.975008)
			(xy 174.655031 -303.999813) (xy 174.64762 -304.048867) (xy 174.632978 -304.096268) (xy 174.611435 -304.140957)
			(xy 174.597822 -304.161698) (xy 174.595282 -304.165254) (xy 174.593758 -304.168048) (xy 174.593758 -304.168556)
			(xy 174.589426 -304.179057) (xy 174.589426 -304.201743) (xy 174.593758 -304.212244) (xy 174.625 -304.270664)
			(xy 174.625 -304.271172) (xy 174.634906 -304.289714) (xy 174.63897 -304.297334) (xy 174.641766 -304.301451)
			(xy 174.648678 -304.308608) (xy 174.652686 -304.311558) (xy 174.654718 -304.312828) (xy 174.713138 -304.312828)
			(xy 174.726092 -304.311304) (xy 174.732442 -304.309526) (xy 174.732442 -304.303684) (xy 175.905668 -304.303684)
			(xy 175.912526 -304.294032) (xy 175.929798 -304.261012) (xy 175.956722 -304.210212) (xy 175.960817 -304.198874)
			(xy 175.959113 -304.174862) (xy 175.95342 -304.164238) (xy 175.951388 -304.16119) (xy 175.94834 -304.156618)
			(xy 175.947832 -304.15611) (xy 175.935134 -304.135898) (xy 175.915051 -304.092597) (xy 175.901399 -304.04686)
			(xy 175.894459 -303.999635) (xy 175.893984 -303.97577) (xy 175.893984 -303.975262) (xy 175.893984 -303.974754)
			(xy 175.894494 -303.948767) (xy 175.902624 -303.897432) (xy 175.918685 -303.848002) (xy 175.942281 -303.801692)
			(xy 175.972831 -303.759644) (xy 176.009582 -303.722893) (xy 176.05163 -303.692343) (xy 176.09794 -303.668747)
			(xy 176.14737 -303.652686) (xy 176.198705 -303.644556) (xy 176.250679 -303.644556) (xy 176.302014 -303.652686)
			(xy 176.351444 -303.668747) (xy 176.397754 -303.692343) (xy 176.439802 -303.722893) (xy 176.476553 -303.759644)
			(xy 176.507103 -303.801692) (xy 176.530699 -303.848002) (xy 176.54676 -303.897432) (xy 176.55489 -303.948767)
			(xy 176.5554 -303.974754) (xy 176.5554 -303.975008) (xy 176.554951 -303.999813) (xy 176.54754 -304.048867)
			(xy 176.5329 -304.096269) (xy 176.511357 -304.140958) (xy 176.497742 -304.161698) (xy 176.495202 -304.165254)
			(xy 176.493678 -304.168048) (xy 176.493678 -304.168556) (xy 176.489346 -304.179057) (xy 176.489346 -304.201743)
			(xy 176.493678 -304.212244) (xy 176.52492 -304.270664) (xy 176.52492 -304.271172) (xy 176.534826 -304.289714)
			(xy 176.53889 -304.297334) (xy 176.541687 -304.30145) (xy 176.5486 -304.308605) (xy 176.552606 -304.311558)
			(xy 176.554638 -304.312828) (xy 176.613058 -304.312828) (xy 176.626012 -304.311304) (xy 176.632362 -304.309526)
			(xy 176.632362 -304.303684) (xy 176.855628 -304.303684) (xy 176.862486 -304.294032) (xy 176.879758 -304.261012)
			(xy 176.906682 -304.210212) (xy 176.910779 -304.198874) (xy 176.909074 -304.174862) (xy 176.90338 -304.164238)
			(xy 176.901348 -304.16119) (xy 176.8983 -304.156618) (xy 176.897792 -304.15611) (xy 176.885092 -304.135899)
			(xy 176.865006 -304.092598) (xy 176.85135 -304.046861) (xy 176.84441 -303.999636) (xy 176.843944 -303.97577)
			(xy 176.843944 -303.975262) (xy 176.843944 -303.974754) (xy 176.844454 -303.948767) (xy 176.852584 -303.897432)
			(xy 176.868645 -303.848002) (xy 176.892241 -303.801692) (xy 176.922791 -303.759644) (xy 176.959542 -303.722893)
			(xy 177.00159 -303.692343) (xy 177.0479 -303.668747) (xy 177.09733 -303.652686) (xy 177.148665 -303.644556)
			(xy 177.200639 -303.644556) (xy 177.251974 -303.652686) (xy 177.301404 -303.668747) (xy 177.347714 -303.692343)
			(xy 177.389762 -303.722893) (xy 177.426513 -303.759644) (xy 177.457063 -303.801692) (xy 177.480659 -303.848002)
			(xy 177.49672 -303.897432) (xy 177.50485 -303.948767) (xy 177.50536 -303.974754) (xy 177.50536 -303.975008)
			(xy 177.504888 -303.999812) (xy 177.497479 -304.048863) (xy 177.482842 -304.096263) (xy 177.461304 -304.140951)
			(xy 177.447702 -304.161698) (xy 177.445162 -304.165254) (xy 177.443638 -304.168048) (xy 177.443638 -304.168556)
			(xy 177.439308 -304.179058) (xy 177.439308 -304.201742) (xy 177.443638 -304.212244) (xy 177.47488 -304.270664)
			(xy 177.47488 -304.271172) (xy 177.484786 -304.289714) (xy 177.48885 -304.297334) (xy 177.491645 -304.301452)
			(xy 177.498556 -304.308611) (xy 177.502566 -304.311558) (xy 177.504598 -304.312828) (xy 177.563018 -304.312828)
			(xy 177.575972 -304.311304) (xy 177.582322 -304.309526) (xy 177.582322 -304.303684) (xy 177.805588 -304.303684)
			(xy 177.812446 -304.294032) (xy 177.829718 -304.261012) (xy 177.856642 -304.210212) (xy 177.860741 -304.198875)
			(xy 177.859034 -304.174862) (xy 177.85334 -304.164238) (xy 177.851308 -304.16119) (xy 177.84826 -304.156618)
			(xy 177.847752 -304.15611) (xy 177.835053 -304.135898) (xy 177.81497 -304.092597) (xy 177.801316 -304.04686)
			(xy 177.794376 -303.999635) (xy 177.793904 -303.97577) (xy 177.793904 -303.975262) (xy 177.793904 -303.974754)
			(xy 177.794414 -303.948767) (xy 177.802544 -303.897432) (xy 177.818605 -303.848002) (xy 177.842201 -303.801692)
			(xy 177.872751 -303.759644) (xy 177.909502 -303.722893) (xy 177.95155 -303.692343) (xy 177.99786 -303.668747)
			(xy 178.04729 -303.652686) (xy 178.098625 -303.644556) (xy 178.150599 -303.644556) (xy 178.201934 -303.652686)
			(xy 178.251364 -303.668747) (xy 178.297674 -303.692343) (xy 178.339722 -303.722893) (xy 178.376473 -303.759644)
			(xy 178.407023 -303.801692) (xy 178.430619 -303.848002) (xy 178.44668 -303.897432) (xy 178.45481 -303.948767)
			(xy 178.45532 -303.974754) (xy 178.45532 -303.975008) (xy 178.454871 -303.999813) (xy 178.44746 -304.048868)
			(xy 178.432821 -304.09627) (xy 178.411279 -304.14096) (xy 178.397662 -304.161698) (xy 178.395122 -304.165254)
			(xy 178.393598 -304.168048) (xy 178.393598 -304.168556) (xy 178.389264 -304.179057) (xy 178.389264 -304.201743)
			(xy 178.393598 -304.212244) (xy 178.42484 -304.270664) (xy 178.42484 -304.271172) (xy 178.434746 -304.289714)
			(xy 178.43881 -304.297334) (xy 178.441604 -304.301453) (xy 178.448511 -304.308617) (xy 178.452526 -304.311558)
			(xy 178.454558 -304.312828) (xy 178.512978 -304.312828) (xy 178.525932 -304.311304) (xy 178.532282 -304.309526)
			(xy 178.532282 -304.303684) (xy 178.755802 -304.303684) (xy 178.76266 -304.294032) (xy 178.779932 -304.261012)
			(xy 178.806856 -304.210212) (xy 178.810954 -304.198874) (xy 178.809248 -304.174862) (xy 178.803554 -304.164238)
			(xy 178.801522 -304.16119) (xy 178.798474 -304.156618) (xy 178.797966 -304.15611) (xy 178.785267 -304.135899)
			(xy 178.765182 -304.092598) (xy 178.751528 -304.04686) (xy 178.744588 -303.999635) (xy 178.744118 -303.97577)
			(xy 178.744118 -303.975262) (xy 178.744118 -303.974754) (xy 178.744628 -303.948767) (xy 178.752758 -303.897432)
			(xy 178.768819 -303.848002) (xy 178.792415 -303.801692) (xy 178.822965 -303.759644) (xy 178.859716 -303.722893)
			(xy 178.901764 -303.692343) (xy 178.948074 -303.668747) (xy 178.997504 -303.652686) (xy 179.048839 -303.644556)
			(xy 179.100813 -303.644556) (xy 179.152148 -303.652686) (xy 179.201578 -303.668747) (xy 179.247888 -303.692343)
			(xy 179.289936 -303.722893) (xy 179.326687 -303.759644) (xy 179.357237 -303.801692) (xy 179.380833 -303.848002)
			(xy 179.396894 -303.897432) (xy 179.405024 -303.948767) (xy 179.405534 -303.974754) (xy 179.405534 -303.975008)
			(xy 179.405085 -303.999813) (xy 179.397675 -304.048868) (xy 179.383036 -304.09627) (xy 179.361495 -304.140961)
			(xy 179.347876 -304.161698) (xy 179.345336 -304.165254) (xy 179.343812 -304.168048) (xy 179.343812 -304.168556)
			(xy 179.339478 -304.179057) (xy 179.339478 -304.201743) (xy 179.343812 -304.212244) (xy 179.375054 -304.270664)
			(xy 179.375054 -304.271172) (xy 179.38496 -304.289714) (xy 179.389024 -304.297334) (xy 179.391818 -304.301453)
			(xy 179.398727 -304.308615) (xy 179.40274 -304.311558) (xy 179.404772 -304.312828) (xy 179.463192 -304.312828)
			(xy 179.476146 -304.311304) (xy 179.482496 -304.309526) (xy 179.482496 -304.303684) (xy 179.705762 -304.303684)
			(xy 179.71262 -304.294032) (xy 179.729892 -304.261012) (xy 179.756816 -304.210212) (xy 179.760911 -304.198874)
			(xy 179.759207 -304.174862) (xy 179.753514 -304.164238) (xy 179.751482 -304.16119) (xy 179.748434 -304.156618)
			(xy 179.747926 -304.15611) (xy 179.735228 -304.135898) (xy 179.715146 -304.092597) (xy 179.701494 -304.046859)
			(xy 179.694554 -303.999635) (xy 179.694078 -303.97577) (xy 179.694078 -303.975262) (xy 179.694078 -303.974754)
			(xy 179.694588 -303.948767) (xy 179.702718 -303.897432) (xy 179.718779 -303.848002) (xy 179.742375 -303.801692)
			(xy 179.772925 -303.759644) (xy 179.809676 -303.722893) (xy 179.851724 -303.692343) (xy 179.898034 -303.668747)
			(xy 179.947464 -303.652686) (xy 179.998799 -303.644556) (xy 180.050773 -303.644556) (xy 180.102108 -303.652686)
			(xy 180.151538 -303.668747) (xy 180.197848 -303.692343) (xy 180.239896 -303.722893) (xy 180.276647 -303.759644)
			(xy 180.307197 -303.801692) (xy 180.330793 -303.848002) (xy 180.346854 -303.897432) (xy 180.354984 -303.948767)
			(xy 180.355494 -303.974754) (xy 180.355494 -303.975008) (xy 180.355045 -303.999813) (xy 180.347634 -304.048867)
			(xy 180.332993 -304.096269) (xy 180.31145 -304.140958) (xy 180.297836 -304.161698) (xy 180.295296 -304.165254)
			(xy 180.293772 -304.168048) (xy 180.293772 -304.168556) (xy 180.28944 -304.179057) (xy 180.28944 -304.201743)
			(xy 180.293772 -304.212244) (xy 180.325014 -304.270664) (xy 180.325014 -304.271172) (xy 180.33492 -304.289714)
			(xy 180.338984 -304.297334) (xy 180.341781 -304.30145) (xy 180.348694 -304.308606) (xy 180.3527 -304.311558)
			(xy 180.354732 -304.312828) (xy 180.413152 -304.312828) (xy 180.426106 -304.311304) (xy 180.432456 -304.309526)
			(xy 180.432456 -304.303684) (xy 180.655722 -304.303684) (xy 180.66258 -304.294032) (xy 180.679852 -304.261012)
			(xy 180.706776 -304.210212) (xy 180.710874 -304.198874) (xy 180.709168 -304.174862) (xy 180.703474 -304.164238)
			(xy 180.701442 -304.16119) (xy 180.698394 -304.156618) (xy 180.697886 -304.15611) (xy 180.685186 -304.135899)
			(xy 180.6651 -304.092598) (xy 180.651445 -304.046861) (xy 180.644505 -303.999635) (xy 180.644038 -303.97577)
			(xy 180.644038 -303.975262) (xy 180.644038 -303.974754) (xy 180.644548 -303.948767) (xy 180.652678 -303.897432)
			(xy 180.668739 -303.848002) (xy 180.692335 -303.801692) (xy 180.722885 -303.759644) (xy 180.759636 -303.722893)
			(xy 180.801684 -303.692343) (xy 180.847994 -303.668747) (xy 180.897424 -303.652686) (xy 180.948759 -303.644556)
			(xy 181.000733 -303.644556) (xy 181.052068 -303.652686) (xy 181.101498 -303.668747) (xy 181.147808 -303.692343)
			(xy 181.189856 -303.722893) (xy 181.226607 -303.759644) (xy 181.257157 -303.801692) (xy 181.280753 -303.848002)
			(xy 181.296814 -303.897432) (xy 181.304944 -303.948767) (xy 181.305454 -303.974754) (xy 181.305454 -303.975008)
			(xy 181.304982 -303.999812) (xy 181.297573 -304.048863) (xy 181.282935 -304.096262) (xy 181.261397 -304.140951)
			(xy 181.247796 -304.161698) (xy 181.245256 -304.165254) (xy 181.243732 -304.168048) (xy 181.243732 -304.168556)
			(xy 181.239402 -304.179058) (xy 181.239402 -304.201742) (xy 181.243732 -304.212244) (xy 181.274974 -304.270664)
			(xy 181.274974 -304.271172) (xy 181.28488 -304.289714) (xy 181.288944 -304.297334) (xy 181.291739 -304.301452)
			(xy 181.298649 -304.308612) (xy 181.30266 -304.311558) (xy 181.304692 -304.312828) (xy 181.363112 -304.312828)
			(xy 181.376066 -304.311304) (xy 181.382416 -304.309526) (xy 181.382416 -304.303684) (xy 181.605682 -304.303684)
			(xy 181.61254 -304.294032) (xy 181.629812 -304.261012) (xy 181.656736 -304.210212) (xy 181.660836 -304.198875)
			(xy 181.659129 -304.174862) (xy 181.653434 -304.164238) (xy 181.651402 -304.16119) (xy 181.648354 -304.156618)
			(xy 181.647846 -304.15611) (xy 181.635148 -304.135898) (xy 181.615064 -304.092597) (xy 181.601411 -304.04686)
			(xy 181.594471 -303.999635) (xy 181.593998 -303.97577) (xy 181.593998 -303.975262) (xy 181.593998 -303.974754)
			(xy 181.594508 -303.948767) (xy 181.602638 -303.897432) (xy 181.618699 -303.848002) (xy 181.642295 -303.801692)
			(xy 181.672845 -303.759644) (xy 181.709596 -303.722893) (xy 181.751644 -303.692343) (xy 181.797954 -303.668747)
			(xy 181.847384 -303.652686) (xy 181.898719 -303.644556) (xy 181.950693 -303.644556) (xy 182.002028 -303.652686)
			(xy 182.051458 -303.668747) (xy 182.097768 -303.692343) (xy 182.139816 -303.722893) (xy 182.176567 -303.759644)
			(xy 182.207117 -303.801692) (xy 182.230713 -303.848002) (xy 182.246774 -303.897432) (xy 182.254904 -303.948767)
			(xy 182.255414 -303.974754) (xy 182.255414 -303.975008) (xy 182.254965 -303.999813) (xy 182.247554 -304.048868)
			(xy 182.232914 -304.096269) (xy 182.211373 -304.140959) (xy 182.197756 -304.161698) (xy 182.195216 -304.165254)
			(xy 182.193692 -304.168048) (xy 182.193692 -304.168556) (xy 182.189359 -304.179057) (xy 182.189359 -304.201743)
			(xy 182.193692 -304.212244) (xy 182.224934 -304.270664) (xy 182.224934 -304.271172) (xy 182.23484 -304.289714)
			(xy 182.238904 -304.297334) (xy 182.241701 -304.301449) (xy 182.248616 -304.308603) (xy 182.25262 -304.311558)
			(xy 182.254652 -304.312828) (xy 182.313072 -304.312828) (xy 182.326026 -304.311304) (xy 182.332376 -304.309526)
			(xy 182.332376 -304.303684) (xy 182.555642 -304.303684) (xy 182.5625 -304.294032) (xy 182.579772 -304.261012)
			(xy 182.606696 -304.210212) (xy 182.610793 -304.198874) (xy 182.609088 -304.174862) (xy 182.603394 -304.164238)
			(xy 182.601362 -304.16119) (xy 182.598314 -304.156618) (xy 182.597806 -304.15611) (xy 182.585106 -304.135899)
			(xy 182.565018 -304.092599) (xy 182.551363 -304.046861) (xy 182.544421 -303.999636) (xy 182.543958 -303.97577)
			(xy 182.543958 -303.975262) (xy 182.543958 -303.974754) (xy 182.544468 -303.948767) (xy 182.552598 -303.897432)
			(xy 182.568659 -303.848002) (xy 182.592255 -303.801692) (xy 182.622805 -303.759644) (xy 182.659556 -303.722893)
			(xy 182.701604 -303.692343) (xy 182.747914 -303.668747) (xy 182.797344 -303.652686) (xy 182.848679 -303.644556)
			(xy 182.900653 -303.644556) (xy 182.951988 -303.652686) (xy 183.001418 -303.668747) (xy 183.047728 -303.692343)
			(xy 183.089776 -303.722893) (xy 183.126527 -303.759644) (xy 183.157077 -303.801692) (xy 183.180673 -303.848002)
			(xy 183.196734 -303.897432) (xy 183.204864 -303.948767) (xy 183.205374 -303.974754) (xy 183.205374 -303.975008)
			(xy 183.204925 -303.999813) (xy 183.197513 -304.048867) (xy 183.182872 -304.096268) (xy 183.161328 -304.140956)
			(xy 183.147716 -304.161698) (xy 183.145176 -304.165254) (xy 183.143652 -304.168048) (xy 183.143652 -304.168556)
			(xy 183.139321 -304.179057) (xy 183.139321 -304.201743) (xy 183.143652 -304.212244) (xy 183.174894 -304.270664)
			(xy 183.174894 -304.271172) (xy 183.1848 -304.289714) (xy 183.188864 -304.297334) (xy 183.19166 -304.301451)
			(xy 183.198571 -304.308609) (xy 183.20258 -304.311558) (xy 183.204612 -304.312828) (xy 183.263032 -304.312828)
			(xy 183.275986 -304.311304) (xy 183.282336 -304.309526) (xy 183.282336 -304.303684) (xy 183.505602 -304.303684)
			(xy 183.51246 -304.294032) (xy 183.529732 -304.261012) (xy 183.556656 -304.210212) (xy 183.560754 -304.198874)
			(xy 183.559048 -304.174862) (xy 183.553354 -304.164238) (xy 183.551322 -304.16119) (xy 183.548274 -304.156618)
			(xy 183.547766 -304.15611) (xy 183.535067 -304.135899) (xy 183.514982 -304.092598) (xy 183.501328 -304.04686)
			(xy 183.494388 -303.999635) (xy 183.493918 -303.97577) (xy 183.493918 -303.975262) (xy 183.493918 -303.974754)
			(xy 183.494428 -303.948767) (xy 183.502558 -303.897432) (xy 183.518619 -303.848002) (xy 183.542215 -303.801692)
			(xy 183.572765 -303.759644) (xy 183.609516 -303.722893) (xy 183.651564 -303.692343) (xy 183.697874 -303.668747)
			(xy 183.747304 -303.652686) (xy 183.798639 -303.644556) (xy 183.850613 -303.644556) (xy 183.901948 -303.652686)
			(xy 183.951378 -303.668747) (xy 183.997688 -303.692343) (xy 184.039736 -303.722893) (xy 184.076487 -303.759644)
			(xy 184.107037 -303.801692) (xy 184.130633 -303.848002) (xy 184.146694 -303.897432) (xy 184.154824 -303.948767)
			(xy 184.155334 -303.974754) (xy 184.155334 -303.975008) (xy 184.154885 -303.999813) (xy 184.147475 -304.048868)
			(xy 184.132836 -304.09627) (xy 184.111295 -304.140961) (xy 184.097676 -304.161698) (xy 184.095136 -304.165254)
			(xy 184.093612 -304.168048) (xy 184.093612 -304.168556) (xy 184.089278 -304.179057) (xy 184.089278 -304.201743)
			(xy 184.093612 -304.212244) (xy 184.124854 -304.270664) (xy 184.124854 -304.271172) (xy 184.13476 -304.289714)
			(xy 184.138824 -304.297334) (xy 184.141618 -304.301453) (xy 184.148527 -304.308615) (xy 184.15254 -304.311558)
			(xy 184.154572 -304.312828) (xy 184.212992 -304.312828) (xy 184.225946 -304.311304) (xy 184.232296 -304.309526)
			(xy 184.232296 -304.303684) (xy 184.359804 -304.303684) (xy 184.366986 -304.303438) (xy 184.380782 -304.299443)
			(xy 184.386982 -304.29581) (xy 184.406032 -304.284634) (xy 184.412636 -304.281078) (xy 184.489852 -304.203862)
			(xy 184.495948 -304.196496) (xy 184.499429 -304.191089) (xy 184.503808 -304.179003) (xy 184.504584 -304.17262)
			(xy 184.505346 -304.163222) (xy 184.500774 -304.14722) (xy 184.497218 -304.141378) (xy 184.485809 -304.121921)
			(xy 184.467792 -304.080571) (xy 184.455567 -304.037155) (xy 184.449361 -303.99248) (xy 184.448958 -303.969928)
			(xy 184.449464 -303.943951) (xy 184.457583 -303.892636) (xy 184.473626 -303.843221) (xy 184.497198 -303.796922)
			(xy 184.527719 -303.754879) (xy 184.564438 -303.718124) (xy 184.606452 -303.687563) (xy 184.652728 -303.663947)
			(xy 184.702128 -303.647857) (xy 184.753436 -303.639689) (xy 184.779412 -303.63922) (xy 184.77992 -303.63922)
			(xy 184.805574 -303.639982) (xy 184.809384 -303.640236) (xy 184.818334 -303.639839) (xy 184.835113 -303.633589)
			(xy 184.84215 -303.628044) (xy 184.876948 -303.59604) (xy 184.898284 -303.576228) (xy 184.905627 -303.56876)
			(xy 184.914039 -303.549604) (xy 184.91454 -303.539144) (xy 184.91454 -303.455324) (xy 184.914044 -303.445512)
			(xy 184.906606 -303.427345) (xy 184.900062 -303.420018) (xy 184.842658 -303.367186) (xy 184.838734 -303.363733)
			(xy 184.829769 -303.358363) (xy 184.824878 -303.356518) (xy 184.814972 -303.353216) (xy 184.80405 -303.354232)
			(xy 184.774586 -303.355502) (xy 184.7486 -303.354991) (xy 184.697268 -303.346859) (xy 184.64784 -303.330797)
			(xy 184.601534 -303.307201) (xy 184.559488 -303.276652) (xy 184.522739 -303.239901) (xy 184.492192 -303.197854)
			(xy 184.468597 -303.151547) (xy 184.452537 -303.102118) (xy 184.444407 -303.050786) (xy 184.444407 -302.998814)
			(xy 184.452537 -302.947482) (xy 184.468597 -302.898053) (xy 184.492192 -302.851746) (xy 184.522739 -302.809699)
			(xy 184.559488 -302.772948) (xy 184.601534 -302.742399) (xy 184.64784 -302.718803) (xy 184.697268 -302.702741)
			(xy 184.7486 -302.694609) (xy 184.774586 -302.694086) (xy 184.80405 -302.695356) (xy 184.814972 -302.696372)
			(xy 184.824878 -302.69307) (xy 184.829766 -302.691222) (xy 184.838721 -302.685839) (xy 184.842658 -302.682402)
			(xy 184.89803 -302.631602) (xy 184.905469 -302.624106) (xy 184.913993 -302.604811) (xy 184.91454 -302.594264)
			(xy 184.91454 -302.505364) (xy 184.914033 -302.495556) (xy 184.90658 -302.477405) (xy 184.900062 -302.470058)
			(xy 184.842658 -302.417226) (xy 184.838735 -302.413771) (xy 184.829772 -302.408396) (xy 184.824878 -302.406558)
			(xy 184.814972 -302.403256) (xy 184.80405 -302.404272) (xy 184.774586 -302.405542) (xy 184.748597 -302.405031)
			(xy 184.697259 -302.396898) (xy 184.647825 -302.380834) (xy 184.601513 -302.357235) (xy 184.559462 -302.326682)
			(xy 184.522709 -302.289927) (xy 184.492157 -302.247875) (xy 184.46856 -302.201562) (xy 184.452499 -302.152128)
			(xy 184.444368 -302.100789) (xy 184.444368 -302.048811) (xy 184.452499 -301.997472) (xy 184.46856 -301.948038)
			(xy 184.492157 -301.901725) (xy 184.522709 -301.859673) (xy 184.559462 -301.822918) (xy 184.601513 -301.792365)
			(xy 184.647825 -301.768766) (xy 184.697259 -301.752702) (xy 184.748597 -301.744569) (xy 184.774586 -301.744126)
			(xy 184.80405 -301.745396) (xy 184.814972 -301.746412) (xy 184.824878 -301.74311) (xy 184.829767 -301.741263)
			(xy 184.838725 -301.735884) (xy 184.842658 -301.732442) (xy 184.89803 -301.681642) (xy 184.905475 -301.674148)
			(xy 184.914015 -301.654854) (xy 184.91454 -301.644304) (xy 184.91454 -301.555404) (xy 184.91404 -301.545593)
			(xy 184.906597 -301.527432) (xy 184.900062 -301.520098) (xy 184.842658 -301.467266) (xy 184.838733 -301.463815)
			(xy 184.829768 -301.458446) (xy 184.824878 -301.456598) (xy 184.814972 -301.453296) (xy 184.80405 -301.454312)
			(xy 184.774586 -301.455582) (xy 184.748602 -301.455071) (xy 184.697273 -301.44694) (xy 184.647848 -301.430879)
			(xy 184.601544 -301.407284) (xy 184.559501 -301.376737) (xy 184.522754 -301.339988) (xy 184.492209 -301.297944)
			(xy 184.468616 -301.251639) (xy 184.452557 -301.202214) (xy 184.444427 -301.150884) (xy 184.444427 -301.098916)
			(xy 184.452557 -301.047586) (xy 184.468616 -300.998161) (xy 184.492209 -300.951856) (xy 184.522754 -300.909812)
			(xy 184.559501 -300.873063) (xy 184.601544 -300.842516) (xy 184.647848 -300.818921) (xy 184.697273 -300.80286)
			(xy 184.748602 -300.794729) (xy 184.774586 -300.794166) (xy 184.80405 -300.795436) (xy 184.814972 -300.796452)
			(xy 184.824878 -300.79315) (xy 184.829765 -300.791301) (xy 184.838719 -300.785917) (xy 184.842658 -300.782482)
			(xy 184.89803 -300.731682) (xy 184.905466 -300.724185) (xy 184.913982 -300.70489) (xy 184.91454 -300.694344)
			(xy 184.91454 -300.605444) (xy 184.914047 -300.59563) (xy 184.906615 -300.577459) (xy 184.900062 -300.570138)
			(xy 184.842658 -300.517306) (xy 184.838734 -300.513852) (xy 184.82977 -300.50848) (xy 184.824878 -300.506638)
			(xy 184.814972 -300.503336) (xy 184.80405 -300.504352) (xy 184.774586 -300.505622) (xy 184.748598 -300.505111)
			(xy 184.697263 -300.496979) (xy 184.647833 -300.480916) (xy 184.601523 -300.457318) (xy 184.559475 -300.426767)
			(xy 184.522724 -300.390014) (xy 184.492174 -300.347965) (xy 184.468579 -300.301654) (xy 184.452518 -300.252223)
			(xy 184.444388 -300.200888) (xy 184.444388 -300.148912) (xy 184.452518 -300.097577) (xy 184.468579 -300.048146)
			(xy 184.492174 -300.001835) (xy 184.522724 -299.959786) (xy 184.559475 -299.923033) (xy 184.601523 -299.892482)
			(xy 184.647833 -299.868884) (xy 184.697263 -299.852821) (xy 184.748598 -299.844689) (xy 184.774586 -299.844206)
			(xy 184.80405 -299.845476) (xy 184.814972 -299.846492) (xy 184.824878 -299.84319) (xy 184.829766 -299.841342)
			(xy 184.838723 -299.835961) (xy 184.842658 -299.832522) (xy 184.89803 -299.781722) (xy 184.905472 -299.774227)
			(xy 184.914004 -299.754933) (xy 184.91454 -299.744384) (xy 184.91454 -299.655484) (xy 184.914037 -299.645675)
			(xy 184.906589 -299.627519) (xy 184.900062 -299.620178) (xy 184.842658 -299.567346) (xy 184.838736 -299.56389)
			(xy 184.829773 -299.558513) (xy 184.824878 -299.556678) (xy 184.814972 -299.553376) (xy 184.80405 -299.554392)
			(xy 184.774586 -299.555662) (xy 184.748603 -299.555151) (xy 184.697278 -299.54702) (xy 184.647856 -299.53096)
			(xy 184.601555 -299.507367) (xy 184.559514 -299.476821) (xy 184.52277 -299.440075) (xy 184.492226 -299.398033)
			(xy 184.468635 -299.351731) (xy 184.452577 -299.302309) (xy 184.444448 -299.250983) (xy 184.444448 -299.199017)
			(xy 184.452577 -299.147691) (xy 184.468635 -299.098269) (xy 184.492226 -299.051967) (xy 184.52277 -299.009925)
			(xy 184.559514 -298.973179) (xy 184.601555 -298.942633) (xy 184.647856 -298.91904) (xy 184.697278 -298.90298)
			(xy 184.748603 -298.894849) (xy 184.774586 -298.894246) (xy 184.80405 -298.895516) (xy 184.814972 -298.896532)
			(xy 184.824878 -298.89323) (xy 184.829767 -298.891384) (xy 184.838727 -298.886006) (xy 184.842658 -298.882562)
			(xy 184.89803 -298.831762) (xy 184.905463 -298.824264) (xy 184.913972 -298.804969) (xy 184.91454 -298.794424)
			(xy 184.91454 -298.70527) (xy 184.914034 -298.695462) (xy 184.906583 -298.677309) (xy 184.900062 -298.669964)
			(xy 184.842658 -298.617132) (xy 184.838735 -298.613677) (xy 184.829772 -298.608301) (xy 184.824878 -298.606464)
			(xy 184.814972 -298.603162) (xy 184.80405 -298.604178) (xy 184.774586 -298.605448) (xy 184.748596 -298.604937)
			(xy 184.697257 -298.596804) (xy 184.647823 -298.58074) (xy 184.60151 -298.55714) (xy 184.559458 -298.526587)
			(xy 184.522704 -298.489831) (xy 184.492152 -298.447778) (xy 184.468555 -298.401464) (xy 184.452493 -298.352029)
			(xy 184.444362 -298.30069) (xy 184.444362 -298.24871) (xy 184.452493 -298.197371) (xy 184.468555 -298.147936)
			(xy 184.492152 -298.101622) (xy 184.522704 -298.059569) (xy 184.559458 -298.022813) (xy 184.60151 -297.99226)
			(xy 184.647823 -297.96866) (xy 184.697257 -297.952596) (xy 184.748596 -297.944463) (xy 184.774586 -297.944032)
			(xy 184.80405 -297.945302) (xy 184.814972 -297.946318) (xy 184.824878 -297.943016) (xy 184.829767 -297.94117)
			(xy 184.838726 -297.935791) (xy 184.842658 -297.932348) (xy 184.89803 -297.881548) (xy 184.905476 -297.874055)
			(xy 184.914018 -297.85476) (xy 184.91454 -297.84421) (xy 184.91454 -297.75531) (xy 184.914041 -297.745499)
			(xy 184.9066 -297.727336) (xy 184.900062 -297.720004) (xy 184.842658 -297.667172) (xy 184.838733 -297.66372)
			(xy 184.829768 -297.658351) (xy 184.824878 -297.656504) (xy 184.814972 -297.653202) (xy 184.80405 -297.654218)
			(xy 184.774586 -297.655488) (xy 184.748601 -297.654977) (xy 184.697271 -297.646846) (xy 184.647846 -297.630784)
			(xy 184.601541 -297.607189) (xy 184.559497 -297.576641) (xy 184.52275 -297.539892) (xy 184.492203 -297.497847)
			(xy 184.46861 -297.451541) (xy 184.452551 -297.402115) (xy 184.444421 -297.350785) (xy 184.444421 -297.298815)
			(xy 184.452551 -297.247485) (xy 184.46861 -297.198059) (xy 184.492203 -297.151753) (xy 184.52275 -297.109708)
			(xy 184.559497 -297.072959) (xy 184.601541 -297.042411) (xy 184.647846 -297.018816) (xy 184.697271 -297.002754)
			(xy 184.748601 -296.994623) (xy 184.774586 -296.994072) (xy 184.80405 -296.995342) (xy 184.814972 -296.996358)
			(xy 184.824878 -296.993056) (xy 184.829766 -296.991207) (xy 184.83872 -296.985824) (xy 184.842658 -296.982388)
			(xy 184.89803 -296.931588) (xy 184.905467 -296.924091) (xy 184.913985 -296.904796) (xy 184.91454 -296.89425)
			(xy 184.91454 -296.80535) (xy 184.914048 -296.795536) (xy 184.906617 -296.777363) (xy 184.900062 -296.770044)
			(xy 184.842658 -296.717212) (xy 184.838735 -296.713758) (xy 184.829771 -296.708385) (xy 184.824878 -296.706544)
			(xy 184.814972 -296.703242) (xy 184.80405 -296.704258) (xy 184.774586 -296.705528) (xy 184.748598 -296.705017)
			(xy 184.697262 -296.696885) (xy 184.64783 -296.680821) (xy 184.60152 -296.657223) (xy 184.559471 -296.626671)
			(xy 184.522719 -296.589918) (xy 184.492169 -296.547868) (xy 184.468573 -296.501557) (xy 184.452512 -296.452124)
			(xy 184.444382 -296.400788) (xy 184.444382 -296.348812) (xy 184.452512 -296.297476) (xy 184.468573 -296.248043)
			(xy 184.492169 -296.201732) (xy 184.522719 -296.159682) (xy 184.559471 -296.122929) (xy 184.60152 -296.092377)
			(xy 184.64783 -296.068779) (xy 184.697262 -296.052715) (xy 184.748598 -296.044583) (xy 184.774586 -296.044112)
			(xy 184.80405 -296.045382) (xy 184.814972 -296.046398) (xy 184.824878 -296.043096) (xy 184.829767 -296.041249)
			(xy 184.838724 -296.035868) (xy 184.842658 -296.032428) (xy 184.89803 -295.981628) (xy 184.905473 -295.974134)
			(xy 184.914007 -295.954839) (xy 184.91454 -295.94429) (xy 184.91454 -294.90543) (xy 184.914045 -294.895617)
			(xy 184.906608 -294.877449) (xy 184.900062 -294.870124) (xy 184.842658 -294.817292) (xy 184.838734 -294.813839)
			(xy 184.829769 -294.808468) (xy 184.824878 -294.806624) (xy 184.814972 -294.803322) (xy 184.80405 -294.804338)
			(xy 184.774586 -294.805608) (xy 184.7486 -294.805097) (xy 184.697267 -294.796965) (xy 184.647838 -294.780903)
			(xy 184.601531 -294.757306) (xy 184.559484 -294.726756) (xy 184.522735 -294.690005) (xy 184.492186 -294.647958)
			(xy 184.468592 -294.601649) (xy 184.452532 -294.55222) (xy 184.444401 -294.500886) (xy 184.444401 -294.448914)
			(xy 184.452532 -294.39758) (xy 184.468592 -294.348151) (xy 184.492186 -294.301842) (xy 184.522735 -294.259795)
			(xy 184.559484 -294.223044) (xy 184.601531 -294.192494) (xy 184.647838 -294.168897) (xy 184.697267 -294.152835)
			(xy 184.7486 -294.144703) (xy 184.774586 -294.144192) (xy 184.80405 -294.145462) (xy 184.814972 -294.146478)
			(xy 184.824878 -294.143176) (xy 184.829766 -294.141328) (xy 184.838722 -294.135946) (xy 184.842658 -294.132508)
			(xy 184.89803 -294.081708) (xy 184.90547 -294.074213) (xy 184.913997 -294.054918) (xy 184.91454 -294.04437)
			(xy 184.91454 -293.95547) (xy 184.914034 -293.945662) (xy 184.906583 -293.927509) (xy 184.900062 -293.920164)
			(xy 184.842658 -293.867332) (xy 184.838735 -293.863877) (xy 184.829772 -293.858501) (xy 184.824878 -293.856664)
			(xy 184.814972 -293.853362) (xy 184.80405 -293.854378) (xy 184.774586 -293.855648) (xy 184.748596 -293.855137)
			(xy 184.697257 -293.847004) (xy 184.647823 -293.83094) (xy 184.60151 -293.80734) (xy 184.559458 -293.776787)
			(xy 184.522704 -293.740031) (xy 184.492152 -293.697978) (xy 184.468555 -293.651664) (xy 184.452493 -293.602229)
			(xy 184.444362 -293.55089) (xy 184.444362 -293.49891) (xy 184.452493 -293.447571) (xy 184.468555 -293.398136)
			(xy 184.492152 -293.351822) (xy 184.522704 -293.309769) (xy 184.559458 -293.273013) (xy 184.60151 -293.24246)
			(xy 184.647823 -293.21886) (xy 184.697257 -293.202796) (xy 184.748596 -293.194663) (xy 184.774586 -293.194232)
			(xy 184.80405 -293.195502) (xy 184.814972 -293.196518) (xy 184.824878 -293.193216) (xy 184.829767 -293.19137)
			(xy 184.838726 -293.185991) (xy 184.842658 -293.182548) (xy 184.89803 -293.131748) (xy 184.905476 -293.124255)
			(xy 184.914018 -293.10496) (xy 184.91454 -293.09441) (xy 184.91454 -293.005256) (xy 184.914032 -292.995449)
			(xy 184.906577 -292.9773) (xy 184.900062 -292.96995) (xy 184.842658 -292.917118) (xy 184.838735 -292.913664)
			(xy 184.829771 -292.90829) (xy 184.824878 -292.90645) (xy 184.814972 -292.903148) (xy 184.80405 -292.904164)
			(xy 184.774586 -292.905434) (xy 184.748597 -292.904923) (xy 184.697261 -292.89679) (xy 184.647828 -292.880727)
			(xy 184.601517 -292.857128) (xy 184.559467 -292.826576) (xy 184.522715 -292.789822) (xy 184.492164 -292.747771)
			(xy 184.468568 -292.701459) (xy 184.452506 -292.652026) (xy 184.444376 -292.600689) (xy 184.444376 -292.548711)
			(xy 184.452506 -292.497374) (xy 184.468568 -292.447941) (xy 184.492164 -292.401629) (xy 184.522715 -292.359578)
			(xy 184.559467 -292.322824) (xy 184.601517 -292.292272) (xy 184.647828 -292.268673) (xy 184.697261 -292.25261)
			(xy 184.748597 -292.244477) (xy 184.774586 -292.244018) (xy 184.80405 -292.245288) (xy 184.814972 -292.246304)
			(xy 184.824878 -292.243002) (xy 184.829767 -292.241155) (xy 184.838724 -292.235775) (xy 184.842658 -292.232334)
			(xy 184.89803 -292.181534) (xy 184.905474 -292.17404) (xy 184.91401 -292.154745) (xy 184.91454 -292.144196)
			(xy 184.91454 -292.055296) (xy 184.914039 -292.045486) (xy 184.906594 -292.027327) (xy 184.900062 -292.01999)
			(xy 184.842658 -291.967158) (xy 184.838733 -291.963707) (xy 184.829767 -291.958339) (xy 184.824878 -291.95649)
			(xy 184.814972 -291.953188) (xy 184.80405 -291.954204) (xy 184.774586 -291.955474) (xy 184.748602 -291.954964)
			(xy 184.697275 -291.946832) (xy 184.647851 -291.930771) (xy 184.601548 -291.907177) (xy 184.559506 -291.87663)
			(xy 184.52276 -291.839883) (xy 184.492215 -291.79784) (xy 184.468623 -291.751536) (xy 184.452565 -291.702112)
			(xy 184.444435 -291.650784) (xy 184.444435 -291.598816) (xy 184.452565 -291.547488) (xy 184.468623 -291.498064)
			(xy 184.492215 -291.45176) (xy 184.52276 -291.409717) (xy 184.559506 -291.37297) (xy 184.601548 -291.342423)
			(xy 184.647851 -291.318829) (xy 184.697275 -291.302768) (xy 184.748602 -291.294636) (xy 184.774586 -291.294058)
			(xy 184.80405 -291.295328) (xy 184.814972 -291.296344) (xy 184.824878 -291.293042) (xy 184.829765 -291.291193)
			(xy 184.838719 -291.285808) (xy 184.842658 -291.282374) (xy 184.89803 -291.231574) (xy 184.905465 -291.224077)
			(xy 184.913978 -291.204782) (xy 184.91454 -291.194236) (xy 184.91454 -291.105336) (xy 184.914046 -291.095523)
			(xy 184.906611 -291.077353) (xy 184.900062 -291.07003) (xy 184.842658 -291.017198) (xy 184.838734 -291.013745)
			(xy 184.82977 -291.008373) (xy 184.824878 -291.00653) (xy 184.814972 -291.003228) (xy 184.80405 -291.004244)
			(xy 184.774586 -291.005514) (xy 184.748599 -291.005003) (xy 184.697265 -290.996871) (xy 184.647836 -290.980808)
			(xy 184.601527 -290.957211) (xy 184.55948 -290.926661) (xy 184.52273 -290.889909) (xy 184.492181 -290.847861)
			(xy 184.468586 -290.801551) (xy 184.452526 -290.752121) (xy 184.444396 -290.700787) (xy 184.444396 -290.648813)
			(xy 184.452526 -290.597479) (xy 184.468586 -290.548049) (xy 184.492181 -290.501739) (xy 184.52273 -290.459691)
			(xy 184.55948 -290.422939) (xy 184.601527 -290.392389) (xy 184.647836 -290.368792) (xy 184.697265 -290.352729)
			(xy 184.748599 -290.344597) (xy 184.774586 -290.344098) (xy 184.80405 -290.345368) (xy 184.814972 -290.346384)
			(xy 184.824878 -290.343082) (xy 184.829766 -290.341234) (xy 184.838722 -290.335853) (xy 184.842658 -290.332414)
			(xy 184.89803 -290.281614) (xy 184.905471 -290.274119) (xy 184.914 -290.254824) (xy 184.91454 -290.244276)
			(xy 184.91454 -290.155376) (xy 184.914035 -290.145567) (xy 184.906585 -290.127413) (xy 184.900062 -290.12007)
			(xy 184.842658 -290.067238) (xy 184.838736 -290.063782) (xy 184.829772 -290.058406) (xy 184.824878 -290.05657)
			(xy 184.814972 -290.053268) (xy 184.80405 -290.054284) (xy 184.774586 -290.055554) (xy 184.748596 -290.055043)
			(xy 184.697256 -290.04691) (xy 184.64782 -290.030845) (xy 184.601506 -290.007246) (xy 184.559454 -289.976691)
			(xy 184.5227 -289.939935) (xy 184.492147 -289.897882) (xy 184.468549 -289.851567) (xy 184.452487 -289.80213)
			(xy 184.444356 -289.75079) (xy 184.444356 -289.69881) (xy 184.452487 -289.64747) (xy 184.468549 -289.598033)
			(xy 184.492147 -289.551718) (xy 184.5227 -289.509665) (xy 184.559454 -289.472909) (xy 184.601506 -289.442354)
			(xy 184.64782 -289.418755) (xy 184.697256 -289.40269) (xy 184.748596 -289.394557) (xy 184.774586 -289.394138)
			(xy 184.80405 -289.395408) (xy 184.814972 -289.396424) (xy 184.824878 -289.393122) (xy 184.829767 -289.391276)
			(xy 184.838726 -289.385897) (xy 184.842658 -289.382454) (xy 184.89803 -289.331654) (xy 184.905477 -289.324161)
			(xy 184.914021 -289.304867) (xy 184.91454 -289.294316) (xy 184.91454 -289.205416) (xy 184.914042 -289.195604)
			(xy 184.906602 -289.17744) (xy 184.900062 -289.17011) (xy 184.842658 -289.117278) (xy 184.838733 -289.113826)
			(xy 184.829768 -289.108456) (xy 184.824878 -289.10661) (xy 184.814972 -289.103308) (xy 184.80405 -289.104324)
			(xy 184.774586 -289.105594) (xy 184.748601 -289.105083) (xy 184.69727 -289.096951) (xy 184.647843 -289.08089)
			(xy 184.601538 -289.057294) (xy 184.559493 -289.026746) (xy 184.522745 -288.989996) (xy 184.492198 -288.94795)
			(xy 184.468605 -288.901644) (xy 184.452545 -288.852216) (xy 184.444415 -288.800885) (xy 184.444415 -288.748915)
			(xy 184.452545 -288.697584) (xy 184.468605 -288.648156) (xy 184.492198 -288.60185) (xy 184.522745 -288.559804)
			(xy 184.559493 -288.523054) (xy 184.601538 -288.492506) (xy 184.647843 -288.46891) (xy 184.69727 -288.452849)
			(xy 184.748601 -288.444717) (xy 184.774586 -288.444178) (xy 184.80405 -288.445448) (xy 184.814972 -288.446464)
			(xy 184.824878 -288.443162) (xy 184.829766 -288.441313) (xy 184.838721 -288.43593) (xy 184.842658 -288.432494)
			(xy 184.89803 -288.381694) (xy 184.905468 -288.374198) (xy 184.913989 -288.354903) (xy 184.91454 -288.344356)
			(xy 184.91454 -288.255456) (xy 184.914032 -288.245649) (xy 184.906577 -288.2275) (xy 184.900062 -288.22015)
			(xy 184.842658 -288.167318) (xy 184.838735 -288.163864) (xy 184.829771 -288.15849) (xy 184.824878 -288.15665)
			(xy 184.814972 -288.153348) (xy 184.80405 -288.154364) (xy 184.774586 -288.155634) (xy 184.748599 -288.155123)
			(xy 184.697264 -288.146991) (xy 184.647834 -288.130929) (xy 184.601525 -288.107333) (xy 184.559476 -288.076784)
			(xy 184.522724 -288.040033) (xy 184.492173 -287.997986) (xy 184.468575 -287.951677) (xy 184.452512 -287.902247)
			(xy 184.444378 -287.850913) (xy 184.443878 -287.824926) (xy 184.444375 -287.799073) (xy 184.452415 -287.747996)
			(xy 184.468304 -287.698792) (xy 184.491655 -287.652658) (xy 184.521898 -287.61072) (xy 184.558298 -287.573997)
			(xy 184.599968 -287.543385) (xy 184.622694 -287.531048) (xy 184.629806 -287.527492) (xy 184.637172 -287.520126)
			(xy 184.643363 -287.512637) (xy 184.650107 -287.494431) (xy 184.649618 -287.475023) (xy 184.641964 -287.45718)
			(xy 184.635394 -287.450022) (xy 184.619138 -287.433766) (xy 184.615405 -287.430249) (xy 184.606827 -287.424629)
			(xy 184.60212 -287.42259) (xy 184.593484 -287.419034) (xy 184.517538 -287.419034) (xy 184.513982 -287.421828)
			(xy 184.4294 -287.433258) (xy 184.418466 -287.434617) (xy 184.396476 -287.436012) (xy 184.385458 -287.436052)
			(xy 184.093866 -287.436052) (xy 184.086246 -287.447228) (xy 184.04967 -287.534858) (xy 184.047384 -287.540446)
			(xy 184.045335 -287.547582) (xy 184.044959 -287.562419) (xy 184.046622 -287.569656) (xy 184.0484 -287.574736)
			(xy 184.05094 -287.580578) (xy 184.05221 -287.583626) (xy 184.052972 -287.585404) (xy 184.059576 -287.592262)
			(xy 184.05983 -287.592516) (xy 184.077613 -287.611199) (xy 184.107743 -287.653059) (xy 184.131001 -287.699094)
			(xy 184.146821 -287.748185) (xy 184.154818 -287.799138) (xy 184.155334 -287.824926) (xy 184.154824 -287.850913)
			(xy 184.146694 -287.902248) (xy 184.130633 -287.951678) (xy 184.107037 -287.997988) (xy 184.076487 -288.040036)
			(xy 184.039736 -288.076787) (xy 183.997688 -288.107337) (xy 183.951378 -288.130933) (xy 183.901948 -288.146994)
			(xy 183.850613 -288.155124) (xy 183.798639 -288.155124) (xy 183.747304 -288.146994) (xy 183.697874 -288.130933)
			(xy 183.651564 -288.107337) (xy 183.609516 -288.076787) (xy 183.572765 -288.040036) (xy 183.542215 -287.997988)
			(xy 183.518619 -287.951678) (xy 183.502558 -287.902248) (xy 183.494428 -287.850913) (xy 183.493918 -287.824926)
			(xy 183.494418 -287.799139) (xy 183.502439 -287.748193) (xy 183.518274 -287.699111) (xy 183.541539 -287.653083)
			(xy 183.571669 -287.611226) (xy 183.589422 -287.592516) (xy 183.589676 -287.592262) (xy 183.59628 -287.585404)
			(xy 183.597042 -287.583626) (xy 183.598312 -287.580578) (xy 183.600852 -287.574736) (xy 183.60263 -287.569656)
			(xy 183.604356 -287.562426) (xy 183.603967 -287.547576) (xy 183.601868 -287.540446) (xy 183.599582 -287.534858)
			(xy 183.563006 -287.447228) (xy 183.555386 -287.436052) (xy 183.143906 -287.436052) (xy 183.136286 -287.447228)
			(xy 183.09971 -287.534858) (xy 183.097424 -287.540446) (xy 183.095376 -287.547582) (xy 183.095001 -287.562419)
			(xy 183.096662 -287.569656) (xy 183.09844 -287.574736) (xy 183.10098 -287.580578) (xy 183.10225 -287.583626)
			(xy 183.103012 -287.585404) (xy 183.109616 -287.592262) (xy 183.10987 -287.592516) (xy 183.127656 -287.611198)
			(xy 183.157791 -287.653056) (xy 183.181053 -287.699091) (xy 183.196876 -287.748182) (xy 183.204875 -287.799137)
			(xy 183.205374 -287.824926) (xy 183.204864 -287.850913) (xy 183.196734 -287.902248) (xy 183.180673 -287.951678)
			(xy 183.157077 -287.997988) (xy 183.126527 -288.040036) (xy 183.089776 -288.076787) (xy 183.047728 -288.107337)
			(xy 183.001418 -288.130933) (xy 182.951988 -288.146994) (xy 182.900653 -288.155124) (xy 182.848679 -288.155124)
			(xy 182.797344 -288.146994) (xy 182.747914 -288.130933) (xy 182.701604 -288.107337) (xy 182.659556 -288.076787)
			(xy 182.622805 -288.040036) (xy 182.592255 -287.997988) (xy 182.568659 -287.951678) (xy 182.552598 -287.902248)
			(xy 182.544468 -287.850913) (xy 182.543958 -287.824926) (xy 182.544458 -287.799139) (xy 182.552478 -287.748192)
			(xy 182.56831 -287.699108) (xy 182.591572 -287.653077) (xy 182.621699 -287.611217) (xy 182.639462 -287.592516)
			(xy 182.639716 -287.592262) (xy 182.64632 -287.585404) (xy 182.647082 -287.583626) (xy 182.648352 -287.580578)
			(xy 182.650892 -287.574736) (xy 182.65267 -287.569656) (xy 182.654395 -287.562426) (xy 182.654007 -287.547576)
			(xy 182.651908 -287.540446) (xy 182.649622 -287.534858) (xy 182.613046 -287.447228) (xy 182.605426 -287.436052)
			(xy 182.193946 -287.436052) (xy 182.186326 -287.447228) (xy 182.14975 -287.534858) (xy 182.147464 -287.540446)
			(xy 182.145415 -287.547582) (xy 182.14504 -287.562419) (xy 182.146702 -287.569656) (xy 182.14848 -287.574736)
			(xy 182.15102 -287.580578) (xy 182.15229 -287.583626) (xy 182.153052 -287.585404) (xy 182.159656 -287.592262)
			(xy 182.15991 -287.592516) (xy 182.177694 -287.611199) (xy 182.207826 -287.653058) (xy 182.231085 -287.699093)
			(xy 182.246906 -287.748184) (xy 182.254904 -287.799137) (xy 182.255414 -287.824926) (xy 182.254904 -287.850913)
			(xy 182.246774 -287.902248) (xy 182.230713 -287.951678) (xy 182.207117 -287.997988) (xy 182.176567 -288.040036)
			(xy 182.139816 -288.076787) (xy 182.097768 -288.107337) (xy 182.051458 -288.130933) (xy 182.002028 -288.146994)
			(xy 181.950693 -288.155124) (xy 181.898719 -288.155124) (xy 181.847384 -288.146994) (xy 181.797954 -288.130933)
			(xy 181.751644 -288.107337) (xy 181.709596 -288.076787) (xy 181.672845 -288.040036) (xy 181.642295 -287.997988)
			(xy 181.618699 -287.951678) (xy 181.602638 -287.902248) (xy 181.594508 -287.850913) (xy 181.593998 -287.824926)
			(xy 181.594498 -287.799139) (xy 181.602519 -287.748193) (xy 181.618353 -287.69911) (xy 181.641616 -287.653081)
			(xy 181.671746 -287.611223) (xy 181.689502 -287.592516) (xy 181.689756 -287.592262) (xy 181.69636 -287.585404)
			(xy 181.697122 -287.583626) (xy 181.698392 -287.580578) (xy 181.700932 -287.574736) (xy 181.70271 -287.569656)
			(xy 181.704434 -287.562426) (xy 181.704046 -287.547576) (xy 181.701948 -287.540446) (xy 181.699662 -287.534858)
			(xy 181.663086 -287.447228) (xy 181.655466 -287.436052) (xy 181.243986 -287.436052) (xy 181.236366 -287.447228)
			(xy 181.19979 -287.534858) (xy 181.197504 -287.540446) (xy 181.195454 -287.547582) (xy 181.195078 -287.562419)
			(xy 181.196742 -287.569656) (xy 181.19852 -287.574736) (xy 181.20106 -287.580578) (xy 181.20233 -287.583626)
			(xy 181.203092 -287.585404) (xy 181.209696 -287.592262) (xy 181.20995 -287.592516) (xy 181.227732 -287.6112)
			(xy 181.25786 -287.653061) (xy 181.281117 -287.699095) (xy 181.296936 -287.748186) (xy 181.304932 -287.799138)
			(xy 181.305454 -287.824926) (xy 181.304944 -287.850913) (xy 181.296814 -287.902248) (xy 181.280753 -287.951678)
			(xy 181.257157 -287.997988) (xy 181.226607 -288.040036) (xy 181.189856 -288.076787) (xy 181.147808 -288.107337)
			(xy 181.101498 -288.130933) (xy 181.052068 -288.146994) (xy 181.000733 -288.155124) (xy 180.948759 -288.155124)
			(xy 180.897424 -288.146994) (xy 180.847994 -288.130933) (xy 180.801684 -288.107337) (xy 180.759636 -288.076787)
			(xy 180.722885 -288.040036) (xy 180.692335 -287.997988) (xy 180.668739 -287.951678) (xy 180.652678 -287.902248)
			(xy 180.644548 -287.850913) (xy 180.644038 -287.824926) (xy 180.644538 -287.799139) (xy 180.652557 -287.748191)
			(xy 180.668389 -287.699107) (xy 180.69165 -287.653075) (xy 180.721775 -287.611213) (xy 180.739542 -287.592516)
			(xy 180.739796 -287.592262) (xy 180.7464 -287.585404) (xy 180.747162 -287.583626) (xy 180.748432 -287.580578)
			(xy 180.750972 -287.574736) (xy 180.75275 -287.569656) (xy 180.754475 -287.562426) (xy 180.754087 -287.547576)
			(xy 180.751988 -287.540446) (xy 180.749702 -287.534858) (xy 180.713126 -287.447228) (xy 180.705506 -287.436052)
			(xy 180.294026 -287.436052) (xy 180.286406 -287.447228) (xy 180.24983 -287.534858) (xy 180.247544 -287.540446)
			(xy 180.245496 -287.547582) (xy 180.245121 -287.562419) (xy 180.246782 -287.569656) (xy 180.24856 -287.574736)
			(xy 180.2511 -287.580578) (xy 180.25237 -287.583626) (xy 180.253132 -287.585404) (xy 180.259736 -287.592262)
			(xy 180.25999 -287.592516) (xy 180.277775 -287.611198) (xy 180.307909 -287.653057) (xy 180.331169 -287.699092)
			(xy 180.346991 -287.748183) (xy 180.354989 -287.799137) (xy 180.355494 -287.824926) (xy 180.354984 -287.850913)
			(xy 180.346854 -287.902248) (xy 180.330793 -287.951678) (xy 180.307197 -287.997988) (xy 180.276647 -288.040036)
			(xy 180.239896 -288.076787) (xy 180.197848 -288.107337) (xy 180.151538 -288.130933) (xy 180.102108 -288.146994)
			(xy 180.050773 -288.155124) (xy 179.998799 -288.155124) (xy 179.947464 -288.146994) (xy 179.898034 -288.130933)
			(xy 179.851724 -288.107337) (xy 179.809676 -288.076787) (xy 179.772925 -288.040036) (xy 179.742375 -287.997988)
			(xy 179.718779 -287.951678) (xy 179.702718 -287.902248) (xy 179.694588 -287.850913) (xy 179.694078 -287.824926)
			(xy 179.694578 -287.799139) (xy 179.702598 -287.748192) (xy 179.718431 -287.699109) (xy 179.741694 -287.653079)
			(xy 179.771822 -287.61122) (xy 179.789582 -287.592516) (xy 179.789836 -287.592262) (xy 179.79644 -287.585404)
			(xy 179.797202 -287.583626) (xy 179.798472 -287.580578) (xy 179.801012 -287.574736) (xy 179.80279 -287.569656)
			(xy 179.804515 -287.562426) (xy 179.804127 -287.547576) (xy 179.802028 -287.540446) (xy 179.799742 -287.534858)
			(xy 179.763166 -287.447228) (xy 179.755546 -287.436052) (xy 179.344066 -287.436052) (xy 179.336446 -287.447228)
			(xy 179.29987 -287.534858) (xy 179.297584 -287.540446) (xy 179.295535 -287.547582) (xy 179.295159 -287.562419)
			(xy 179.296822 -287.569656) (xy 179.2986 -287.574736) (xy 179.30114 -287.580578) (xy 179.30241 -287.583626)
			(xy 179.303172 -287.585404) (xy 179.309776 -287.592262) (xy 179.31003 -287.592516) (xy 179.327813 -287.611199)
			(xy 179.357943 -287.653059) (xy 179.381201 -287.699094) (xy 179.397021 -287.748185) (xy 179.405018 -287.799138)
			(xy 179.405534 -287.824926) (xy 179.405024 -287.850913) (xy 179.396894 -287.902248) (xy 179.380833 -287.951678)
			(xy 179.357237 -287.997988) (xy 179.326687 -288.040036) (xy 179.289936 -288.076787) (xy 179.247888 -288.107337)
			(xy 179.201578 -288.130933) (xy 179.152148 -288.146994) (xy 179.100813 -288.155124) (xy 179.048839 -288.155124)
			(xy 178.997504 -288.146994) (xy 178.948074 -288.130933) (xy 178.901764 -288.107337) (xy 178.859716 -288.076787)
			(xy 178.822965 -288.040036) (xy 178.792415 -287.997988) (xy 178.768819 -287.951678) (xy 178.752758 -287.902248)
			(xy 178.744628 -287.850913) (xy 178.744118 -287.824926) (xy 178.744618 -287.799139) (xy 178.752639 -287.748193)
			(xy 178.768474 -287.699111) (xy 178.791739 -287.653083) (xy 178.821869 -287.611226) (xy 178.839622 -287.592516)
			(xy 178.839876 -287.592262) (xy 178.84648 -287.585404) (xy 178.847242 -287.583626) (xy 178.848512 -287.580578)
			(xy 178.851052 -287.574736) (xy 178.85283 -287.569656) (xy 178.854556 -287.562426) (xy 178.854167 -287.547576)
			(xy 178.852068 -287.540446) (xy 178.849782 -287.534858) (xy 178.813206 -287.447228) (xy 178.805586 -287.436052)
			(xy 178.393852 -287.436052) (xy 178.386232 -287.447228) (xy 178.349656 -287.534858) (xy 178.34737 -287.540446)
			(xy 178.345321 -287.547582) (xy 178.344946 -287.562419) (xy 178.346608 -287.569656) (xy 178.348386 -287.574736)
			(xy 178.350926 -287.580578) (xy 178.352196 -287.583626) (xy 178.352958 -287.585404) (xy 178.359562 -287.592262)
			(xy 178.359816 -287.592516) (xy 178.377599 -287.611199) (xy 178.407731 -287.653059) (xy 178.43099 -287.699094)
			(xy 178.44681 -287.748184) (xy 178.454808 -287.799137) (xy 178.45532 -287.824926) (xy 178.45481 -287.850913)
			(xy 178.44668 -287.902248) (xy 178.430619 -287.951678) (xy 178.407023 -287.997988) (xy 178.376473 -288.040036)
			(xy 178.339722 -288.076787) (xy 178.297674 -288.107337) (xy 178.251364 -288.130933) (xy 178.201934 -288.146994)
			(xy 178.150599 -288.155124) (xy 178.098625 -288.155124) (xy 178.04729 -288.146994) (xy 177.99786 -288.130933)
			(xy 177.95155 -288.107337) (xy 177.909502 -288.076787) (xy 177.872751 -288.040036) (xy 177.842201 -287.997988)
			(xy 177.818605 -287.951678) (xy 177.802544 -287.902248) (xy 177.794414 -287.850913) (xy 177.793904 -287.824926)
			(xy 177.794404 -287.799139) (xy 177.802425 -287.748193) (xy 177.818259 -287.69911) (xy 177.841523 -287.653082)
			(xy 177.871653 -287.611224) (xy 177.889408 -287.592516) (xy 177.889662 -287.592262) (xy 177.896266 -287.585404)
			(xy 177.897028 -287.583626) (xy 177.898298 -287.580578) (xy 177.900838 -287.574736) (xy 177.902616 -287.569656)
			(xy 177.904342 -287.562427) (xy 177.903954 -287.547576) (xy 177.901854 -287.540446) (xy 177.899568 -287.534858)
			(xy 177.862992 -287.447228) (xy 177.855372 -287.436052) (xy 177.443892 -287.436052) (xy 177.436272 -287.447228)
			(xy 177.399696 -287.534858) (xy 177.39741 -287.540446) (xy 177.39536 -287.547582) (xy 177.394984 -287.562419)
			(xy 177.396648 -287.569656) (xy 177.398426 -287.574736) (xy 177.400966 -287.580578) (xy 177.402236 -287.583626)
			(xy 177.402998 -287.585404) (xy 177.409602 -287.592262) (xy 177.409856 -287.592516) (xy 177.427637 -287.6112)
			(xy 177.457766 -287.653061) (xy 177.481022 -287.699096) (xy 177.49684 -287.748186) (xy 177.504837 -287.799138)
			(xy 177.50536 -287.824926) (xy 177.50485 -287.850913) (xy 177.49672 -287.902248) (xy 177.480659 -287.951678)
			(xy 177.457063 -287.997988) (xy 177.426513 -288.040036) (xy 177.389762 -288.076787) (xy 177.347714 -288.107337)
			(xy 177.301404 -288.130933) (xy 177.251974 -288.146994) (xy 177.200639 -288.155124) (xy 177.148665 -288.155124)
			(xy 177.09733 -288.146994) (xy 177.0479 -288.130933) (xy 177.00159 -288.107337) (xy 176.959542 -288.076787)
			(xy 176.922791 -288.040036) (xy 176.892241 -287.997988) (xy 176.868645 -287.951678) (xy 176.852584 -287.902248)
			(xy 176.844454 -287.850913) (xy 176.843944 -287.824926) (xy 176.844444 -287.799139) (xy 176.852463 -287.748191)
			(xy 176.868295 -287.699107) (xy 176.891556 -287.653076) (xy 176.921682 -287.611214) (xy 176.939448 -287.592516)
			(xy 176.939702 -287.592262) (xy 176.946306 -287.585404) (xy 176.947068 -287.583626) (xy 176.948338 -287.580578)
			(xy 176.950878 -287.574736) (xy 176.952656 -287.569656) (xy 176.954381 -287.562426) (xy 176.953993 -287.547576)
			(xy 176.951894 -287.540446) (xy 176.949608 -287.534858) (xy 176.913032 -287.447228) (xy 176.905412 -287.436052)
			(xy 174.705264 -287.436052) (xy 174.701962 -287.440116) (xy 174.677578 -287.477962) (xy 174.653448 -287.515554)
			(xy 174.650654 -287.521142) (xy 174.650654 -287.562544) (xy 174.654718 -287.572196) (xy 174.662829 -287.592464)
			(xy 174.674248 -287.634601) (xy 174.680014 -287.677876) (xy 174.680372 -287.699704) (xy 174.680372 -287.699958)
			(xy 174.679862 -287.725945) (xy 174.671732 -287.77728) (xy 174.655671 -287.82671) (xy 174.632075 -287.87302)
			(xy 174.612577 -287.899856) (xy 175.919142 -287.899856) (xy 175.923102 -287.850802) (xy 175.934879 -287.803018)
			(xy 175.95417 -287.757742) (xy 175.980473 -287.716146) (xy 176.013108 -287.679309) (xy 176.051229 -287.648184)
			(xy 176.09385 -287.623577) (xy 176.139866 -287.606125) (xy 176.188085 -287.596281) (xy 176.23726 -287.5943)
			(xy 176.286115 -287.600232) (xy 176.333386 -287.613924) (xy 176.377848 -287.635022) (xy 176.418351 -287.662978)
			(xy 176.453844 -287.69707) (xy 176.483409 -287.736414) (xy 176.50628 -287.779991) (xy 176.521864 -287.826672)
			(xy 176.529759 -287.875249) (xy 176.530254 -287.899856) (xy 176.529759 -287.924463) (xy 176.521864 -287.97304)
			(xy 176.50628 -288.019721) (xy 176.483409 -288.063298) (xy 176.453844 -288.102642) (xy 176.418351 -288.136734)
			(xy 176.377848 -288.16469) (xy 176.333386 -288.185788) (xy 176.286115 -288.19948) (xy 176.23726 -288.205412)
			(xy 176.188085 -288.203431) (xy 176.139866 -288.193587) (xy 176.09385 -288.176135) (xy 176.051229 -288.151528)
			(xy 176.013108 -288.120403) (xy 175.980473 -288.083566) (xy 175.95417 -288.04197) (xy 175.934879 -287.996694)
			(xy 175.923102 -287.94891) (xy 175.919142 -287.899856) (xy 174.612577 -287.899856) (xy 174.601525 -287.915068)
			(xy 174.564774 -287.951819) (xy 174.522726 -287.982369) (xy 174.476416 -288.005965) (xy 174.426986 -288.022026)
			(xy 174.375651 -288.030156) (xy 174.323677 -288.030156) (xy 174.272342 -288.022026) (xy 174.222912 -288.005965)
			(xy 174.176602 -287.982369) (xy 174.134554 -287.951819) (xy 174.097803 -287.915068) (xy 174.067253 -287.87302)
			(xy 174.043657 -287.82671) (xy 174.027596 -287.77728) (xy 174.019466 -287.725945) (xy 174.018956 -287.699958)
			(xy 174.018956 -287.699704) (xy 174.019379 -287.676207) (xy 174.026064 -287.629691) (xy 174.039286 -287.584596)
			(xy 174.048674 -287.563052) (xy 174.048674 -287.562544) (xy 174.053006 -287.551317) (xy 174.051804 -287.527317)
			(xy 174.046388 -287.51657) (xy 174.04461 -287.513522) (xy 174.040038 -287.50641) (xy 174.039784 -287.506156)
			(xy 173.997366 -287.440116) (xy 173.994064 -287.436052) (xy 173.644052 -287.436052) (xy 173.636432 -287.447228)
			(xy 173.599856 -287.534858) (xy 173.59757 -287.540446) (xy 173.595521 -287.547582) (xy 173.595146 -287.562419)
			(xy 173.596808 -287.569656) (xy 173.598586 -287.574736) (xy 173.601126 -287.580578) (xy 173.602396 -287.583626)
			(xy 173.603158 -287.585404) (xy 173.609762 -287.592262) (xy 173.610016 -287.592516) (xy 173.627799 -287.611199)
			(xy 173.657931 -287.653059) (xy 173.68119 -287.699094) (xy 173.69701 -287.748184) (xy 173.705008 -287.799137)
			(xy 173.70552 -287.824926) (xy 173.70501 -287.850913) (xy 173.69688 -287.902248) (xy 173.680819 -287.951678)
			(xy 173.657223 -287.997988) (xy 173.626673 -288.040036) (xy 173.589922 -288.076787) (xy 173.547874 -288.107337)
			(xy 173.501564 -288.130933) (xy 173.452134 -288.146994) (xy 173.400799 -288.155124) (xy 173.348825 -288.155124)
			(xy 173.29749 -288.146994) (xy 173.24806 -288.130933) (xy 173.20175 -288.107337) (xy 173.159702 -288.076787)
			(xy 173.122951 -288.040036) (xy 173.092401 -287.997988) (xy 173.068805 -287.951678) (xy 173.052744 -287.902248)
			(xy 173.044614 -287.850913) (xy 173.044104 -287.824926) (xy 173.044604 -287.799139) (xy 173.052625 -287.748193)
			(xy 173.068459 -287.69911) (xy 173.091723 -287.653082) (xy 173.121853 -287.611224) (xy 173.139608 -287.592516)
			(xy 173.139862 -287.592262) (xy 173.146466 -287.585404) (xy 173.147228 -287.583626) (xy 173.148498 -287.580578)
			(xy 173.151038 -287.574736) (xy 173.152816 -287.569656) (xy 173.154542 -287.562427) (xy 173.154154 -287.547576)
			(xy 173.152054 -287.540446) (xy 173.149768 -287.534858) (xy 173.113192 -287.447228) (xy 173.105572 -287.436052)
			(xy 172.693838 -287.436052) (xy 172.686218 -287.447228) (xy 172.649642 -287.534858) (xy 172.647356 -287.540446)
			(xy 172.645307 -287.547582) (xy 172.644932 -287.562419) (xy 172.646594 -287.569656) (xy 172.648372 -287.574736)
			(xy 172.650912 -287.580578) (xy 172.652182 -287.583626) (xy 172.652944 -287.585404) (xy 172.659548 -287.592262)
			(xy 172.659802 -287.592516) (xy 172.677586 -287.611198) (xy 172.707719 -287.653058) (xy 172.730979 -287.699093)
			(xy 172.7468 -287.748184) (xy 172.754798 -287.799137) (xy 172.755306 -287.824926) (xy 172.754796 -287.850913)
			(xy 172.746666 -287.902248) (xy 172.730605 -287.951678) (xy 172.707009 -287.997988) (xy 172.676459 -288.040036)
			(xy 172.639708 -288.076787) (xy 172.59766 -288.107337) (xy 172.55135 -288.130933) (xy 172.50192 -288.146994)
			(xy 172.450585 -288.155124) (xy 172.398611 -288.155124) (xy 172.347276 -288.146994) (xy 172.297846 -288.130933)
			(xy 172.251536 -288.107337) (xy 172.209488 -288.076787) (xy 172.172737 -288.040036) (xy 172.142187 -287.997988)
			(xy 172.118591 -287.951678) (xy 172.10253 -287.902248) (xy 172.0944 -287.850913) (xy 172.09389 -287.824926)
			(xy 172.09439 -287.799139) (xy 172.10241 -287.748193) (xy 172.118244 -287.699109) (xy 172.141508 -287.65308)
			(xy 172.171636 -287.611222) (xy 172.189394 -287.592516) (xy 172.189648 -287.592262) (xy 172.196252 -287.585404)
			(xy 172.197014 -287.583626) (xy 172.198284 -287.580578) (xy 172.200824 -287.574736) (xy 172.202602 -287.569656)
			(xy 172.204326 -287.562426) (xy 172.203938 -287.547576) (xy 172.20184 -287.540446) (xy 172.199554 -287.534858)
			(xy 172.162978 -287.447228) (xy 172.155358 -287.436052) (xy 171.743878 -287.436052) (xy 171.736258 -287.447228)
			(xy 171.699682 -287.534858) (xy 171.697396 -287.540446) (xy 171.695346 -287.547582) (xy 171.694971 -287.562419)
			(xy 171.696634 -287.569656) (xy 171.698412 -287.574736) (xy 171.700952 -287.580578) (xy 171.702222 -287.583626)
			(xy 171.702984 -287.585404) (xy 171.709588 -287.592262) (xy 171.709842 -287.592516) (xy 171.727624 -287.611199)
			(xy 171.757753 -287.65306) (xy 171.78101 -287.699095) (xy 171.79683 -287.748185) (xy 171.804827 -287.799138)
			(xy 171.805346 -287.824926) (xy 171.804836 -287.850913) (xy 171.796706 -287.902248) (xy 171.780645 -287.951678)
			(xy 171.757049 -287.997988) (xy 171.726499 -288.040036) (xy 171.689748 -288.076787) (xy 171.6477 -288.107337)
			(xy 171.60139 -288.130933) (xy 171.55196 -288.146994) (xy 171.500625 -288.155124) (xy 171.448651 -288.155124)
			(xy 171.397316 -288.146994) (xy 171.347886 -288.130933) (xy 171.301576 -288.107337) (xy 171.259528 -288.076787)
			(xy 171.222777 -288.040036) (xy 171.192227 -287.997988) (xy 171.168631 -287.951678) (xy 171.15257 -287.902248)
			(xy 171.14444 -287.850913) (xy 171.14393 -287.824926) (xy 171.144431 -287.799139) (xy 171.152451 -287.748194)
			(xy 171.168286 -287.699112) (xy 171.191552 -287.653084) (xy 171.221683 -287.611228) (xy 171.239434 -287.592516)
			(xy 171.239688 -287.592262) (xy 171.246292 -287.585404) (xy 171.247054 -287.583626) (xy 171.248324 -287.580578)
			(xy 171.250864 -287.574736) (xy 171.252642 -287.569656) (xy 171.254367 -287.562426) (xy 171.253979 -287.547576)
			(xy 171.25188 -287.540446) (xy 171.249594 -287.534858) (xy 171.213018 -287.447228) (xy 171.205398 -287.436052)
			(xy 170.793918 -287.436052) (xy 170.786298 -287.447228) (xy 170.749722 -287.534858) (xy 170.747436 -287.540446)
			(xy 170.745388 -287.547582) (xy 170.745013 -287.562419) (xy 170.746674 -287.569656) (xy 170.748452 -287.574736)
			(xy 170.750992 -287.580578) (xy 170.752262 -287.583626) (xy 170.753024 -287.585404) (xy 170.759628 -287.592262)
			(xy 170.759882 -287.592516) (xy 170.777667 -287.611198) (xy 170.807802 -287.653057) (xy 170.831063 -287.699092)
			(xy 170.846885 -287.748183) (xy 170.854884 -287.799137) (xy 170.855386 -287.824926) (xy 170.854876 -287.850913)
			(xy 170.846746 -287.902248) (xy 170.830685 -287.951678) (xy 170.807089 -287.997988) (xy 170.776539 -288.040036)
			(xy 170.739788 -288.076787) (xy 170.69774 -288.107337) (xy 170.65143 -288.130933) (xy 170.602 -288.146994)
			(xy 170.550665 -288.155124) (xy 170.498691 -288.155124) (xy 170.447356 -288.146994) (xy 170.397926 -288.130933)
			(xy 170.351616 -288.107337) (xy 170.309568 -288.076787) (xy 170.272817 -288.040036) (xy 170.242267 -287.997988)
			(xy 170.218671 -287.951678) (xy 170.20261 -287.902248) (xy 170.19448 -287.850913) (xy 170.19397 -287.824926)
			(xy 170.19447 -287.799139) (xy 170.20249 -287.748192) (xy 170.218323 -287.699108) (xy 170.241585 -287.653078)
			(xy 170.271713 -287.611219) (xy 170.289474 -287.592516) (xy 170.289728 -287.592262) (xy 170.296332 -287.585404)
			(xy 170.297094 -287.583626) (xy 170.298364 -287.580578) (xy 170.300904 -287.574736) (xy 170.302682 -287.569656)
			(xy 170.304407 -287.562426) (xy 170.304019 -287.547576) (xy 170.30192 -287.540446) (xy 170.299634 -287.534858)
			(xy 170.263058 -287.447228) (xy 170.255438 -287.436052) (xy 169.843958 -287.436052) (xy 169.836338 -287.447228)
			(xy 169.799762 -287.534858) (xy 169.797476 -287.540446) (xy 169.795427 -287.547582) (xy 169.795051 -287.562419)
			(xy 169.796714 -287.569656) (xy 169.798492 -287.574736) (xy 169.801032 -287.580578) (xy 169.802302 -287.583626)
			(xy 169.803064 -287.585404) (xy 169.809668 -287.592262) (xy 169.809922 -287.592516) (xy 169.827705 -287.611199)
			(xy 169.857836 -287.653059) (xy 169.881095 -287.699094) (xy 169.896915 -287.748184) (xy 169.904912 -287.799137)
			(xy 169.905426 -287.824926) (xy 169.904916 -287.850913) (xy 169.896786 -287.902248) (xy 169.880725 -287.951678)
			(xy 169.857129 -287.997988) (xy 169.826579 -288.040036) (xy 169.789828 -288.076787) (xy 169.74778 -288.107337)
			(xy 169.70147 -288.130933) (xy 169.65204 -288.146994) (xy 169.600705 -288.155124) (xy 169.548731 -288.155124)
			(xy 169.497396 -288.146994) (xy 169.447966 -288.130933) (xy 169.401656 -288.107337) (xy 169.359608 -288.076787)
			(xy 169.322857 -288.040036) (xy 169.292307 -287.997988) (xy 169.268711 -287.951678) (xy 169.25265 -287.902248)
			(xy 169.24452 -287.850913) (xy 169.24401 -287.824926) (xy 169.24451 -287.799139) (xy 169.252531 -287.748193)
			(xy 169.268365 -287.69911) (xy 169.29163 -287.653082) (xy 169.32176 -287.611225) (xy 169.339514 -287.592516)
			(xy 169.339768 -287.592262) (xy 169.346372 -287.585404) (xy 169.347134 -287.583626) (xy 169.348404 -287.580578)
			(xy 169.350944 -287.574736) (xy 169.352722 -287.569656) (xy 169.354448 -287.562426) (xy 169.35406 -287.547576)
			(xy 169.35196 -287.540446) (xy 169.349674 -287.534858) (xy 169.313098 -287.447228) (xy 169.305478 -287.436052)
			(xy 168.893998 -287.436052) (xy 168.886378 -287.447228) (xy 168.849802 -287.534858) (xy 168.847516 -287.540446)
			(xy 168.845465 -287.547582) (xy 168.84509 -287.562419) (xy 168.846754 -287.569656) (xy 168.848532 -287.574736)
			(xy 168.851072 -287.580578) (xy 168.852342 -287.583626) (xy 168.853104 -287.585404) (xy 168.859708 -287.592262)
			(xy 168.859962 -287.592516) (xy 168.877748 -287.611197) (xy 168.907884 -287.653056) (xy 168.931147 -287.699091)
			(xy 168.94697 -287.748182) (xy 168.954969 -287.799137) (xy 168.955466 -287.824926) (xy 168.954956 -287.850913)
			(xy 168.946826 -287.902248) (xy 168.930765 -287.951678) (xy 168.907169 -287.997988) (xy 168.876619 -288.040036)
			(xy 168.839868 -288.076787) (xy 168.79782 -288.107337) (xy 168.75151 -288.130933) (xy 168.70208 -288.146994)
			(xy 168.650745 -288.155124) (xy 168.598771 -288.155124) (xy 168.547436 -288.146994) (xy 168.498006 -288.130933)
			(xy 168.451696 -288.107337) (xy 168.409648 -288.076787) (xy 168.372897 -288.040036) (xy 168.342347 -287.997988)
			(xy 168.318751 -287.951678) (xy 168.30269 -287.902248) (xy 168.29456 -287.850913) (xy 168.29405 -287.824926)
			(xy 168.29455 -287.799139) (xy 168.302569 -287.748192) (xy 168.318402 -287.699107) (xy 168.341663 -287.653076)
			(xy 168.371789 -287.611215) (xy 168.389554 -287.592516) (xy 168.389808 -287.592262) (xy 168.396412 -287.585404)
			(xy 168.397174 -287.583626) (xy 168.398444 -287.580578) (xy 168.400984 -287.574736) (xy 168.402762 -287.569656)
			(xy 168.404487 -287.562426) (xy 168.404099 -287.547576) (xy 168.402 -287.540446) (xy 168.399714 -287.534858)
			(xy 168.363138 -287.447228) (xy 168.355518 -287.436052) (xy 167.944038 -287.436052) (xy 167.936418 -287.447228)
			(xy 167.899842 -287.534858) (xy 167.897556 -287.540446) (xy 167.895507 -287.547582) (xy 167.895132 -287.562419)
			(xy 167.896794 -287.569656) (xy 167.898572 -287.574736) (xy 167.901112 -287.580578) (xy 167.902382 -287.583626)
			(xy 167.903144 -287.585404) (xy 167.909748 -287.592262) (xy 167.910002 -287.592516) (xy 167.927786 -287.611198)
			(xy 167.957919 -287.653058) (xy 167.981179 -287.699093) (xy 167.997 -287.748184) (xy 168.004998 -287.799137)
			(xy 168.005506 -287.824926) (xy 168.004996 -287.850913) (xy 167.996866 -287.902248) (xy 167.980805 -287.951678)
			(xy 167.957209 -287.997988) (xy 167.926659 -288.040036) (xy 167.889908 -288.076787) (xy 167.84786 -288.107337)
			(xy 167.80155 -288.130933) (xy 167.75212 -288.146994) (xy 167.700785 -288.155124) (xy 167.648811 -288.155124)
			(xy 167.597476 -288.146994) (xy 167.548046 -288.130933) (xy 167.501736 -288.107337) (xy 167.459688 -288.076787)
			(xy 167.422937 -288.040036) (xy 167.392387 -287.997988) (xy 167.368791 -287.951678) (xy 167.35273 -287.902248)
			(xy 167.3446 -287.850913) (xy 167.34409 -287.824926) (xy 167.34459 -287.799139) (xy 167.35261 -287.748193)
			(xy 167.368444 -287.699109) (xy 167.391708 -287.65308) (xy 167.421836 -287.611222) (xy 167.439594 -287.592516)
			(xy 167.439848 -287.592262) (xy 167.446452 -287.585404) (xy 167.447214 -287.583626) (xy 167.448484 -287.580578)
			(xy 167.451024 -287.574736) (xy 167.452802 -287.569656) (xy 167.454526 -287.562426) (xy 167.454138 -287.547576)
			(xy 167.45204 -287.540446) (xy 167.449754 -287.534858) (xy 167.413178 -287.447228) (xy 167.405558 -287.436052)
			(xy 166.994078 -287.436052) (xy 166.986458 -287.447228) (xy 166.949882 -287.534858) (xy 166.947596 -287.540446)
			(xy 166.945546 -287.547582) (xy 166.945171 -287.562419) (xy 166.946834 -287.569656) (xy 166.948612 -287.574736)
			(xy 166.951152 -287.580578) (xy 166.952422 -287.583626) (xy 166.953184 -287.585404) (xy 166.959788 -287.592262)
			(xy 166.960042 -287.592516) (xy 166.977824 -287.611199) (xy 167.007953 -287.65306) (xy 167.03121 -287.699095)
			(xy 167.04703 -287.748185) (xy 167.055027 -287.799138) (xy 167.055546 -287.824926) (xy 167.055036 -287.850913)
			(xy 167.046906 -287.902248) (xy 167.030845 -287.951678) (xy 167.007249 -287.997988) (xy 166.976699 -288.040036)
			(xy 166.939948 -288.076787) (xy 166.8979 -288.107337) (xy 166.85159 -288.130933) (xy 166.80216 -288.146994)
			(xy 166.750825 -288.155124) (xy 166.698851 -288.155124) (xy 166.647516 -288.146994) (xy 166.598086 -288.130933)
			(xy 166.551776 -288.107337) (xy 166.509728 -288.076787) (xy 166.472977 -288.040036) (xy 166.442427 -287.997988)
			(xy 166.418831 -287.951678) (xy 166.40277 -287.902248) (xy 166.39464 -287.850913) (xy 166.39413 -287.824926)
			(xy 166.394631 -287.799139) (xy 166.402651 -287.748194) (xy 166.418486 -287.699112) (xy 166.441752 -287.653084)
			(xy 166.471883 -287.611228) (xy 166.489634 -287.592516) (xy 166.489888 -287.592262) (xy 166.496492 -287.585404)
			(xy 166.497254 -287.583626) (xy 166.498524 -287.580578) (xy 166.501064 -287.574736) (xy 166.502842 -287.569656)
			(xy 166.504567 -287.562426) (xy 166.504179 -287.547576) (xy 166.50208 -287.540446) (xy 166.499794 -287.534858)
			(xy 166.463218 -287.447228) (xy 166.455598 -287.436052) (xy 166.163498 -287.436052) (xy 166.145039 -287.435726)
			(xy 166.108373 -287.431397) (xy 166.090346 -287.427416) (xy 166.065708 -287.421574) (xy 166.061615 -287.423026)
			(xy 166.053949 -287.427105) (xy 166.050468 -287.429702) (xy 166.045414 -287.433889) (xy 166.037428 -287.444298)
			(xy 166.03472 -287.450276) (xy 166.023798 -287.476692) (xy 166.016686 -287.49371) (xy 165.99789 -287.539176)
			(xy 165.995062 -287.548064) (xy 165.995314 -287.566697) (xy 165.998398 -287.575498) (xy 165.998906 -287.577022)
			(xy 166.000519 -287.580447) (xy 166.004602 -287.586821) (xy 166.007034 -287.589722) (xy 166.009066 -287.591754)
			(xy 166.026979 -287.610461) (xy 166.057345 -287.652416) (xy 166.08079 -287.698597) (xy 166.09674 -287.747871)
			(xy 166.104804 -287.79903) (xy 166.105332 -287.824926) (xy 166.104828 -287.851058) (xy 166.096591 -287.90267)
			(xy 166.080341 -287.952344) (xy 166.056483 -287.998846) (xy 166.02561 -288.041018) (xy 165.98849 -288.077811)
			(xy 165.946047 -288.10831) (xy 165.899336 -288.131756) (xy 165.84952 -288.147566) (xy 165.797838 -288.155347)
			(xy 165.745575 -288.154905) (xy 165.694032 -288.146251) (xy 165.64449 -288.129601) (xy 165.598183 -288.105368)
			(xy 165.556262 -288.074155) (xy 165.537642 -288.055812) (xy 165.537134 -288.055304) (xy 165.536626 -288.054796)
			(xy 165.529192 -288.04808) (xy 165.510692 -288.040444) (xy 165.490678 -288.040444) (xy 165.472178 -288.04808)
			(xy 165.464744 -288.054796) (xy 165.438328 -288.081212) (xy 165.43148 -288.08861) (xy 165.423746 -288.107208)
			(xy 165.423342 -288.11728) (xy 165.423342 -288.45383) (xy 165.42385 -288.46145) (xy 165.426114 -288.472802)
			(xy 165.439196 -288.491869) (xy 165.448996 -288.498026) (xy 165.45179 -288.49955) (xy 165.547294 -288.546286)
			(xy 165.575996 -288.543238) (xy 165.587426 -288.534094) (xy 165.607663 -288.518983) (xy 165.652063 -288.494917)
			(xy 165.699819 -288.478486) (xy 165.749627 -288.470138) (xy 165.774878 -288.469578) (xy 165.800138 -288.470069)
			(xy 165.84997 -288.478381) (xy 165.897753 -288.494782) (xy 165.942186 -288.518825) (xy 165.982054 -288.549853)
			(xy 166.016272 -288.587021) (xy 166.043905 -288.629314) (xy 166.064199 -288.675578) (xy 166.076602 -288.724553)
			(xy 166.080773 -288.774886) (xy 166.419288 -288.774886) (xy 166.423248 -288.725832) (xy 166.435025 -288.678048)
			(xy 166.454316 -288.632772) (xy 166.480619 -288.591176) (xy 166.513254 -288.554339) (xy 166.551375 -288.523214)
			(xy 166.593996 -288.498607) (xy 166.640012 -288.481155) (xy 166.688231 -288.471311) (xy 166.737406 -288.46933)
			(xy 166.786261 -288.475262) (xy 166.833532 -288.488954) (xy 166.877994 -288.510052) (xy 166.918497 -288.538008)
			(xy 166.95399 -288.5721) (xy 166.983555 -288.611444) (xy 167.006426 -288.655021) (xy 167.02201 -288.701702)
			(xy 167.029905 -288.750279) (xy 167.0304 -288.774886) (xy 167.369248 -288.774886) (xy 167.373208 -288.725832)
			(xy 167.384985 -288.678048) (xy 167.404276 -288.632772) (xy 167.430579 -288.591176) (xy 167.463214 -288.554339)
			(xy 167.501335 -288.523214) (xy 167.543956 -288.498607) (xy 167.589972 -288.481155) (xy 167.638191 -288.471311)
			(xy 167.687366 -288.46933) (xy 167.736221 -288.475262) (xy 167.783492 -288.488954) (xy 167.827954 -288.510052)
			(xy 167.868457 -288.538008) (xy 167.90395 -288.5721) (xy 167.933515 -288.611444) (xy 167.956386 -288.655021)
			(xy 167.97197 -288.701702) (xy 167.979865 -288.750279) (xy 167.98036 -288.774886) (xy 168.319208 -288.774886)
			(xy 168.323168 -288.725832) (xy 168.334945 -288.678048) (xy 168.354236 -288.632772) (xy 168.380539 -288.591176)
			(xy 168.413174 -288.554339) (xy 168.451295 -288.523214) (xy 168.493916 -288.498607) (xy 168.539932 -288.481155)
			(xy 168.588151 -288.471311) (xy 168.637326 -288.46933) (xy 168.686181 -288.475262) (xy 168.733452 -288.488954)
			(xy 168.777914 -288.510052) (xy 168.818417 -288.538008) (xy 168.85391 -288.5721) (xy 168.883475 -288.611444)
			(xy 168.906346 -288.655021) (xy 168.92193 -288.701702) (xy 168.929825 -288.750279) (xy 168.93032 -288.774886)
			(xy 169.269168 -288.774886) (xy 169.273128 -288.725832) (xy 169.284905 -288.678048) (xy 169.304196 -288.632772)
			(xy 169.330499 -288.591176) (xy 169.363134 -288.554339) (xy 169.401255 -288.523214) (xy 169.443876 -288.498607)
			(xy 169.489892 -288.481155) (xy 169.538111 -288.471311) (xy 169.587286 -288.46933) (xy 169.636141 -288.475262)
			(xy 169.683412 -288.488954) (xy 169.727874 -288.510052) (xy 169.768377 -288.538008) (xy 169.80387 -288.5721)
			(xy 169.833435 -288.611444) (xy 169.856306 -288.655021) (xy 169.87189 -288.701702) (xy 169.879785 -288.750279)
			(xy 169.88028 -288.774886) (xy 170.219128 -288.774886) (xy 170.223088 -288.725832) (xy 170.234865 -288.678048)
			(xy 170.254156 -288.632772) (xy 170.280459 -288.591176) (xy 170.313094 -288.554339) (xy 170.351215 -288.523214)
			(xy 170.393836 -288.498607) (xy 170.439852 -288.481155) (xy 170.488071 -288.471311) (xy 170.537246 -288.46933)
			(xy 170.586101 -288.475262) (xy 170.633372 -288.488954) (xy 170.677834 -288.510052) (xy 170.718337 -288.538008)
			(xy 170.75383 -288.5721) (xy 170.783395 -288.611444) (xy 170.806266 -288.655021) (xy 170.82185 -288.701702)
			(xy 170.829745 -288.750279) (xy 170.83024 -288.774886) (xy 171.169088 -288.774886) (xy 171.173048 -288.725832)
			(xy 171.184825 -288.678048) (xy 171.204116 -288.632772) (xy 171.230419 -288.591176) (xy 171.263054 -288.554339)
			(xy 171.301175 -288.523214) (xy 171.343796 -288.498607) (xy 171.389812 -288.481155) (xy 171.438031 -288.471311)
			(xy 171.487206 -288.46933) (xy 171.536061 -288.475262) (xy 171.583332 -288.488954) (xy 171.627794 -288.510052)
			(xy 171.668297 -288.538008) (xy 171.70379 -288.5721) (xy 171.733355 -288.611444) (xy 171.756226 -288.655021)
			(xy 171.77181 -288.701702) (xy 171.779705 -288.750279) (xy 171.7802 -288.774886) (xy 172.119048 -288.774886)
			(xy 172.123008 -288.725832) (xy 172.134785 -288.678048) (xy 172.154076 -288.632772) (xy 172.180379 -288.591176)
			(xy 172.213014 -288.554339) (xy 172.251135 -288.523214) (xy 172.293756 -288.498607) (xy 172.339772 -288.481155)
			(xy 172.387991 -288.471311) (xy 172.437166 -288.46933) (xy 172.486021 -288.475262) (xy 172.533292 -288.488954)
			(xy 172.577754 -288.510052) (xy 172.618257 -288.538008) (xy 172.65375 -288.5721) (xy 172.683315 -288.611444)
			(xy 172.706186 -288.655021) (xy 172.72177 -288.701702) (xy 172.729665 -288.750279) (xy 172.73016 -288.774886)
			(xy 173.069262 -288.774886) (xy 173.073222 -288.725832) (xy 173.084999 -288.678048) (xy 173.10429 -288.632772)
			(xy 173.130593 -288.591176) (xy 173.163228 -288.554339) (xy 173.201349 -288.523214) (xy 173.24397 -288.498607)
			(xy 173.289986 -288.481155) (xy 173.338205 -288.471311) (xy 173.38738 -288.46933) (xy 173.436235 -288.475262)
			(xy 173.483506 -288.488954) (xy 173.527968 -288.510052) (xy 173.568471 -288.538008) (xy 173.603964 -288.5721)
			(xy 173.633529 -288.611444) (xy 173.6564 -288.655021) (xy 173.671984 -288.701702) (xy 173.679879 -288.750279)
			(xy 173.680374 -288.774886) (xy 174.019222 -288.774886) (xy 174.023182 -288.725832) (xy 174.034959 -288.678048)
			(xy 174.05425 -288.632772) (xy 174.080553 -288.591176) (xy 174.113188 -288.554339) (xy 174.151309 -288.523214)
			(xy 174.19393 -288.498607) (xy 174.239946 -288.481155) (xy 174.288165 -288.471311) (xy 174.33734 -288.46933)
			(xy 174.386195 -288.475262) (xy 174.433466 -288.488954) (xy 174.477928 -288.510052) (xy 174.518431 -288.538008)
			(xy 174.553924 -288.5721) (xy 174.583489 -288.611444) (xy 174.60636 -288.655021) (xy 174.621944 -288.701702)
			(xy 174.629839 -288.750279) (xy 174.630334 -288.774886) (xy 175.919142 -288.774886) (xy 175.923102 -288.725832)
			(xy 175.934879 -288.678048) (xy 175.95417 -288.632772) (xy 175.980473 -288.591176) (xy 176.013108 -288.554339)
			(xy 176.051229 -288.523214) (xy 176.09385 -288.498607) (xy 176.139866 -288.481155) (xy 176.188085 -288.471311)
			(xy 176.23726 -288.46933) (xy 176.286115 -288.475262) (xy 176.333386 -288.488954) (xy 176.377848 -288.510052)
			(xy 176.418351 -288.538008) (xy 176.453844 -288.5721) (xy 176.483409 -288.611444) (xy 176.50628 -288.655021)
			(xy 176.521864 -288.701702) (xy 176.529759 -288.750279) (xy 176.530254 -288.774886) (xy 176.869102 -288.774886)
			(xy 176.873062 -288.725832) (xy 176.884839 -288.678048) (xy 176.90413 -288.632772) (xy 176.930433 -288.591176)
			(xy 176.963068 -288.554339) (xy 177.001189 -288.523214) (xy 177.04381 -288.498607) (xy 177.089826 -288.481155)
			(xy 177.138045 -288.471311) (xy 177.18722 -288.46933) (xy 177.236075 -288.475262) (xy 177.283346 -288.488954)
			(xy 177.327808 -288.510052) (xy 177.368311 -288.538008) (xy 177.403804 -288.5721) (xy 177.433369 -288.611444)
			(xy 177.45624 -288.655021) (xy 177.471824 -288.701702) (xy 177.479719 -288.750279) (xy 177.480214 -288.774886)
			(xy 177.819062 -288.774886) (xy 177.823022 -288.725832) (xy 177.834799 -288.678048) (xy 177.85409 -288.632772)
			(xy 177.880393 -288.591176) (xy 177.913028 -288.554339) (xy 177.951149 -288.523214) (xy 177.99377 -288.498607)
			(xy 178.039786 -288.481155) (xy 178.088005 -288.471311) (xy 178.13718 -288.46933) (xy 178.186035 -288.475262)
			(xy 178.233306 -288.488954) (xy 178.277768 -288.510052) (xy 178.318271 -288.538008) (xy 178.353764 -288.5721)
			(xy 178.383329 -288.611444) (xy 178.4062 -288.655021) (xy 178.421784 -288.701702) (xy 178.429679 -288.750279)
			(xy 178.430174 -288.774886) (xy 178.769276 -288.774886) (xy 178.773236 -288.725832) (xy 178.785013 -288.678048)
			(xy 178.804304 -288.632772) (xy 178.830607 -288.591176) (xy 178.863242 -288.554339) (xy 178.901363 -288.523214)
			(xy 178.943984 -288.498607) (xy 178.99 -288.481155) (xy 179.038219 -288.471311) (xy 179.087394 -288.46933)
			(xy 179.136249 -288.475262) (xy 179.18352 -288.488954) (xy 179.227982 -288.510052) (xy 179.268485 -288.538008)
			(xy 179.303978 -288.5721) (xy 179.333543 -288.611444) (xy 179.356414 -288.655021) (xy 179.371998 -288.701702)
			(xy 179.379893 -288.750279) (xy 179.380388 -288.774886) (xy 179.719236 -288.774886) (xy 179.723196 -288.725832)
			(xy 179.734973 -288.678048) (xy 179.754264 -288.632772) (xy 179.780567 -288.591176) (xy 179.813202 -288.554339)
			(xy 179.851323 -288.523214) (xy 179.893944 -288.498607) (xy 179.93996 -288.481155) (xy 179.988179 -288.471311)
			(xy 180.037354 -288.46933) (xy 180.086209 -288.475262) (xy 180.13348 -288.488954) (xy 180.177942 -288.510052)
			(xy 180.218445 -288.538008) (xy 180.253938 -288.5721) (xy 180.283503 -288.611444) (xy 180.306374 -288.655021)
			(xy 180.321958 -288.701702) (xy 180.329853 -288.750279) (xy 180.330348 -288.774886) (xy 180.669196 -288.774886)
			(xy 180.673156 -288.725832) (xy 180.684933 -288.678048) (xy 180.704224 -288.632772) (xy 180.730527 -288.591176)
			(xy 180.763162 -288.554339) (xy 180.801283 -288.523214) (xy 180.843904 -288.498607) (xy 180.88992 -288.481155)
			(xy 180.938139 -288.471311) (xy 180.987314 -288.46933) (xy 181.036169 -288.475262) (xy 181.08344 -288.488954)
			(xy 181.127902 -288.510052) (xy 181.168405 -288.538008) (xy 181.203898 -288.5721) (xy 181.233463 -288.611444)
			(xy 181.256334 -288.655021) (xy 181.271918 -288.701702) (xy 181.279813 -288.750279) (xy 181.280308 -288.774886)
			(xy 181.619156 -288.774886) (xy 181.623116 -288.725832) (xy 181.634893 -288.678048) (xy 181.654184 -288.632772)
			(xy 181.680487 -288.591176) (xy 181.713122 -288.554339) (xy 181.751243 -288.523214) (xy 181.793864 -288.498607)
			(xy 181.83988 -288.481155) (xy 181.888099 -288.471311) (xy 181.937274 -288.46933) (xy 181.986129 -288.475262)
			(xy 182.0334 -288.488954) (xy 182.077862 -288.510052) (xy 182.118365 -288.538008) (xy 182.153858 -288.5721)
			(xy 182.183423 -288.611444) (xy 182.206294 -288.655021) (xy 182.221878 -288.701702) (xy 182.229773 -288.750279)
			(xy 182.230268 -288.774886) (xy 182.569116 -288.774886) (xy 182.573076 -288.725832) (xy 182.584853 -288.678048)
			(xy 182.604144 -288.632772) (xy 182.630447 -288.591176) (xy 182.663082 -288.554339) (xy 182.701203 -288.523214)
			(xy 182.743824 -288.498607) (xy 182.78984 -288.481155) (xy 182.838059 -288.471311) (xy 182.887234 -288.46933)
			(xy 182.936089 -288.475262) (xy 182.98336 -288.488954) (xy 183.027822 -288.510052) (xy 183.068325 -288.538008)
			(xy 183.103818 -288.5721) (xy 183.133383 -288.611444) (xy 183.156254 -288.655021) (xy 183.171838 -288.701702)
			(xy 183.179733 -288.750279) (xy 183.180228 -288.774886) (xy 183.519076 -288.774886) (xy 183.523036 -288.725832)
			(xy 183.534813 -288.678048) (xy 183.554104 -288.632772) (xy 183.580407 -288.591176) (xy 183.613042 -288.554339)
			(xy 183.651163 -288.523214) (xy 183.693784 -288.498607) (xy 183.7398 -288.481155) (xy 183.788019 -288.471311)
			(xy 183.837194 -288.46933) (xy 183.886049 -288.475262) (xy 183.93332 -288.488954) (xy 183.977782 -288.510052)
			(xy 184.018285 -288.538008) (xy 184.053778 -288.5721) (xy 184.083343 -288.611444) (xy 184.106214 -288.655021)
			(xy 184.121798 -288.701702) (xy 184.129693 -288.750279) (xy 184.130188 -288.774886) (xy 184.129693 -288.799493)
			(xy 184.121798 -288.84807) (xy 184.106214 -288.894751) (xy 184.083343 -288.938328) (xy 184.053778 -288.977672)
			(xy 184.018285 -289.011764) (xy 183.977782 -289.03972) (xy 183.93332 -289.060818) (xy 183.886049 -289.07451)
			(xy 183.837194 -289.080442) (xy 183.788019 -289.078461) (xy 183.7398 -289.068617) (xy 183.693784 -289.051165)
			(xy 183.651163 -289.026558) (xy 183.613042 -288.995433) (xy 183.580407 -288.958596) (xy 183.554104 -288.917)
			(xy 183.534813 -288.871724) (xy 183.523036 -288.82394) (xy 183.519076 -288.774886) (xy 183.180228 -288.774886)
			(xy 183.179733 -288.799493) (xy 183.171838 -288.84807) (xy 183.156254 -288.894751) (xy 183.133383 -288.938328)
			(xy 183.103818 -288.977672) (xy 183.068325 -289.011764) (xy 183.027822 -289.03972) (xy 182.98336 -289.060818)
			(xy 182.936089 -289.07451) (xy 182.887234 -289.080442) (xy 182.838059 -289.078461) (xy 182.78984 -289.068617)
			(xy 182.743824 -289.051165) (xy 182.701203 -289.026558) (xy 182.663082 -288.995433) (xy 182.630447 -288.958596)
			(xy 182.604144 -288.917) (xy 182.584853 -288.871724) (xy 182.573076 -288.82394) (xy 182.569116 -288.774886)
			(xy 182.230268 -288.774886) (xy 182.229773 -288.799493) (xy 182.221878 -288.84807) (xy 182.206294 -288.894751)
			(xy 182.183423 -288.938328) (xy 182.153858 -288.977672) (xy 182.118365 -289.011764) (xy 182.077862 -289.03972)
			(xy 182.0334 -289.060818) (xy 181.986129 -289.07451) (xy 181.937274 -289.080442) (xy 181.888099 -289.078461)
			(xy 181.83988 -289.068617) (xy 181.793864 -289.051165) (xy 181.751243 -289.026558) (xy 181.713122 -288.995433)
			(xy 181.680487 -288.958596) (xy 181.654184 -288.917) (xy 181.634893 -288.871724) (xy 181.623116 -288.82394)
			(xy 181.619156 -288.774886) (xy 181.280308 -288.774886) (xy 181.279813 -288.799493) (xy 181.271918 -288.84807)
			(xy 181.256334 -288.894751) (xy 181.233463 -288.938328) (xy 181.203898 -288.977672) (xy 181.168405 -289.011764)
			(xy 181.127902 -289.03972) (xy 181.08344 -289.060818) (xy 181.036169 -289.07451) (xy 180.987314 -289.080442)
			(xy 180.938139 -289.078461) (xy 180.88992 -289.068617) (xy 180.843904 -289.051165) (xy 180.801283 -289.026558)
			(xy 180.763162 -288.995433) (xy 180.730527 -288.958596) (xy 180.704224 -288.917) (xy 180.684933 -288.871724)
			(xy 180.673156 -288.82394) (xy 180.669196 -288.774886) (xy 180.330348 -288.774886) (xy 180.329853 -288.799493)
			(xy 180.321958 -288.84807) (xy 180.306374 -288.894751) (xy 180.283503 -288.938328) (xy 180.253938 -288.977672)
			(xy 180.218445 -289.011764) (xy 180.177942 -289.03972) (xy 180.13348 -289.060818) (xy 180.086209 -289.07451)
			(xy 180.037354 -289.080442) (xy 179.988179 -289.078461) (xy 179.93996 -289.068617) (xy 179.893944 -289.051165)
			(xy 179.851323 -289.026558) (xy 179.813202 -288.995433) (xy 179.780567 -288.958596) (xy 179.754264 -288.917)
			(xy 179.734973 -288.871724) (xy 179.723196 -288.82394) (xy 179.719236 -288.774886) (xy 179.380388 -288.774886)
			(xy 179.379893 -288.799493) (xy 179.371998 -288.84807) (xy 179.356414 -288.894751) (xy 179.333543 -288.938328)
			(xy 179.303978 -288.977672) (xy 179.268485 -289.011764) (xy 179.227982 -289.03972) (xy 179.18352 -289.060818)
			(xy 179.136249 -289.07451) (xy 179.087394 -289.080442) (xy 179.038219 -289.078461) (xy 178.99 -289.068617)
			(xy 178.943984 -289.051165) (xy 178.901363 -289.026558) (xy 178.863242 -288.995433) (xy 178.830607 -288.958596)
			(xy 178.804304 -288.917) (xy 178.785013 -288.871724) (xy 178.773236 -288.82394) (xy 178.769276 -288.774886)
			(xy 178.430174 -288.774886) (xy 178.429679 -288.799493) (xy 178.421784 -288.84807) (xy 178.4062 -288.894751)
			(xy 178.383329 -288.938328) (xy 178.353764 -288.977672) (xy 178.318271 -289.011764) (xy 178.277768 -289.03972)
			(xy 178.233306 -289.060818) (xy 178.186035 -289.07451) (xy 178.13718 -289.080442) (xy 178.088005 -289.078461)
			(xy 178.039786 -289.068617) (xy 177.99377 -289.051165) (xy 177.951149 -289.026558) (xy 177.913028 -288.995433)
			(xy 177.880393 -288.958596) (xy 177.85409 -288.917) (xy 177.834799 -288.871724) (xy 177.823022 -288.82394)
			(xy 177.819062 -288.774886) (xy 177.480214 -288.774886) (xy 177.479719 -288.799493) (xy 177.471824 -288.84807)
			(xy 177.45624 -288.894751) (xy 177.433369 -288.938328) (xy 177.403804 -288.977672) (xy 177.368311 -289.011764)
			(xy 177.327808 -289.03972) (xy 177.283346 -289.060818) (xy 177.236075 -289.07451) (xy 177.18722 -289.080442)
			(xy 177.138045 -289.078461) (xy 177.089826 -289.068617) (xy 177.04381 -289.051165) (xy 177.001189 -289.026558)
			(xy 176.963068 -288.995433) (xy 176.930433 -288.958596) (xy 176.90413 -288.917) (xy 176.884839 -288.871724)
			(xy 176.873062 -288.82394) (xy 176.869102 -288.774886) (xy 176.530254 -288.774886) (xy 176.529759 -288.799493)
			(xy 176.521864 -288.84807) (xy 176.50628 -288.894751) (xy 176.483409 -288.938328) (xy 176.453844 -288.977672)
			(xy 176.418351 -289.011764) (xy 176.377848 -289.03972) (xy 176.333386 -289.060818) (xy 176.286115 -289.07451)
			(xy 176.23726 -289.080442) (xy 176.188085 -289.078461) (xy 176.139866 -289.068617) (xy 176.09385 -289.051165)
			(xy 176.051229 -289.026558) (xy 176.013108 -288.995433) (xy 175.980473 -288.958596) (xy 175.95417 -288.917)
			(xy 175.934879 -288.871724) (xy 175.923102 -288.82394) (xy 175.919142 -288.774886) (xy 174.630334 -288.774886)
			(xy 174.629839 -288.799493) (xy 174.621944 -288.84807) (xy 174.60636 -288.894751) (xy 174.583489 -288.938328)
			(xy 174.553924 -288.977672) (xy 174.518431 -289.011764) (xy 174.477928 -289.03972) (xy 174.433466 -289.060818)
			(xy 174.386195 -289.07451) (xy 174.33734 -289.080442) (xy 174.288165 -289.078461) (xy 174.239946 -289.068617)
			(xy 174.19393 -289.051165) (xy 174.151309 -289.026558) (xy 174.113188 -288.995433) (xy 174.080553 -288.958596)
			(xy 174.05425 -288.917) (xy 174.034959 -288.871724) (xy 174.023182 -288.82394) (xy 174.019222 -288.774886)
			(xy 173.680374 -288.774886) (xy 173.679879 -288.799493) (xy 173.671984 -288.84807) (xy 173.6564 -288.894751)
			(xy 173.633529 -288.938328) (xy 173.603964 -288.977672) (xy 173.568471 -289.011764) (xy 173.527968 -289.03972)
			(xy 173.483506 -289.060818) (xy 173.436235 -289.07451) (xy 173.38738 -289.080442) (xy 173.338205 -289.078461)
			(xy 173.289986 -289.068617) (xy 173.24397 -289.051165) (xy 173.201349 -289.026558) (xy 173.163228 -288.995433)
			(xy 173.130593 -288.958596) (xy 173.10429 -288.917) (xy 173.084999 -288.871724) (xy 173.073222 -288.82394)
			(xy 173.069262 -288.774886) (xy 172.73016 -288.774886) (xy 172.729665 -288.799493) (xy 172.72177 -288.84807)
			(xy 172.706186 -288.894751) (xy 172.683315 -288.938328) (xy 172.65375 -288.977672) (xy 172.618257 -289.011764)
			(xy 172.577754 -289.03972) (xy 172.533292 -289.060818) (xy 172.486021 -289.07451) (xy 172.437166 -289.080442)
			(xy 172.387991 -289.078461) (xy 172.339772 -289.068617) (xy 172.293756 -289.051165) (xy 172.251135 -289.026558)
			(xy 172.213014 -288.995433) (xy 172.180379 -288.958596) (xy 172.154076 -288.917) (xy 172.134785 -288.871724)
			(xy 172.123008 -288.82394) (xy 172.119048 -288.774886) (xy 171.7802 -288.774886) (xy 171.779705 -288.799493)
			(xy 171.77181 -288.84807) (xy 171.756226 -288.894751) (xy 171.733355 -288.938328) (xy 171.70379 -288.977672)
			(xy 171.668297 -289.011764) (xy 171.627794 -289.03972) (xy 171.583332 -289.060818) (xy 171.536061 -289.07451)
			(xy 171.487206 -289.080442) (xy 171.438031 -289.078461) (xy 171.389812 -289.068617) (xy 171.343796 -289.051165)
			(xy 171.301175 -289.026558) (xy 171.263054 -288.995433) (xy 171.230419 -288.958596) (xy 171.204116 -288.917)
			(xy 171.184825 -288.871724) (xy 171.173048 -288.82394) (xy 171.169088 -288.774886) (xy 170.83024 -288.774886)
			(xy 170.829745 -288.799493) (xy 170.82185 -288.84807) (xy 170.806266 -288.894751) (xy 170.783395 -288.938328)
			(xy 170.75383 -288.977672) (xy 170.718337 -289.011764) (xy 170.677834 -289.03972) (xy 170.633372 -289.060818)
			(xy 170.586101 -289.07451) (xy 170.537246 -289.080442) (xy 170.488071 -289.078461) (xy 170.439852 -289.068617)
			(xy 170.393836 -289.051165) (xy 170.351215 -289.026558) (xy 170.313094 -288.995433) (xy 170.280459 -288.958596)
			(xy 170.254156 -288.917) (xy 170.234865 -288.871724) (xy 170.223088 -288.82394) (xy 170.219128 -288.774886)
			(xy 169.88028 -288.774886) (xy 169.879785 -288.799493) (xy 169.87189 -288.84807) (xy 169.856306 -288.894751)
			(xy 169.833435 -288.938328) (xy 169.80387 -288.977672) (xy 169.768377 -289.011764) (xy 169.727874 -289.03972)
			(xy 169.683412 -289.060818) (xy 169.636141 -289.07451) (xy 169.587286 -289.080442) (xy 169.538111 -289.078461)
			(xy 169.489892 -289.068617) (xy 169.443876 -289.051165) (xy 169.401255 -289.026558) (xy 169.363134 -288.995433)
			(xy 169.330499 -288.958596) (xy 169.304196 -288.917) (xy 169.284905 -288.871724) (xy 169.273128 -288.82394)
			(xy 169.269168 -288.774886) (xy 168.93032 -288.774886) (xy 168.929825 -288.799493) (xy 168.92193 -288.84807)
			(xy 168.906346 -288.894751) (xy 168.883475 -288.938328) (xy 168.85391 -288.977672) (xy 168.818417 -289.011764)
			(xy 168.777914 -289.03972) (xy 168.733452 -289.060818) (xy 168.686181 -289.07451) (xy 168.637326 -289.080442)
			(xy 168.588151 -289.078461) (xy 168.539932 -289.068617) (xy 168.493916 -289.051165) (xy 168.451295 -289.026558)
			(xy 168.413174 -288.995433) (xy 168.380539 -288.958596) (xy 168.354236 -288.917) (xy 168.334945 -288.871724)
			(xy 168.323168 -288.82394) (xy 168.319208 -288.774886) (xy 167.98036 -288.774886) (xy 167.979865 -288.799493)
			(xy 167.97197 -288.84807) (xy 167.956386 -288.894751) (xy 167.933515 -288.938328) (xy 167.90395 -288.977672)
			(xy 167.868457 -289.011764) (xy 167.827954 -289.03972) (xy 167.783492 -289.060818) (xy 167.736221 -289.07451)
			(xy 167.687366 -289.080442) (xy 167.638191 -289.078461) (xy 167.589972 -289.068617) (xy 167.543956 -289.051165)
			(xy 167.501335 -289.026558) (xy 167.463214 -288.995433) (xy 167.430579 -288.958596) (xy 167.404276 -288.917)
			(xy 167.384985 -288.871724) (xy 167.373208 -288.82394) (xy 167.369248 -288.774886) (xy 167.0304 -288.774886)
			(xy 167.029905 -288.799493) (xy 167.02201 -288.84807) (xy 167.006426 -288.894751) (xy 166.983555 -288.938328)
			(xy 166.95399 -288.977672) (xy 166.918497 -289.011764) (xy 166.877994 -289.03972) (xy 166.833532 -289.060818)
			(xy 166.786261 -289.07451) (xy 166.737406 -289.080442) (xy 166.688231 -289.078461) (xy 166.640012 -289.068617)
			(xy 166.593996 -289.051165) (xy 166.551375 -289.026558) (xy 166.513254 -288.995433) (xy 166.480619 -288.958596)
			(xy 166.454316 -288.917) (xy 166.435025 -288.871724) (xy 166.423248 -288.82394) (xy 166.419288 -288.774886)
			(xy 166.080773 -288.774886) (xy 166.080774 -288.7749) (xy 166.076602 -288.825247) (xy 166.064199 -288.874222)
			(xy 166.043905 -288.920486) (xy 166.016272 -288.962779) (xy 165.982054 -288.999947) (xy 165.942186 -289.030975)
			(xy 165.897753 -289.055018) (xy 165.84997 -289.071419) (xy 165.800138 -289.079731) (xy 165.774878 -289.080194)
			(xy 165.751594 -289.079714) (xy 165.705577 -289.072556) (xy 165.661184 -289.058485) (xy 165.619445 -289.037829)
			(xy 165.600126 -289.024822) (xy 165.599872 -289.024822) (xy 165.593415 -289.0207) (xy 165.578822 -289.016061)
			(xy 165.57117 -289.015678) (xy 165.53434 -289.015678) (xy 165.528615 -289.015827) (xy 165.517457 -289.018392)
			(xy 165.512242 -289.020758) (xy 165.45179 -289.050222) (xy 165.447218 -289.052762) (xy 165.438142 -289.059057)
			(xy 165.426021 -289.077493) (xy 165.42385 -289.088322) (xy 165.423342 -289.095942) (xy 165.423342 -289.364166)
			(xy 165.422905 -289.37423) (xy 165.415167 -289.392811) (xy 165.408356 -289.400234) (xy 165.21811 -289.59048)
			(xy 165.210713 -289.59733) (xy 165.192115 -289.605072) (xy 165.182042 -289.605466) (xy 165.174422 -289.605466)
			(xy 165.164409 -289.60595) (xy 165.145904 -289.613604) (xy 165.131736 -289.627757) (xy 165.124061 -289.646253)
			(xy 165.123622 -289.656266) (xy 165.123622 -289.661346) (xy 165.124638 -289.666172) (xy 165.127258 -289.68057)
			(xy 165.13006 -289.709704) (xy 165.130226 -289.724338) (xy 165.130226 -289.724846) (xy 165.469074 -289.724846)
			(xy 165.473034 -289.675792) (xy 165.484811 -289.628008) (xy 165.504102 -289.582732) (xy 165.530405 -289.541136)
			(xy 165.56304 -289.504299) (xy 165.601161 -289.473174) (xy 165.643782 -289.448567) (xy 165.689798 -289.431115)
			(xy 165.738017 -289.421271) (xy 165.787192 -289.41929) (xy 165.836047 -289.425222) (xy 165.883318 -289.438914)
			(xy 165.92778 -289.460012) (xy 165.968283 -289.487968) (xy 166.003776 -289.52206) (xy 166.033341 -289.561404)
			(xy 166.056212 -289.604981) (xy 166.071796 -289.651662) (xy 166.079691 -289.700239) (xy 166.080186 -289.724846)
			(xy 166.419288 -289.724846) (xy 166.423248 -289.675792) (xy 166.435025 -289.628008) (xy 166.454316 -289.582732)
			(xy 166.480619 -289.541136) (xy 166.513254 -289.504299) (xy 166.551375 -289.473174) (xy 166.593996 -289.448567)
			(xy 166.640012 -289.431115) (xy 166.688231 -289.421271) (xy 166.737406 -289.41929) (xy 166.786261 -289.425222)
			(xy 166.833532 -289.438914) (xy 166.877994 -289.460012) (xy 166.918497 -289.487968) (xy 166.95399 -289.52206)
			(xy 166.983555 -289.561404) (xy 167.006426 -289.604981) (xy 167.02201 -289.651662) (xy 167.029905 -289.700239)
			(xy 167.0304 -289.724846) (xy 167.369248 -289.724846) (xy 167.373208 -289.675792) (xy 167.384985 -289.628008)
			(xy 167.404276 -289.582732) (xy 167.430579 -289.541136) (xy 167.463214 -289.504299) (xy 167.501335 -289.473174)
			(xy 167.543956 -289.448567) (xy 167.589972 -289.431115) (xy 167.638191 -289.421271) (xy 167.687366 -289.41929)
			(xy 167.736221 -289.425222) (xy 167.783492 -289.438914) (xy 167.827954 -289.460012) (xy 167.868457 -289.487968)
			(xy 167.90395 -289.52206) (xy 167.933515 -289.561404) (xy 167.956386 -289.604981) (xy 167.97197 -289.651662)
			(xy 167.979865 -289.700239) (xy 167.98036 -289.724846) (xy 168.319208 -289.724846) (xy 168.323168 -289.675792)
			(xy 168.334945 -289.628008) (xy 168.354236 -289.582732) (xy 168.380539 -289.541136) (xy 168.413174 -289.504299)
			(xy 168.451295 -289.473174) (xy 168.493916 -289.448567) (xy 168.539932 -289.431115) (xy 168.588151 -289.421271)
			(xy 168.637326 -289.41929) (xy 168.686181 -289.425222) (xy 168.733452 -289.438914) (xy 168.777914 -289.460012)
			(xy 168.818417 -289.487968) (xy 168.85391 -289.52206) (xy 168.883475 -289.561404) (xy 168.906346 -289.604981)
			(xy 168.92193 -289.651662) (xy 168.929825 -289.700239) (xy 168.93032 -289.724846) (xy 169.269168 -289.724846)
			(xy 169.273128 -289.675792) (xy 169.284905 -289.628008) (xy 169.304196 -289.582732) (xy 169.330499 -289.541136)
			(xy 169.363134 -289.504299) (xy 169.401255 -289.473174) (xy 169.443876 -289.448567) (xy 169.489892 -289.431115)
			(xy 169.538111 -289.421271) (xy 169.587286 -289.41929) (xy 169.636141 -289.425222) (xy 169.683412 -289.438914)
			(xy 169.727874 -289.460012) (xy 169.768377 -289.487968) (xy 169.80387 -289.52206) (xy 169.833435 -289.561404)
			(xy 169.856306 -289.604981) (xy 169.87189 -289.651662) (xy 169.879785 -289.700239) (xy 169.88028 -289.724846)
			(xy 170.219128 -289.724846) (xy 170.223088 -289.675792) (xy 170.234865 -289.628008) (xy 170.254156 -289.582732)
			(xy 170.280459 -289.541136) (xy 170.313094 -289.504299) (xy 170.351215 -289.473174) (xy 170.393836 -289.448567)
			(xy 170.439852 -289.431115) (xy 170.488071 -289.421271) (xy 170.537246 -289.41929) (xy 170.586101 -289.425222)
			(xy 170.633372 -289.438914) (xy 170.677834 -289.460012) (xy 170.718337 -289.487968) (xy 170.75383 -289.52206)
			(xy 170.783395 -289.561404) (xy 170.806266 -289.604981) (xy 170.82185 -289.651662) (xy 170.829745 -289.700239)
			(xy 170.83024 -289.724846) (xy 171.169088 -289.724846) (xy 171.173048 -289.675792) (xy 171.184825 -289.628008)
			(xy 171.204116 -289.582732) (xy 171.230419 -289.541136) (xy 171.263054 -289.504299) (xy 171.301175 -289.473174)
			(xy 171.343796 -289.448567) (xy 171.389812 -289.431115) (xy 171.438031 -289.421271) (xy 171.487206 -289.41929)
			(xy 171.536061 -289.425222) (xy 171.583332 -289.438914) (xy 171.627794 -289.460012) (xy 171.668297 -289.487968)
			(xy 171.70379 -289.52206) (xy 171.733355 -289.561404) (xy 171.756226 -289.604981) (xy 171.77181 -289.651662)
			(xy 171.779705 -289.700239) (xy 171.7802 -289.724846) (xy 172.119048 -289.724846) (xy 172.123008 -289.675792)
			(xy 172.134785 -289.628008) (xy 172.154076 -289.582732) (xy 172.180379 -289.541136) (xy 172.213014 -289.504299)
			(xy 172.251135 -289.473174) (xy 172.293756 -289.448567) (xy 172.339772 -289.431115) (xy 172.387991 -289.421271)
			(xy 172.437166 -289.41929) (xy 172.486021 -289.425222) (xy 172.533292 -289.438914) (xy 172.577754 -289.460012)
			(xy 172.618257 -289.487968) (xy 172.65375 -289.52206) (xy 172.683315 -289.561404) (xy 172.706186 -289.604981)
			(xy 172.72177 -289.651662) (xy 172.729665 -289.700239) (xy 172.73016 -289.724846) (xy 173.069262 -289.724846)
			(xy 173.073222 -289.675792) (xy 173.084999 -289.628008) (xy 173.10429 -289.582732) (xy 173.130593 -289.541136)
			(xy 173.163228 -289.504299) (xy 173.201349 -289.473174) (xy 173.24397 -289.448567) (xy 173.289986 -289.431115)
			(xy 173.338205 -289.421271) (xy 173.38738 -289.41929) (xy 173.436235 -289.425222) (xy 173.483506 -289.438914)
			(xy 173.527968 -289.460012) (xy 173.568471 -289.487968) (xy 173.603964 -289.52206) (xy 173.633529 -289.561404)
			(xy 173.6564 -289.604981) (xy 173.671984 -289.651662) (xy 173.679879 -289.700239) (xy 173.680374 -289.724846)
			(xy 174.019222 -289.724846) (xy 174.023182 -289.675792) (xy 174.034959 -289.628008) (xy 174.05425 -289.582732)
			(xy 174.080553 -289.541136) (xy 174.113188 -289.504299) (xy 174.151309 -289.473174) (xy 174.19393 -289.448567)
			(xy 174.239946 -289.431115) (xy 174.288165 -289.421271) (xy 174.33734 -289.41929) (xy 174.386195 -289.425222)
			(xy 174.433466 -289.438914) (xy 174.477928 -289.460012) (xy 174.518431 -289.487968) (xy 174.553924 -289.52206)
			(xy 174.583489 -289.561404) (xy 174.60636 -289.604981) (xy 174.621944 -289.651662) (xy 174.629839 -289.700239)
			(xy 174.630334 -289.724846) (xy 175.919142 -289.724846) (xy 175.923102 -289.675792) (xy 175.934879 -289.628008)
			(xy 175.95417 -289.582732) (xy 175.980473 -289.541136) (xy 176.013108 -289.504299) (xy 176.051229 -289.473174)
			(xy 176.09385 -289.448567) (xy 176.139866 -289.431115) (xy 176.188085 -289.421271) (xy 176.23726 -289.41929)
			(xy 176.286115 -289.425222) (xy 176.333386 -289.438914) (xy 176.377848 -289.460012) (xy 176.418351 -289.487968)
			(xy 176.453844 -289.52206) (xy 176.483409 -289.561404) (xy 176.50628 -289.604981) (xy 176.521864 -289.651662)
			(xy 176.529759 -289.700239) (xy 176.530254 -289.724846) (xy 176.869102 -289.724846) (xy 176.873062 -289.675792)
			(xy 176.884839 -289.628008) (xy 176.90413 -289.582732) (xy 176.930433 -289.541136) (xy 176.963068 -289.504299)
			(xy 177.001189 -289.473174) (xy 177.04381 -289.448567) (xy 177.089826 -289.431115) (xy 177.138045 -289.421271)
			(xy 177.18722 -289.41929) (xy 177.236075 -289.425222) (xy 177.283346 -289.438914) (xy 177.327808 -289.460012)
			(xy 177.368311 -289.487968) (xy 177.403804 -289.52206) (xy 177.433369 -289.561404) (xy 177.45624 -289.604981)
			(xy 177.471824 -289.651662) (xy 177.479719 -289.700239) (xy 177.480214 -289.724846) (xy 177.819062 -289.724846)
			(xy 177.823022 -289.675792) (xy 177.834799 -289.628008) (xy 177.85409 -289.582732) (xy 177.880393 -289.541136)
			(xy 177.913028 -289.504299) (xy 177.951149 -289.473174) (xy 177.99377 -289.448567) (xy 178.039786 -289.431115)
			(xy 178.088005 -289.421271) (xy 178.13718 -289.41929) (xy 178.186035 -289.425222) (xy 178.233306 -289.438914)
			(xy 178.277768 -289.460012) (xy 178.318271 -289.487968) (xy 178.353764 -289.52206) (xy 178.383329 -289.561404)
			(xy 178.4062 -289.604981) (xy 178.421784 -289.651662) (xy 178.429679 -289.700239) (xy 178.430174 -289.724846)
			(xy 178.769276 -289.724846) (xy 178.773236 -289.675792) (xy 178.785013 -289.628008) (xy 178.804304 -289.582732)
			(xy 178.830607 -289.541136) (xy 178.863242 -289.504299) (xy 178.901363 -289.473174) (xy 178.943984 -289.448567)
			(xy 178.99 -289.431115) (xy 179.038219 -289.421271) (xy 179.087394 -289.41929) (xy 179.136249 -289.425222)
			(xy 179.18352 -289.438914) (xy 179.227982 -289.460012) (xy 179.268485 -289.487968) (xy 179.303978 -289.52206)
			(xy 179.333543 -289.561404) (xy 179.356414 -289.604981) (xy 179.371998 -289.651662) (xy 179.379893 -289.700239)
			(xy 179.380388 -289.724846) (xy 179.719236 -289.724846) (xy 179.723196 -289.675792) (xy 179.734973 -289.628008)
			(xy 179.754264 -289.582732) (xy 179.780567 -289.541136) (xy 179.813202 -289.504299) (xy 179.851323 -289.473174)
			(xy 179.893944 -289.448567) (xy 179.93996 -289.431115) (xy 179.988179 -289.421271) (xy 180.037354 -289.41929)
			(xy 180.086209 -289.425222) (xy 180.13348 -289.438914) (xy 180.177942 -289.460012) (xy 180.218445 -289.487968)
			(xy 180.253938 -289.52206) (xy 180.283503 -289.561404) (xy 180.306374 -289.604981) (xy 180.321958 -289.651662)
			(xy 180.329853 -289.700239) (xy 180.330348 -289.724846) (xy 180.669196 -289.724846) (xy 180.673156 -289.675792)
			(xy 180.684933 -289.628008) (xy 180.704224 -289.582732) (xy 180.730527 -289.541136) (xy 180.763162 -289.504299)
			(xy 180.801283 -289.473174) (xy 180.843904 -289.448567) (xy 180.88992 -289.431115) (xy 180.938139 -289.421271)
			(xy 180.987314 -289.41929) (xy 181.036169 -289.425222) (xy 181.08344 -289.438914) (xy 181.127902 -289.460012)
			(xy 181.168405 -289.487968) (xy 181.203898 -289.52206) (xy 181.233463 -289.561404) (xy 181.256334 -289.604981)
			(xy 181.271918 -289.651662) (xy 181.279813 -289.700239) (xy 181.280308 -289.724846) (xy 181.619156 -289.724846)
			(xy 181.623116 -289.675792) (xy 181.634893 -289.628008) (xy 181.654184 -289.582732) (xy 181.680487 -289.541136)
			(xy 181.713122 -289.504299) (xy 181.751243 -289.473174) (xy 181.793864 -289.448567) (xy 181.83988 -289.431115)
			(xy 181.888099 -289.421271) (xy 181.937274 -289.41929) (xy 181.986129 -289.425222) (xy 182.0334 -289.438914)
			(xy 182.077862 -289.460012) (xy 182.118365 -289.487968) (xy 182.153858 -289.52206) (xy 182.183423 -289.561404)
			(xy 182.206294 -289.604981) (xy 182.221878 -289.651662) (xy 182.229773 -289.700239) (xy 182.230268 -289.724846)
			(xy 182.569116 -289.724846) (xy 182.573076 -289.675792) (xy 182.584853 -289.628008) (xy 182.604144 -289.582732)
			(xy 182.630447 -289.541136) (xy 182.663082 -289.504299) (xy 182.701203 -289.473174) (xy 182.743824 -289.448567)
			(xy 182.78984 -289.431115) (xy 182.838059 -289.421271) (xy 182.887234 -289.41929) (xy 182.936089 -289.425222)
			(xy 182.98336 -289.438914) (xy 183.027822 -289.460012) (xy 183.068325 -289.487968) (xy 183.103818 -289.52206)
			(xy 183.133383 -289.561404) (xy 183.156254 -289.604981) (xy 183.171838 -289.651662) (xy 183.179733 -289.700239)
			(xy 183.180228 -289.724846) (xy 183.519076 -289.724846) (xy 183.523036 -289.675792) (xy 183.534813 -289.628008)
			(xy 183.554104 -289.582732) (xy 183.580407 -289.541136) (xy 183.613042 -289.504299) (xy 183.651163 -289.473174)
			(xy 183.693784 -289.448567) (xy 183.7398 -289.431115) (xy 183.788019 -289.421271) (xy 183.837194 -289.41929)
			(xy 183.886049 -289.425222) (xy 183.93332 -289.438914) (xy 183.977782 -289.460012) (xy 184.018285 -289.487968)
			(xy 184.053778 -289.52206) (xy 184.083343 -289.561404) (xy 184.106214 -289.604981) (xy 184.121798 -289.651662)
			(xy 184.129693 -289.700239) (xy 184.130188 -289.724846) (xy 184.129693 -289.749453) (xy 184.121798 -289.79803)
			(xy 184.106214 -289.844711) (xy 184.083343 -289.888288) (xy 184.053778 -289.927632) (xy 184.018285 -289.961724)
			(xy 183.977782 -289.98968) (xy 183.93332 -290.010778) (xy 183.886049 -290.02447) (xy 183.837194 -290.030402)
			(xy 183.788019 -290.028421) (xy 183.7398 -290.018577) (xy 183.693784 -290.001125) (xy 183.651163 -289.976518)
			(xy 183.613042 -289.945393) (xy 183.580407 -289.908556) (xy 183.554104 -289.86696) (xy 183.534813 -289.821684)
			(xy 183.523036 -289.7739) (xy 183.519076 -289.724846) (xy 183.180228 -289.724846) (xy 183.179733 -289.749453)
			(xy 183.171838 -289.79803) (xy 183.156254 -289.844711) (xy 183.133383 -289.888288) (xy 183.103818 -289.927632)
			(xy 183.068325 -289.961724) (xy 183.027822 -289.98968) (xy 182.98336 -290.010778) (xy 182.936089 -290.02447)
			(xy 182.887234 -290.030402) (xy 182.838059 -290.028421) (xy 182.78984 -290.018577) (xy 182.743824 -290.001125)
			(xy 182.701203 -289.976518) (xy 182.663082 -289.945393) (xy 182.630447 -289.908556) (xy 182.604144 -289.86696)
			(xy 182.584853 -289.821684) (xy 182.573076 -289.7739) (xy 182.569116 -289.724846) (xy 182.230268 -289.724846)
			(xy 182.229773 -289.749453) (xy 182.221878 -289.79803) (xy 182.206294 -289.844711) (xy 182.183423 -289.888288)
			(xy 182.153858 -289.927632) (xy 182.118365 -289.961724) (xy 182.077862 -289.98968) (xy 182.0334 -290.010778)
			(xy 181.986129 -290.02447) (xy 181.937274 -290.030402) (xy 181.888099 -290.028421) (xy 181.83988 -290.018577)
			(xy 181.793864 -290.001125) (xy 181.751243 -289.976518) (xy 181.713122 -289.945393) (xy 181.680487 -289.908556)
			(xy 181.654184 -289.86696) (xy 181.634893 -289.821684) (xy 181.623116 -289.7739) (xy 181.619156 -289.724846)
			(xy 181.280308 -289.724846) (xy 181.279813 -289.749453) (xy 181.271918 -289.79803) (xy 181.256334 -289.844711)
			(xy 181.233463 -289.888288) (xy 181.203898 -289.927632) (xy 181.168405 -289.961724) (xy 181.127902 -289.98968)
			(xy 181.08344 -290.010778) (xy 181.036169 -290.02447) (xy 180.987314 -290.030402) (xy 180.938139 -290.028421)
			(xy 180.88992 -290.018577) (xy 180.843904 -290.001125) (xy 180.801283 -289.976518) (xy 180.763162 -289.945393)
			(xy 180.730527 -289.908556) (xy 180.704224 -289.86696) (xy 180.684933 -289.821684) (xy 180.673156 -289.7739)
			(xy 180.669196 -289.724846) (xy 180.330348 -289.724846) (xy 180.329853 -289.749453) (xy 180.321958 -289.79803)
			(xy 180.306374 -289.844711) (xy 180.283503 -289.888288) (xy 180.253938 -289.927632) (xy 180.218445 -289.961724)
			(xy 180.177942 -289.98968) (xy 180.13348 -290.010778) (xy 180.086209 -290.02447) (xy 180.037354 -290.030402)
			(xy 179.988179 -290.028421) (xy 179.93996 -290.018577) (xy 179.893944 -290.001125) (xy 179.851323 -289.976518)
			(xy 179.813202 -289.945393) (xy 179.780567 -289.908556) (xy 179.754264 -289.86696) (xy 179.734973 -289.821684)
			(xy 179.723196 -289.7739) (xy 179.719236 -289.724846) (xy 179.380388 -289.724846) (xy 179.379893 -289.749453)
			(xy 179.371998 -289.79803) (xy 179.356414 -289.844711) (xy 179.333543 -289.888288) (xy 179.303978 -289.927632)
			(xy 179.268485 -289.961724) (xy 179.227982 -289.98968) (xy 179.18352 -290.010778) (xy 179.136249 -290.02447)
			(xy 179.087394 -290.030402) (xy 179.038219 -290.028421) (xy 178.99 -290.018577) (xy 178.943984 -290.001125)
			(xy 178.901363 -289.976518) (xy 178.863242 -289.945393) (xy 178.830607 -289.908556) (xy 178.804304 -289.86696)
			(xy 178.785013 -289.821684) (xy 178.773236 -289.7739) (xy 178.769276 -289.724846) (xy 178.430174 -289.724846)
			(xy 178.429679 -289.749453) (xy 178.421784 -289.79803) (xy 178.4062 -289.844711) (xy 178.383329 -289.888288)
			(xy 178.353764 -289.927632) (xy 178.318271 -289.961724) (xy 178.277768 -289.98968) (xy 178.233306 -290.010778)
			(xy 178.186035 -290.02447) (xy 178.13718 -290.030402) (xy 178.088005 -290.028421) (xy 178.039786 -290.018577)
			(xy 177.99377 -290.001125) (xy 177.951149 -289.976518) (xy 177.913028 -289.945393) (xy 177.880393 -289.908556)
			(xy 177.85409 -289.86696) (xy 177.834799 -289.821684) (xy 177.823022 -289.7739) (xy 177.819062 -289.724846)
			(xy 177.480214 -289.724846) (xy 177.479719 -289.749453) (xy 177.471824 -289.79803) (xy 177.45624 -289.844711)
			(xy 177.433369 -289.888288) (xy 177.403804 -289.927632) (xy 177.368311 -289.961724) (xy 177.327808 -289.98968)
			(xy 177.283346 -290.010778) (xy 177.236075 -290.02447) (xy 177.18722 -290.030402) (xy 177.138045 -290.028421)
			(xy 177.089826 -290.018577) (xy 177.04381 -290.001125) (xy 177.001189 -289.976518) (xy 176.963068 -289.945393)
			(xy 176.930433 -289.908556) (xy 176.90413 -289.86696) (xy 176.884839 -289.821684) (xy 176.873062 -289.7739)
			(xy 176.869102 -289.724846) (xy 176.530254 -289.724846) (xy 176.529759 -289.749453) (xy 176.521864 -289.79803)
			(xy 176.50628 -289.844711) (xy 176.483409 -289.888288) (xy 176.453844 -289.927632) (xy 176.418351 -289.961724)
			(xy 176.377848 -289.98968) (xy 176.333386 -290.010778) (xy 176.286115 -290.02447) (xy 176.23726 -290.030402)
			(xy 176.188085 -290.028421) (xy 176.139866 -290.018577) (xy 176.09385 -290.001125) (xy 176.051229 -289.976518)
			(xy 176.013108 -289.945393) (xy 175.980473 -289.908556) (xy 175.95417 -289.86696) (xy 175.934879 -289.821684)
			(xy 175.923102 -289.7739) (xy 175.919142 -289.724846) (xy 174.630334 -289.724846) (xy 174.629839 -289.749453)
			(xy 174.621944 -289.79803) (xy 174.60636 -289.844711) (xy 174.583489 -289.888288) (xy 174.553924 -289.927632)
			(xy 174.518431 -289.961724) (xy 174.477928 -289.98968) (xy 174.433466 -290.010778) (xy 174.386195 -290.02447)
			(xy 174.33734 -290.030402) (xy 174.288165 -290.028421) (xy 174.239946 -290.018577) (xy 174.19393 -290.001125)
			(xy 174.151309 -289.976518) (xy 174.113188 -289.945393) (xy 174.080553 -289.908556) (xy 174.05425 -289.86696)
			(xy 174.034959 -289.821684) (xy 174.023182 -289.7739) (xy 174.019222 -289.724846) (xy 173.680374 -289.724846)
			(xy 173.679879 -289.749453) (xy 173.671984 -289.79803) (xy 173.6564 -289.844711) (xy 173.633529 -289.888288)
			(xy 173.603964 -289.927632) (xy 173.568471 -289.961724) (xy 173.527968 -289.98968) (xy 173.483506 -290.010778)
			(xy 173.436235 -290.02447) (xy 173.38738 -290.030402) (xy 173.338205 -290.028421) (xy 173.289986 -290.018577)
			(xy 173.24397 -290.001125) (xy 173.201349 -289.976518) (xy 173.163228 -289.945393) (xy 173.130593 -289.908556)
			(xy 173.10429 -289.86696) (xy 173.084999 -289.821684) (xy 173.073222 -289.7739) (xy 173.069262 -289.724846)
			(xy 172.73016 -289.724846) (xy 172.729665 -289.749453) (xy 172.72177 -289.79803) (xy 172.706186 -289.844711)
			(xy 172.683315 -289.888288) (xy 172.65375 -289.927632) (xy 172.618257 -289.961724) (xy 172.577754 -289.98968)
			(xy 172.533292 -290.010778) (xy 172.486021 -290.02447) (xy 172.437166 -290.030402) (xy 172.387991 -290.028421)
			(xy 172.339772 -290.018577) (xy 172.293756 -290.001125) (xy 172.251135 -289.976518) (xy 172.213014 -289.945393)
			(xy 172.180379 -289.908556) (xy 172.154076 -289.86696) (xy 172.134785 -289.821684) (xy 172.123008 -289.7739)
			(xy 172.119048 -289.724846) (xy 171.7802 -289.724846) (xy 171.779705 -289.749453) (xy 171.77181 -289.79803)
			(xy 171.756226 -289.844711) (xy 171.733355 -289.888288) (xy 171.70379 -289.927632) (xy 171.668297 -289.961724)
			(xy 171.627794 -289.98968) (xy 171.583332 -290.010778) (xy 171.536061 -290.02447) (xy 171.487206 -290.030402)
			(xy 171.438031 -290.028421) (xy 171.389812 -290.018577) (xy 171.343796 -290.001125) (xy 171.301175 -289.976518)
			(xy 171.263054 -289.945393) (xy 171.230419 -289.908556) (xy 171.204116 -289.86696) (xy 171.184825 -289.821684)
			(xy 171.173048 -289.7739) (xy 171.169088 -289.724846) (xy 170.83024 -289.724846) (xy 170.829745 -289.749453)
			(xy 170.82185 -289.79803) (xy 170.806266 -289.844711) (xy 170.783395 -289.888288) (xy 170.75383 -289.927632)
			(xy 170.718337 -289.961724) (xy 170.677834 -289.98968) (xy 170.633372 -290.010778) (xy 170.586101 -290.02447)
			(xy 170.537246 -290.030402) (xy 170.488071 -290.028421) (xy 170.439852 -290.018577) (xy 170.393836 -290.001125)
			(xy 170.351215 -289.976518) (xy 170.313094 -289.945393) (xy 170.280459 -289.908556) (xy 170.254156 -289.86696)
			(xy 170.234865 -289.821684) (xy 170.223088 -289.7739) (xy 170.219128 -289.724846) (xy 169.88028 -289.724846)
			(xy 169.879785 -289.749453) (xy 169.87189 -289.79803) (xy 169.856306 -289.844711) (xy 169.833435 -289.888288)
			(xy 169.80387 -289.927632) (xy 169.768377 -289.961724) (xy 169.727874 -289.98968) (xy 169.683412 -290.010778)
			(xy 169.636141 -290.02447) (xy 169.587286 -290.030402) (xy 169.538111 -290.028421) (xy 169.489892 -290.018577)
			(xy 169.443876 -290.001125) (xy 169.401255 -289.976518) (xy 169.363134 -289.945393) (xy 169.330499 -289.908556)
			(xy 169.304196 -289.86696) (xy 169.284905 -289.821684) (xy 169.273128 -289.7739) (xy 169.269168 -289.724846)
			(xy 168.93032 -289.724846) (xy 168.929825 -289.749453) (xy 168.92193 -289.79803) (xy 168.906346 -289.844711)
			(xy 168.883475 -289.888288) (xy 168.85391 -289.927632) (xy 168.818417 -289.961724) (xy 168.777914 -289.98968)
			(xy 168.733452 -290.010778) (xy 168.686181 -290.02447) (xy 168.637326 -290.030402) (xy 168.588151 -290.028421)
			(xy 168.539932 -290.018577) (xy 168.493916 -290.001125) (xy 168.451295 -289.976518) (xy 168.413174 -289.945393)
			(xy 168.380539 -289.908556) (xy 168.354236 -289.86696) (xy 168.334945 -289.821684) (xy 168.323168 -289.7739)
			(xy 168.319208 -289.724846) (xy 167.98036 -289.724846) (xy 167.979865 -289.749453) (xy 167.97197 -289.79803)
			(xy 167.956386 -289.844711) (xy 167.933515 -289.888288) (xy 167.90395 -289.927632) (xy 167.868457 -289.961724)
			(xy 167.827954 -289.98968) (xy 167.783492 -290.010778) (xy 167.736221 -290.02447) (xy 167.687366 -290.030402)
			(xy 167.638191 -290.028421) (xy 167.589972 -290.018577) (xy 167.543956 -290.001125) (xy 167.501335 -289.976518)
			(xy 167.463214 -289.945393) (xy 167.430579 -289.908556) (xy 167.404276 -289.86696) (xy 167.384985 -289.821684)
			(xy 167.373208 -289.7739) (xy 167.369248 -289.724846) (xy 167.0304 -289.724846) (xy 167.029905 -289.749453)
			(xy 167.02201 -289.79803) (xy 167.006426 -289.844711) (xy 166.983555 -289.888288) (xy 166.95399 -289.927632)
			(xy 166.918497 -289.961724) (xy 166.877994 -289.98968) (xy 166.833532 -290.010778) (xy 166.786261 -290.02447)
			(xy 166.737406 -290.030402) (xy 166.688231 -290.028421) (xy 166.640012 -290.018577) (xy 166.593996 -290.001125)
			(xy 166.551375 -289.976518) (xy 166.513254 -289.945393) (xy 166.480619 -289.908556) (xy 166.454316 -289.86696)
			(xy 166.435025 -289.821684) (xy 166.423248 -289.7739) (xy 166.419288 -289.724846) (xy 166.080186 -289.724846)
			(xy 166.079691 -289.749453) (xy 166.071796 -289.79803) (xy 166.056212 -289.844711) (xy 166.033341 -289.888288)
			(xy 166.003776 -289.927632) (xy 165.968283 -289.961724) (xy 165.92778 -289.98968) (xy 165.883318 -290.010778)
			(xy 165.836047 -290.02447) (xy 165.787192 -290.030402) (xy 165.738017 -290.028421) (xy 165.689798 -290.018577)
			(xy 165.643782 -290.001125) (xy 165.601161 -289.976518) (xy 165.56304 -289.945393) (xy 165.530405 -289.908556)
			(xy 165.504102 -289.86696) (xy 165.484811 -289.821684) (xy 165.473034 -289.7739) (xy 165.469074 -289.724846)
			(xy 165.130226 -289.724846) (xy 165.129704 -289.750101) (xy 165.121391 -289.799923) (xy 165.10499 -289.847697)
			(xy 165.080949 -289.89212) (xy 165.049925 -289.93198) (xy 165.012763 -289.96619) (xy 164.970477 -289.993816)
			(xy 164.924221 -290.014106) (xy 164.875256 -290.026506) (xy 164.824918 -290.030677) (xy 164.77458 -290.026506)
			(xy 164.725615 -290.014106) (xy 164.679359 -289.993816) (xy 164.637073 -289.96619) (xy 164.599911 -289.93198)
			(xy 164.568887 -289.89212) (xy 164.544846 -289.847697) (xy 164.528445 -289.799923) (xy 164.520132 -289.750101)
			(xy 164.51961 -289.724846) (xy 164.519864 -289.711384) (xy 164.520372 -289.700716) (xy 164.513006 -289.681412)
			(xy 164.45484 -289.62096) (xy 164.447388 -289.61391) (xy 164.428513 -289.60592) (xy 164.418264 -289.605466)
			(xy 164.281358 -289.605466) (xy 164.271093 -289.605997) (xy 164.252236 -289.614133) (xy 164.244782 -289.621214)
			(xy 164.194236 -289.673792) (xy 164.187394 -289.681599) (xy 164.180072 -289.701002) (xy 164.180012 -289.711384)
			(xy 164.180266 -289.724846) (xy 164.179744 -289.750101) (xy 164.171431 -289.799923) (xy 164.15503 -289.847697)
			(xy 164.130989 -289.89212) (xy 164.099965 -289.93198) (xy 164.062803 -289.96619) (xy 164.020517 -289.993816)
			(xy 163.974261 -290.014106) (xy 163.925296 -290.026506) (xy 163.874958 -290.030677) (xy 163.82462 -290.026506)
			(xy 163.775655 -290.014106) (xy 163.729399 -289.993816) (xy 163.687113 -289.96619) (xy 163.649951 -289.93198)
			(xy 163.618927 -289.89212) (xy 163.594886 -289.847697) (xy 163.578485 -289.799923) (xy 163.570172 -289.750101)
			(xy 163.56965 -289.724846) (xy 163.570135 -289.700708) (xy 163.577784 -289.65304) (xy 163.592837 -289.607169)
			(xy 163.614918 -289.564237) (xy 163.628832 -289.544506) (xy 163.633868 -289.536991) (xy 163.638801 -289.5196)
			(xy 163.637402 -289.501577) (xy 163.629845 -289.485155) (xy 163.623752 -289.478466) (xy 163.52266 -289.377374)
			(xy 163.515818 -289.371069) (xy 163.49889 -289.363384) (xy 163.48964 -289.362388) (xy 163.351464 -289.362388)
			(xy 163.341462 -289.361894) (xy 163.322985 -289.354227) (xy 163.308846 -289.340075) (xy 163.301197 -289.32159)
			(xy 163.300664 -289.311588) (xy 163.300664 -289.19424) (xy 163.300229 -289.184175) (xy 163.292495 -289.16559)
			(xy 163.285678 -289.158172) (xy 163.14801 -289.020504) (xy 163.111688 -289.016948) (xy 163.098734 -289.025584)
			(xy 163.098226 -289.026092) (xy 163.079025 -289.038843) (xy 163.037596 -289.059043) (xy 162.993602 -289.07279)
			(xy 162.948043 -289.079772) (xy 162.924998 -289.080194) (xy 162.901005 -289.079748) (xy 162.853611 -289.072241)
			(xy 162.807974 -289.057412) (xy 162.76522 -289.035626) (xy 162.726399 -289.00742) (xy 162.692469 -288.973488)
			(xy 162.664266 -288.934667) (xy 162.642482 -288.891911) (xy 162.627656 -288.846273) (xy 162.620151 -288.798879)
			(xy 162.61969 -288.774886) (xy 162.620133 -288.752115) (xy 162.626938 -288.707083) (xy 162.640351 -288.66356)
			(xy 162.660074 -288.622509) (xy 162.672522 -288.603436) (xy 162.678699 -288.593365) (xy 162.681952 -288.569994)
			(xy 162.674394 -288.547641) (xy 162.666426 -288.53892) (xy 162.229038 -288.101786) (xy 162.222497 -288.095816)
			(xy 162.206447 -288.088365) (xy 162.188818 -288.08684) (xy 162.171727 -288.091425) (xy 162.164268 -288.096198)
			(xy 162.164014 -288.096198) (xy 162.142605 -288.110535) (xy 162.096287 -288.133107) (xy 162.04703 -288.148221)
			(xy 161.996024 -288.155512) (xy 161.944505 -288.154805) (xy 161.893719 -288.146115) (xy 161.844896 -288.129653)
			(xy 161.799216 -288.105819) (xy 161.757786 -288.075187) (xy 161.721608 -288.038501) (xy 161.691558 -287.996647)
			(xy 161.668363 -287.950639) (xy 161.652585 -287.901591) (xy 161.644605 -287.850688) (xy 161.644076 -287.824926)
			(xy 161.644076 -287.824672) (xy 161.64423 -287.810954) (xy 161.646518 -287.783614) (xy 161.648648 -287.770062)
			(xy 161.648902 -287.768792) (xy 161.648902 -287.76803) (xy 161.649664 -287.763204) (xy 161.649918 -287.762442)
			(xy 161.64687 -287.752028) (xy 161.64523 -287.746894) (xy 161.640107 -287.737416) (xy 161.63671 -287.733232)
			(xy 161.585148 -287.67278) (xy 161.578346 -287.666071) (xy 161.561114 -287.65785) (xy 161.55162 -287.656778)
			(xy 161.54781 -287.656524) (xy 161.451798 -287.656524) (xy 161.448242 -287.656524) (xy 161.438747 -287.657588)
			(xy 161.421525 -287.665824) (xy 161.414714 -287.672526) (xy 161.404808 -287.68421) (xy 161.3662 -287.729168)
			(xy 161.362898 -287.732978) (xy 161.359493 -287.737158) (xy 161.354358 -287.746633) (xy 161.352738 -287.751774)
			(xy 161.34969 -287.762188) (xy 161.350452 -287.767014) (xy 161.350706 -287.768538) (xy 161.352974 -287.78246)
			(xy 161.355393 -287.810567) (xy 161.355532 -287.824672) (xy 161.355532 -287.824926) (xy 161.355022 -287.850913)
			(xy 161.346892 -287.902248) (xy 161.330831 -287.951678) (xy 161.307235 -287.997988) (xy 161.276685 -288.040036)
			(xy 161.239934 -288.076787) (xy 161.197886 -288.107337) (xy 161.151576 -288.130933) (xy 161.102146 -288.146994)
			(xy 161.050811 -288.155124) (xy 160.998837 -288.155124) (xy 160.947502 -288.146994) (xy 160.898072 -288.130933)
			(xy 160.851762 -288.107337) (xy 160.809714 -288.076787) (xy 160.772963 -288.040036) (xy 160.742413 -287.997988)
			(xy 160.718817 -287.951678) (xy 160.702756 -287.902248) (xy 160.694626 -287.850913) (xy 160.694116 -287.824926)
			(xy 160.694116 -287.824672) (xy 160.694271 -287.810954) (xy 160.696559 -287.783614) (xy 160.698688 -287.770062)
			(xy 160.698942 -287.768792) (xy 160.698942 -287.76803) (xy 160.699704 -287.763204) (xy 160.699958 -287.762442)
			(xy 160.69691 -287.752028) (xy 160.695268 -287.746896) (xy 160.69014 -287.737421) (xy 160.68675 -287.733232)
			(xy 160.635188 -287.67278) (xy 160.628388 -287.666065) (xy 160.611158 -287.657831) (xy 160.60166 -287.656778)
			(xy 160.59785 -287.656524) (xy 157.89148 -287.656524) (xy 157.863504 -287.655952) (xy 157.808247 -287.647159)
			(xy 157.755042 -287.62984) (xy 157.705197 -287.60442) (xy 157.659937 -287.571524) (xy 157.639766 -287.55213)
			(xy 157.55366 -287.466278) (xy 157.544592 -287.458235) (xy 157.521511 -287.450956) (xy 157.509464 -287.452308)
			(xy 157.50794 -287.452562) (xy 157.501913 -287.453934) (xy 157.490731 -287.459195) (xy 157.485842 -287.462976)
			(xy 157.481016 -287.466786) (xy 157.47365 -287.476692) (xy 157.450028 -287.533842) (xy 157.447742 -287.539684)
			(xy 157.445032 -287.54847) (xy 157.44542 -287.566837) (xy 157.448504 -287.575498) (xy 157.449012 -287.577022)
			(xy 157.450659 -287.58053) (xy 157.454871 -287.587034) (xy 157.457394 -287.589976) (xy 157.475634 -287.608719)
			(xy 157.506554 -287.650898) (xy 157.530441 -287.697422) (xy 157.546698 -287.747129) (xy 157.55492 -287.798777)
			(xy 157.555438 -287.824926) (xy 157.554928 -287.850913) (xy 157.546798 -287.902248) (xy 157.530737 -287.951678)
			(xy 157.507141 -287.997988) (xy 157.476591 -288.040036) (xy 157.43984 -288.076787) (xy 157.397792 -288.107337)
			(xy 157.351482 -288.130933) (xy 157.302052 -288.146994) (xy 157.250717 -288.155124) (xy 157.198743 -288.155124)
			(xy 157.147408 -288.146994) (xy 157.097978 -288.130933) (xy 157.051668 -288.107337) (xy 157.00962 -288.076787)
			(xy 156.972869 -288.040036) (xy 156.942319 -287.997988) (xy 156.918723 -287.951678) (xy 156.902662 -287.902248)
			(xy 156.894532 -287.850913) (xy 156.894022 -287.824926) (xy 156.894525 -287.799104) (xy 156.902568 -287.748088)
			(xy 156.918446 -287.698945) (xy 156.941774 -287.652868) (xy 156.971983 -287.61098) (xy 156.98978 -287.592262)
			(xy 156.990034 -287.592008) (xy 156.995007 -287.586574) (xy 157.001837 -287.573532) (xy 157.003496 -287.566354)
			(xy 157.003496 -287.565846) (xy 157.004608 -287.559226) (xy 157.003716 -287.545837) (xy 157.001718 -287.53943)
			(xy 156.983684 -287.495996) (xy 156.964634 -287.450276) (xy 156.960558 -287.441538) (xy 156.947123 -287.42773)
			(xy 156.929536 -287.419865) (xy 156.91993 -287.419034) (xy 154.681682 -287.419034) (xy 154.673323 -287.419411)
			(xy 154.657507 -287.424845) (xy 154.650694 -287.429702) (xy 154.645645 -287.433893) (xy 154.63767 -287.444307)
			(xy 154.634946 -287.450276) (xy 154.631898 -287.457388) (xy 154.616912 -287.49371) (xy 154.598116 -287.539176)
			(xy 154.595287 -287.548064) (xy 154.595539 -287.566697) (xy 154.598624 -287.575498) (xy 154.599132 -287.577022)
			(xy 154.600743 -287.580448) (xy 154.604821 -287.586826) (xy 154.60726 -287.589722) (xy 154.609292 -287.591754)
			(xy 154.627204 -287.610462) (xy 154.657567 -287.652418) (xy 154.681011 -287.698598) (xy 154.696959 -287.747872)
			(xy 154.705023 -287.799031) (xy 154.705558 -287.824926) (xy 154.705048 -287.850913) (xy 154.696918 -287.902248)
			(xy 154.680857 -287.951678) (xy 154.657261 -287.997988) (xy 154.626711 -288.040036) (xy 154.58996 -288.076787)
			(xy 154.547912 -288.107337) (xy 154.501602 -288.130933) (xy 154.452172 -288.146994) (xy 154.400837 -288.155124)
			(xy 154.348863 -288.155124) (xy 154.297528 -288.146994) (xy 154.248098 -288.130933) (xy 154.201788 -288.107337)
			(xy 154.15974 -288.076787) (xy 154.122989 -288.040036) (xy 154.092439 -287.997988) (xy 154.068843 -287.951678)
			(xy 154.052782 -287.902248) (xy 154.044652 -287.850913) (xy 154.044142 -287.824926) (xy 154.044645 -287.799104)
			(xy 154.052689 -287.748089) (xy 154.068568 -287.698946) (xy 154.091896 -287.65287) (xy 154.122106 -287.610983)
			(xy 154.1399 -287.592262) (xy 154.140154 -287.592008) (xy 154.145126 -287.586573) (xy 154.151953 -287.57353)
			(xy 154.153616 -287.566354) (xy 154.153616 -287.565846) (xy 154.15473 -287.559227) (xy 154.153836 -287.545838)
			(xy 154.151838 -287.53943) (xy 154.133804 -287.495996) (xy 154.114754 -287.450276) (xy 154.110679 -287.441536)
			(xy 154.097245 -287.427723) (xy 154.079658 -287.41985) (xy 154.07005 -287.419034) (xy 153.731468 -287.419034)
			(xy 153.723109 -287.419413) (xy 153.707296 -287.424851) (xy 153.70048 -287.429702) (xy 153.695425 -287.433888)
			(xy 153.687437 -287.444297) (xy 153.684732 -287.450276) (xy 153.681684 -287.457388) (xy 153.666698 -287.49371)
			(xy 153.647902 -287.539176) (xy 153.645073 -287.548064) (xy 153.645325 -287.566697) (xy 153.64841 -287.575498)
			(xy 153.648918 -287.577022) (xy 153.650531 -287.580447) (xy 153.654615 -287.58682) (xy 153.657046 -287.589722)
			(xy 153.659078 -287.591754) (xy 153.676991 -287.610461) (xy 153.707355 -287.652417) (xy 153.7308 -287.698597)
			(xy 153.746749 -287.747871) (xy 153.754813 -287.79903) (xy 153.755344 -287.824926) (xy 153.754834 -287.850913)
			(xy 153.746704 -287.902248) (xy 153.730643 -287.951678) (xy 153.707047 -287.997988) (xy 153.676497 -288.040036)
			(xy 153.639746 -288.076787) (xy 153.597698 -288.107337) (xy 153.551388 -288.130933) (xy 153.501958 -288.146994)
			(xy 153.450623 -288.155124) (xy 153.398649 -288.155124) (xy 153.347314 -288.146994) (xy 153.297884 -288.130933)
			(xy 153.251574 -288.107337) (xy 153.209526 -288.076787) (xy 153.172775 -288.040036) (xy 153.142225 -287.997988)
			(xy 153.118629 -287.951678) (xy 153.102568 -287.902248) (xy 153.094438 -287.850913) (xy 153.093928 -287.824926)
			(xy 153.094431 -287.799104) (xy 153.102474 -287.748089) (xy 153.118353 -287.698945) (xy 153.141681 -287.652869)
			(xy 153.17189 -287.610981) (xy 153.189686 -287.592262) (xy 153.18994 -287.592008) (xy 153.194913 -287.586574)
			(xy 153.201742 -287.573531) (xy 153.203402 -287.566354) (xy 153.203402 -287.565846) (xy 153.204514 -287.559226)
			(xy 153.203622 -287.545837) (xy 153.201624 -287.53943) (xy 153.18359 -287.495996) (xy 153.16454 -287.450276)
			(xy 153.160464 -287.441538) (xy 153.14703 -287.427728) (xy 153.129443 -287.41986) (xy 153.119836 -287.419034)
			(xy 152.781508 -287.419034) (xy 152.773153 -287.419423) (xy 152.757351 -287.424874) (xy 152.75052 -287.429702)
			(xy 152.745469 -287.433891) (xy 152.73749 -287.444304) (xy 152.734772 -287.450276) (xy 152.731724 -287.457388)
			(xy 152.716738 -287.49371) (xy 152.697942 -287.539176) (xy 152.695112 -287.548063) (xy 152.695364 -287.566697)
			(xy 152.69845 -287.575498) (xy 152.698958 -287.577022) (xy 152.700569 -287.580448) (xy 152.70465 -287.586824)
			(xy 152.707086 -287.589722) (xy 152.709118 -287.591754) (xy 152.727029 -287.610462) (xy 152.75739 -287.652419)
			(xy 152.780831 -287.6986) (xy 152.796779 -287.747873) (xy 152.804841 -287.799031) (xy 152.805384 -287.824926)
			(xy 152.804874 -287.850913) (xy 152.796744 -287.902248) (xy 152.780683 -287.951678) (xy 152.757087 -287.997988)
			(xy 152.726537 -288.040036) (xy 152.689786 -288.076787) (xy 152.647738 -288.107337) (xy 152.601428 -288.130933)
			(xy 152.551998 -288.146994) (xy 152.500663 -288.155124) (xy 152.448689 -288.155124) (xy 152.397354 -288.146994)
			(xy 152.347924 -288.130933) (xy 152.301614 -288.107337) (xy 152.259566 -288.076787) (xy 152.222815 -288.040036)
			(xy 152.192265 -287.997988) (xy 152.168669 -287.951678) (xy 152.152608 -287.902248) (xy 152.144478 -287.850913)
			(xy 152.143968 -287.824926) (xy 152.144471 -287.799103) (xy 152.152513 -287.748087) (xy 152.168389 -287.698942)
			(xy 152.191714 -287.652863) (xy 152.22192 -287.610971) (xy 152.239726 -287.592262) (xy 152.23998 -287.592008)
			(xy 152.244958 -287.586577) (xy 152.251795 -287.573535) (xy 152.253442 -287.566354) (xy 152.253442 -287.565846)
			(xy 152.254555 -287.559227) (xy 152.253662 -287.545838) (xy 152.251664 -287.53943) (xy 152.23363 -287.495996)
			(xy 152.21458 -287.450276) (xy 152.210506 -287.441533) (xy 152.197074 -287.427713) (xy 152.179487 -287.419832)
			(xy 152.169876 -287.419034) (xy 150.323296 -287.419034) (xy 150.312882 -287.420304) (xy 150.2918 -287.425638)
			(xy 150.286212 -287.428686) (xy 150.25799 -287.443374) (xy 150.197874 -287.464191) (xy 150.135141 -287.474765)
			(xy 150.103332 -287.475422) (xy 150.09368 -287.475422) (xy 150.064202 -287.474107) (xy 150.006154 -287.463518)
			(xy 149.97811 -287.45434) (xy 149.977602 -287.45434) (xy 149.960838 -287.447736) (xy 149.96033 -287.447736)
			(xy 149.950195 -287.443536) (xy 149.930371 -287.434131) (xy 149.920706 -287.42894) (xy 149.917912 -287.427416)
			(xy 149.914864 -287.425892) (xy 149.895052 -287.420812) (xy 149.882352 -287.419034) (xy 149.436836 -287.419034)
			(xy 149.426422 -287.420304) (xy 149.40534 -287.425638) (xy 149.399752 -287.428686) (xy 149.37153 -287.443377)
			(xy 149.311415 -287.4642) (xy 149.248681 -287.474781) (xy 149.216872 -287.475422) (xy 149.20722 -287.475422)
			(xy 149.177741 -287.47411) (xy 149.119691 -287.463527) (xy 149.09165 -287.45434) (xy 149.091142 -287.45434)
			(xy 149.074378 -287.447736) (xy 149.07387 -287.447736) (xy 149.063734 -287.443537) (xy 149.04391 -287.434134)
			(xy 149.034246 -287.42894) (xy 149.031452 -287.427416) (xy 149.028404 -287.425892) (xy 149.008592 -287.420812)
			(xy 148.995892 -287.419034) (xy 148.039836 -287.419034) (xy 148.029422 -287.420304) (xy 148.00834 -287.425638)
			(xy 148.002752 -287.428686) (xy 147.97453 -287.443377) (xy 147.914415 -287.4642) (xy 147.851681 -287.474781)
			(xy 147.819872 -287.475422) (xy 147.81022 -287.475422) (xy 147.780741 -287.47411) (xy 147.722691 -287.463527)
			(xy 147.69465 -287.45434) (xy 147.694142 -287.45434) (xy 147.677378 -287.447736) (xy 147.67687 -287.447736)
			(xy 147.666734 -287.443537) (xy 147.64691 -287.434134) (xy 147.637246 -287.42894) (xy 147.634452 -287.427416)
			(xy 147.631404 -287.425892) (xy 147.611592 -287.420812) (xy 147.598892 -287.419034) (xy 136.907524 -287.419034)
			(xy 136.901515 -287.419204) (xy 136.889837 -287.422035) (xy 136.88441 -287.424622) (xy 136.880935 -287.426461)
			(xy 136.874555 -287.431053) (xy 136.87171 -287.433766) (xy 136.364726 -287.94075) (xy 136.361205 -287.94448)
			(xy 136.355576 -287.953055) (xy 136.35355 -287.957768) (xy 136.349994 -287.966404) (xy 136.349994 -288.230056)
			(xy 141.911576 -288.230056) (xy 141.915647 -288.174434) (xy 141.927773 -288.119997) (xy 141.947696 -288.067906)
			(xy 141.974992 -288.019271) (xy 142.009078 -287.975128) (xy 142.049227 -287.936419) (xy 142.094585 -287.903968)
			(xy 142.144185 -287.878467) (xy 142.196969 -287.86046) (xy 142.251812 -287.85033) (xy 142.307546 -287.848293)
			(xy 142.362983 -287.854393) (xy 142.41694 -287.868499) (xy 142.468269 -287.890311) (xy 142.515875 -287.919365)
			(xy 142.558743 -287.95504) (xy 142.59596 -287.996577) (xy 142.626733 -288.04309) (xy 142.650405 -288.093587)
			(xy 142.666473 -288.146994) (xy 142.674593 -288.20217) (xy 142.675102 -288.230056) (xy 143.396714 -288.230056)
			(xy 143.400785 -288.174434) (xy 143.412911 -288.119997) (xy 143.432834 -288.067906) (xy 143.46013 -288.019271)
			(xy 143.494216 -287.975128) (xy 143.534365 -287.936419) (xy 143.579723 -287.903968) (xy 143.629323 -287.878467)
			(xy 143.682107 -287.86046) (xy 143.73695 -287.85033) (xy 143.792684 -287.848293) (xy 143.848121 -287.854393)
			(xy 143.902078 -287.868499) (xy 143.953407 -287.890311) (xy 144.001013 -287.919365) (xy 144.043881 -287.95504)
			(xy 144.081098 -287.996577) (xy 144.111871 -288.04309) (xy 144.135543 -288.093587) (xy 144.151611 -288.146994)
			(xy 144.159731 -288.20217) (xy 144.16024 -288.230056) (xy 144.159731 -288.257942) (xy 144.151611 -288.313118)
			(xy 144.135543 -288.366525) (xy 144.111871 -288.417022) (xy 144.081098 -288.463535) (xy 144.043881 -288.505072)
			(xy 144.001013 -288.540747) (xy 143.953407 -288.569801) (xy 143.902078 -288.591613) (xy 143.848121 -288.605719)
			(xy 143.792684 -288.611819) (xy 143.73695 -288.609782) (xy 143.682107 -288.599652) (xy 143.629323 -288.581645)
			(xy 143.579723 -288.556144) (xy 143.534365 -288.523693) (xy 143.494216 -288.484984) (xy 143.46013 -288.440841)
			(xy 143.432834 -288.392206) (xy 143.412911 -288.340115) (xy 143.400785 -288.285678) (xy 143.396714 -288.230056)
			(xy 142.675102 -288.230056) (xy 142.674593 -288.257942) (xy 142.666473 -288.313118) (xy 142.650405 -288.366525)
			(xy 142.626733 -288.417022) (xy 142.59596 -288.463535) (xy 142.558743 -288.505072) (xy 142.515875 -288.540747)
			(xy 142.468269 -288.569801) (xy 142.41694 -288.591613) (xy 142.362983 -288.605719) (xy 142.307546 -288.611819)
			(xy 142.251812 -288.609782) (xy 142.196969 -288.599652) (xy 142.144185 -288.581645) (xy 142.094585 -288.556144)
			(xy 142.049227 -288.523693) (xy 142.009078 -288.484984) (xy 141.974992 -288.440841) (xy 141.947696 -288.392206)
			(xy 141.927773 -288.340115) (xy 141.915647 -288.285678) (xy 141.911576 -288.230056) (xy 136.349994 -288.230056)
			(xy 136.349994 -288.774886) (xy 152.169126 -288.774886) (xy 152.173086 -288.725832) (xy 152.184863 -288.678048)
			(xy 152.204154 -288.632772) (xy 152.230457 -288.591176) (xy 152.263092 -288.554339) (xy 152.301213 -288.523214)
			(xy 152.343834 -288.498607) (xy 152.38985 -288.481155) (xy 152.438069 -288.471311) (xy 152.487244 -288.46933)
			(xy 152.536099 -288.475262) (xy 152.58337 -288.488954) (xy 152.627832 -288.510052) (xy 152.668335 -288.538008)
			(xy 152.703828 -288.5721) (xy 152.733393 -288.611444) (xy 152.756264 -288.655021) (xy 152.771848 -288.701702)
			(xy 152.779743 -288.750279) (xy 152.780238 -288.774886) (xy 153.119086 -288.774886) (xy 153.123046 -288.725832)
			(xy 153.134823 -288.678048) (xy 153.154114 -288.632772) (xy 153.180417 -288.591176) (xy 153.213052 -288.554339)
			(xy 153.251173 -288.523214) (xy 153.293794 -288.498607) (xy 153.33981 -288.481155) (xy 153.388029 -288.471311)
			(xy 153.437204 -288.46933) (xy 153.486059 -288.475262) (xy 153.53333 -288.488954) (xy 153.577792 -288.510052)
			(xy 153.618295 -288.538008) (xy 153.653788 -288.5721) (xy 153.683353 -288.611444) (xy 153.706224 -288.655021)
			(xy 153.721808 -288.701702) (xy 153.729703 -288.750279) (xy 153.730198 -288.774886) (xy 154.0693 -288.774886)
			(xy 154.07326 -288.725832) (xy 154.085037 -288.678048) (xy 154.104328 -288.632772) (xy 154.130631 -288.591176)
			(xy 154.163266 -288.554339) (xy 154.201387 -288.523214) (xy 154.244008 -288.498607) (xy 154.290024 -288.481155)
			(xy 154.338243 -288.471311) (xy 154.387418 -288.46933) (xy 154.436273 -288.475262) (xy 154.483544 -288.488954)
			(xy 154.528006 -288.510052) (xy 154.568509 -288.538008) (xy 154.604002 -288.5721) (xy 154.633567 -288.611444)
			(xy 154.656438 -288.655021) (xy 154.672022 -288.701702) (xy 154.679917 -288.750279) (xy 154.680412 -288.774886)
			(xy 158.8191 -288.774886) (xy 158.82306 -288.725832) (xy 158.834837 -288.678048) (xy 158.854128 -288.632772)
			(xy 158.880431 -288.591176) (xy 158.913066 -288.554339) (xy 158.951187 -288.523214) (xy 158.993808 -288.498607)
			(xy 159.039824 -288.481155) (xy 159.088043 -288.471311) (xy 159.137218 -288.46933) (xy 159.186073 -288.475262)
			(xy 159.233344 -288.488954) (xy 159.277806 -288.510052) (xy 159.318309 -288.538008) (xy 159.353802 -288.5721)
			(xy 159.383367 -288.611444) (xy 159.406238 -288.655021) (xy 159.421822 -288.701702) (xy 159.429717 -288.750279)
			(xy 159.430212 -288.774886) (xy 159.76906 -288.774886) (xy 159.77302 -288.725832) (xy 159.784797 -288.678048)
			(xy 159.804088 -288.632772) (xy 159.830391 -288.591176) (xy 159.863026 -288.554339) (xy 159.901147 -288.523214)
			(xy 159.943768 -288.498607) (xy 159.989784 -288.481155) (xy 160.038003 -288.471311) (xy 160.087178 -288.46933)
			(xy 160.136033 -288.475262) (xy 160.183304 -288.488954) (xy 160.227766 -288.510052) (xy 160.268269 -288.538008)
			(xy 160.303762 -288.5721) (xy 160.333327 -288.611444) (xy 160.356198 -288.655021) (xy 160.371782 -288.701702)
			(xy 160.379677 -288.750279) (xy 160.380172 -288.774886) (xy 160.719274 -288.774886) (xy 160.723234 -288.725832)
			(xy 160.735011 -288.678048) (xy 160.754302 -288.632772) (xy 160.780605 -288.591176) (xy 160.81324 -288.554339)
			(xy 160.851361 -288.523214) (xy 160.893982 -288.498607) (xy 160.939998 -288.481155) (xy 160.988217 -288.471311)
			(xy 161.037392 -288.46933) (xy 161.086247 -288.475262) (xy 161.133518 -288.488954) (xy 161.17798 -288.510052)
			(xy 161.218483 -288.538008) (xy 161.253976 -288.5721) (xy 161.283541 -288.611444) (xy 161.306412 -288.655021)
			(xy 161.321996 -288.701702) (xy 161.329891 -288.750279) (xy 161.330386 -288.774886) (xy 161.669234 -288.774886)
			(xy 161.673194 -288.725832) (xy 161.684971 -288.678048) (xy 161.704262 -288.632772) (xy 161.730565 -288.591176)
			(xy 161.7632 -288.554339) (xy 161.801321 -288.523214) (xy 161.843942 -288.498607) (xy 161.889958 -288.481155)
			(xy 161.938177 -288.471311) (xy 161.987352 -288.46933) (xy 162.036207 -288.475262) (xy 162.083478 -288.488954)
			(xy 162.12794 -288.510052) (xy 162.168443 -288.538008) (xy 162.203936 -288.5721) (xy 162.233501 -288.611444)
			(xy 162.256372 -288.655021) (xy 162.271956 -288.701702) (xy 162.279851 -288.750279) (xy 162.280346 -288.774886)
			(xy 162.279851 -288.799493) (xy 162.271956 -288.84807) (xy 162.256372 -288.894751) (xy 162.233501 -288.938328)
			(xy 162.203936 -288.977672) (xy 162.168443 -289.011764) (xy 162.12794 -289.03972) (xy 162.083478 -289.060818)
			(xy 162.036207 -289.07451) (xy 161.987352 -289.080442) (xy 161.938177 -289.078461) (xy 161.889958 -289.068617)
			(xy 161.843942 -289.051165) (xy 161.801321 -289.026558) (xy 161.7632 -288.995433) (xy 161.730565 -288.958596)
			(xy 161.704262 -288.917) (xy 161.684971 -288.871724) (xy 161.673194 -288.82394) (xy 161.669234 -288.774886)
			(xy 161.330386 -288.774886) (xy 161.329891 -288.799493) (xy 161.321996 -288.84807) (xy 161.306412 -288.894751)
			(xy 161.283541 -288.938328) (xy 161.253976 -288.977672) (xy 161.218483 -289.011764) (xy 161.17798 -289.03972)
			(xy 161.133518 -289.060818) (xy 161.086247 -289.07451) (xy 161.037392 -289.080442) (xy 160.988217 -289.078461)
			(xy 160.939998 -289.068617) (xy 160.893982 -289.051165) (xy 160.851361 -289.026558) (xy 160.81324 -288.995433)
			(xy 160.780605 -288.958596) (xy 160.754302 -288.917) (xy 160.735011 -288.871724) (xy 160.723234 -288.82394)
			(xy 160.719274 -288.774886) (xy 160.380172 -288.774886) (xy 160.379677 -288.799493) (xy 160.371782 -288.84807)
			(xy 160.356198 -288.894751) (xy 160.333327 -288.938328) (xy 160.303762 -288.977672) (xy 160.268269 -289.011764)
			(xy 160.227766 -289.03972) (xy 160.183304 -289.060818) (xy 160.136033 -289.07451) (xy 160.087178 -289.080442)
			(xy 160.038003 -289.078461) (xy 159.989784 -289.068617) (xy 159.943768 -289.051165) (xy 159.901147 -289.026558)
			(xy 159.863026 -288.995433) (xy 159.830391 -288.958596) (xy 159.804088 -288.917) (xy 159.784797 -288.871724)
			(xy 159.77302 -288.82394) (xy 159.76906 -288.774886) (xy 159.430212 -288.774886) (xy 159.429717 -288.799493)
			(xy 159.421822 -288.84807) (xy 159.406238 -288.894751) (xy 159.383367 -288.938328) (xy 159.353802 -288.977672)
			(xy 159.318309 -289.011764) (xy 159.277806 -289.03972) (xy 159.233344 -289.060818) (xy 159.186073 -289.07451)
			(xy 159.137218 -289.080442) (xy 159.088043 -289.078461) (xy 159.039824 -289.068617) (xy 158.993808 -289.051165)
			(xy 158.951187 -289.026558) (xy 158.913066 -288.995433) (xy 158.880431 -288.958596) (xy 158.854128 -288.917)
			(xy 158.834837 -288.871724) (xy 158.82306 -288.82394) (xy 158.8191 -288.774886) (xy 154.680412 -288.774886)
			(xy 154.679917 -288.799493) (xy 154.672022 -288.84807) (xy 154.656438 -288.894751) (xy 154.633567 -288.938328)
			(xy 154.604002 -288.977672) (xy 154.568509 -289.011764) (xy 154.528006 -289.03972) (xy 154.483544 -289.060818)
			(xy 154.436273 -289.07451) (xy 154.387418 -289.080442) (xy 154.338243 -289.078461) (xy 154.290024 -289.068617)
			(xy 154.244008 -289.051165) (xy 154.201387 -289.026558) (xy 154.163266 -288.995433) (xy 154.130631 -288.958596)
			(xy 154.104328 -288.917) (xy 154.085037 -288.871724) (xy 154.07326 -288.82394) (xy 154.0693 -288.774886)
			(xy 153.730198 -288.774886) (xy 153.729703 -288.799493) (xy 153.721808 -288.84807) (xy 153.706224 -288.894751)
			(xy 153.683353 -288.938328) (xy 153.653788 -288.977672) (xy 153.618295 -289.011764) (xy 153.577792 -289.03972)
			(xy 153.53333 -289.060818) (xy 153.486059 -289.07451) (xy 153.437204 -289.080442) (xy 153.388029 -289.078461)
			(xy 153.33981 -289.068617) (xy 153.293794 -289.051165) (xy 153.251173 -289.026558) (xy 153.213052 -288.995433)
			(xy 153.180417 -288.958596) (xy 153.154114 -288.917) (xy 153.134823 -288.871724) (xy 153.123046 -288.82394)
			(xy 153.119086 -288.774886) (xy 152.780238 -288.774886) (xy 152.779743 -288.799493) (xy 152.771848 -288.84807)
			(xy 152.756264 -288.894751) (xy 152.733393 -288.938328) (xy 152.703828 -288.977672) (xy 152.668335 -289.011764)
			(xy 152.627832 -289.03972) (xy 152.58337 -289.060818) (xy 152.536099 -289.07451) (xy 152.487244 -289.080442)
			(xy 152.438069 -289.078461) (xy 152.38985 -289.068617) (xy 152.343834 -289.051165) (xy 152.301213 -289.026558)
			(xy 152.263092 -288.995433) (xy 152.230457 -288.958596) (xy 152.204154 -288.917) (xy 152.184863 -288.871724)
			(xy 152.173086 -288.82394) (xy 152.169126 -288.774886) (xy 136.349994 -288.774886) (xy 136.349994 -289.532314)
			(xy 141.911576 -289.532314) (xy 141.915647 -289.476692) (xy 141.927773 -289.422255) (xy 141.947696 -289.370164)
			(xy 141.974992 -289.321529) (xy 142.009078 -289.277386) (xy 142.049227 -289.238677) (xy 142.094585 -289.206226)
			(xy 142.144185 -289.180725) (xy 142.196969 -289.162718) (xy 142.251812 -289.152588) (xy 142.307546 -289.150551)
			(xy 142.362983 -289.156651) (xy 142.41694 -289.170757) (xy 142.468269 -289.192569) (xy 142.515875 -289.221623)
			(xy 142.558743 -289.257298) (xy 142.59596 -289.298835) (xy 142.626733 -289.345348) (xy 142.650405 -289.395845)
			(xy 142.666473 -289.449252) (xy 142.674593 -289.504428) (xy 142.675102 -289.532314) (xy 143.387062 -289.532314)
			(xy 143.391133 -289.476692) (xy 143.403259 -289.422255) (xy 143.423182 -289.370164) (xy 143.450478 -289.321529)
			(xy 143.484564 -289.277386) (xy 143.524713 -289.238677) (xy 143.570071 -289.206226) (xy 143.619671 -289.180725)
			(xy 143.672455 -289.162718) (xy 143.727298 -289.152588) (xy 143.783032 -289.150551) (xy 143.838469 -289.156651)
			(xy 143.892426 -289.170757) (xy 143.943755 -289.192569) (xy 143.991361 -289.221623) (xy 144.034229 -289.257298)
			(xy 144.071446 -289.298835) (xy 144.102219 -289.345348) (xy 144.125891 -289.395845) (xy 144.141959 -289.449252)
			(xy 144.150079 -289.504428) (xy 144.150588 -289.532314) (xy 144.276062 -289.532314) (xy 144.280133 -289.476692)
			(xy 144.292259 -289.422255) (xy 144.312182 -289.370164) (xy 144.339478 -289.321529) (xy 144.373564 -289.277386)
			(xy 144.413713 -289.238677) (xy 144.459071 -289.206226) (xy 144.508671 -289.180725) (xy 144.561455 -289.162718)
			(xy 144.616298 -289.152588) (xy 144.672032 -289.150551) (xy 144.727469 -289.156651) (xy 144.781426 -289.170757)
			(xy 144.832755 -289.192569) (xy 144.880361 -289.221623) (xy 144.923229 -289.257298) (xy 144.960446 -289.298835)
			(xy 144.991219 -289.345348) (xy 145.014891 -289.395845) (xy 145.030959 -289.449252) (xy 145.039079 -289.504428)
			(xy 145.039588 -289.532314) (xy 145.039079 -289.5602) (xy 145.030959 -289.615376) (xy 145.014891 -289.668783)
			(xy 144.991219 -289.71928) (xy 144.960446 -289.765793) (xy 144.923229 -289.80733) (xy 144.880361 -289.843005)
			(xy 144.832755 -289.872059) (xy 144.781426 -289.893871) (xy 144.727469 -289.907977) (xy 144.672032 -289.914077)
			(xy 144.616298 -289.91204) (xy 144.561455 -289.90191) (xy 144.508671 -289.883903) (xy 144.459071 -289.858402)
			(xy 144.413713 -289.825951) (xy 144.373564 -289.787242) (xy 144.339478 -289.743099) (xy 144.312182 -289.694464)
			(xy 144.292259 -289.642373) (xy 144.280133 -289.587936) (xy 144.276062 -289.532314) (xy 144.150588 -289.532314)
			(xy 144.150079 -289.5602) (xy 144.141959 -289.615376) (xy 144.125891 -289.668783) (xy 144.102219 -289.71928)
			(xy 144.071446 -289.765793) (xy 144.034229 -289.80733) (xy 143.991361 -289.843005) (xy 143.943755 -289.872059)
			(xy 143.892426 -289.893871) (xy 143.838469 -289.907977) (xy 143.783032 -289.914077) (xy 143.727298 -289.91204)
			(xy 143.672455 -289.90191) (xy 143.619671 -289.883903) (xy 143.570071 -289.858402) (xy 143.524713 -289.825951)
			(xy 143.484564 -289.787242) (xy 143.450478 -289.743099) (xy 143.423182 -289.694464) (xy 143.403259 -289.642373)
			(xy 143.391133 -289.587936) (xy 143.387062 -289.532314) (xy 142.675102 -289.532314) (xy 142.674593 -289.5602)
			(xy 142.666473 -289.615376) (xy 142.650405 -289.668783) (xy 142.626733 -289.71928) (xy 142.59596 -289.765793)
			(xy 142.558743 -289.80733) (xy 142.515875 -289.843005) (xy 142.468269 -289.872059) (xy 142.41694 -289.893871)
			(xy 142.362983 -289.907977) (xy 142.307546 -289.914077) (xy 142.251812 -289.91204) (xy 142.196969 -289.90191)
			(xy 142.144185 -289.883903) (xy 142.094585 -289.858402) (xy 142.049227 -289.825951) (xy 142.009078 -289.787242)
			(xy 141.974992 -289.743099) (xy 141.947696 -289.694464) (xy 141.927773 -289.642373) (xy 141.915647 -289.587936)
			(xy 141.911576 -289.532314) (xy 136.349994 -289.532314) (xy 136.349994 -290.294314) (xy 147.43811 -290.294314)
			(xy 147.438654 -290.264932) (xy 147.447683 -290.206865) (xy 147.465514 -290.150871) (xy 147.491725 -290.098275)
			(xy 147.525695 -290.050324) (xy 147.56662 -290.008152) (xy 147.589748 -289.990022) (xy 147.598672 -289.982542)
			(xy 147.609132 -289.961768) (xy 147.609814 -289.950144) (xy 147.611084 -289.858196) (xy 147.601178 -289.837114)
			(xy 147.592034 -289.829748) (xy 147.570186 -289.811542) (xy 147.531644 -289.769724) (xy 147.499736 -289.722649)
			(xy 147.475169 -289.671359) (xy 147.458486 -289.616991) (xy 147.450058 -289.560749) (xy 147.44954 -289.532314)
			(xy 147.450026 -289.505063) (xy 147.457782 -289.451115) (xy 147.473137 -289.39882) (xy 147.495779 -289.349243)
			(xy 147.525245 -289.303393) (xy 147.560936 -289.262202) (xy 147.602127 -289.226511) (xy 147.647977 -289.197045)
			(xy 147.697554 -289.174403) (xy 147.749849 -289.159048) (xy 147.803797 -289.151292) (xy 147.858299 -289.151292)
			(xy 147.912247 -289.159048) (xy 147.964542 -289.174403) (xy 148.014119 -289.197045) (xy 148.059969 -289.226511)
			(xy 148.10116 -289.262202) (xy 148.136851 -289.303393) (xy 148.166317 -289.349243) (xy 148.188959 -289.39882)
			(xy 148.204314 -289.451115) (xy 148.21207 -289.505063) (xy 148.212556 -289.532314) (xy 148.212006 -289.561696)
			(xy 148.202975 -289.619761) (xy 148.185143 -289.675754) (xy 148.160679 -289.724846) (xy 152.169126 -289.724846)
			(xy 152.173086 -289.675792) (xy 152.184863 -289.628008) (xy 152.204154 -289.582732) (xy 152.230457 -289.541136)
			(xy 152.263092 -289.504299) (xy 152.301213 -289.473174) (xy 152.343834 -289.448567) (xy 152.38985 -289.431115)
			(xy 152.438069 -289.421271) (xy 152.487244 -289.41929) (xy 152.536099 -289.425222) (xy 152.58337 -289.438914)
			(xy 152.627832 -289.460012) (xy 152.668335 -289.487968) (xy 152.703828 -289.52206) (xy 152.733393 -289.561404)
			(xy 152.756264 -289.604981) (xy 152.771848 -289.651662) (xy 152.779743 -289.700239) (xy 152.780238 -289.724846)
			(xy 153.119086 -289.724846) (xy 153.123046 -289.675792) (xy 153.134823 -289.628008) (xy 153.154114 -289.582732)
			(xy 153.180417 -289.541136) (xy 153.213052 -289.504299) (xy 153.251173 -289.473174) (xy 153.293794 -289.448567)
			(xy 153.33981 -289.431115) (xy 153.388029 -289.421271) (xy 153.437204 -289.41929) (xy 153.486059 -289.425222)
			(xy 153.53333 -289.438914) (xy 153.577792 -289.460012) (xy 153.618295 -289.487968) (xy 153.653788 -289.52206)
			(xy 153.683353 -289.561404) (xy 153.706224 -289.604981) (xy 153.721808 -289.651662) (xy 153.729703 -289.700239)
			(xy 153.730198 -289.724846) (xy 154.0693 -289.724846) (xy 154.07326 -289.675792) (xy 154.085037 -289.628008)
			(xy 154.104328 -289.582732) (xy 154.130631 -289.541136) (xy 154.163266 -289.504299) (xy 154.201387 -289.473174)
			(xy 154.244008 -289.448567) (xy 154.290024 -289.431115) (xy 154.338243 -289.421271) (xy 154.387418 -289.41929)
			(xy 154.436273 -289.425222) (xy 154.483544 -289.438914) (xy 154.528006 -289.460012) (xy 154.568509 -289.487968)
			(xy 154.604002 -289.52206) (xy 154.633567 -289.561404) (xy 154.656438 -289.604981) (xy 154.672022 -289.651662)
			(xy 154.679917 -289.700239) (xy 154.680412 -289.724846) (xy 155.01926 -289.724846) (xy 155.02322 -289.675792)
			(xy 155.034997 -289.628008) (xy 155.054288 -289.582732) (xy 155.080591 -289.541136) (xy 155.113226 -289.504299)
			(xy 155.151347 -289.473174) (xy 155.193968 -289.448567) (xy 155.239984 -289.431115) (xy 155.288203 -289.421271)
			(xy 155.337378 -289.41929) (xy 155.386233 -289.425222) (xy 155.433504 -289.438914) (xy 155.477966 -289.460012)
			(xy 155.518469 -289.487968) (xy 155.553962 -289.52206) (xy 155.583527 -289.561404) (xy 155.606398 -289.604981)
			(xy 155.621982 -289.651662) (xy 155.629877 -289.700239) (xy 155.630372 -289.724846) (xy 155.96922 -289.724846)
			(xy 155.97318 -289.675792) (xy 155.984957 -289.628008) (xy 156.004248 -289.582732) (xy 156.030551 -289.541136)
			(xy 156.063186 -289.504299) (xy 156.101307 -289.473174) (xy 156.143928 -289.448567) (xy 156.189944 -289.431115)
			(xy 156.238163 -289.421271) (xy 156.287338 -289.41929) (xy 156.336193 -289.425222) (xy 156.383464 -289.438914)
			(xy 156.427926 -289.460012) (xy 156.468429 -289.487968) (xy 156.503922 -289.52206) (xy 156.533487 -289.561404)
			(xy 156.556358 -289.604981) (xy 156.571942 -289.651662) (xy 156.579837 -289.700239) (xy 156.580332 -289.724846)
			(xy 156.91918 -289.724846) (xy 156.92314 -289.675792) (xy 156.934917 -289.628008) (xy 156.954208 -289.582732)
			(xy 156.980511 -289.541136) (xy 157.013146 -289.504299) (xy 157.051267 -289.473174) (xy 157.093888 -289.448567)
			(xy 157.139904 -289.431115) (xy 157.188123 -289.421271) (xy 157.237298 -289.41929) (xy 157.286153 -289.425222)
			(xy 157.333424 -289.438914) (xy 157.377886 -289.460012) (xy 157.418389 -289.487968) (xy 157.453882 -289.52206)
			(xy 157.483447 -289.561404) (xy 157.506318 -289.604981) (xy 157.521902 -289.651662) (xy 157.529797 -289.700239)
			(xy 157.530292 -289.724846) (xy 157.86914 -289.724846) (xy 157.8731 -289.675792) (xy 157.884877 -289.628008)
			(xy 157.904168 -289.582732) (xy 157.930471 -289.541136) (xy 157.963106 -289.504299) (xy 158.001227 -289.473174)
			(xy 158.043848 -289.448567) (xy 158.089864 -289.431115) (xy 158.138083 -289.421271) (xy 158.187258 -289.41929)
			(xy 158.236113 -289.425222) (xy 158.283384 -289.438914) (xy 158.327846 -289.460012) (xy 158.368349 -289.487968)
			(xy 158.403842 -289.52206) (xy 158.433407 -289.561404) (xy 158.456278 -289.604981) (xy 158.471862 -289.651662)
			(xy 158.479757 -289.700239) (xy 158.480252 -289.724846) (xy 158.8191 -289.724846) (xy 158.82306 -289.675792)
			(xy 158.834837 -289.628008) (xy 158.854128 -289.582732) (xy 158.880431 -289.541136) (xy 158.913066 -289.504299)
			(xy 158.951187 -289.473174) (xy 158.993808 -289.448567) (xy 159.039824 -289.431115) (xy 159.088043 -289.421271)
			(xy 159.137218 -289.41929) (xy 159.186073 -289.425222) (xy 159.233344 -289.438914) (xy 159.277806 -289.460012)
			(xy 159.318309 -289.487968) (xy 159.353802 -289.52206) (xy 159.383367 -289.561404) (xy 159.406238 -289.604981)
			(xy 159.421822 -289.651662) (xy 159.429717 -289.700239) (xy 159.430212 -289.724846) (xy 159.76906 -289.724846)
			(xy 159.77302 -289.675792) (xy 159.784797 -289.628008) (xy 159.804088 -289.582732) (xy 159.830391 -289.541136)
			(xy 159.863026 -289.504299) (xy 159.901147 -289.473174) (xy 159.943768 -289.448567) (xy 159.989784 -289.431115)
			(xy 160.038003 -289.421271) (xy 160.087178 -289.41929) (xy 160.136033 -289.425222) (xy 160.183304 -289.438914)
			(xy 160.227766 -289.460012) (xy 160.268269 -289.487968) (xy 160.303762 -289.52206) (xy 160.333327 -289.561404)
			(xy 160.356198 -289.604981) (xy 160.371782 -289.651662) (xy 160.379677 -289.700239) (xy 160.380172 -289.724846)
			(xy 160.719274 -289.724846) (xy 160.723234 -289.675792) (xy 160.735011 -289.628008) (xy 160.754302 -289.582732)
			(xy 160.780605 -289.541136) (xy 160.81324 -289.504299) (xy 160.851361 -289.473174) (xy 160.893982 -289.448567)
			(xy 160.939998 -289.431115) (xy 160.988217 -289.421271) (xy 161.037392 -289.41929) (xy 161.086247 -289.425222)
			(xy 161.133518 -289.438914) (xy 161.17798 -289.460012) (xy 161.218483 -289.487968) (xy 161.253976 -289.52206)
			(xy 161.283541 -289.561404) (xy 161.306412 -289.604981) (xy 161.321996 -289.651662) (xy 161.329891 -289.700239)
			(xy 161.330386 -289.724846) (xy 161.669234 -289.724846) (xy 161.673194 -289.675792) (xy 161.684971 -289.628008)
			(xy 161.704262 -289.582732) (xy 161.730565 -289.541136) (xy 161.7632 -289.504299) (xy 161.801321 -289.473174)
			(xy 161.843942 -289.448567) (xy 161.889958 -289.431115) (xy 161.938177 -289.421271) (xy 161.987352 -289.41929)
			(xy 162.036207 -289.425222) (xy 162.083478 -289.438914) (xy 162.12794 -289.460012) (xy 162.168443 -289.487968)
			(xy 162.203936 -289.52206) (xy 162.233501 -289.561404) (xy 162.256372 -289.604981) (xy 162.271956 -289.651662)
			(xy 162.279851 -289.700239) (xy 162.280346 -289.724846) (xy 162.619194 -289.724846) (xy 162.623154 -289.675792)
			(xy 162.634931 -289.628008) (xy 162.654222 -289.582732) (xy 162.680525 -289.541136) (xy 162.71316 -289.504299)
			(xy 162.751281 -289.473174) (xy 162.793902 -289.448567) (xy 162.839918 -289.431115) (xy 162.888137 -289.421271)
			(xy 162.937312 -289.41929) (xy 162.986167 -289.425222) (xy 163.033438 -289.438914) (xy 163.0779 -289.460012)
			(xy 163.118403 -289.487968) (xy 163.153896 -289.52206) (xy 163.183461 -289.561404) (xy 163.206332 -289.604981)
			(xy 163.221916 -289.651662) (xy 163.229811 -289.700239) (xy 163.230306 -289.724846) (xy 163.229811 -289.749453)
			(xy 163.221916 -289.79803) (xy 163.206332 -289.844711) (xy 163.183461 -289.888288) (xy 163.153896 -289.927632)
			(xy 163.118403 -289.961724) (xy 163.0779 -289.98968) (xy 163.033438 -290.010778) (xy 162.986167 -290.02447)
			(xy 162.937312 -290.030402) (xy 162.888137 -290.028421) (xy 162.839918 -290.018577) (xy 162.793902 -290.001125)
			(xy 162.751281 -289.976518) (xy 162.71316 -289.945393) (xy 162.680525 -289.908556) (xy 162.654222 -289.86696)
			(xy 162.634931 -289.821684) (xy 162.623154 -289.7739) (xy 162.619194 -289.724846) (xy 162.280346 -289.724846)
			(xy 162.279851 -289.749453) (xy 162.271956 -289.79803) (xy 162.256372 -289.844711) (xy 162.233501 -289.888288)
			(xy 162.203936 -289.927632) (xy 162.168443 -289.961724) (xy 162.12794 -289.98968) (xy 162.083478 -290.010778)
			(xy 162.036207 -290.02447) (xy 161.987352 -290.030402) (xy 161.938177 -290.028421) (xy 161.889958 -290.018577)
			(xy 161.843942 -290.001125) (xy 161.801321 -289.976518) (xy 161.7632 -289.945393) (xy 161.730565 -289.908556)
			(xy 161.704262 -289.86696) (xy 161.684971 -289.821684) (xy 161.673194 -289.7739) (xy 161.669234 -289.724846)
			(xy 161.330386 -289.724846) (xy 161.329891 -289.749453) (xy 161.321996 -289.79803) (xy 161.306412 -289.844711)
			(xy 161.283541 -289.888288) (xy 161.253976 -289.927632) (xy 161.218483 -289.961724) (xy 161.17798 -289.98968)
			(xy 161.133518 -290.010778) (xy 161.086247 -290.02447) (xy 161.037392 -290.030402) (xy 160.988217 -290.028421)
			(xy 160.939998 -290.018577) (xy 160.893982 -290.001125) (xy 160.851361 -289.976518) (xy 160.81324 -289.945393)
			(xy 160.780605 -289.908556) (xy 160.754302 -289.86696) (xy 160.735011 -289.821684) (xy 160.723234 -289.7739)
			(xy 160.719274 -289.724846) (xy 160.380172 -289.724846) (xy 160.379677 -289.749453) (xy 160.371782 -289.79803)
			(xy 160.356198 -289.844711) (xy 160.333327 -289.888288) (xy 160.303762 -289.927632) (xy 160.268269 -289.961724)
			(xy 160.227766 -289.98968) (xy 160.183304 -290.010778) (xy 160.136033 -290.02447) (xy 160.087178 -290.030402)
			(xy 160.038003 -290.028421) (xy 159.989784 -290.018577) (xy 159.943768 -290.001125) (xy 159.901147 -289.976518)
			(xy 159.863026 -289.945393) (xy 159.830391 -289.908556) (xy 159.804088 -289.86696) (xy 159.784797 -289.821684)
			(xy 159.77302 -289.7739) (xy 159.76906 -289.724846) (xy 159.430212 -289.724846) (xy 159.429717 -289.749453)
			(xy 159.421822 -289.79803) (xy 159.406238 -289.844711) (xy 159.383367 -289.888288) (xy 159.353802 -289.927632)
			(xy 159.318309 -289.961724) (xy 159.277806 -289.98968) (xy 159.233344 -290.010778) (xy 159.186073 -290.02447)
			(xy 159.137218 -290.030402) (xy 159.088043 -290.028421) (xy 159.039824 -290.018577) (xy 158.993808 -290.001125)
			(xy 158.951187 -289.976518) (xy 158.913066 -289.945393) (xy 158.880431 -289.908556) (xy 158.854128 -289.86696)
			(xy 158.834837 -289.821684) (xy 158.82306 -289.7739) (xy 158.8191 -289.724846) (xy 158.480252 -289.724846)
			(xy 158.479757 -289.749453) (xy 158.471862 -289.79803) (xy 158.456278 -289.844711) (xy 158.433407 -289.888288)
			(xy 158.403842 -289.927632) (xy 158.368349 -289.961724) (xy 158.327846 -289.98968) (xy 158.283384 -290.010778)
			(xy 158.236113 -290.02447) (xy 158.187258 -290.030402) (xy 158.138083 -290.028421) (xy 158.089864 -290.018577)
			(xy 158.043848 -290.001125) (xy 158.001227 -289.976518) (xy 157.963106 -289.945393) (xy 157.930471 -289.908556)
			(xy 157.904168 -289.86696) (xy 157.884877 -289.821684) (xy 157.8731 -289.7739) (xy 157.86914 -289.724846)
			(xy 157.530292 -289.724846) (xy 157.529797 -289.749453) (xy 157.521902 -289.79803) (xy 157.506318 -289.844711)
			(xy 157.483447 -289.888288) (xy 157.453882 -289.927632) (xy 157.418389 -289.961724) (xy 157.377886 -289.98968)
			(xy 157.333424 -290.010778) (xy 157.286153 -290.02447) (xy 157.237298 -290.030402) (xy 157.188123 -290.028421)
			(xy 157.139904 -290.018577) (xy 157.093888 -290.001125) (xy 157.051267 -289.976518) (xy 157.013146 -289.945393)
			(xy 156.980511 -289.908556) (xy 156.954208 -289.86696) (xy 156.934917 -289.821684) (xy 156.92314 -289.7739)
			(xy 156.91918 -289.724846) (xy 156.580332 -289.724846) (xy 156.579837 -289.749453) (xy 156.571942 -289.79803)
			(xy 156.556358 -289.844711) (xy 156.533487 -289.888288) (xy 156.503922 -289.927632) (xy 156.468429 -289.961724)
			(xy 156.427926 -289.98968) (xy 156.383464 -290.010778) (xy 156.336193 -290.02447) (xy 156.287338 -290.030402)
			(xy 156.238163 -290.028421) (xy 156.189944 -290.018577) (xy 156.143928 -290.001125) (xy 156.101307 -289.976518)
			(xy 156.063186 -289.945393) (xy 156.030551 -289.908556) (xy 156.004248 -289.86696) (xy 155.984957 -289.821684)
			(xy 155.97318 -289.7739) (xy 155.96922 -289.724846) (xy 155.630372 -289.724846) (xy 155.629877 -289.749453)
			(xy 155.621982 -289.79803) (xy 155.606398 -289.844711) (xy 155.583527 -289.888288) (xy 155.553962 -289.927632)
			(xy 155.518469 -289.961724) (xy 155.477966 -289.98968) (xy 155.433504 -290.010778) (xy 155.386233 -290.02447)
			(xy 155.337378 -290.030402) (xy 155.288203 -290.028421) (xy 155.239984 -290.018577) (xy 155.193968 -290.001125)
			(xy 155.151347 -289.976518) (xy 155.113226 -289.945393) (xy 155.080591 -289.908556) (xy 155.054288 -289.86696)
			(xy 155.034997 -289.821684) (xy 155.02322 -289.7739) (xy 155.01926 -289.724846) (xy 154.680412 -289.724846)
			(xy 154.679917 -289.749453) (xy 154.672022 -289.79803) (xy 154.656438 -289.844711) (xy 154.633567 -289.888288)
			(xy 154.604002 -289.927632) (xy 154.568509 -289.961724) (xy 154.528006 -289.98968) (xy 154.483544 -290.010778)
			(xy 154.436273 -290.02447) (xy 154.387418 -290.030402) (xy 154.338243 -290.028421) (xy 154.290024 -290.018577)
			(xy 154.244008 -290.001125) (xy 154.201387 -289.976518) (xy 154.163266 -289.945393) (xy 154.130631 -289.908556)
			(xy 154.104328 -289.86696) (xy 154.085037 -289.821684) (xy 154.07326 -289.7739) (xy 154.0693 -289.724846)
			(xy 153.730198 -289.724846) (xy 153.729703 -289.749453) (xy 153.721808 -289.79803) (xy 153.706224 -289.844711)
			(xy 153.683353 -289.888288) (xy 153.653788 -289.927632) (xy 153.618295 -289.961724) (xy 153.577792 -289.98968)
			(xy 153.53333 -290.010778) (xy 153.486059 -290.02447) (xy 153.437204 -290.030402) (xy 153.388029 -290.028421)
			(xy 153.33981 -290.018577) (xy 153.293794 -290.001125) (xy 153.251173 -289.976518) (xy 153.213052 -289.945393)
			(xy 153.180417 -289.908556) (xy 153.154114 -289.86696) (xy 153.134823 -289.821684) (xy 153.123046 -289.7739)
			(xy 153.119086 -289.724846) (xy 152.780238 -289.724846) (xy 152.779743 -289.749453) (xy 152.771848 -289.79803)
			(xy 152.756264 -289.844711) (xy 152.733393 -289.888288) (xy 152.703828 -289.927632) (xy 152.668335 -289.961724)
			(xy 152.627832 -289.98968) (xy 152.58337 -290.010778) (xy 152.536099 -290.02447) (xy 152.487244 -290.030402)
			(xy 152.438069 -290.028421) (xy 152.38985 -290.018577) (xy 152.343834 -290.001125) (xy 152.301213 -289.976518)
			(xy 152.263092 -289.945393) (xy 152.230457 -289.908556) (xy 152.204154 -289.86696) (xy 152.184863 -289.821684)
			(xy 152.173086 -289.7739) (xy 152.169126 -289.724846) (xy 148.160679 -289.724846) (xy 148.158933 -289.728349)
			(xy 148.124966 -289.776301) (xy 148.084044 -289.818474) (xy 148.060918 -289.836606) (xy 148.051975 -289.844067)
			(xy 148.041527 -289.864856) (xy 148.040852 -289.876484) (xy 148.039582 -289.968432) (xy 148.049488 -289.989514)
			(xy 148.058632 -289.99688) (xy 148.080459 -290.015109) (xy 148.118999 -290.056924) (xy 148.150908 -290.103995)
			(xy 148.175478 -290.15528) (xy 148.192166 -290.209643) (xy 148.200603 -290.265881) (xy 148.201126 -290.294314)
			(xy 148.8346 -290.294314) (xy 148.838671 -290.238692) (xy 148.850797 -290.184255) (xy 148.87072 -290.132164)
			(xy 148.898016 -290.083529) (xy 148.932102 -290.039386) (xy 148.972251 -290.000677) (xy 149.017609 -289.968226)
			(xy 149.067209 -289.942725) (xy 149.119993 -289.924718) (xy 149.174836 -289.914588) (xy 149.23057 -289.912551)
			(xy 149.286007 -289.918651) (xy 149.339964 -289.932757) (xy 149.391293 -289.954569) (xy 149.438899 -289.983623)
			(xy 149.481767 -290.019298) (xy 149.518984 -290.060835) (xy 149.549757 -290.107348) (xy 149.573429 -290.157845)
			(xy 149.589497 -290.211252) (xy 149.597617 -290.266428) (xy 149.598126 -290.294314) (xy 149.72106 -290.294314)
			(xy 149.725131 -290.238692) (xy 149.737257 -290.184255) (xy 149.75718 -290.132164) (xy 149.784476 -290.083529)
			(xy 149.818562 -290.039386) (xy 149.858711 -290.000677) (xy 149.904069 -289.968226) (xy 149.953669 -289.942725)
			(xy 150.006453 -289.924718) (xy 150.061296 -289.914588) (xy 150.11703 -289.912551) (xy 150.172467 -289.918651)
			(xy 150.226424 -289.932757) (xy 150.277753 -289.954569) (xy 150.325359 -289.983623) (xy 150.368227 -290.019298)
			(xy 150.405444 -290.060835) (xy 150.436217 -290.107348) (xy 150.459889 -290.157845) (xy 150.475957 -290.211252)
			(xy 150.484077 -290.266428) (xy 150.484586 -290.294314) (xy 150.484077 -290.3222) (xy 150.475957 -290.377376)
			(xy 150.459889 -290.430783) (xy 150.436217 -290.48128) (xy 150.405444 -290.527793) (xy 150.368227 -290.56933)
			(xy 150.325359 -290.605005) (xy 150.277753 -290.634059) (xy 150.226424 -290.655871) (xy 150.172467 -290.669977)
			(xy 150.128581 -290.674806) (xy 152.169126 -290.674806) (xy 152.173086 -290.625752) (xy 152.184863 -290.577968)
			(xy 152.204154 -290.532692) (xy 152.230457 -290.491096) (xy 152.263092 -290.454259) (xy 152.301213 -290.423134)
			(xy 152.343834 -290.398527) (xy 152.38985 -290.381075) (xy 152.438069 -290.371231) (xy 152.487244 -290.36925)
			(xy 152.536099 -290.375182) (xy 152.58337 -290.388874) (xy 152.627832 -290.409972) (xy 152.668335 -290.437928)
			(xy 152.703828 -290.47202) (xy 152.733393 -290.511364) (xy 152.756264 -290.554941) (xy 152.771848 -290.601622)
			(xy 152.779743 -290.650199) (xy 152.780238 -290.674806) (xy 153.119086 -290.674806) (xy 153.123046 -290.625752)
			(xy 153.134823 -290.577968) (xy 153.154114 -290.532692) (xy 153.180417 -290.491096) (xy 153.213052 -290.454259)
			(xy 153.251173 -290.423134) (xy 153.293794 -290.398527) (xy 153.33981 -290.381075) (xy 153.388029 -290.371231)
			(xy 153.437204 -290.36925) (xy 153.486059 -290.375182) (xy 153.53333 -290.388874) (xy 153.577792 -290.409972)
			(xy 153.618295 -290.437928) (xy 153.653788 -290.47202) (xy 153.683353 -290.511364) (xy 153.706224 -290.554941)
			(xy 153.721808 -290.601622) (xy 153.729703 -290.650199) (xy 153.730198 -290.674806) (xy 154.0693 -290.674806)
			(xy 154.07326 -290.625752) (xy 154.085037 -290.577968) (xy 154.104328 -290.532692) (xy 154.130631 -290.491096)
			(xy 154.163266 -290.454259) (xy 154.201387 -290.423134) (xy 154.244008 -290.398527) (xy 154.290024 -290.381075)
			(xy 154.338243 -290.371231) (xy 154.387418 -290.36925) (xy 154.436273 -290.375182) (xy 154.483544 -290.388874)
			(xy 154.528006 -290.409972) (xy 154.568509 -290.437928) (xy 154.604002 -290.47202) (xy 154.633567 -290.511364)
			(xy 154.656438 -290.554941) (xy 154.672022 -290.601622) (xy 154.679917 -290.650199) (xy 154.680412 -290.674806)
			(xy 156.91918 -290.674806) (xy 156.92314 -290.625752) (xy 156.934917 -290.577968) (xy 156.954208 -290.532692)
			(xy 156.980511 -290.491096) (xy 157.013146 -290.454259) (xy 157.051267 -290.423134) (xy 157.093888 -290.398527)
			(xy 157.139904 -290.381075) (xy 157.188123 -290.371231) (xy 157.237298 -290.36925) (xy 157.286153 -290.375182)
			(xy 157.333424 -290.388874) (xy 157.377886 -290.409972) (xy 157.418389 -290.437928) (xy 157.453882 -290.47202)
			(xy 157.483447 -290.511364) (xy 157.506318 -290.554941) (xy 157.521902 -290.601622) (xy 157.529797 -290.650199)
			(xy 157.530292 -290.674806) (xy 157.86914 -290.674806) (xy 157.8731 -290.625752) (xy 157.884877 -290.577968)
			(xy 157.904168 -290.532692) (xy 157.930471 -290.491096) (xy 157.963106 -290.454259) (xy 158.001227 -290.423134)
			(xy 158.043848 -290.398527) (xy 158.089864 -290.381075) (xy 158.138083 -290.371231) (xy 158.187258 -290.36925)
			(xy 158.236113 -290.375182) (xy 158.283384 -290.388874) (xy 158.327846 -290.409972) (xy 158.368349 -290.437928)
			(xy 158.403842 -290.47202) (xy 158.433407 -290.511364) (xy 158.456278 -290.554941) (xy 158.471862 -290.601622)
			(xy 158.479757 -290.650199) (xy 158.480252 -290.674806) (xy 158.8191 -290.674806) (xy 158.82306 -290.625752)
			(xy 158.834837 -290.577968) (xy 158.854128 -290.532692) (xy 158.880431 -290.491096) (xy 158.913066 -290.454259)
			(xy 158.951187 -290.423134) (xy 158.993808 -290.398527) (xy 159.039824 -290.381075) (xy 159.088043 -290.371231)
			(xy 159.137218 -290.36925) (xy 159.186073 -290.375182) (xy 159.233344 -290.388874) (xy 159.277806 -290.409972)
			(xy 159.318309 -290.437928) (xy 159.353802 -290.47202) (xy 159.383367 -290.511364) (xy 159.406238 -290.554941)
			(xy 159.421822 -290.601622) (xy 159.429717 -290.650199) (xy 159.430212 -290.674806) (xy 159.76906 -290.674806)
			(xy 159.77302 -290.625752) (xy 159.784797 -290.577968) (xy 159.804088 -290.532692) (xy 159.830391 -290.491096)
			(xy 159.863026 -290.454259) (xy 159.901147 -290.423134) (xy 159.943768 -290.398527) (xy 159.989784 -290.381075)
			(xy 160.038003 -290.371231) (xy 160.087178 -290.36925) (xy 160.136033 -290.375182) (xy 160.183304 -290.388874)
			(xy 160.227766 -290.409972) (xy 160.268269 -290.437928) (xy 160.303762 -290.47202) (xy 160.333327 -290.511364)
			(xy 160.356198 -290.554941) (xy 160.371782 -290.601622) (xy 160.379677 -290.650199) (xy 160.380172 -290.674806)
			(xy 160.719274 -290.674806) (xy 160.723234 -290.625752) (xy 160.735011 -290.577968) (xy 160.754302 -290.532692)
			(xy 160.780605 -290.491096) (xy 160.81324 -290.454259) (xy 160.851361 -290.423134) (xy 160.893982 -290.398527)
			(xy 160.939998 -290.381075) (xy 160.988217 -290.371231) (xy 161.037392 -290.36925) (xy 161.086247 -290.375182)
			(xy 161.133518 -290.388874) (xy 161.17798 -290.409972) (xy 161.218483 -290.437928) (xy 161.253976 -290.47202)
			(xy 161.283541 -290.511364) (xy 161.306412 -290.554941) (xy 161.321996 -290.601622) (xy 161.329891 -290.650199)
			(xy 161.330386 -290.674806) (xy 161.669234 -290.674806) (xy 161.673194 -290.625752) (xy 161.684971 -290.577968)
			(xy 161.704262 -290.532692) (xy 161.730565 -290.491096) (xy 161.7632 -290.454259) (xy 161.801321 -290.423134)
			(xy 161.843942 -290.398527) (xy 161.889958 -290.381075) (xy 161.938177 -290.371231) (xy 161.987352 -290.36925)
			(xy 162.036207 -290.375182) (xy 162.083478 -290.388874) (xy 162.12794 -290.409972) (xy 162.168443 -290.437928)
			(xy 162.203936 -290.47202) (xy 162.233501 -290.511364) (xy 162.256372 -290.554941) (xy 162.271956 -290.601622)
			(xy 162.279851 -290.650199) (xy 162.280346 -290.674806) (xy 162.619194 -290.674806) (xy 162.623154 -290.625752)
			(xy 162.634931 -290.577968) (xy 162.654222 -290.532692) (xy 162.680525 -290.491096) (xy 162.71316 -290.454259)
			(xy 162.751281 -290.423134) (xy 162.793902 -290.398527) (xy 162.839918 -290.381075) (xy 162.888137 -290.371231)
			(xy 162.937312 -290.36925) (xy 162.986167 -290.375182) (xy 163.033438 -290.388874) (xy 163.0779 -290.409972)
			(xy 163.118403 -290.437928) (xy 163.153896 -290.47202) (xy 163.183461 -290.511364) (xy 163.206332 -290.554941)
			(xy 163.221916 -290.601622) (xy 163.229811 -290.650199) (xy 163.230306 -290.674806) (xy 163.569154 -290.674806)
			(xy 163.573114 -290.625752) (xy 163.584891 -290.577968) (xy 163.604182 -290.532692) (xy 163.630485 -290.491096)
			(xy 163.66312 -290.454259) (xy 163.701241 -290.423134) (xy 163.743862 -290.398527) (xy 163.789878 -290.381075)
			(xy 163.838097 -290.371231) (xy 163.887272 -290.36925) (xy 163.936127 -290.375182) (xy 163.983398 -290.388874)
			(xy 164.02786 -290.409972) (xy 164.068363 -290.437928) (xy 164.103856 -290.47202) (xy 164.133421 -290.511364)
			(xy 164.156292 -290.554941) (xy 164.171876 -290.601622) (xy 164.179771 -290.650199) (xy 164.180266 -290.674806)
			(xy 165.469074 -290.674806) (xy 165.473034 -290.625752) (xy 165.484811 -290.577968) (xy 165.504102 -290.532692)
			(xy 165.530405 -290.491096) (xy 165.56304 -290.454259) (xy 165.601161 -290.423134) (xy 165.643782 -290.398527)
			(xy 165.689798 -290.381075) (xy 165.738017 -290.371231) (xy 165.787192 -290.36925) (xy 165.836047 -290.375182)
			(xy 165.883318 -290.388874) (xy 165.92778 -290.409972) (xy 165.968283 -290.437928) (xy 166.003776 -290.47202)
			(xy 166.033341 -290.511364) (xy 166.056212 -290.554941) (xy 166.071796 -290.601622) (xy 166.079691 -290.650199)
			(xy 166.080186 -290.674806) (xy 166.419288 -290.674806) (xy 166.423248 -290.625752) (xy 166.435025 -290.577968)
			(xy 166.454316 -290.532692) (xy 166.480619 -290.491096) (xy 166.513254 -290.454259) (xy 166.551375 -290.423134)
			(xy 166.593996 -290.398527) (xy 166.640012 -290.381075) (xy 166.688231 -290.371231) (xy 166.737406 -290.36925)
			(xy 166.786261 -290.375182) (xy 166.833532 -290.388874) (xy 166.877994 -290.409972) (xy 166.918497 -290.437928)
			(xy 166.95399 -290.47202) (xy 166.983555 -290.511364) (xy 167.006426 -290.554941) (xy 167.02201 -290.601622)
			(xy 167.029905 -290.650199) (xy 167.0304 -290.674806) (xy 167.369248 -290.674806) (xy 167.373208 -290.625752)
			(xy 167.384985 -290.577968) (xy 167.404276 -290.532692) (xy 167.430579 -290.491096) (xy 167.463214 -290.454259)
			(xy 167.501335 -290.423134) (xy 167.543956 -290.398527) (xy 167.589972 -290.381075) (xy 167.638191 -290.371231)
			(xy 167.687366 -290.36925) (xy 167.736221 -290.375182) (xy 167.783492 -290.388874) (xy 167.827954 -290.409972)
			(xy 167.868457 -290.437928) (xy 167.90395 -290.47202) (xy 167.933515 -290.511364) (xy 167.956386 -290.554941)
			(xy 167.97197 -290.601622) (xy 167.979865 -290.650199) (xy 167.98036 -290.674806) (xy 168.319208 -290.674806)
			(xy 168.323168 -290.625752) (xy 168.334945 -290.577968) (xy 168.354236 -290.532692) (xy 168.380539 -290.491096)
			(xy 168.413174 -290.454259) (xy 168.451295 -290.423134) (xy 168.493916 -290.398527) (xy 168.539932 -290.381075)
			(xy 168.588151 -290.371231) (xy 168.637326 -290.36925) (xy 168.686181 -290.375182) (xy 168.733452 -290.388874)
			(xy 168.777914 -290.409972) (xy 168.818417 -290.437928) (xy 168.85391 -290.47202) (xy 168.883475 -290.511364)
			(xy 168.906346 -290.554941) (xy 168.92193 -290.601622) (xy 168.929825 -290.650199) (xy 168.93032 -290.674806)
			(xy 169.269168 -290.674806) (xy 169.273128 -290.625752) (xy 169.284905 -290.577968) (xy 169.304196 -290.532692)
			(xy 169.330499 -290.491096) (xy 169.363134 -290.454259) (xy 169.401255 -290.423134) (xy 169.443876 -290.398527)
			(xy 169.489892 -290.381075) (xy 169.538111 -290.371231) (xy 169.587286 -290.36925) (xy 169.636141 -290.375182)
			(xy 169.683412 -290.388874) (xy 169.727874 -290.409972) (xy 169.768377 -290.437928) (xy 169.80387 -290.47202)
			(xy 169.833435 -290.511364) (xy 169.856306 -290.554941) (xy 169.87189 -290.601622) (xy 169.879785 -290.650199)
			(xy 169.88028 -290.674806) (xy 170.219128 -290.674806) (xy 170.223088 -290.625752) (xy 170.234865 -290.577968)
			(xy 170.254156 -290.532692) (xy 170.280459 -290.491096) (xy 170.313094 -290.454259) (xy 170.351215 -290.423134)
			(xy 170.393836 -290.398527) (xy 170.439852 -290.381075) (xy 170.488071 -290.371231) (xy 170.537246 -290.36925)
			(xy 170.586101 -290.375182) (xy 170.633372 -290.388874) (xy 170.677834 -290.409972) (xy 170.718337 -290.437928)
			(xy 170.75383 -290.47202) (xy 170.783395 -290.511364) (xy 170.806266 -290.554941) (xy 170.82185 -290.601622)
			(xy 170.829745 -290.650199) (xy 170.83024 -290.674806) (xy 171.169088 -290.674806) (xy 171.173048 -290.625752)
			(xy 171.184825 -290.577968) (xy 171.204116 -290.532692) (xy 171.230419 -290.491096) (xy 171.263054 -290.454259)
			(xy 171.301175 -290.423134) (xy 171.343796 -290.398527) (xy 171.389812 -290.381075) (xy 171.438031 -290.371231)
			(xy 171.487206 -290.36925) (xy 171.536061 -290.375182) (xy 171.583332 -290.388874) (xy 171.627794 -290.409972)
			(xy 171.668297 -290.437928) (xy 171.70379 -290.47202) (xy 171.733355 -290.511364) (xy 171.756226 -290.554941)
			(xy 171.77181 -290.601622) (xy 171.779705 -290.650199) (xy 171.7802 -290.674806) (xy 172.119048 -290.674806)
			(xy 172.123008 -290.625752) (xy 172.134785 -290.577968) (xy 172.154076 -290.532692) (xy 172.180379 -290.491096)
			(xy 172.213014 -290.454259) (xy 172.251135 -290.423134) (xy 172.293756 -290.398527) (xy 172.339772 -290.381075)
			(xy 172.387991 -290.371231) (xy 172.437166 -290.36925) (xy 172.486021 -290.375182) (xy 172.533292 -290.388874)
			(xy 172.577754 -290.409972) (xy 172.618257 -290.437928) (xy 172.65375 -290.47202) (xy 172.683315 -290.511364)
			(xy 172.706186 -290.554941) (xy 172.72177 -290.601622) (xy 172.729665 -290.650199) (xy 172.73016 -290.674806)
			(xy 173.069262 -290.674806) (xy 173.073222 -290.625752) (xy 173.084999 -290.577968) (xy 173.10429 -290.532692)
			(xy 173.130593 -290.491096) (xy 173.163228 -290.454259) (xy 173.201349 -290.423134) (xy 173.24397 -290.398527)
			(xy 173.289986 -290.381075) (xy 173.338205 -290.371231) (xy 173.38738 -290.36925) (xy 173.436235 -290.375182)
			(xy 173.483506 -290.388874) (xy 173.527968 -290.409972) (xy 173.568471 -290.437928) (xy 173.603964 -290.47202)
			(xy 173.633529 -290.511364) (xy 173.6564 -290.554941) (xy 173.671984 -290.601622) (xy 173.679879 -290.650199)
			(xy 173.680374 -290.674806) (xy 174.019222 -290.674806) (xy 174.023182 -290.625752) (xy 174.034959 -290.577968)
			(xy 174.05425 -290.532692) (xy 174.080553 -290.491096) (xy 174.113188 -290.454259) (xy 174.151309 -290.423134)
			(xy 174.19393 -290.398527) (xy 174.239946 -290.381075) (xy 174.288165 -290.371231) (xy 174.33734 -290.36925)
			(xy 174.386195 -290.375182) (xy 174.433466 -290.388874) (xy 174.477928 -290.409972) (xy 174.518431 -290.437928)
			(xy 174.553924 -290.47202) (xy 174.583489 -290.511364) (xy 174.60636 -290.554941) (xy 174.621944 -290.601622)
			(xy 174.629839 -290.650199) (xy 174.630334 -290.674806) (xy 175.919142 -290.674806) (xy 175.923102 -290.625752)
			(xy 175.934879 -290.577968) (xy 175.95417 -290.532692) (xy 175.980473 -290.491096) (xy 176.013108 -290.454259)
			(xy 176.051229 -290.423134) (xy 176.09385 -290.398527) (xy 176.139866 -290.381075) (xy 176.188085 -290.371231)
			(xy 176.23726 -290.36925) (xy 176.286115 -290.375182) (xy 176.333386 -290.388874) (xy 176.377848 -290.409972)
			(xy 176.418351 -290.437928) (xy 176.453844 -290.47202) (xy 176.483409 -290.511364) (xy 176.50628 -290.554941)
			(xy 176.521864 -290.601622) (xy 176.529759 -290.650199) (xy 176.530254 -290.674806) (xy 176.869102 -290.674806)
			(xy 176.873062 -290.625752) (xy 176.884839 -290.577968) (xy 176.90413 -290.532692) (xy 176.930433 -290.491096)
			(xy 176.963068 -290.454259) (xy 177.001189 -290.423134) (xy 177.04381 -290.398527) (xy 177.089826 -290.381075)
			(xy 177.138045 -290.371231) (xy 177.18722 -290.36925) (xy 177.236075 -290.375182) (xy 177.283346 -290.388874)
			(xy 177.327808 -290.409972) (xy 177.368311 -290.437928) (xy 177.403804 -290.47202) (xy 177.433369 -290.511364)
			(xy 177.45624 -290.554941) (xy 177.471824 -290.601622) (xy 177.479719 -290.650199) (xy 177.480214 -290.674806)
			(xy 177.819062 -290.674806) (xy 177.823022 -290.625752) (xy 177.834799 -290.577968) (xy 177.85409 -290.532692)
			(xy 177.880393 -290.491096) (xy 177.913028 -290.454259) (xy 177.951149 -290.423134) (xy 177.99377 -290.398527)
			(xy 178.039786 -290.381075) (xy 178.088005 -290.371231) (xy 178.13718 -290.36925) (xy 178.186035 -290.375182)
			(xy 178.233306 -290.388874) (xy 178.277768 -290.409972) (xy 178.318271 -290.437928) (xy 178.353764 -290.47202)
			(xy 178.383329 -290.511364) (xy 178.4062 -290.554941) (xy 178.421784 -290.601622) (xy 178.429679 -290.650199)
			(xy 178.430174 -290.674806) (xy 178.769276 -290.674806) (xy 178.773236 -290.625752) (xy 178.785013 -290.577968)
			(xy 178.804304 -290.532692) (xy 178.830607 -290.491096) (xy 178.863242 -290.454259) (xy 178.901363 -290.423134)
			(xy 178.943984 -290.398527) (xy 178.99 -290.381075) (xy 179.038219 -290.371231) (xy 179.087394 -290.36925)
			(xy 179.136249 -290.375182) (xy 179.18352 -290.388874) (xy 179.227982 -290.409972) (xy 179.268485 -290.437928)
			(xy 179.303978 -290.47202) (xy 179.333543 -290.511364) (xy 179.356414 -290.554941) (xy 179.371998 -290.601622)
			(xy 179.379893 -290.650199) (xy 179.380388 -290.674806) (xy 179.719236 -290.674806) (xy 179.723196 -290.625752)
			(xy 179.734973 -290.577968) (xy 179.754264 -290.532692) (xy 179.780567 -290.491096) (xy 179.813202 -290.454259)
			(xy 179.851323 -290.423134) (xy 179.893944 -290.398527) (xy 179.93996 -290.381075) (xy 179.988179 -290.371231)
			(xy 180.037354 -290.36925) (xy 180.086209 -290.375182) (xy 180.13348 -290.388874) (xy 180.177942 -290.409972)
			(xy 180.218445 -290.437928) (xy 180.253938 -290.47202) (xy 180.283503 -290.511364) (xy 180.306374 -290.554941)
			(xy 180.321958 -290.601622) (xy 180.329853 -290.650199) (xy 180.330348 -290.674806) (xy 180.669196 -290.674806)
			(xy 180.673156 -290.625752) (xy 180.684933 -290.577968) (xy 180.704224 -290.532692) (xy 180.730527 -290.491096)
			(xy 180.763162 -290.454259) (xy 180.801283 -290.423134) (xy 180.843904 -290.398527) (xy 180.88992 -290.381075)
			(xy 180.938139 -290.371231) (xy 180.987314 -290.36925) (xy 181.036169 -290.375182) (xy 181.08344 -290.388874)
			(xy 181.127902 -290.409972) (xy 181.168405 -290.437928) (xy 181.203898 -290.47202) (xy 181.233463 -290.511364)
			(xy 181.256334 -290.554941) (xy 181.271918 -290.601622) (xy 181.279813 -290.650199) (xy 181.280308 -290.674806)
			(xy 181.619156 -290.674806) (xy 181.623116 -290.625752) (xy 181.634893 -290.577968) (xy 181.654184 -290.532692)
			(xy 181.680487 -290.491096) (xy 181.713122 -290.454259) (xy 181.751243 -290.423134) (xy 181.793864 -290.398527)
			(xy 181.83988 -290.381075) (xy 181.888099 -290.371231) (xy 181.937274 -290.36925) (xy 181.986129 -290.375182)
			(xy 182.0334 -290.388874) (xy 182.077862 -290.409972) (xy 182.118365 -290.437928) (xy 182.153858 -290.47202)
			(xy 182.183423 -290.511364) (xy 182.206294 -290.554941) (xy 182.221878 -290.601622) (xy 182.229773 -290.650199)
			(xy 182.230268 -290.674806) (xy 182.569116 -290.674806) (xy 182.573076 -290.625752) (xy 182.584853 -290.577968)
			(xy 182.604144 -290.532692) (xy 182.630447 -290.491096) (xy 182.663082 -290.454259) (xy 182.701203 -290.423134)
			(xy 182.743824 -290.398527) (xy 182.78984 -290.381075) (xy 182.838059 -290.371231) (xy 182.887234 -290.36925)
			(xy 182.936089 -290.375182) (xy 182.98336 -290.388874) (xy 183.027822 -290.409972) (xy 183.068325 -290.437928)
			(xy 183.103818 -290.47202) (xy 183.133383 -290.511364) (xy 183.156254 -290.554941) (xy 183.171838 -290.601622)
			(xy 183.179733 -290.650199) (xy 183.180228 -290.674806) (xy 183.519076 -290.674806) (xy 183.523036 -290.625752)
			(xy 183.534813 -290.577968) (xy 183.554104 -290.532692) (xy 183.580407 -290.491096) (xy 183.613042 -290.454259)
			(xy 183.651163 -290.423134) (xy 183.693784 -290.398527) (xy 183.7398 -290.381075) (xy 183.788019 -290.371231)
			(xy 183.837194 -290.36925) (xy 183.886049 -290.375182) (xy 183.93332 -290.388874) (xy 183.977782 -290.409972)
			(xy 184.018285 -290.437928) (xy 184.053778 -290.47202) (xy 184.083343 -290.511364) (xy 184.106214 -290.554941)
			(xy 184.121798 -290.601622) (xy 184.129693 -290.650199) (xy 184.130188 -290.674806) (xy 184.129693 -290.699413)
			(xy 184.121798 -290.74799) (xy 184.106214 -290.794671) (xy 184.083343 -290.838248) (xy 184.053778 -290.877592)
			(xy 184.018285 -290.911684) (xy 183.977782 -290.93964) (xy 183.93332 -290.960738) (xy 183.886049 -290.97443)
			(xy 183.837194 -290.980362) (xy 183.788019 -290.978381) (xy 183.7398 -290.968537) (xy 183.693784 -290.951085)
			(xy 183.651163 -290.926478) (xy 183.613042 -290.895353) (xy 183.580407 -290.858516) (xy 183.554104 -290.81692)
			(xy 183.534813 -290.771644) (xy 183.523036 -290.72386) (xy 183.519076 -290.674806) (xy 183.180228 -290.674806)
			(xy 183.179733 -290.699413) (xy 183.171838 -290.74799) (xy 183.156254 -290.794671) (xy 183.133383 -290.838248)
			(xy 183.103818 -290.877592) (xy 183.068325 -290.911684) (xy 183.027822 -290.93964) (xy 182.98336 -290.960738)
			(xy 182.936089 -290.97443) (xy 182.887234 -290.980362) (xy 182.838059 -290.978381) (xy 182.78984 -290.968537)
			(xy 182.743824 -290.951085) (xy 182.701203 -290.926478) (xy 182.663082 -290.895353) (xy 182.630447 -290.858516)
			(xy 182.604144 -290.81692) (xy 182.584853 -290.771644) (xy 182.573076 -290.72386) (xy 182.569116 -290.674806)
			(xy 182.230268 -290.674806) (xy 182.229773 -290.699413) (xy 182.221878 -290.74799) (xy 182.206294 -290.794671)
			(xy 182.183423 -290.838248) (xy 182.153858 -290.877592) (xy 182.118365 -290.911684) (xy 182.077862 -290.93964)
			(xy 182.0334 -290.960738) (xy 181.986129 -290.97443) (xy 181.937274 -290.980362) (xy 181.888099 -290.978381)
			(xy 181.83988 -290.968537) (xy 181.793864 -290.951085) (xy 181.751243 -290.926478) (xy 181.713122 -290.895353)
			(xy 181.680487 -290.858516) (xy 181.654184 -290.81692) (xy 181.634893 -290.771644) (xy 181.623116 -290.72386)
			(xy 181.619156 -290.674806) (xy 181.280308 -290.674806) (xy 181.279813 -290.699413) (xy 181.271918 -290.74799)
			(xy 181.256334 -290.794671) (xy 181.233463 -290.838248) (xy 181.203898 -290.877592) (xy 181.168405 -290.911684)
			(xy 181.127902 -290.93964) (xy 181.08344 -290.960738) (xy 181.036169 -290.97443) (xy 180.987314 -290.980362)
			(xy 180.938139 -290.978381) (xy 180.88992 -290.968537) (xy 180.843904 -290.951085) (xy 180.801283 -290.926478)
			(xy 180.763162 -290.895353) (xy 180.730527 -290.858516) (xy 180.704224 -290.81692) (xy 180.684933 -290.771644)
			(xy 180.673156 -290.72386) (xy 180.669196 -290.674806) (xy 180.330348 -290.674806) (xy 180.329853 -290.699413)
			(xy 180.321958 -290.74799) (xy 180.306374 -290.794671) (xy 180.283503 -290.838248) (xy 180.253938 -290.877592)
			(xy 180.218445 -290.911684) (xy 180.177942 -290.93964) (xy 180.13348 -290.960738) (xy 180.086209 -290.97443)
			(xy 180.037354 -290.980362) (xy 179.988179 -290.978381) (xy 179.93996 -290.968537) (xy 179.893944 -290.951085)
			(xy 179.851323 -290.926478) (xy 179.813202 -290.895353) (xy 179.780567 -290.858516) (xy 179.754264 -290.81692)
			(xy 179.734973 -290.771644) (xy 179.723196 -290.72386) (xy 179.719236 -290.674806) (xy 179.380388 -290.674806)
			(xy 179.379893 -290.699413) (xy 179.371998 -290.74799) (xy 179.356414 -290.794671) (xy 179.333543 -290.838248)
			(xy 179.303978 -290.877592) (xy 179.268485 -290.911684) (xy 179.227982 -290.93964) (xy 179.18352 -290.960738)
			(xy 179.136249 -290.97443) (xy 179.087394 -290.980362) (xy 179.038219 -290.978381) (xy 178.99 -290.968537)
			(xy 178.943984 -290.951085) (xy 178.901363 -290.926478) (xy 178.863242 -290.895353) (xy 178.830607 -290.858516)
			(xy 178.804304 -290.81692) (xy 178.785013 -290.771644) (xy 178.773236 -290.72386) (xy 178.769276 -290.674806)
			(xy 178.430174 -290.674806) (xy 178.429679 -290.699413) (xy 178.421784 -290.74799) (xy 178.4062 -290.794671)
			(xy 178.383329 -290.838248) (xy 178.353764 -290.877592) (xy 178.318271 -290.911684) (xy 178.277768 -290.93964)
			(xy 178.233306 -290.960738) (xy 178.186035 -290.97443) (xy 178.13718 -290.980362) (xy 178.088005 -290.978381)
			(xy 178.039786 -290.968537) (xy 177.99377 -290.951085) (xy 177.951149 -290.926478) (xy 177.913028 -290.895353)
			(xy 177.880393 -290.858516) (xy 177.85409 -290.81692) (xy 177.834799 -290.771644) (xy 177.823022 -290.72386)
			(xy 177.819062 -290.674806) (xy 177.480214 -290.674806) (xy 177.479719 -290.699413) (xy 177.471824 -290.74799)
			(xy 177.45624 -290.794671) (xy 177.433369 -290.838248) (xy 177.403804 -290.877592) (xy 177.368311 -290.911684)
			(xy 177.327808 -290.93964) (xy 177.283346 -290.960738) (xy 177.236075 -290.97443) (xy 177.18722 -290.980362)
			(xy 177.138045 -290.978381) (xy 177.089826 -290.968537) (xy 177.04381 -290.951085) (xy 177.001189 -290.926478)
			(xy 176.963068 -290.895353) (xy 176.930433 -290.858516) (xy 176.90413 -290.81692) (xy 176.884839 -290.771644)
			(xy 176.873062 -290.72386) (xy 176.869102 -290.674806) (xy 176.530254 -290.674806) (xy 176.529759 -290.699413)
			(xy 176.521864 -290.74799) (xy 176.50628 -290.794671) (xy 176.483409 -290.838248) (xy 176.453844 -290.877592)
			(xy 176.418351 -290.911684) (xy 176.377848 -290.93964) (xy 176.333386 -290.960738) (xy 176.286115 -290.97443)
			(xy 176.23726 -290.980362) (xy 176.188085 -290.978381) (xy 176.139866 -290.968537) (xy 176.09385 -290.951085)
			(xy 176.051229 -290.926478) (xy 176.013108 -290.895353) (xy 175.980473 -290.858516) (xy 175.95417 -290.81692)
			(xy 175.934879 -290.771644) (xy 175.923102 -290.72386) (xy 175.919142 -290.674806) (xy 174.630334 -290.674806)
			(xy 174.629839 -290.699413) (xy 174.621944 -290.74799) (xy 174.60636 -290.794671) (xy 174.583489 -290.838248)
			(xy 174.553924 -290.877592) (xy 174.518431 -290.911684) (xy 174.477928 -290.93964) (xy 174.433466 -290.960738)
			(xy 174.386195 -290.97443) (xy 174.33734 -290.980362) (xy 174.288165 -290.978381) (xy 174.239946 -290.968537)
			(xy 174.19393 -290.951085) (xy 174.151309 -290.926478) (xy 174.113188 -290.895353) (xy 174.080553 -290.858516)
			(xy 174.05425 -290.81692) (xy 174.034959 -290.771644) (xy 174.023182 -290.72386) (xy 174.019222 -290.674806)
			(xy 173.680374 -290.674806) (xy 173.679879 -290.699413) (xy 173.671984 -290.74799) (xy 173.6564 -290.794671)
			(xy 173.633529 -290.838248) (xy 173.603964 -290.877592) (xy 173.568471 -290.911684) (xy 173.527968 -290.93964)
			(xy 173.483506 -290.960738) (xy 173.436235 -290.97443) (xy 173.38738 -290.980362) (xy 173.338205 -290.978381)
			(xy 173.289986 -290.968537) (xy 173.24397 -290.951085) (xy 173.201349 -290.926478) (xy 173.163228 -290.895353)
			(xy 173.130593 -290.858516) (xy 173.10429 -290.81692) (xy 173.084999 -290.771644) (xy 173.073222 -290.72386)
			(xy 173.069262 -290.674806) (xy 172.73016 -290.674806) (xy 172.729665 -290.699413) (xy 172.72177 -290.74799)
			(xy 172.706186 -290.794671) (xy 172.683315 -290.838248) (xy 172.65375 -290.877592) (xy 172.618257 -290.911684)
			(xy 172.577754 -290.93964) (xy 172.533292 -290.960738) (xy 172.486021 -290.97443) (xy 172.437166 -290.980362)
			(xy 172.387991 -290.978381) (xy 172.339772 -290.968537) (xy 172.293756 -290.951085) (xy 172.251135 -290.926478)
			(xy 172.213014 -290.895353) (xy 172.180379 -290.858516) (xy 172.154076 -290.81692) (xy 172.134785 -290.771644)
			(xy 172.123008 -290.72386) (xy 172.119048 -290.674806) (xy 171.7802 -290.674806) (xy 171.779705 -290.699413)
			(xy 171.77181 -290.74799) (xy 171.756226 -290.794671) (xy 171.733355 -290.838248) (xy 171.70379 -290.877592)
			(xy 171.668297 -290.911684) (xy 171.627794 -290.93964) (xy 171.583332 -290.960738) (xy 171.536061 -290.97443)
			(xy 171.487206 -290.980362) (xy 171.438031 -290.978381) (xy 171.389812 -290.968537) (xy 171.343796 -290.951085)
			(xy 171.301175 -290.926478) (xy 171.263054 -290.895353) (xy 171.230419 -290.858516) (xy 171.204116 -290.81692)
			(xy 171.184825 -290.771644) (xy 171.173048 -290.72386) (xy 171.169088 -290.674806) (xy 170.83024 -290.674806)
			(xy 170.829745 -290.699413) (xy 170.82185 -290.74799) (xy 170.806266 -290.794671) (xy 170.783395 -290.838248)
			(xy 170.75383 -290.877592) (xy 170.718337 -290.911684) (xy 170.677834 -290.93964) (xy 170.633372 -290.960738)
			(xy 170.586101 -290.97443) (xy 170.537246 -290.980362) (xy 170.488071 -290.978381) (xy 170.439852 -290.968537)
			(xy 170.393836 -290.951085) (xy 170.351215 -290.926478) (xy 170.313094 -290.895353) (xy 170.280459 -290.858516)
			(xy 170.254156 -290.81692) (xy 170.234865 -290.771644) (xy 170.223088 -290.72386) (xy 170.219128 -290.674806)
			(xy 169.88028 -290.674806) (xy 169.879785 -290.699413) (xy 169.87189 -290.74799) (xy 169.856306 -290.794671)
			(xy 169.833435 -290.838248) (xy 169.80387 -290.877592) (xy 169.768377 -290.911684) (xy 169.727874 -290.93964)
			(xy 169.683412 -290.960738) (xy 169.636141 -290.97443) (xy 169.587286 -290.980362) (xy 169.538111 -290.978381)
			(xy 169.489892 -290.968537) (xy 169.443876 -290.951085) (xy 169.401255 -290.926478) (xy 169.363134 -290.895353)
			(xy 169.330499 -290.858516) (xy 169.304196 -290.81692) (xy 169.284905 -290.771644) (xy 169.273128 -290.72386)
			(xy 169.269168 -290.674806) (xy 168.93032 -290.674806) (xy 168.929825 -290.699413) (xy 168.92193 -290.74799)
			(xy 168.906346 -290.794671) (xy 168.883475 -290.838248) (xy 168.85391 -290.877592) (xy 168.818417 -290.911684)
			(xy 168.777914 -290.93964) (xy 168.733452 -290.960738) (xy 168.686181 -290.97443) (xy 168.637326 -290.980362)
			(xy 168.588151 -290.978381) (xy 168.539932 -290.968537) (xy 168.493916 -290.951085) (xy 168.451295 -290.926478)
			(xy 168.413174 -290.895353) (xy 168.380539 -290.858516) (xy 168.354236 -290.81692) (xy 168.334945 -290.771644)
			(xy 168.323168 -290.72386) (xy 168.319208 -290.674806) (xy 167.98036 -290.674806) (xy 167.979865 -290.699413)
			(xy 167.97197 -290.74799) (xy 167.956386 -290.794671) (xy 167.933515 -290.838248) (xy 167.90395 -290.877592)
			(xy 167.868457 -290.911684) (xy 167.827954 -290.93964) (xy 167.783492 -290.960738) (xy 167.736221 -290.97443)
			(xy 167.687366 -290.980362) (xy 167.638191 -290.978381) (xy 167.589972 -290.968537) (xy 167.543956 -290.951085)
			(xy 167.501335 -290.926478) (xy 167.463214 -290.895353) (xy 167.430579 -290.858516) (xy 167.404276 -290.81692)
			(xy 167.384985 -290.771644) (xy 167.373208 -290.72386) (xy 167.369248 -290.674806) (xy 167.0304 -290.674806)
			(xy 167.029905 -290.699413) (xy 167.02201 -290.74799) (xy 167.006426 -290.794671) (xy 166.983555 -290.838248)
			(xy 166.95399 -290.877592) (xy 166.918497 -290.911684) (xy 166.877994 -290.93964) (xy 166.833532 -290.960738)
			(xy 166.786261 -290.97443) (xy 166.737406 -290.980362) (xy 166.688231 -290.978381) (xy 166.640012 -290.968537)
			(xy 166.593996 -290.951085) (xy 166.551375 -290.926478) (xy 166.513254 -290.895353) (xy 166.480619 -290.858516)
			(xy 166.454316 -290.81692) (xy 166.435025 -290.771644) (xy 166.423248 -290.72386) (xy 166.419288 -290.674806)
			(xy 166.080186 -290.674806) (xy 166.079691 -290.699413) (xy 166.071796 -290.74799) (xy 166.056212 -290.794671)
			(xy 166.033341 -290.838248) (xy 166.003776 -290.877592) (xy 165.968283 -290.911684) (xy 165.92778 -290.93964)
			(xy 165.883318 -290.960738) (xy 165.836047 -290.97443) (xy 165.787192 -290.980362) (xy 165.738017 -290.978381)
			(xy 165.689798 -290.968537) (xy 165.643782 -290.951085) (xy 165.601161 -290.926478) (xy 165.56304 -290.895353)
			(xy 165.530405 -290.858516) (xy 165.504102 -290.81692) (xy 165.484811 -290.771644) (xy 165.473034 -290.72386)
			(xy 165.469074 -290.674806) (xy 164.180266 -290.674806) (xy 164.179771 -290.699413) (xy 164.171876 -290.74799)
			(xy 164.156292 -290.794671) (xy 164.133421 -290.838248) (xy 164.103856 -290.877592) (xy 164.068363 -290.911684)
			(xy 164.02786 -290.93964) (xy 163.983398 -290.960738) (xy 163.936127 -290.97443) (xy 163.887272 -290.980362)
			(xy 163.838097 -290.978381) (xy 163.789878 -290.968537) (xy 163.743862 -290.951085) (xy 163.701241 -290.926478)
			(xy 163.66312 -290.895353) (xy 163.630485 -290.858516) (xy 163.604182 -290.81692) (xy 163.584891 -290.771644)
			(xy 163.573114 -290.72386) (xy 163.569154 -290.674806) (xy 163.230306 -290.674806) (xy 163.229811 -290.699413)
			(xy 163.221916 -290.74799) (xy 163.206332 -290.794671) (xy 163.183461 -290.838248) (xy 163.153896 -290.877592)
			(xy 163.118403 -290.911684) (xy 163.0779 -290.93964) (xy 163.033438 -290.960738) (xy 162.986167 -290.97443)
			(xy 162.937312 -290.980362) (xy 162.888137 -290.978381) (xy 162.839918 -290.968537) (xy 162.793902 -290.951085)
			(xy 162.751281 -290.926478) (xy 162.71316 -290.895353) (xy 162.680525 -290.858516) (xy 162.654222 -290.81692)
			(xy 162.634931 -290.771644) (xy 162.623154 -290.72386) (xy 162.619194 -290.674806) (xy 162.280346 -290.674806)
			(xy 162.279851 -290.699413) (xy 162.271956 -290.74799) (xy 162.256372 -290.794671) (xy 162.233501 -290.838248)
			(xy 162.203936 -290.877592) (xy 162.168443 -290.911684) (xy 162.12794 -290.93964) (xy 162.083478 -290.960738)
			(xy 162.036207 -290.97443) (xy 161.987352 -290.980362) (xy 161.938177 -290.978381) (xy 161.889958 -290.968537)
			(xy 161.843942 -290.951085) (xy 161.801321 -290.926478) (xy 161.7632 -290.895353) (xy 161.730565 -290.858516)
			(xy 161.704262 -290.81692) (xy 161.684971 -290.771644) (xy 161.673194 -290.72386) (xy 161.669234 -290.674806)
			(xy 161.330386 -290.674806) (xy 161.329891 -290.699413) (xy 161.321996 -290.74799) (xy 161.306412 -290.794671)
			(xy 161.283541 -290.838248) (xy 161.253976 -290.877592) (xy 161.218483 -290.911684) (xy 161.17798 -290.93964)
			(xy 161.133518 -290.960738) (xy 161.086247 -290.97443) (xy 161.037392 -290.980362) (xy 160.988217 -290.978381)
			(xy 160.939998 -290.968537) (xy 160.893982 -290.951085) (xy 160.851361 -290.926478) (xy 160.81324 -290.895353)
			(xy 160.780605 -290.858516) (xy 160.754302 -290.81692) (xy 160.735011 -290.771644) (xy 160.723234 -290.72386)
			(xy 160.719274 -290.674806) (xy 160.380172 -290.674806) (xy 160.379677 -290.699413) (xy 160.371782 -290.74799)
			(xy 160.356198 -290.794671) (xy 160.333327 -290.838248) (xy 160.303762 -290.877592) (xy 160.268269 -290.911684)
			(xy 160.227766 -290.93964) (xy 160.183304 -290.960738) (xy 160.136033 -290.97443) (xy 160.087178 -290.980362)
			(xy 160.038003 -290.978381) (xy 159.989784 -290.968537) (xy 159.943768 -290.951085) (xy 159.901147 -290.926478)
			(xy 159.863026 -290.895353) (xy 159.830391 -290.858516) (xy 159.804088 -290.81692) (xy 159.784797 -290.771644)
			(xy 159.77302 -290.72386) (xy 159.76906 -290.674806) (xy 159.430212 -290.674806) (xy 159.429717 -290.699413)
			(xy 159.421822 -290.74799) (xy 159.406238 -290.794671) (xy 159.383367 -290.838248) (xy 159.353802 -290.877592)
			(xy 159.318309 -290.911684) (xy 159.277806 -290.93964) (xy 159.233344 -290.960738) (xy 159.186073 -290.97443)
			(xy 159.137218 -290.980362) (xy 159.088043 -290.978381) (xy 159.039824 -290.968537) (xy 158.993808 -290.951085)
			(xy 158.951187 -290.926478) (xy 158.913066 -290.895353) (xy 158.880431 -290.858516) (xy 158.854128 -290.81692)
			(xy 158.834837 -290.771644) (xy 158.82306 -290.72386) (xy 158.8191 -290.674806) (xy 158.480252 -290.674806)
			(xy 158.479757 -290.699413) (xy 158.471862 -290.74799) (xy 158.456278 -290.794671) (xy 158.433407 -290.838248)
			(xy 158.403842 -290.877592) (xy 158.368349 -290.911684) (xy 158.327846 -290.93964) (xy 158.283384 -290.960738)
			(xy 158.236113 -290.97443) (xy 158.187258 -290.980362) (xy 158.138083 -290.978381) (xy 158.089864 -290.968537)
			(xy 158.043848 -290.951085) (xy 158.001227 -290.926478) (xy 157.963106 -290.895353) (xy 157.930471 -290.858516)
			(xy 157.904168 -290.81692) (xy 157.884877 -290.771644) (xy 157.8731 -290.72386) (xy 157.86914 -290.674806)
			(xy 157.530292 -290.674806) (xy 157.529797 -290.699413) (xy 157.521902 -290.74799) (xy 157.506318 -290.794671)
			(xy 157.483447 -290.838248) (xy 157.453882 -290.877592) (xy 157.418389 -290.911684) (xy 157.377886 -290.93964)
			(xy 157.333424 -290.960738) (xy 157.286153 -290.97443) (xy 157.237298 -290.980362) (xy 157.188123 -290.978381)
			(xy 157.139904 -290.968537) (xy 157.093888 -290.951085) (xy 157.051267 -290.926478) (xy 157.013146 -290.895353)
			(xy 156.980511 -290.858516) (xy 156.954208 -290.81692) (xy 156.934917 -290.771644) (xy 156.92314 -290.72386)
			(xy 156.91918 -290.674806) (xy 154.680412 -290.674806) (xy 154.679917 -290.699413) (xy 154.672022 -290.74799)
			(xy 154.656438 -290.794671) (xy 154.633567 -290.838248) (xy 154.604002 -290.877592) (xy 154.568509 -290.911684)
			(xy 154.528006 -290.93964) (xy 154.483544 -290.960738) (xy 154.436273 -290.97443) (xy 154.387418 -290.980362)
			(xy 154.338243 -290.978381) (xy 154.290024 -290.968537) (xy 154.244008 -290.951085) (xy 154.201387 -290.926478)
			(xy 154.163266 -290.895353) (xy 154.130631 -290.858516) (xy 154.104328 -290.81692) (xy 154.085037 -290.771644)
			(xy 154.07326 -290.72386) (xy 154.0693 -290.674806) (xy 153.730198 -290.674806) (xy 153.729703 -290.699413)
			(xy 153.721808 -290.74799) (xy 153.706224 -290.794671) (xy 153.683353 -290.838248) (xy 153.653788 -290.877592)
			(xy 153.618295 -290.911684) (xy 153.577792 -290.93964) (xy 153.53333 -290.960738) (xy 153.486059 -290.97443)
			(xy 153.437204 -290.980362) (xy 153.388029 -290.978381) (xy 153.33981 -290.968537) (xy 153.293794 -290.951085)
			(xy 153.251173 -290.926478) (xy 153.213052 -290.895353) (xy 153.180417 -290.858516) (xy 153.154114 -290.81692)
			(xy 153.134823 -290.771644) (xy 153.123046 -290.72386) (xy 153.119086 -290.674806) (xy 152.780238 -290.674806)
			(xy 152.779743 -290.699413) (xy 152.771848 -290.74799) (xy 152.756264 -290.794671) (xy 152.733393 -290.838248)
			(xy 152.703828 -290.877592) (xy 152.668335 -290.911684) (xy 152.627832 -290.93964) (xy 152.58337 -290.960738)
			(xy 152.536099 -290.97443) (xy 152.487244 -290.980362) (xy 152.438069 -290.978381) (xy 152.38985 -290.968537)
			(xy 152.343834 -290.951085) (xy 152.301213 -290.926478) (xy 152.263092 -290.895353) (xy 152.230457 -290.858516)
			(xy 152.204154 -290.81692) (xy 152.184863 -290.771644) (xy 152.173086 -290.72386) (xy 152.169126 -290.674806)
			(xy 150.128581 -290.674806) (xy 150.11703 -290.676077) (xy 150.061296 -290.67404) (xy 150.006453 -290.66391)
			(xy 149.953669 -290.645903) (xy 149.904069 -290.620402) (xy 149.858711 -290.587951) (xy 149.818562 -290.549242)
			(xy 149.784476 -290.505099) (xy 149.75718 -290.456464) (xy 149.737257 -290.404373) (xy 149.725131 -290.349936)
			(xy 149.72106 -290.294314) (xy 149.598126 -290.294314) (xy 149.597617 -290.3222) (xy 149.589497 -290.377376)
			(xy 149.573429 -290.430783) (xy 149.549757 -290.48128) (xy 149.518984 -290.527793) (xy 149.481767 -290.56933)
			(xy 149.438899 -290.605005) (xy 149.391293 -290.634059) (xy 149.339964 -290.655871) (xy 149.286007 -290.669977)
			(xy 149.23057 -290.676077) (xy 149.174836 -290.67404) (xy 149.119993 -290.66391) (xy 149.067209 -290.645903)
			(xy 149.017609 -290.620402) (xy 148.972251 -290.587951) (xy 148.932102 -290.549242) (xy 148.898016 -290.505099)
			(xy 148.87072 -290.456464) (xy 148.850797 -290.404373) (xy 148.838671 -290.349936) (xy 148.8346 -290.294314)
			(xy 148.201126 -290.294314) (xy 148.20064 -290.321565) (xy 148.192884 -290.375513) (xy 148.177529 -290.427808)
			(xy 148.154887 -290.477385) (xy 148.125421 -290.523235) (xy 148.08973 -290.564426) (xy 148.048539 -290.600117)
			(xy 148.002689 -290.629583) (xy 147.953112 -290.652225) (xy 147.900817 -290.66758) (xy 147.846869 -290.675336)
			(xy 147.792367 -290.675336) (xy 147.738419 -290.66758) (xy 147.686124 -290.652225) (xy 147.636547 -290.629583)
			(xy 147.590697 -290.600117) (xy 147.549506 -290.564426) (xy 147.513815 -290.523235) (xy 147.484349 -290.477385)
			(xy 147.461707 -290.427808) (xy 147.446352 -290.375513) (xy 147.438596 -290.321565) (xy 147.43811 -290.294314)
			(xy 136.349994 -290.294314) (xy 136.349994 -291.430456) (xy 141.911576 -291.430456) (xy 141.915647 -291.374834)
			(xy 141.927773 -291.320397) (xy 141.947696 -291.268306) (xy 141.974992 -291.219671) (xy 142.009078 -291.175528)
			(xy 142.049227 -291.136819) (xy 142.094585 -291.104368) (xy 142.144185 -291.078867) (xy 142.196969 -291.06086)
			(xy 142.251812 -291.05073) (xy 142.307546 -291.048693) (xy 142.362983 -291.054793) (xy 142.41694 -291.068899)
			(xy 142.468269 -291.090711) (xy 142.515875 -291.119765) (xy 142.558743 -291.15544) (xy 142.59596 -291.196977)
			(xy 142.626733 -291.24349) (xy 142.650405 -291.293987) (xy 142.666473 -291.347394) (xy 142.674593 -291.40257)
			(xy 142.675102 -291.430456) (xy 143.396714 -291.430456) (xy 143.400785 -291.374834) (xy 143.412911 -291.320397)
			(xy 143.432834 -291.268306) (xy 143.46013 -291.219671) (xy 143.494216 -291.175528) (xy 143.534365 -291.136819)
			(xy 143.579723 -291.104368) (xy 143.629323 -291.078867) (xy 143.682107 -291.06086) (xy 143.73695 -291.05073)
			(xy 143.792684 -291.048693) (xy 143.848121 -291.054793) (xy 143.902078 -291.068899) (xy 143.953407 -291.090711)
			(xy 144.001013 -291.119765) (xy 144.043881 -291.15544) (xy 144.081098 -291.196977) (xy 144.111871 -291.24349)
			(xy 144.135543 -291.293987) (xy 144.151611 -291.347394) (xy 144.159731 -291.40257) (xy 144.16024 -291.430456)
			(xy 144.159731 -291.458342) (xy 144.151611 -291.513518) (xy 144.135543 -291.566925) (xy 144.111871 -291.617422)
			(xy 144.107012 -291.624766) (xy 152.169126 -291.624766) (xy 152.173086 -291.575712) (xy 152.184863 -291.527928)
			(xy 152.204154 -291.482652) (xy 152.230457 -291.441056) (xy 152.263092 -291.404219) (xy 152.301213 -291.373094)
			(xy 152.343834 -291.348487) (xy 152.38985 -291.331035) (xy 152.438069 -291.321191) (xy 152.487244 -291.31921)
			(xy 152.536099 -291.325142) (xy 152.58337 -291.338834) (xy 152.627832 -291.359932) (xy 152.668335 -291.387888)
			(xy 152.703828 -291.42198) (xy 152.733393 -291.461324) (xy 152.756264 -291.504901) (xy 152.771848 -291.551582)
			(xy 152.779743 -291.600159) (xy 152.780238 -291.624766) (xy 153.119086 -291.624766) (xy 153.123046 -291.575712)
			(xy 153.134823 -291.527928) (xy 153.154114 -291.482652) (xy 153.180417 -291.441056) (xy 153.213052 -291.404219)
			(xy 153.251173 -291.373094) (xy 153.293794 -291.348487) (xy 153.33981 -291.331035) (xy 153.388029 -291.321191)
			(xy 153.437204 -291.31921) (xy 153.486059 -291.325142) (xy 153.53333 -291.338834) (xy 153.577792 -291.359932)
			(xy 153.618295 -291.387888) (xy 153.653788 -291.42198) (xy 153.683353 -291.461324) (xy 153.706224 -291.504901)
			(xy 153.721808 -291.551582) (xy 153.729703 -291.600159) (xy 153.730198 -291.624766) (xy 154.0693 -291.624766)
			(xy 154.07326 -291.575712) (xy 154.085037 -291.527928) (xy 154.104328 -291.482652) (xy 154.130631 -291.441056)
			(xy 154.163266 -291.404219) (xy 154.201387 -291.373094) (xy 154.244008 -291.348487) (xy 154.290024 -291.331035)
			(xy 154.338243 -291.321191) (xy 154.387418 -291.31921) (xy 154.436273 -291.325142) (xy 154.483544 -291.338834)
			(xy 154.528006 -291.359932) (xy 154.568509 -291.387888) (xy 154.604002 -291.42198) (xy 154.633567 -291.461324)
			(xy 154.656438 -291.504901) (xy 154.672022 -291.551582) (xy 154.679917 -291.600159) (xy 154.680412 -291.624766)
			(xy 156.91918 -291.624766) (xy 156.92314 -291.575712) (xy 156.934917 -291.527928) (xy 156.954208 -291.482652)
			(xy 156.980511 -291.441056) (xy 157.013146 -291.404219) (xy 157.051267 -291.373094) (xy 157.093888 -291.348487)
			(xy 157.139904 -291.331035) (xy 157.188123 -291.321191) (xy 157.237298 -291.31921) (xy 157.286153 -291.325142)
			(xy 157.333424 -291.338834) (xy 157.377886 -291.359932) (xy 157.418389 -291.387888) (xy 157.453882 -291.42198)
			(xy 157.483447 -291.461324) (xy 157.506318 -291.504901) (xy 157.521902 -291.551582) (xy 157.529797 -291.600159)
			(xy 157.530292 -291.624766) (xy 157.86914 -291.624766) (xy 157.8731 -291.575712) (xy 157.884877 -291.527928)
			(xy 157.904168 -291.482652) (xy 157.930471 -291.441056) (xy 157.963106 -291.404219) (xy 158.001227 -291.373094)
			(xy 158.043848 -291.348487) (xy 158.089864 -291.331035) (xy 158.138083 -291.321191) (xy 158.187258 -291.31921)
			(xy 158.236113 -291.325142) (xy 158.283384 -291.338834) (xy 158.327846 -291.359932) (xy 158.368349 -291.387888)
			(xy 158.403842 -291.42198) (xy 158.433407 -291.461324) (xy 158.456278 -291.504901) (xy 158.471862 -291.551582)
			(xy 158.479757 -291.600159) (xy 158.480252 -291.624766) (xy 158.8191 -291.624766) (xy 158.82306 -291.575712)
			(xy 158.834837 -291.527928) (xy 158.854128 -291.482652) (xy 158.880431 -291.441056) (xy 158.913066 -291.404219)
			(xy 158.951187 -291.373094) (xy 158.993808 -291.348487) (xy 159.039824 -291.331035) (xy 159.088043 -291.321191)
			(xy 159.137218 -291.31921) (xy 159.186073 -291.325142) (xy 159.233344 -291.338834) (xy 159.277806 -291.359932)
			(xy 159.318309 -291.387888) (xy 159.353802 -291.42198) (xy 159.383367 -291.461324) (xy 159.406238 -291.504901)
			(xy 159.421822 -291.551582) (xy 159.429717 -291.600159) (xy 159.430212 -291.624766) (xy 159.76906 -291.624766)
			(xy 159.77302 -291.575712) (xy 159.784797 -291.527928) (xy 159.804088 -291.482652) (xy 159.830391 -291.441056)
			(xy 159.863026 -291.404219) (xy 159.901147 -291.373094) (xy 159.943768 -291.348487) (xy 159.989784 -291.331035)
			(xy 160.038003 -291.321191) (xy 160.087178 -291.31921) (xy 160.136033 -291.325142) (xy 160.183304 -291.338834)
			(xy 160.227766 -291.359932) (xy 160.268269 -291.387888) (xy 160.303762 -291.42198) (xy 160.333327 -291.461324)
			(xy 160.356198 -291.504901) (xy 160.371782 -291.551582) (xy 160.379677 -291.600159) (xy 160.380172 -291.624766)
			(xy 160.719274 -291.624766) (xy 160.723234 -291.575712) (xy 160.735011 -291.527928) (xy 160.754302 -291.482652)
			(xy 160.780605 -291.441056) (xy 160.81324 -291.404219) (xy 160.851361 -291.373094) (xy 160.893982 -291.348487)
			(xy 160.939998 -291.331035) (xy 160.988217 -291.321191) (xy 161.037392 -291.31921) (xy 161.086247 -291.325142)
			(xy 161.133518 -291.338834) (xy 161.17798 -291.359932) (xy 161.218483 -291.387888) (xy 161.253976 -291.42198)
			(xy 161.283541 -291.461324) (xy 161.306412 -291.504901) (xy 161.321996 -291.551582) (xy 161.329891 -291.600159)
			(xy 161.330386 -291.624766) (xy 161.669234 -291.624766) (xy 161.673194 -291.575712) (xy 161.684971 -291.527928)
			(xy 161.704262 -291.482652) (xy 161.730565 -291.441056) (xy 161.7632 -291.404219) (xy 161.801321 -291.373094)
			(xy 161.843942 -291.348487) (xy 161.889958 -291.331035) (xy 161.938177 -291.321191) (xy 161.987352 -291.31921)
			(xy 162.036207 -291.325142) (xy 162.083478 -291.338834) (xy 162.12794 -291.359932) (xy 162.168443 -291.387888)
			(xy 162.203936 -291.42198) (xy 162.233501 -291.461324) (xy 162.256372 -291.504901) (xy 162.271956 -291.551582)
			(xy 162.279851 -291.600159) (xy 162.280346 -291.624766) (xy 163.569154 -291.624766) (xy 163.573114 -291.575712)
			(xy 163.584891 -291.527928) (xy 163.604182 -291.482652) (xy 163.630485 -291.441056) (xy 163.66312 -291.404219)
			(xy 163.701241 -291.373094) (xy 163.743862 -291.348487) (xy 163.789878 -291.331035) (xy 163.838097 -291.321191)
			(xy 163.887272 -291.31921) (xy 163.936127 -291.325142) (xy 163.983398 -291.338834) (xy 164.02786 -291.359932)
			(xy 164.068363 -291.387888) (xy 164.103856 -291.42198) (xy 164.133421 -291.461324) (xy 164.156292 -291.504901)
			(xy 164.171876 -291.551582) (xy 164.179771 -291.600159) (xy 164.180266 -291.624766) (xy 164.519114 -291.624766)
			(xy 164.523074 -291.575712) (xy 164.534851 -291.527928) (xy 164.554142 -291.482652) (xy 164.580445 -291.441056)
			(xy 164.61308 -291.404219) (xy 164.651201 -291.373094) (xy 164.693822 -291.348487) (xy 164.739838 -291.331035)
			(xy 164.788057 -291.321191) (xy 164.837232 -291.31921) (xy 164.886087 -291.325142) (xy 164.933358 -291.338834)
			(xy 164.97782 -291.359932) (xy 165.018323 -291.387888) (xy 165.053816 -291.42198) (xy 165.083381 -291.461324)
			(xy 165.106252 -291.504901) (xy 165.121836 -291.551582) (xy 165.129731 -291.600159) (xy 165.130226 -291.624766)
			(xy 166.419288 -291.624766) (xy 166.423248 -291.575712) (xy 166.435025 -291.527928) (xy 166.454316 -291.482652)
			(xy 166.480619 -291.441056) (xy 166.513254 -291.404219) (xy 166.551375 -291.373094) (xy 166.593996 -291.348487)
			(xy 166.640012 -291.331035) (xy 166.688231 -291.321191) (xy 166.737406 -291.31921) (xy 166.786261 -291.325142)
			(xy 166.833532 -291.338834) (xy 166.877994 -291.359932) (xy 166.918497 -291.387888) (xy 166.95399 -291.42198)
			(xy 166.983555 -291.461324) (xy 167.006426 -291.504901) (xy 167.02201 -291.551582) (xy 167.029905 -291.600159)
			(xy 167.0304 -291.624766) (xy 167.369248 -291.624766) (xy 167.373208 -291.575712) (xy 167.384985 -291.527928)
			(xy 167.404276 -291.482652) (xy 167.430579 -291.441056) (xy 167.463214 -291.404219) (xy 167.501335 -291.373094)
			(xy 167.543956 -291.348487) (xy 167.589972 -291.331035) (xy 167.638191 -291.321191) (xy 167.687366 -291.31921)
			(xy 167.736221 -291.325142) (xy 167.783492 -291.338834) (xy 167.827954 -291.359932) (xy 167.868457 -291.387888)
			(xy 167.90395 -291.42198) (xy 167.933515 -291.461324) (xy 167.956386 -291.504901) (xy 167.97197 -291.551582)
			(xy 167.979865 -291.600159) (xy 167.98036 -291.624766) (xy 168.319208 -291.624766) (xy 168.323168 -291.575712)
			(xy 168.334945 -291.527928) (xy 168.354236 -291.482652) (xy 168.380539 -291.441056) (xy 168.413174 -291.404219)
			(xy 168.451295 -291.373094) (xy 168.493916 -291.348487) (xy 168.539932 -291.331035) (xy 168.588151 -291.321191)
			(xy 168.637326 -291.31921) (xy 168.686181 -291.325142) (xy 168.733452 -291.338834) (xy 168.777914 -291.359932)
			(xy 168.818417 -291.387888) (xy 168.85391 -291.42198) (xy 168.883475 -291.461324) (xy 168.906346 -291.504901)
			(xy 168.92193 -291.551582) (xy 168.929825 -291.600159) (xy 168.93032 -291.624766) (xy 169.269168 -291.624766)
			(xy 169.273128 -291.575712) (xy 169.284905 -291.527928) (xy 169.304196 -291.482652) (xy 169.330499 -291.441056)
			(xy 169.363134 -291.404219) (xy 169.401255 -291.373094) (xy 169.443876 -291.348487) (xy 169.489892 -291.331035)
			(xy 169.538111 -291.321191) (xy 169.587286 -291.31921) (xy 169.636141 -291.325142) (xy 169.683412 -291.338834)
			(xy 169.727874 -291.359932) (xy 169.768377 -291.387888) (xy 169.80387 -291.42198) (xy 169.833435 -291.461324)
			(xy 169.856306 -291.504901) (xy 169.87189 -291.551582) (xy 169.879785 -291.600159) (xy 169.88028 -291.624766)
			(xy 170.219128 -291.624766) (xy 170.223088 -291.575712) (xy 170.234865 -291.527928) (xy 170.254156 -291.482652)
			(xy 170.280459 -291.441056) (xy 170.313094 -291.404219) (xy 170.351215 -291.373094) (xy 170.393836 -291.348487)
			(xy 170.439852 -291.331035) (xy 170.488071 -291.321191) (xy 170.537246 -291.31921) (xy 170.586101 -291.325142)
			(xy 170.633372 -291.338834) (xy 170.677834 -291.359932) (xy 170.718337 -291.387888) (xy 170.75383 -291.42198)
			(xy 170.783395 -291.461324) (xy 170.806266 -291.504901) (xy 170.82185 -291.551582) (xy 170.829745 -291.600159)
			(xy 170.83024 -291.624766) (xy 171.169088 -291.624766) (xy 171.173048 -291.575712) (xy 171.184825 -291.527928)
			(xy 171.204116 -291.482652) (xy 171.230419 -291.441056) (xy 171.263054 -291.404219) (xy 171.301175 -291.373094)
			(xy 171.343796 -291.348487) (xy 171.389812 -291.331035) (xy 171.438031 -291.321191) (xy 171.487206 -291.31921)
			(xy 171.536061 -291.325142) (xy 171.583332 -291.338834) (xy 171.627794 -291.359932) (xy 171.668297 -291.387888)
			(xy 171.70379 -291.42198) (xy 171.733355 -291.461324) (xy 171.756226 -291.504901) (xy 171.77181 -291.551582)
			(xy 171.779705 -291.600159) (xy 171.7802 -291.624766) (xy 172.119048 -291.624766) (xy 172.123008 -291.575712)
			(xy 172.134785 -291.527928) (xy 172.154076 -291.482652) (xy 172.180379 -291.441056) (xy 172.213014 -291.404219)
			(xy 172.251135 -291.373094) (xy 172.293756 -291.348487) (xy 172.339772 -291.331035) (xy 172.387991 -291.321191)
			(xy 172.437166 -291.31921) (xy 172.486021 -291.325142) (xy 172.533292 -291.338834) (xy 172.577754 -291.359932)
			(xy 172.618257 -291.387888) (xy 172.65375 -291.42198) (xy 172.683315 -291.461324) (xy 172.706186 -291.504901)
			(xy 172.72177 -291.551582) (xy 172.729665 -291.600159) (xy 172.73016 -291.624766) (xy 173.069262 -291.624766)
			(xy 173.073222 -291.575712) (xy 173.084999 -291.527928) (xy 173.10429 -291.482652) (xy 173.130593 -291.441056)
			(xy 173.163228 -291.404219) (xy 173.201349 -291.373094) (xy 173.24397 -291.348487) (xy 173.289986 -291.331035)
			(xy 173.338205 -291.321191) (xy 173.38738 -291.31921) (xy 173.436235 -291.325142) (xy 173.483506 -291.338834)
			(xy 173.527968 -291.359932) (xy 173.568471 -291.387888) (xy 173.603964 -291.42198) (xy 173.633529 -291.461324)
			(xy 173.6564 -291.504901) (xy 173.671984 -291.551582) (xy 173.679879 -291.600159) (xy 173.680374 -291.624766)
			(xy 174.019222 -291.624766) (xy 174.023182 -291.575712) (xy 174.034959 -291.527928) (xy 174.05425 -291.482652)
			(xy 174.080553 -291.441056) (xy 174.113188 -291.404219) (xy 174.151309 -291.373094) (xy 174.19393 -291.348487)
			(xy 174.239946 -291.331035) (xy 174.288165 -291.321191) (xy 174.33734 -291.31921) (xy 174.386195 -291.325142)
			(xy 174.433466 -291.338834) (xy 174.477928 -291.359932) (xy 174.518431 -291.387888) (xy 174.553924 -291.42198)
			(xy 174.583489 -291.461324) (xy 174.60636 -291.504901) (xy 174.621944 -291.551582) (xy 174.629839 -291.600159)
			(xy 174.630334 -291.624766) (xy 175.919142 -291.624766) (xy 175.923102 -291.575712) (xy 175.934879 -291.527928)
			(xy 175.95417 -291.482652) (xy 175.980473 -291.441056) (xy 176.013108 -291.404219) (xy 176.051229 -291.373094)
			(xy 176.09385 -291.348487) (xy 176.139866 -291.331035) (xy 176.188085 -291.321191) (xy 176.23726 -291.31921)
			(xy 176.286115 -291.325142) (xy 176.333386 -291.338834) (xy 176.377848 -291.359932) (xy 176.418351 -291.387888)
			(xy 176.453844 -291.42198) (xy 176.483409 -291.461324) (xy 176.50628 -291.504901) (xy 176.521864 -291.551582)
			(xy 176.529759 -291.600159) (xy 176.530254 -291.624766) (xy 176.869102 -291.624766) (xy 176.873062 -291.575712)
			(xy 176.884839 -291.527928) (xy 176.90413 -291.482652) (xy 176.930433 -291.441056) (xy 176.963068 -291.404219)
			(xy 177.001189 -291.373094) (xy 177.04381 -291.348487) (xy 177.089826 -291.331035) (xy 177.138045 -291.321191)
			(xy 177.18722 -291.31921) (xy 177.236075 -291.325142) (xy 177.283346 -291.338834) (xy 177.327808 -291.359932)
			(xy 177.368311 -291.387888) (xy 177.403804 -291.42198) (xy 177.433369 -291.461324) (xy 177.45624 -291.504901)
			(xy 177.471824 -291.551582) (xy 177.479719 -291.600159) (xy 177.480214 -291.624766) (xy 177.819062 -291.624766)
			(xy 177.823022 -291.575712) (xy 177.834799 -291.527928) (xy 177.85409 -291.482652) (xy 177.880393 -291.441056)
			(xy 177.913028 -291.404219) (xy 177.951149 -291.373094) (xy 177.99377 -291.348487) (xy 178.039786 -291.331035)
			(xy 178.088005 -291.321191) (xy 178.13718 -291.31921) (xy 178.186035 -291.325142) (xy 178.233306 -291.338834)
			(xy 178.277768 -291.359932) (xy 178.318271 -291.387888) (xy 178.353764 -291.42198) (xy 178.383329 -291.461324)
			(xy 178.4062 -291.504901) (xy 178.421784 -291.551582) (xy 178.429679 -291.600159) (xy 178.430174 -291.624766)
			(xy 178.769276 -291.624766) (xy 178.773236 -291.575712) (xy 178.785013 -291.527928) (xy 178.804304 -291.482652)
			(xy 178.830607 -291.441056) (xy 178.863242 -291.404219) (xy 178.901363 -291.373094) (xy 178.943984 -291.348487)
			(xy 178.99 -291.331035) (xy 179.038219 -291.321191) (xy 179.087394 -291.31921) (xy 179.136249 -291.325142)
			(xy 179.18352 -291.338834) (xy 179.227982 -291.359932) (xy 179.268485 -291.387888) (xy 179.303978 -291.42198)
			(xy 179.333543 -291.461324) (xy 179.356414 -291.504901) (xy 179.371998 -291.551582) (xy 179.379893 -291.600159)
			(xy 179.380388 -291.624766) (xy 179.719236 -291.624766) (xy 179.723196 -291.575712) (xy 179.734973 -291.527928)
			(xy 179.754264 -291.482652) (xy 179.780567 -291.441056) (xy 179.813202 -291.404219) (xy 179.851323 -291.373094)
			(xy 179.893944 -291.348487) (xy 179.93996 -291.331035) (xy 179.988179 -291.321191) (xy 180.037354 -291.31921)
			(xy 180.086209 -291.325142) (xy 180.13348 -291.338834) (xy 180.177942 -291.359932) (xy 180.218445 -291.387888)
			(xy 180.253938 -291.42198) (xy 180.283503 -291.461324) (xy 180.306374 -291.504901) (xy 180.321958 -291.551582)
			(xy 180.329853 -291.600159) (xy 180.330348 -291.624766) (xy 180.669196 -291.624766) (xy 180.673156 -291.575712)
			(xy 180.684933 -291.527928) (xy 180.704224 -291.482652) (xy 180.730527 -291.441056) (xy 180.763162 -291.404219)
			(xy 180.801283 -291.373094) (xy 180.843904 -291.348487) (xy 180.88992 -291.331035) (xy 180.938139 -291.321191)
			(xy 180.987314 -291.31921) (xy 181.036169 -291.325142) (xy 181.08344 -291.338834) (xy 181.127902 -291.359932)
			(xy 181.168405 -291.387888) (xy 181.203898 -291.42198) (xy 181.233463 -291.461324) (xy 181.256334 -291.504901)
			(xy 181.271918 -291.551582) (xy 181.279813 -291.600159) (xy 181.280308 -291.624766) (xy 181.619156 -291.624766)
			(xy 181.623116 -291.575712) (xy 181.634893 -291.527928) (xy 181.654184 -291.482652) (xy 181.680487 -291.441056)
			(xy 181.713122 -291.404219) (xy 181.751243 -291.373094) (xy 181.793864 -291.348487) (xy 181.83988 -291.331035)
			(xy 181.888099 -291.321191) (xy 181.937274 -291.31921) (xy 181.986129 -291.325142) (xy 182.0334 -291.338834)
			(xy 182.077862 -291.359932) (xy 182.118365 -291.387888) (xy 182.153858 -291.42198) (xy 182.183423 -291.461324)
			(xy 182.206294 -291.504901) (xy 182.221878 -291.551582) (xy 182.229773 -291.600159) (xy 182.230268 -291.624766)
			(xy 182.569116 -291.624766) (xy 182.573076 -291.575712) (xy 182.584853 -291.527928) (xy 182.604144 -291.482652)
			(xy 182.630447 -291.441056) (xy 182.663082 -291.404219) (xy 182.701203 -291.373094) (xy 182.743824 -291.348487)
			(xy 182.78984 -291.331035) (xy 182.838059 -291.321191) (xy 182.887234 -291.31921) (xy 182.936089 -291.325142)
			(xy 182.98336 -291.338834) (xy 183.027822 -291.359932) (xy 183.068325 -291.387888) (xy 183.103818 -291.42198)
			(xy 183.133383 -291.461324) (xy 183.156254 -291.504901) (xy 183.171838 -291.551582) (xy 183.179733 -291.600159)
			(xy 183.180228 -291.624766) (xy 183.519076 -291.624766) (xy 183.523036 -291.575712) (xy 183.534813 -291.527928)
			(xy 183.554104 -291.482652) (xy 183.580407 -291.441056) (xy 183.613042 -291.404219) (xy 183.651163 -291.373094)
			(xy 183.693784 -291.348487) (xy 183.7398 -291.331035) (xy 183.788019 -291.321191) (xy 183.837194 -291.31921)
			(xy 183.886049 -291.325142) (xy 183.93332 -291.338834) (xy 183.977782 -291.359932) (xy 184.018285 -291.387888)
			(xy 184.053778 -291.42198) (xy 184.083343 -291.461324) (xy 184.106214 -291.504901) (xy 184.121798 -291.551582)
			(xy 184.129693 -291.600159) (xy 184.130188 -291.624766) (xy 184.129693 -291.649373) (xy 184.121798 -291.69795)
			(xy 184.106214 -291.744631) (xy 184.083343 -291.788208) (xy 184.053778 -291.827552) (xy 184.018285 -291.861644)
			(xy 183.977782 -291.8896) (xy 183.93332 -291.910698) (xy 183.886049 -291.92439) (xy 183.837194 -291.930322)
			(xy 183.788019 -291.928341) (xy 183.7398 -291.918497) (xy 183.693784 -291.901045) (xy 183.651163 -291.876438)
			(xy 183.613042 -291.845313) (xy 183.580407 -291.808476) (xy 183.554104 -291.76688) (xy 183.534813 -291.721604)
			(xy 183.523036 -291.67382) (xy 183.519076 -291.624766) (xy 183.180228 -291.624766) (xy 183.179733 -291.649373)
			(xy 183.171838 -291.69795) (xy 183.156254 -291.744631) (xy 183.133383 -291.788208) (xy 183.103818 -291.827552)
			(xy 183.068325 -291.861644) (xy 183.027822 -291.8896) (xy 182.98336 -291.910698) (xy 182.936089 -291.92439)
			(xy 182.887234 -291.930322) (xy 182.838059 -291.928341) (xy 182.78984 -291.918497) (xy 182.743824 -291.901045)
			(xy 182.701203 -291.876438) (xy 182.663082 -291.845313) (xy 182.630447 -291.808476) (xy 182.604144 -291.76688)
			(xy 182.584853 -291.721604) (xy 182.573076 -291.67382) (xy 182.569116 -291.624766) (xy 182.230268 -291.624766)
			(xy 182.229773 -291.649373) (xy 182.221878 -291.69795) (xy 182.206294 -291.744631) (xy 182.183423 -291.788208)
			(xy 182.153858 -291.827552) (xy 182.118365 -291.861644) (xy 182.077862 -291.8896) (xy 182.0334 -291.910698)
			(xy 181.986129 -291.92439) (xy 181.937274 -291.930322) (xy 181.888099 -291.928341) (xy 181.83988 -291.918497)
			(xy 181.793864 -291.901045) (xy 181.751243 -291.876438) (xy 181.713122 -291.845313) (xy 181.680487 -291.808476)
			(xy 181.654184 -291.76688) (xy 181.634893 -291.721604) (xy 181.623116 -291.67382) (xy 181.619156 -291.624766)
			(xy 181.280308 -291.624766) (xy 181.279813 -291.649373) (xy 181.271918 -291.69795) (xy 181.256334 -291.744631)
			(xy 181.233463 -291.788208) (xy 181.203898 -291.827552) (xy 181.168405 -291.861644) (xy 181.127902 -291.8896)
			(xy 181.08344 -291.910698) (xy 181.036169 -291.92439) (xy 180.987314 -291.930322) (xy 180.938139 -291.928341)
			(xy 180.88992 -291.918497) (xy 180.843904 -291.901045) (xy 180.801283 -291.876438) (xy 180.763162 -291.845313)
			(xy 180.730527 -291.808476) (xy 180.704224 -291.76688) (xy 180.684933 -291.721604) (xy 180.673156 -291.67382)
			(xy 180.669196 -291.624766) (xy 180.330348 -291.624766) (xy 180.329853 -291.649373) (xy 180.321958 -291.69795)
			(xy 180.306374 -291.744631) (xy 180.283503 -291.788208) (xy 180.253938 -291.827552) (xy 180.218445 -291.861644)
			(xy 180.177942 -291.8896) (xy 180.13348 -291.910698) (xy 180.086209 -291.92439) (xy 180.037354 -291.930322)
			(xy 179.988179 -291.928341) (xy 179.93996 -291.918497) (xy 179.893944 -291.901045) (xy 179.851323 -291.876438)
			(xy 179.813202 -291.845313) (xy 179.780567 -291.808476) (xy 179.754264 -291.76688) (xy 179.734973 -291.721604)
			(xy 179.723196 -291.67382) (xy 179.719236 -291.624766) (xy 179.380388 -291.624766) (xy 179.379893 -291.649373)
			(xy 179.371998 -291.69795) (xy 179.356414 -291.744631) (xy 179.333543 -291.788208) (xy 179.303978 -291.827552)
			(xy 179.268485 -291.861644) (xy 179.227982 -291.8896) (xy 179.18352 -291.910698) (xy 179.136249 -291.92439)
			(xy 179.087394 -291.930322) (xy 179.038219 -291.928341) (xy 178.99 -291.918497) (xy 178.943984 -291.901045)
			(xy 178.901363 -291.876438) (xy 178.863242 -291.845313) (xy 178.830607 -291.808476) (xy 178.804304 -291.76688)
			(xy 178.785013 -291.721604) (xy 178.773236 -291.67382) (xy 178.769276 -291.624766) (xy 178.430174 -291.624766)
			(xy 178.429679 -291.649373) (xy 178.421784 -291.69795) (xy 178.4062 -291.744631) (xy 178.383329 -291.788208)
			(xy 178.353764 -291.827552) (xy 178.318271 -291.861644) (xy 178.277768 -291.8896) (xy 178.233306 -291.910698)
			(xy 178.186035 -291.92439) (xy 178.13718 -291.930322) (xy 178.088005 -291.928341) (xy 178.039786 -291.918497)
			(xy 177.99377 -291.901045) (xy 177.951149 -291.876438) (xy 177.913028 -291.845313) (xy 177.880393 -291.808476)
			(xy 177.85409 -291.76688) (xy 177.834799 -291.721604) (xy 177.823022 -291.67382) (xy 177.819062 -291.624766)
			(xy 177.480214 -291.624766) (xy 177.479719 -291.649373) (xy 177.471824 -291.69795) (xy 177.45624 -291.744631)
			(xy 177.433369 -291.788208) (xy 177.403804 -291.827552) (xy 177.368311 -291.861644) (xy 177.327808 -291.8896)
			(xy 177.283346 -291.910698) (xy 177.236075 -291.92439) (xy 177.18722 -291.930322) (xy 177.138045 -291.928341)
			(xy 177.089826 -291.918497) (xy 177.04381 -291.901045) (xy 177.001189 -291.876438) (xy 176.963068 -291.845313)
			(xy 176.930433 -291.808476) (xy 176.90413 -291.76688) (xy 176.884839 -291.721604) (xy 176.873062 -291.67382)
			(xy 176.869102 -291.624766) (xy 176.530254 -291.624766) (xy 176.529759 -291.649373) (xy 176.521864 -291.69795)
			(xy 176.50628 -291.744631) (xy 176.483409 -291.788208) (xy 176.453844 -291.827552) (xy 176.418351 -291.861644)
			(xy 176.377848 -291.8896) (xy 176.333386 -291.910698) (xy 176.286115 -291.92439) (xy 176.23726 -291.930322)
			(xy 176.188085 -291.928341) (xy 176.139866 -291.918497) (xy 176.09385 -291.901045) (xy 176.051229 -291.876438)
			(xy 176.013108 -291.845313) (xy 175.980473 -291.808476) (xy 175.95417 -291.76688) (xy 175.934879 -291.721604)
			(xy 175.923102 -291.67382) (xy 175.919142 -291.624766) (xy 174.630334 -291.624766) (xy 174.629839 -291.649373)
			(xy 174.621944 -291.69795) (xy 174.60636 -291.744631) (xy 174.583489 -291.788208) (xy 174.553924 -291.827552)
			(xy 174.518431 -291.861644) (xy 174.477928 -291.8896) (xy 174.433466 -291.910698) (xy 174.386195 -291.92439)
			(xy 174.33734 -291.930322) (xy 174.288165 -291.928341) (xy 174.239946 -291.918497) (xy 174.19393 -291.901045)
			(xy 174.151309 -291.876438) (xy 174.113188 -291.845313) (xy 174.080553 -291.808476) (xy 174.05425 -291.76688)
			(xy 174.034959 -291.721604) (xy 174.023182 -291.67382) (xy 174.019222 -291.624766) (xy 173.680374 -291.624766)
			(xy 173.679879 -291.649373) (xy 173.671984 -291.69795) (xy 173.6564 -291.744631) (xy 173.633529 -291.788208)
			(xy 173.603964 -291.827552) (xy 173.568471 -291.861644) (xy 173.527968 -291.8896) (xy 173.483506 -291.910698)
			(xy 173.436235 -291.92439) (xy 173.38738 -291.930322) (xy 173.338205 -291.928341) (xy 173.289986 -291.918497)
			(xy 173.24397 -291.901045) (xy 173.201349 -291.876438) (xy 173.163228 -291.845313) (xy 173.130593 -291.808476)
			(xy 173.10429 -291.76688) (xy 173.084999 -291.721604) (xy 173.073222 -291.67382) (xy 173.069262 -291.624766)
			(xy 172.73016 -291.624766) (xy 172.729665 -291.649373) (xy 172.72177 -291.69795) (xy 172.706186 -291.744631)
			(xy 172.683315 -291.788208) (xy 172.65375 -291.827552) (xy 172.618257 -291.861644) (xy 172.577754 -291.8896)
			(xy 172.533292 -291.910698) (xy 172.486021 -291.92439) (xy 172.437166 -291.930322) (xy 172.387991 -291.928341)
			(xy 172.339772 -291.918497) (xy 172.293756 -291.901045) (xy 172.251135 -291.876438) (xy 172.213014 -291.845313)
			(xy 172.180379 -291.808476) (xy 172.154076 -291.76688) (xy 172.134785 -291.721604) (xy 172.123008 -291.67382)
			(xy 172.119048 -291.624766) (xy 171.7802 -291.624766) (xy 171.779705 -291.649373) (xy 171.77181 -291.69795)
			(xy 171.756226 -291.744631) (xy 171.733355 -291.788208) (xy 171.70379 -291.827552) (xy 171.668297 -291.861644)
			(xy 171.627794 -291.8896) (xy 171.583332 -291.910698) (xy 171.536061 -291.92439) (xy 171.487206 -291.930322)
			(xy 171.438031 -291.928341) (xy 171.389812 -291.918497) (xy 171.343796 -291.901045) (xy 171.301175 -291.876438)
			(xy 171.263054 -291.845313) (xy 171.230419 -291.808476) (xy 171.204116 -291.76688) (xy 171.184825 -291.721604)
			(xy 171.173048 -291.67382) (xy 171.169088 -291.624766) (xy 170.83024 -291.624766) (xy 170.829745 -291.649373)
			(xy 170.82185 -291.69795) (xy 170.806266 -291.744631) (xy 170.783395 -291.788208) (xy 170.75383 -291.827552)
			(xy 170.718337 -291.861644) (xy 170.677834 -291.8896) (xy 170.633372 -291.910698) (xy 170.586101 -291.92439)
			(xy 170.537246 -291.930322) (xy 170.488071 -291.928341) (xy 170.439852 -291.918497) (xy 170.393836 -291.901045)
			(xy 170.351215 -291.876438) (xy 170.313094 -291.845313) (xy 170.280459 -291.808476) (xy 170.254156 -291.76688)
			(xy 170.234865 -291.721604) (xy 170.223088 -291.67382) (xy 170.219128 -291.624766) (xy 169.88028 -291.624766)
			(xy 169.879785 -291.649373) (xy 169.87189 -291.69795) (xy 169.856306 -291.744631) (xy 169.833435 -291.788208)
			(xy 169.80387 -291.827552) (xy 169.768377 -291.861644) (xy 169.727874 -291.8896) (xy 169.683412 -291.910698)
			(xy 169.636141 -291.92439) (xy 169.587286 -291.930322) (xy 169.538111 -291.928341) (xy 169.489892 -291.918497)
			(xy 169.443876 -291.901045) (xy 169.401255 -291.876438) (xy 169.363134 -291.845313) (xy 169.330499 -291.808476)
			(xy 169.304196 -291.76688) (xy 169.284905 -291.721604) (xy 169.273128 -291.67382) (xy 169.269168 -291.624766)
			(xy 168.93032 -291.624766) (xy 168.929825 -291.649373) (xy 168.92193 -291.69795) (xy 168.906346 -291.744631)
			(xy 168.883475 -291.788208) (xy 168.85391 -291.827552) (xy 168.818417 -291.861644) (xy 168.777914 -291.8896)
			(xy 168.733452 -291.910698) (xy 168.686181 -291.92439) (xy 168.637326 -291.930322) (xy 168.588151 -291.928341)
			(xy 168.539932 -291.918497) (xy 168.493916 -291.901045) (xy 168.451295 -291.876438) (xy 168.413174 -291.845313)
			(xy 168.380539 -291.808476) (xy 168.354236 -291.76688) (xy 168.334945 -291.721604) (xy 168.323168 -291.67382)
			(xy 168.319208 -291.624766) (xy 167.98036 -291.624766) (xy 167.979865 -291.649373) (xy 167.97197 -291.69795)
			(xy 167.956386 -291.744631) (xy 167.933515 -291.788208) (xy 167.90395 -291.827552) (xy 167.868457 -291.861644)
			(xy 167.827954 -291.8896) (xy 167.783492 -291.910698) (xy 167.736221 -291.92439) (xy 167.687366 -291.930322)
			(xy 167.638191 -291.928341) (xy 167.589972 -291.918497) (xy 167.543956 -291.901045) (xy 167.501335 -291.876438)
			(xy 167.463214 -291.845313) (xy 167.430579 -291.808476) (xy 167.404276 -291.76688) (xy 167.384985 -291.721604)
			(xy 167.373208 -291.67382) (xy 167.369248 -291.624766) (xy 167.0304 -291.624766) (xy 167.029905 -291.649373)
			(xy 167.02201 -291.69795) (xy 167.006426 -291.744631) (xy 166.983555 -291.788208) (xy 166.95399 -291.827552)
			(xy 166.918497 -291.861644) (xy 166.877994 -291.8896) (xy 166.833532 -291.910698) (xy 166.786261 -291.92439)
			(xy 166.737406 -291.930322) (xy 166.688231 -291.928341) (xy 166.640012 -291.918497) (xy 166.593996 -291.901045)
			(xy 166.551375 -291.876438) (xy 166.513254 -291.845313) (xy 166.480619 -291.808476) (xy 166.454316 -291.76688)
			(xy 166.435025 -291.721604) (xy 166.423248 -291.67382) (xy 166.419288 -291.624766) (xy 165.130226 -291.624766)
			(xy 165.129731 -291.649373) (xy 165.121836 -291.69795) (xy 165.106252 -291.744631) (xy 165.083381 -291.788208)
			(xy 165.053816 -291.827552) (xy 165.018323 -291.861644) (xy 164.97782 -291.8896) (xy 164.933358 -291.910698)
			(xy 164.886087 -291.92439) (xy 164.837232 -291.930322) (xy 164.788057 -291.928341) (xy 164.739838 -291.918497)
			(xy 164.693822 -291.901045) (xy 164.651201 -291.876438) (xy 164.61308 -291.845313) (xy 164.580445 -291.808476)
			(xy 164.554142 -291.76688) (xy 164.534851 -291.721604) (xy 164.523074 -291.67382) (xy 164.519114 -291.624766)
			(xy 164.180266 -291.624766) (xy 164.179771 -291.649373) (xy 164.171876 -291.69795) (xy 164.156292 -291.744631)
			(xy 164.133421 -291.788208) (xy 164.103856 -291.827552) (xy 164.068363 -291.861644) (xy 164.02786 -291.8896)
			(xy 163.983398 -291.910698) (xy 163.936127 -291.92439) (xy 163.887272 -291.930322) (xy 163.838097 -291.928341)
			(xy 163.789878 -291.918497) (xy 163.743862 -291.901045) (xy 163.701241 -291.876438) (xy 163.66312 -291.845313)
			(xy 163.630485 -291.808476) (xy 163.604182 -291.76688) (xy 163.584891 -291.721604) (xy 163.573114 -291.67382)
			(xy 163.569154 -291.624766) (xy 162.280346 -291.624766) (xy 162.279851 -291.649373) (xy 162.271956 -291.69795)
			(xy 162.256372 -291.744631) (xy 162.233501 -291.788208) (xy 162.203936 -291.827552) (xy 162.168443 -291.861644)
			(xy 162.12794 -291.8896) (xy 162.083478 -291.910698) (xy 162.036207 -291.92439) (xy 161.987352 -291.930322)
			(xy 161.938177 -291.928341) (xy 161.889958 -291.918497) (xy 161.843942 -291.901045) (xy 161.801321 -291.876438)
			(xy 161.7632 -291.845313) (xy 161.730565 -291.808476) (xy 161.704262 -291.76688) (xy 161.684971 -291.721604)
			(xy 161.673194 -291.67382) (xy 161.669234 -291.624766) (xy 161.330386 -291.624766) (xy 161.329891 -291.649373)
			(xy 161.321996 -291.69795) (xy 161.306412 -291.744631) (xy 161.283541 -291.788208) (xy 161.253976 -291.827552)
			(xy 161.218483 -291.861644) (xy 161.17798 -291.8896) (xy 161.133518 -291.910698) (xy 161.086247 -291.92439)
			(xy 161.037392 -291.930322) (xy 160.988217 -291.928341) (xy 160.939998 -291.918497) (xy 160.893982 -291.901045)
			(xy 160.851361 -291.876438) (xy 160.81324 -291.845313) (xy 160.780605 -291.808476) (xy 160.754302 -291.76688)
			(xy 160.735011 -291.721604) (xy 160.723234 -291.67382) (xy 160.719274 -291.624766) (xy 160.380172 -291.624766)
			(xy 160.379677 -291.649373) (xy 160.371782 -291.69795) (xy 160.356198 -291.744631) (xy 160.333327 -291.788208)
			(xy 160.303762 -291.827552) (xy 160.268269 -291.861644) (xy 160.227766 -291.8896) (xy 160.183304 -291.910698)
			(xy 160.136033 -291.92439) (xy 160.087178 -291.930322) (xy 160.038003 -291.928341) (xy 159.989784 -291.918497)
			(xy 159.943768 -291.901045) (xy 159.901147 -291.876438) (xy 159.863026 -291.845313) (xy 159.830391 -291.808476)
			(xy 159.804088 -291.76688) (xy 159.784797 -291.721604) (xy 159.77302 -291.67382) (xy 159.76906 -291.624766)
			(xy 159.430212 -291.624766) (xy 159.429717 -291.649373) (xy 159.421822 -291.69795) (xy 159.406238 -291.744631)
			(xy 159.383367 -291.788208) (xy 159.353802 -291.827552) (xy 159.318309 -291.861644) (xy 159.277806 -291.8896)
			(xy 159.233344 -291.910698) (xy 159.186073 -291.92439) (xy 159.137218 -291.930322) (xy 159.088043 -291.928341)
			(xy 159.039824 -291.918497) (xy 158.993808 -291.901045) (xy 158.951187 -291.876438) (xy 158.913066 -291.845313)
			(xy 158.880431 -291.808476) (xy 158.854128 -291.76688) (xy 158.834837 -291.721604) (xy 158.82306 -291.67382)
			(xy 158.8191 -291.624766) (xy 158.480252 -291.624766) (xy 158.479757 -291.649373) (xy 158.471862 -291.69795)
			(xy 158.456278 -291.744631) (xy 158.433407 -291.788208) (xy 158.403842 -291.827552) (xy 158.368349 -291.861644)
			(xy 158.327846 -291.8896) (xy 158.283384 -291.910698) (xy 158.236113 -291.92439) (xy 158.187258 -291.930322)
			(xy 158.138083 -291.928341) (xy 158.089864 -291.918497) (xy 158.043848 -291.901045) (xy 158.001227 -291.876438)
			(xy 157.963106 -291.845313) (xy 157.930471 -291.808476) (xy 157.904168 -291.76688) (xy 157.884877 -291.721604)
			(xy 157.8731 -291.67382) (xy 157.86914 -291.624766) (xy 157.530292 -291.624766) (xy 157.529797 -291.649373)
			(xy 157.521902 -291.69795) (xy 157.506318 -291.744631) (xy 157.483447 -291.788208) (xy 157.453882 -291.827552)
			(xy 157.418389 -291.861644) (xy 157.377886 -291.8896) (xy 157.333424 -291.910698) (xy 157.286153 -291.92439)
			(xy 157.237298 -291.930322) (xy 157.188123 -291.928341) (xy 157.139904 -291.918497) (xy 157.093888 -291.901045)
			(xy 157.051267 -291.876438) (xy 157.013146 -291.845313) (xy 156.980511 -291.808476) (xy 156.954208 -291.76688)
			(xy 156.934917 -291.721604) (xy 156.92314 -291.67382) (xy 156.91918 -291.624766) (xy 154.680412 -291.624766)
			(xy 154.679917 -291.649373) (xy 154.672022 -291.69795) (xy 154.656438 -291.744631) (xy 154.633567 -291.788208)
			(xy 154.604002 -291.827552) (xy 154.568509 -291.861644) (xy 154.528006 -291.8896) (xy 154.483544 -291.910698)
			(xy 154.436273 -291.92439) (xy 154.387418 -291.930322) (xy 154.338243 -291.928341) (xy 154.290024 -291.918497)
			(xy 154.244008 -291.901045) (xy 154.201387 -291.876438) (xy 154.163266 -291.845313) (xy 154.130631 -291.808476)
			(xy 154.104328 -291.76688) (xy 154.085037 -291.721604) (xy 154.07326 -291.67382) (xy 154.0693 -291.624766)
			(xy 153.730198 -291.624766) (xy 153.729703 -291.649373) (xy 153.721808 -291.69795) (xy 153.706224 -291.744631)
			(xy 153.683353 -291.788208) (xy 153.653788 -291.827552) (xy 153.618295 -291.861644) (xy 153.577792 -291.8896)
			(xy 153.53333 -291.910698) (xy 153.486059 -291.92439) (xy 153.437204 -291.930322) (xy 153.388029 -291.928341)
			(xy 153.33981 -291.918497) (xy 153.293794 -291.901045) (xy 153.251173 -291.876438) (xy 153.213052 -291.845313)
			(xy 153.180417 -291.808476) (xy 153.154114 -291.76688) (xy 153.134823 -291.721604) (xy 153.123046 -291.67382)
			(xy 153.119086 -291.624766) (xy 152.780238 -291.624766) (xy 152.779743 -291.649373) (xy 152.771848 -291.69795)
			(xy 152.756264 -291.744631) (xy 152.733393 -291.788208) (xy 152.703828 -291.827552) (xy 152.668335 -291.861644)
			(xy 152.627832 -291.8896) (xy 152.58337 -291.910698) (xy 152.536099 -291.92439) (xy 152.487244 -291.930322)
			(xy 152.438069 -291.928341) (xy 152.38985 -291.918497) (xy 152.343834 -291.901045) (xy 152.301213 -291.876438)
			(xy 152.263092 -291.845313) (xy 152.230457 -291.808476) (xy 152.204154 -291.76688) (xy 152.184863 -291.721604)
			(xy 152.173086 -291.67382) (xy 152.169126 -291.624766) (xy 144.107012 -291.624766) (xy 144.081098 -291.663935)
			(xy 144.043881 -291.705472) (xy 144.001013 -291.741147) (xy 143.953407 -291.770201) (xy 143.902078 -291.792013)
			(xy 143.848121 -291.806119) (xy 143.792684 -291.812219) (xy 143.73695 -291.810182) (xy 143.682107 -291.800052)
			(xy 143.629323 -291.782045) (xy 143.579723 -291.756544) (xy 143.534365 -291.724093) (xy 143.494216 -291.685384)
			(xy 143.46013 -291.641241) (xy 143.432834 -291.592606) (xy 143.412911 -291.540515) (xy 143.400785 -291.486078)
			(xy 143.396714 -291.430456) (xy 142.675102 -291.430456) (xy 142.674593 -291.458342) (xy 142.666473 -291.513518)
			(xy 142.650405 -291.566925) (xy 142.626733 -291.617422) (xy 142.59596 -291.663935) (xy 142.558743 -291.705472)
			(xy 142.515875 -291.741147) (xy 142.468269 -291.770201) (xy 142.41694 -291.792013) (xy 142.362983 -291.806119)
			(xy 142.307546 -291.812219) (xy 142.251812 -291.810182) (xy 142.196969 -291.800052) (xy 142.144185 -291.782045)
			(xy 142.094585 -291.756544) (xy 142.049227 -291.724093) (xy 142.009078 -291.685384) (xy 141.974992 -291.641241)
			(xy 141.947696 -291.592606) (xy 141.927773 -291.540515) (xy 141.915647 -291.486078) (xy 141.911576 -291.430456)
			(xy 136.349994 -291.430456) (xy 136.349994 -292.732714) (xy 141.911576 -292.732714) (xy 141.915647 -292.677092)
			(xy 141.927773 -292.622655) (xy 141.947696 -292.570564) (xy 141.974992 -292.521929) (xy 142.009078 -292.477786)
			(xy 142.049227 -292.439077) (xy 142.094585 -292.406626) (xy 142.144185 -292.381125) (xy 142.196969 -292.363118)
			(xy 142.251812 -292.352988) (xy 142.307546 -292.350951) (xy 142.362983 -292.357051) (xy 142.41694 -292.371157)
			(xy 142.468269 -292.392969) (xy 142.515875 -292.422023) (xy 142.558743 -292.457698) (xy 142.59596 -292.499235)
			(xy 142.626733 -292.545748) (xy 142.650405 -292.596245) (xy 142.666473 -292.649652) (xy 142.674593 -292.704828)
			(xy 142.675102 -292.732714) (xy 143.387062 -292.732714) (xy 143.391133 -292.677092) (xy 143.403259 -292.622655)
			(xy 143.423182 -292.570564) (xy 143.450478 -292.521929) (xy 143.484564 -292.477786) (xy 143.524713 -292.439077)
			(xy 143.570071 -292.406626) (xy 143.619671 -292.381125) (xy 143.672455 -292.363118) (xy 143.727298 -292.352988)
			(xy 143.783032 -292.350951) (xy 143.838469 -292.357051) (xy 143.892426 -292.371157) (xy 143.943755 -292.392969)
			(xy 143.991361 -292.422023) (xy 144.034229 -292.457698) (xy 144.071446 -292.499235) (xy 144.102219 -292.545748)
			(xy 144.125891 -292.596245) (xy 144.141959 -292.649652) (xy 144.150079 -292.704828) (xy 144.150588 -292.732714)
			(xy 144.276062 -292.732714) (xy 144.280133 -292.677092) (xy 144.292259 -292.622655) (xy 144.312182 -292.570564)
			(xy 144.339478 -292.521929) (xy 144.373564 -292.477786) (xy 144.413713 -292.439077) (xy 144.459071 -292.406626)
			(xy 144.508671 -292.381125) (xy 144.561455 -292.363118) (xy 144.616298 -292.352988) (xy 144.672032 -292.350951)
			(xy 144.727469 -292.357051) (xy 144.781426 -292.371157) (xy 144.832755 -292.392969) (xy 144.880361 -292.422023)
			(xy 144.923229 -292.457698) (xy 144.960446 -292.499235) (xy 144.991219 -292.545748) (xy 145.014891 -292.596245)
			(xy 145.030959 -292.649652) (xy 145.039079 -292.704828) (xy 145.039588 -292.732714) (xy 145.039079 -292.7606)
			(xy 145.030959 -292.815776) (xy 145.014891 -292.869183) (xy 144.991219 -292.91968) (xy 144.960446 -292.966193)
			(xy 144.923229 -293.00773) (xy 144.880361 -293.043405) (xy 144.832755 -293.072459) (xy 144.781426 -293.094271)
			(xy 144.727469 -293.108377) (xy 144.672032 -293.114477) (xy 144.616298 -293.11244) (xy 144.561455 -293.10231)
			(xy 144.508671 -293.084303) (xy 144.459071 -293.058802) (xy 144.413713 -293.026351) (xy 144.373564 -292.987642)
			(xy 144.339478 -292.943499) (xy 144.312182 -292.894864) (xy 144.292259 -292.842773) (xy 144.280133 -292.788336)
			(xy 144.276062 -292.732714) (xy 144.150588 -292.732714) (xy 144.150079 -292.7606) (xy 144.141959 -292.815776)
			(xy 144.125891 -292.869183) (xy 144.102219 -292.91968) (xy 144.071446 -292.966193) (xy 144.034229 -293.00773)
			(xy 143.991361 -293.043405) (xy 143.943755 -293.072459) (xy 143.892426 -293.094271) (xy 143.838469 -293.108377)
			(xy 143.783032 -293.114477) (xy 143.727298 -293.11244) (xy 143.672455 -293.10231) (xy 143.619671 -293.084303)
			(xy 143.570071 -293.058802) (xy 143.524713 -293.026351) (xy 143.484564 -292.987642) (xy 143.450478 -292.943499)
			(xy 143.423182 -292.894864) (xy 143.403259 -292.842773) (xy 143.391133 -292.788336) (xy 143.387062 -292.732714)
			(xy 142.675102 -292.732714) (xy 142.674593 -292.7606) (xy 142.666473 -292.815776) (xy 142.650405 -292.869183)
			(xy 142.626733 -292.91968) (xy 142.59596 -292.966193) (xy 142.558743 -293.00773) (xy 142.515875 -293.043405)
			(xy 142.468269 -293.072459) (xy 142.41694 -293.094271) (xy 142.362983 -293.108377) (xy 142.307546 -293.114477)
			(xy 142.251812 -293.11244) (xy 142.196969 -293.10231) (xy 142.144185 -293.084303) (xy 142.094585 -293.058802)
			(xy 142.049227 -293.026351) (xy 142.009078 -292.987642) (xy 141.974992 -292.943499) (xy 141.947696 -292.894864)
			(xy 141.927773 -292.842773) (xy 141.915647 -292.788336) (xy 141.911576 -292.732714) (xy 136.349994 -292.732714)
			(xy 136.349994 -292.943788) (xy 136.349573 -292.953859) (xy 136.341861 -292.972466) (xy 136.335008 -292.979856)
			(xy 135.82015 -293.494714) (xy 147.43811 -293.494714) (xy 147.438654 -293.465332) (xy 147.447683 -293.407265)
			(xy 147.465514 -293.351271) (xy 147.491725 -293.298675) (xy 147.525695 -293.250724) (xy 147.56662 -293.208552)
			(xy 147.589748 -293.190422) (xy 147.598672 -293.182942) (xy 147.609132 -293.162168) (xy 147.609814 -293.150544)
			(xy 147.611084 -293.058596) (xy 147.601178 -293.037514) (xy 147.592034 -293.030148) (xy 147.570186 -293.011942)
			(xy 147.531644 -292.970124) (xy 147.499736 -292.923049) (xy 147.475169 -292.871759) (xy 147.458486 -292.817391)
			(xy 147.450058 -292.761149) (xy 147.44954 -292.732714) (xy 147.450026 -292.705463) (xy 147.457782 -292.651515)
			(xy 147.473137 -292.59922) (xy 147.495779 -292.549643) (xy 147.525245 -292.503793) (xy 147.560936 -292.462602)
			(xy 147.602127 -292.426911) (xy 147.647977 -292.397445) (xy 147.697554 -292.374803) (xy 147.749849 -292.359448)
			(xy 147.803797 -292.351692) (xy 147.858299 -292.351692) (xy 147.912247 -292.359448) (xy 147.964542 -292.374803)
			(xy 148.014119 -292.397445) (xy 148.059969 -292.426911) (xy 148.10116 -292.462602) (xy 148.136851 -292.503793)
			(xy 148.166317 -292.549643) (xy 148.177889 -292.57498) (xy 152.169126 -292.57498) (xy 152.173086 -292.525926)
			(xy 152.184863 -292.478142) (xy 152.204154 -292.432866) (xy 152.230457 -292.39127) (xy 152.263092 -292.354433)
			(xy 152.301213 -292.323308) (xy 152.343834 -292.298701) (xy 152.38985 -292.281249) (xy 152.438069 -292.271405)
			(xy 152.487244 -292.269424) (xy 152.536099 -292.275356) (xy 152.58337 -292.289048) (xy 152.627832 -292.310146)
			(xy 152.668335 -292.338102) (xy 152.703828 -292.372194) (xy 152.733393 -292.411538) (xy 152.756264 -292.455115)
			(xy 152.771848 -292.501796) (xy 152.779743 -292.550373) (xy 152.780238 -292.57498) (xy 153.119086 -292.57498)
			(xy 153.123046 -292.525926) (xy 153.134823 -292.478142) (xy 153.154114 -292.432866) (xy 153.180417 -292.39127)
			(xy 153.213052 -292.354433) (xy 153.251173 -292.323308) (xy 153.293794 -292.298701) (xy 153.33981 -292.281249)
			(xy 153.388029 -292.271405) (xy 153.437204 -292.269424) (xy 153.486059 -292.275356) (xy 153.53333 -292.289048)
			(xy 153.577792 -292.310146) (xy 153.618295 -292.338102) (xy 153.653788 -292.372194) (xy 153.683353 -292.411538)
			(xy 153.706224 -292.455115) (xy 153.721808 -292.501796) (xy 153.729703 -292.550373) (xy 153.730198 -292.57498)
			(xy 154.0693 -292.57498) (xy 154.07326 -292.525926) (xy 154.085037 -292.478142) (xy 154.104328 -292.432866)
			(xy 154.130631 -292.39127) (xy 154.163266 -292.354433) (xy 154.201387 -292.323308) (xy 154.244008 -292.298701)
			(xy 154.290024 -292.281249) (xy 154.338243 -292.271405) (xy 154.387418 -292.269424) (xy 154.436273 -292.275356)
			(xy 154.483544 -292.289048) (xy 154.528006 -292.310146) (xy 154.568509 -292.338102) (xy 154.604002 -292.372194)
			(xy 154.633567 -292.411538) (xy 154.656438 -292.455115) (xy 154.672022 -292.501796) (xy 154.679917 -292.550373)
			(xy 154.680407 -292.574726) (xy 155.01926 -292.574726) (xy 155.02322 -292.525672) (xy 155.034997 -292.477888)
			(xy 155.054288 -292.432612) (xy 155.080591 -292.391016) (xy 155.113226 -292.354179) (xy 155.151347 -292.323054)
			(xy 155.193968 -292.298447) (xy 155.239984 -292.280995) (xy 155.288203 -292.271151) (xy 155.337378 -292.26917)
			(xy 155.386233 -292.275102) (xy 155.433504 -292.288794) (xy 155.477966 -292.309892) (xy 155.518469 -292.337848)
			(xy 155.553962 -292.37194) (xy 155.583527 -292.411284) (xy 155.606398 -292.454861) (xy 155.621982 -292.501542)
			(xy 155.629877 -292.550119) (xy 155.630372 -292.574726) (xy 155.96922 -292.574726) (xy 155.97318 -292.525672)
			(xy 155.984957 -292.477888) (xy 156.004248 -292.432612) (xy 156.030551 -292.391016) (xy 156.063186 -292.354179)
			(xy 156.101307 -292.323054) (xy 156.143928 -292.298447) (xy 156.189944 -292.280995) (xy 156.238163 -292.271151)
			(xy 156.287338 -292.26917) (xy 156.336193 -292.275102) (xy 156.383464 -292.288794) (xy 156.427926 -292.309892)
			(xy 156.468429 -292.337848) (xy 156.503922 -292.37194) (xy 156.533487 -292.411284) (xy 156.556358 -292.454861)
			(xy 156.571942 -292.501542) (xy 156.579837 -292.550119) (xy 156.580332 -292.574726) (xy 156.580327 -292.57498)
			(xy 156.91918 -292.57498) (xy 156.92314 -292.525926) (xy 156.934917 -292.478142) (xy 156.954208 -292.432866)
			(xy 156.980511 -292.39127) (xy 157.013146 -292.354433) (xy 157.051267 -292.323308) (xy 157.093888 -292.298701)
			(xy 157.139904 -292.281249) (xy 157.188123 -292.271405) (xy 157.237298 -292.269424) (xy 157.286153 -292.275356)
			(xy 157.333424 -292.289048) (xy 157.377886 -292.310146) (xy 157.418389 -292.338102) (xy 157.453882 -292.372194)
			(xy 157.483447 -292.411538) (xy 157.506318 -292.455115) (xy 157.521902 -292.501796) (xy 157.529797 -292.550373)
			(xy 157.530292 -292.57498) (xy 157.529797 -292.599587) (xy 157.529465 -292.601629) (xy 157.819334 -292.601629)
			(xy 157.819334 -292.548331) (xy 157.827277 -292.495627) (xy 157.842987 -292.444697) (xy 157.866113 -292.396676)
			(xy 157.896137 -292.352639) (xy 157.932389 -292.313568) (xy 157.97406 -292.280337) (xy 158.020218 -292.253688)
			(xy 158.069832 -292.234216) (xy 158.121794 -292.222356) (xy 158.174944 -292.218373) (xy 158.228094 -292.222356)
			(xy 158.280056 -292.234216) (xy 158.32967 -292.253688) (xy 158.375828 -292.280337) (xy 158.417499 -292.313568)
			(xy 158.453751 -292.352639) (xy 158.483775 -292.396676) (xy 158.506901 -292.444697) (xy 158.522611 -292.495627)
			(xy 158.530554 -292.548331) (xy 158.531052 -292.57498) (xy 158.8191 -292.57498) (xy 158.82306 -292.525926)
			(xy 158.834837 -292.478142) (xy 158.854128 -292.432866) (xy 158.880431 -292.39127) (xy 158.913066 -292.354433)
			(xy 158.951187 -292.323308) (xy 158.993808 -292.298701) (xy 159.039824 -292.281249) (xy 159.088043 -292.271405)
			(xy 159.137218 -292.269424) (xy 159.186073 -292.275356) (xy 159.233344 -292.289048) (xy 159.277806 -292.310146)
			(xy 159.318309 -292.338102) (xy 159.353802 -292.372194) (xy 159.383367 -292.411538) (xy 159.406238 -292.455115)
			(xy 159.421822 -292.501796) (xy 159.429717 -292.550373) (xy 159.430212 -292.57498) (xy 159.76906 -292.57498)
			(xy 159.77302 -292.525926) (xy 159.784797 -292.478142) (xy 159.804088 -292.432866) (xy 159.830391 -292.39127)
			(xy 159.863026 -292.354433) (xy 159.901147 -292.323308) (xy 159.943768 -292.298701) (xy 159.989784 -292.281249)
			(xy 160.038003 -292.271405) (xy 160.087178 -292.269424) (xy 160.136033 -292.275356) (xy 160.183304 -292.289048)
			(xy 160.227766 -292.310146) (xy 160.268269 -292.338102) (xy 160.303762 -292.372194) (xy 160.333327 -292.411538)
			(xy 160.356198 -292.455115) (xy 160.371782 -292.501796) (xy 160.379677 -292.550373) (xy 160.380172 -292.57498)
			(xy 160.719274 -292.57498) (xy 160.723234 -292.525926) (xy 160.735011 -292.478142) (xy 160.754302 -292.432866)
			(xy 160.780605 -292.39127) (xy 160.81324 -292.354433) (xy 160.851361 -292.323308) (xy 160.893982 -292.298701)
			(xy 160.939998 -292.281249) (xy 160.988217 -292.271405) (xy 161.037392 -292.269424) (xy 161.086247 -292.275356)
			(xy 161.133518 -292.289048) (xy 161.17798 -292.310146) (xy 161.218483 -292.338102) (xy 161.253976 -292.372194)
			(xy 161.283541 -292.411538) (xy 161.306412 -292.455115) (xy 161.321996 -292.501796) (xy 161.329891 -292.550373)
			(xy 161.330386 -292.57498) (xy 161.669234 -292.57498) (xy 161.673194 -292.525926) (xy 161.684971 -292.478142)
			(xy 161.704262 -292.432866) (xy 161.730565 -292.39127) (xy 161.7632 -292.354433) (xy 161.801321 -292.323308)
			(xy 161.843942 -292.298701) (xy 161.889958 -292.281249) (xy 161.938177 -292.271405) (xy 161.987352 -292.269424)
			(xy 162.036207 -292.275356) (xy 162.083478 -292.289048) (xy 162.12794 -292.310146) (xy 162.168443 -292.338102)
			(xy 162.203936 -292.372194) (xy 162.233501 -292.411538) (xy 162.256372 -292.455115) (xy 162.271956 -292.501796)
			(xy 162.279851 -292.550373) (xy 162.280346 -292.57498) (xy 162.619194 -292.57498) (xy 162.623154 -292.525926)
			(xy 162.634931 -292.478142) (xy 162.654222 -292.432866) (xy 162.680525 -292.39127) (xy 162.71316 -292.354433)
			(xy 162.751281 -292.323308) (xy 162.793902 -292.298701) (xy 162.839918 -292.281249) (xy 162.888137 -292.271405)
			(xy 162.937312 -292.269424) (xy 162.986167 -292.275356) (xy 163.033438 -292.289048) (xy 163.0779 -292.310146)
			(xy 163.118403 -292.338102) (xy 163.153896 -292.372194) (xy 163.183461 -292.411538) (xy 163.206332 -292.455115)
			(xy 163.221916 -292.501796) (xy 163.229811 -292.550373) (xy 163.230306 -292.57498) (xy 163.569154 -292.57498)
			(xy 163.573114 -292.525926) (xy 163.584891 -292.478142) (xy 163.604182 -292.432866) (xy 163.630485 -292.39127)
			(xy 163.66312 -292.354433) (xy 163.701241 -292.323308) (xy 163.743862 -292.298701) (xy 163.789878 -292.281249)
			(xy 163.838097 -292.271405) (xy 163.887272 -292.269424) (xy 163.936127 -292.275356) (xy 163.983398 -292.289048)
			(xy 164.02786 -292.310146) (xy 164.068363 -292.338102) (xy 164.103856 -292.372194) (xy 164.133421 -292.411538)
			(xy 164.156292 -292.455115) (xy 164.171876 -292.501796) (xy 164.179771 -292.550373) (xy 164.180261 -292.574726)
			(xy 165.469074 -292.574726) (xy 165.473034 -292.525672) (xy 165.484811 -292.477888) (xy 165.504102 -292.432612)
			(xy 165.530405 -292.391016) (xy 165.56304 -292.354179) (xy 165.601161 -292.323054) (xy 165.643782 -292.298447)
			(xy 165.689798 -292.280995) (xy 165.738017 -292.271151) (xy 165.787192 -292.26917) (xy 165.836047 -292.275102)
			(xy 165.883318 -292.288794) (xy 165.92778 -292.309892) (xy 165.968283 -292.337848) (xy 166.003776 -292.37194)
			(xy 166.033341 -292.411284) (xy 166.056212 -292.454861) (xy 166.071796 -292.501542) (xy 166.079691 -292.550119)
			(xy 166.080186 -292.574726) (xy 166.080181 -292.57498) (xy 166.419288 -292.57498) (xy 166.423248 -292.525926)
			(xy 166.435025 -292.478142) (xy 166.454316 -292.432866) (xy 166.480619 -292.39127) (xy 166.513254 -292.354433)
			(xy 166.551375 -292.323308) (xy 166.593996 -292.298701) (xy 166.640012 -292.281249) (xy 166.688231 -292.271405)
			(xy 166.737406 -292.269424) (xy 166.786261 -292.275356) (xy 166.833532 -292.289048) (xy 166.877994 -292.310146)
			(xy 166.918497 -292.338102) (xy 166.95399 -292.372194) (xy 166.983555 -292.411538) (xy 167.006426 -292.455115)
			(xy 167.02201 -292.501796) (xy 167.029905 -292.550373) (xy 167.0304 -292.57498) (xy 167.369248 -292.57498)
			(xy 167.373208 -292.525926) (xy 167.384985 -292.478142) (xy 167.404276 -292.432866) (xy 167.430579 -292.39127)
			(xy 167.463214 -292.354433) (xy 167.501335 -292.323308) (xy 167.543956 -292.298701) (xy 167.589972 -292.281249)
			(xy 167.638191 -292.271405) (xy 167.687366 -292.269424) (xy 167.736221 -292.275356) (xy 167.783492 -292.289048)
			(xy 167.827954 -292.310146) (xy 167.868457 -292.338102) (xy 167.90395 -292.372194) (xy 167.933515 -292.411538)
			(xy 167.956386 -292.455115) (xy 167.97197 -292.501796) (xy 167.979865 -292.550373) (xy 167.98036 -292.57498)
			(xy 168.319208 -292.57498) (xy 168.323168 -292.525926) (xy 168.334945 -292.478142) (xy 168.354236 -292.432866)
			(xy 168.380539 -292.39127) (xy 168.413174 -292.354433) (xy 168.451295 -292.323308) (xy 168.493916 -292.298701)
			(xy 168.539932 -292.281249) (xy 168.588151 -292.271405) (xy 168.637326 -292.269424) (xy 168.686181 -292.275356)
			(xy 168.733452 -292.289048) (xy 168.777914 -292.310146) (xy 168.818417 -292.338102) (xy 168.85391 -292.372194)
			(xy 168.883475 -292.411538) (xy 168.906346 -292.455115) (xy 168.92193 -292.501796) (xy 168.929825 -292.550373)
			(xy 168.93032 -292.57498) (xy 169.269168 -292.57498) (xy 169.273128 -292.525926) (xy 169.284905 -292.478142)
			(xy 169.304196 -292.432866) (xy 169.330499 -292.39127) (xy 169.363134 -292.354433) (xy 169.401255 -292.323308)
			(xy 169.443876 -292.298701) (xy 169.489892 -292.281249) (xy 169.538111 -292.271405) (xy 169.587286 -292.269424)
			(xy 169.636141 -292.275356) (xy 169.683412 -292.289048) (xy 169.727874 -292.310146) (xy 169.768377 -292.338102)
			(xy 169.80387 -292.372194) (xy 169.833435 -292.411538) (xy 169.856306 -292.455115) (xy 169.87189 -292.501796)
			(xy 169.879785 -292.550373) (xy 169.88028 -292.57498) (xy 170.219128 -292.57498) (xy 170.223088 -292.525926)
			(xy 170.234865 -292.478142) (xy 170.254156 -292.432866) (xy 170.280459 -292.39127) (xy 170.313094 -292.354433)
			(xy 170.351215 -292.323308) (xy 170.393836 -292.298701) (xy 170.439852 -292.281249) (xy 170.488071 -292.271405)
			(xy 170.537246 -292.269424) (xy 170.586101 -292.275356) (xy 170.633372 -292.289048) (xy 170.677834 -292.310146)
			(xy 170.718337 -292.338102) (xy 170.75383 -292.372194) (xy 170.783395 -292.411538) (xy 170.806266 -292.455115)
			(xy 170.82185 -292.501796) (xy 170.829745 -292.550373) (xy 170.83024 -292.57498) (xy 171.169088 -292.57498)
			(xy 171.173048 -292.525926) (xy 171.184825 -292.478142) (xy 171.204116 -292.432866) (xy 171.230419 -292.39127)
			(xy 171.263054 -292.354433) (xy 171.301175 -292.323308) (xy 171.343796 -292.298701) (xy 171.389812 -292.281249)
			(xy 171.438031 -292.271405) (xy 171.487206 -292.269424) (xy 171.536061 -292.275356) (xy 171.583332 -292.289048)
			(xy 171.627794 -292.310146) (xy 171.668297 -292.338102) (xy 171.70379 -292.372194) (xy 171.733355 -292.411538)
			(xy 171.756226 -292.455115) (xy 171.77181 -292.501796) (xy 171.779705 -292.550373) (xy 171.7802 -292.57498)
			(xy 172.119302 -292.57498) (xy 172.123262 -292.525926) (xy 172.135039 -292.478142) (xy 172.15433 -292.432866)
			(xy 172.180633 -292.39127) (xy 172.213268 -292.354433) (xy 172.251389 -292.323308) (xy 172.29401 -292.298701)
			(xy 172.340026 -292.281249) (xy 172.388245 -292.271405) (xy 172.43742 -292.269424) (xy 172.486275 -292.275356)
			(xy 172.533546 -292.289048) (xy 172.578008 -292.310146) (xy 172.618511 -292.338102) (xy 172.654004 -292.372194)
			(xy 172.683569 -292.411538) (xy 172.70644 -292.455115) (xy 172.722024 -292.501796) (xy 172.729919 -292.550373)
			(xy 172.730414 -292.57498) (xy 173.069262 -292.57498) (xy 173.073222 -292.525926) (xy 173.084999 -292.478142)
			(xy 173.10429 -292.432866) (xy 173.130593 -292.39127) (xy 173.163228 -292.354433) (xy 173.201349 -292.323308)
			(xy 173.24397 -292.298701) (xy 173.289986 -292.281249) (xy 173.338205 -292.271405) (xy 173.38738 -292.269424)
			(xy 173.436235 -292.275356) (xy 173.483506 -292.289048) (xy 173.527968 -292.310146) (xy 173.568471 -292.338102)
			(xy 173.603964 -292.372194) (xy 173.633529 -292.411538) (xy 173.6564 -292.455115) (xy 173.671984 -292.501796)
			(xy 173.679879 -292.550373) (xy 173.680374 -292.57498) (xy 174.019222 -292.57498) (xy 174.023182 -292.525926)
			(xy 174.034959 -292.478142) (xy 174.05425 -292.432866) (xy 174.080553 -292.39127) (xy 174.113188 -292.354433)
			(xy 174.151309 -292.323308) (xy 174.19393 -292.298701) (xy 174.239946 -292.281249) (xy 174.288165 -292.271405)
			(xy 174.33734 -292.269424) (xy 174.386195 -292.275356) (xy 174.433466 -292.289048) (xy 174.477928 -292.310146)
			(xy 174.518431 -292.338102) (xy 174.553924 -292.372194) (xy 174.583489 -292.411538) (xy 174.60636 -292.455115)
			(xy 174.621944 -292.501796) (xy 174.629839 -292.550373) (xy 174.630329 -292.574726) (xy 175.919142 -292.574726)
			(xy 175.923102 -292.525672) (xy 175.934879 -292.477888) (xy 175.95417 -292.432612) (xy 175.980473 -292.391016)
			(xy 176.013108 -292.354179) (xy 176.051229 -292.323054) (xy 176.09385 -292.298447) (xy 176.139866 -292.280995)
			(xy 176.188085 -292.271151) (xy 176.23726 -292.26917) (xy 176.286115 -292.275102) (xy 176.333386 -292.288794)
			(xy 176.377848 -292.309892) (xy 176.418351 -292.337848) (xy 176.453844 -292.37194) (xy 176.483409 -292.411284)
			(xy 176.50628 -292.454861) (xy 176.521864 -292.501542) (xy 176.529759 -292.550119) (xy 176.530254 -292.574726)
			(xy 176.869102 -292.574726) (xy 176.873062 -292.525672) (xy 176.884839 -292.477888) (xy 176.90413 -292.432612)
			(xy 176.930433 -292.391016) (xy 176.963068 -292.354179) (xy 177.001189 -292.323054) (xy 177.04381 -292.298447)
			(xy 177.089826 -292.280995) (xy 177.138045 -292.271151) (xy 177.18722 -292.26917) (xy 177.236075 -292.275102)
			(xy 177.283346 -292.288794) (xy 177.327808 -292.309892) (xy 177.368311 -292.337848) (xy 177.403804 -292.37194)
			(xy 177.433369 -292.411284) (xy 177.45624 -292.454861) (xy 177.471824 -292.501542) (xy 177.479719 -292.550119)
			(xy 177.480214 -292.574726) (xy 177.819062 -292.574726) (xy 177.823022 -292.525672) (xy 177.834799 -292.477888)
			(xy 177.85409 -292.432612) (xy 177.880393 -292.391016) (xy 177.913028 -292.354179) (xy 177.951149 -292.323054)
			(xy 177.99377 -292.298447) (xy 178.039786 -292.280995) (xy 178.088005 -292.271151) (xy 178.13718 -292.26917)
			(xy 178.186035 -292.275102) (xy 178.233306 -292.288794) (xy 178.277768 -292.309892) (xy 178.318271 -292.337848)
			(xy 178.353764 -292.37194) (xy 178.383329 -292.411284) (xy 178.4062 -292.454861) (xy 178.421784 -292.501542)
			(xy 178.429679 -292.550119) (xy 178.430174 -292.574726) (xy 178.769276 -292.574726) (xy 178.773236 -292.525672)
			(xy 178.785013 -292.477888) (xy 178.804304 -292.432612) (xy 178.830607 -292.391016) (xy 178.863242 -292.354179)
			(xy 178.901363 -292.323054) (xy 178.943984 -292.298447) (xy 178.99 -292.280995) (xy 179.038219 -292.271151)
			(xy 179.087394 -292.26917) (xy 179.136249 -292.275102) (xy 179.18352 -292.288794) (xy 179.227982 -292.309892)
			(xy 179.268485 -292.337848) (xy 179.303978 -292.37194) (xy 179.333543 -292.411284) (xy 179.356414 -292.454861)
			(xy 179.371998 -292.501542) (xy 179.379893 -292.550119) (xy 179.380388 -292.574726) (xy 179.719236 -292.574726)
			(xy 179.723196 -292.525672) (xy 179.734973 -292.477888) (xy 179.754264 -292.432612) (xy 179.780567 -292.391016)
			(xy 179.813202 -292.354179) (xy 179.851323 -292.323054) (xy 179.893944 -292.298447) (xy 179.93996 -292.280995)
			(xy 179.988179 -292.271151) (xy 180.037354 -292.26917) (xy 180.086209 -292.275102) (xy 180.13348 -292.288794)
			(xy 180.177942 -292.309892) (xy 180.218445 -292.337848) (xy 180.253938 -292.37194) (xy 180.283503 -292.411284)
			(xy 180.306374 -292.454861) (xy 180.321958 -292.501542) (xy 180.329853 -292.550119) (xy 180.330348 -292.574726)
			(xy 180.669196 -292.574726) (xy 180.673156 -292.525672) (xy 180.684933 -292.477888) (xy 180.704224 -292.432612)
			(xy 180.730527 -292.391016) (xy 180.763162 -292.354179) (xy 180.801283 -292.323054) (xy 180.843904 -292.298447)
			(xy 180.88992 -292.280995) (xy 180.938139 -292.271151) (xy 180.987314 -292.26917) (xy 181.036169 -292.275102)
			(xy 181.08344 -292.288794) (xy 181.127902 -292.309892) (xy 181.168405 -292.337848) (xy 181.203898 -292.37194)
			(xy 181.233463 -292.411284) (xy 181.256334 -292.454861) (xy 181.271918 -292.501542) (xy 181.279813 -292.550119)
			(xy 181.280308 -292.574726) (xy 181.619156 -292.574726) (xy 181.623116 -292.525672) (xy 181.634893 -292.477888)
			(xy 181.654184 -292.432612) (xy 181.680487 -292.391016) (xy 181.713122 -292.354179) (xy 181.751243 -292.323054)
			(xy 181.793864 -292.298447) (xy 181.83988 -292.280995) (xy 181.888099 -292.271151) (xy 181.937274 -292.26917)
			(xy 181.986129 -292.275102) (xy 182.0334 -292.288794) (xy 182.077862 -292.309892) (xy 182.118365 -292.337848)
			(xy 182.153858 -292.37194) (xy 182.183423 -292.411284) (xy 182.206294 -292.454861) (xy 182.221878 -292.501542)
			(xy 182.229773 -292.550119) (xy 182.230268 -292.574726) (xy 182.569116 -292.574726) (xy 182.573076 -292.525672)
			(xy 182.584853 -292.477888) (xy 182.604144 -292.432612) (xy 182.630447 -292.391016) (xy 182.663082 -292.354179)
			(xy 182.701203 -292.323054) (xy 182.743824 -292.298447) (xy 182.78984 -292.280995) (xy 182.838059 -292.271151)
			(xy 182.887234 -292.26917) (xy 182.936089 -292.275102) (xy 182.98336 -292.288794) (xy 183.027822 -292.309892)
			(xy 183.068325 -292.337848) (xy 183.103818 -292.37194) (xy 183.133383 -292.411284) (xy 183.156254 -292.454861)
			(xy 183.171838 -292.501542) (xy 183.179733 -292.550119) (xy 183.180228 -292.574726) (xy 183.519076 -292.574726)
			(xy 183.523036 -292.525672) (xy 183.534813 -292.477888) (xy 183.554104 -292.432612) (xy 183.580407 -292.391016)
			(xy 183.613042 -292.354179) (xy 183.651163 -292.323054) (xy 183.693784 -292.298447) (xy 183.7398 -292.280995)
			(xy 183.788019 -292.271151) (xy 183.837194 -292.26917) (xy 183.886049 -292.275102) (xy 183.93332 -292.288794)
			(xy 183.977782 -292.309892) (xy 184.018285 -292.337848) (xy 184.053778 -292.37194) (xy 184.083343 -292.411284)
			(xy 184.106214 -292.454861) (xy 184.121798 -292.501542) (xy 184.129693 -292.550119) (xy 184.130188 -292.574726)
			(xy 184.129693 -292.599333) (xy 184.121798 -292.64791) (xy 184.106214 -292.694591) (xy 184.083343 -292.738168)
			(xy 184.053778 -292.777512) (xy 184.018285 -292.811604) (xy 183.977782 -292.83956) (xy 183.93332 -292.860658)
			(xy 183.886049 -292.87435) (xy 183.837194 -292.880282) (xy 183.788019 -292.878301) (xy 183.7398 -292.868457)
			(xy 183.693784 -292.851005) (xy 183.651163 -292.826398) (xy 183.613042 -292.795273) (xy 183.580407 -292.758436)
			(xy 183.554104 -292.71684) (xy 183.534813 -292.671564) (xy 183.523036 -292.62378) (xy 183.519076 -292.574726)
			(xy 183.180228 -292.574726) (xy 183.179733 -292.599333) (xy 183.171838 -292.64791) (xy 183.156254 -292.694591)
			(xy 183.133383 -292.738168) (xy 183.103818 -292.777512) (xy 183.068325 -292.811604) (xy 183.027822 -292.83956)
			(xy 182.98336 -292.860658) (xy 182.936089 -292.87435) (xy 182.887234 -292.880282) (xy 182.838059 -292.878301)
			(xy 182.78984 -292.868457) (xy 182.743824 -292.851005) (xy 182.701203 -292.826398) (xy 182.663082 -292.795273)
			(xy 182.630447 -292.758436) (xy 182.604144 -292.71684) (xy 182.584853 -292.671564) (xy 182.573076 -292.62378)
			(xy 182.569116 -292.574726) (xy 182.230268 -292.574726) (xy 182.229773 -292.599333) (xy 182.221878 -292.64791)
			(xy 182.206294 -292.694591) (xy 182.183423 -292.738168) (xy 182.153858 -292.777512) (xy 182.118365 -292.811604)
			(xy 182.077862 -292.83956) (xy 182.0334 -292.860658) (xy 181.986129 -292.87435) (xy 181.937274 -292.880282)
			(xy 181.888099 -292.878301) (xy 181.83988 -292.868457) (xy 181.793864 -292.851005) (xy 181.751243 -292.826398)
			(xy 181.713122 -292.795273) (xy 181.680487 -292.758436) (xy 181.654184 -292.71684) (xy 181.634893 -292.671564)
			(xy 181.623116 -292.62378) (xy 181.619156 -292.574726) (xy 181.280308 -292.574726) (xy 181.279813 -292.599333)
			(xy 181.271918 -292.64791) (xy 181.256334 -292.694591) (xy 181.233463 -292.738168) (xy 181.203898 -292.777512)
			(xy 181.168405 -292.811604) (xy 181.127902 -292.83956) (xy 181.08344 -292.860658) (xy 181.036169 -292.87435)
			(xy 180.987314 -292.880282) (xy 180.938139 -292.878301) (xy 180.88992 -292.868457) (xy 180.843904 -292.851005)
			(xy 180.801283 -292.826398) (xy 180.763162 -292.795273) (xy 180.730527 -292.758436) (xy 180.704224 -292.71684)
			(xy 180.684933 -292.671564) (xy 180.673156 -292.62378) (xy 180.669196 -292.574726) (xy 180.330348 -292.574726)
			(xy 180.329853 -292.599333) (xy 180.321958 -292.64791) (xy 180.306374 -292.694591) (xy 180.283503 -292.738168)
			(xy 180.253938 -292.777512) (xy 180.218445 -292.811604) (xy 180.177942 -292.83956) (xy 180.13348 -292.860658)
			(xy 180.086209 -292.87435) (xy 180.037354 -292.880282) (xy 179.988179 -292.878301) (xy 179.93996 -292.868457)
			(xy 179.893944 -292.851005) (xy 179.851323 -292.826398) (xy 179.813202 -292.795273) (xy 179.780567 -292.758436)
			(xy 179.754264 -292.71684) (xy 179.734973 -292.671564) (xy 179.723196 -292.62378) (xy 179.719236 -292.574726)
			(xy 179.380388 -292.574726) (xy 179.379893 -292.599333) (xy 179.371998 -292.64791) (xy 179.356414 -292.694591)
			(xy 179.333543 -292.738168) (xy 179.303978 -292.777512) (xy 179.268485 -292.811604) (xy 179.227982 -292.83956)
			(xy 179.18352 -292.860658) (xy 179.136249 -292.87435) (xy 179.087394 -292.880282) (xy 179.038219 -292.878301)
			(xy 178.99 -292.868457) (xy 178.943984 -292.851005) (xy 178.901363 -292.826398) (xy 178.863242 -292.795273)
			(xy 178.830607 -292.758436) (xy 178.804304 -292.71684) (xy 178.785013 -292.671564) (xy 178.773236 -292.62378)
			(xy 178.769276 -292.574726) (xy 178.430174 -292.574726) (xy 178.429679 -292.599333) (xy 178.421784 -292.64791)
			(xy 178.4062 -292.694591) (xy 178.383329 -292.738168) (xy 178.353764 -292.777512) (xy 178.318271 -292.811604)
			(xy 178.277768 -292.83956) (xy 178.233306 -292.860658) (xy 178.186035 -292.87435) (xy 178.13718 -292.880282)
			(xy 178.088005 -292.878301) (xy 178.039786 -292.868457) (xy 177.99377 -292.851005) (xy 177.951149 -292.826398)
			(xy 177.913028 -292.795273) (xy 177.880393 -292.758436) (xy 177.85409 -292.71684) (xy 177.834799 -292.671564)
			(xy 177.823022 -292.62378) (xy 177.819062 -292.574726) (xy 177.480214 -292.574726) (xy 177.479719 -292.599333)
			(xy 177.471824 -292.64791) (xy 177.45624 -292.694591) (xy 177.433369 -292.738168) (xy 177.403804 -292.777512)
			(xy 177.368311 -292.811604) (xy 177.327808 -292.83956) (xy 177.283346 -292.860658) (xy 177.236075 -292.87435)
			(xy 177.18722 -292.880282) (xy 177.138045 -292.878301) (xy 177.089826 -292.868457) (xy 177.04381 -292.851005)
			(xy 177.001189 -292.826398) (xy 176.963068 -292.795273) (xy 176.930433 -292.758436) (xy 176.90413 -292.71684)
			(xy 176.884839 -292.671564) (xy 176.873062 -292.62378) (xy 176.869102 -292.574726) (xy 176.530254 -292.574726)
			(xy 176.529759 -292.599333) (xy 176.521864 -292.64791) (xy 176.50628 -292.694591) (xy 176.483409 -292.738168)
			(xy 176.453844 -292.777512) (xy 176.418351 -292.811604) (xy 176.377848 -292.83956) (xy 176.333386 -292.860658)
			(xy 176.286115 -292.87435) (xy 176.23726 -292.880282) (xy 176.188085 -292.878301) (xy 176.139866 -292.868457)
			(xy 176.09385 -292.851005) (xy 176.051229 -292.826398) (xy 176.013108 -292.795273) (xy 175.980473 -292.758436)
			(xy 175.95417 -292.71684) (xy 175.934879 -292.671564) (xy 175.923102 -292.62378) (xy 175.919142 -292.574726)
			(xy 174.630329 -292.574726) (xy 174.630334 -292.57498) (xy 174.629839 -292.599587) (xy 174.621944 -292.648164)
			(xy 174.60636 -292.694845) (xy 174.583489 -292.738422) (xy 174.553924 -292.777766) (xy 174.518431 -292.811858)
			(xy 174.477928 -292.839814) (xy 174.433466 -292.860912) (xy 174.386195 -292.874604) (xy 174.33734 -292.880536)
			(xy 174.288165 -292.878555) (xy 174.239946 -292.868711) (xy 174.19393 -292.851259) (xy 174.151309 -292.826652)
			(xy 174.113188 -292.795527) (xy 174.080553 -292.75869) (xy 174.05425 -292.717094) (xy 174.034959 -292.671818)
			(xy 174.023182 -292.624034) (xy 174.019222 -292.57498) (xy 173.680374 -292.57498) (xy 173.679879 -292.599587)
			(xy 173.671984 -292.648164) (xy 173.6564 -292.694845) (xy 173.633529 -292.738422) (xy 173.603964 -292.777766)
			(xy 173.568471 -292.811858) (xy 173.527968 -292.839814) (xy 173.483506 -292.860912) (xy 173.436235 -292.874604)
			(xy 173.38738 -292.880536) (xy 173.338205 -292.878555) (xy 173.289986 -292.868711) (xy 173.24397 -292.851259)
			(xy 173.201349 -292.826652) (xy 173.163228 -292.795527) (xy 173.130593 -292.75869) (xy 173.10429 -292.717094)
			(xy 173.084999 -292.671818) (xy 173.073222 -292.624034) (xy 173.069262 -292.57498) (xy 172.730414 -292.57498)
			(xy 172.729919 -292.599587) (xy 172.722024 -292.648164) (xy 172.70644 -292.694845) (xy 172.683569 -292.738422)
			(xy 172.654004 -292.777766) (xy 172.618511 -292.811858) (xy 172.578008 -292.839814) (xy 172.533546 -292.860912)
			(xy 172.486275 -292.874604) (xy 172.43742 -292.880536) (xy 172.388245 -292.878555) (xy 172.340026 -292.868711)
			(xy 172.29401 -292.851259) (xy 172.251389 -292.826652) (xy 172.213268 -292.795527) (xy 172.180633 -292.75869)
			(xy 172.15433 -292.717094) (xy 172.135039 -292.671818) (xy 172.123262 -292.624034) (xy 172.119302 -292.57498)
			(xy 171.7802 -292.57498) (xy 171.779705 -292.599587) (xy 171.77181 -292.648164) (xy 171.756226 -292.694845)
			(xy 171.733355 -292.738422) (xy 171.70379 -292.777766) (xy 171.668297 -292.811858) (xy 171.627794 -292.839814)
			(xy 171.583332 -292.860912) (xy 171.536061 -292.874604) (xy 171.487206 -292.880536) (xy 171.438031 -292.878555)
			(xy 171.389812 -292.868711) (xy 171.343796 -292.851259) (xy 171.301175 -292.826652) (xy 171.263054 -292.795527)
			(xy 171.230419 -292.75869) (xy 171.204116 -292.717094) (xy 171.184825 -292.671818) (xy 171.173048 -292.624034)
			(xy 171.169088 -292.57498) (xy 170.83024 -292.57498) (xy 170.829745 -292.599587) (xy 170.82185 -292.648164)
			(xy 170.806266 -292.694845) (xy 170.783395 -292.738422) (xy 170.75383 -292.777766) (xy 170.718337 -292.811858)
			(xy 170.677834 -292.839814) (xy 170.633372 -292.860912) (xy 170.586101 -292.874604) (xy 170.537246 -292.880536)
			(xy 170.488071 -292.878555) (xy 170.439852 -292.868711) (xy 170.393836 -292.851259) (xy 170.351215 -292.826652)
			(xy 170.313094 -292.795527) (xy 170.280459 -292.75869) (xy 170.254156 -292.717094) (xy 170.234865 -292.671818)
			(xy 170.223088 -292.624034) (xy 170.219128 -292.57498) (xy 169.88028 -292.57498) (xy 169.879785 -292.599587)
			(xy 169.87189 -292.648164) (xy 169.856306 -292.694845) (xy 169.833435 -292.738422) (xy 169.80387 -292.777766)
			(xy 169.768377 -292.811858) (xy 169.727874 -292.839814) (xy 169.683412 -292.860912) (xy 169.636141 -292.874604)
			(xy 169.587286 -292.880536) (xy 169.538111 -292.878555) (xy 169.489892 -292.868711) (xy 169.443876 -292.851259)
			(xy 169.401255 -292.826652) (xy 169.363134 -292.795527) (xy 169.330499 -292.75869) (xy 169.304196 -292.717094)
			(xy 169.284905 -292.671818) (xy 169.273128 -292.624034) (xy 169.269168 -292.57498) (xy 168.93032 -292.57498)
			(xy 168.929825 -292.599587) (xy 168.92193 -292.648164) (xy 168.906346 -292.694845) (xy 168.883475 -292.738422)
			(xy 168.85391 -292.777766) (xy 168.818417 -292.811858) (xy 168.777914 -292.839814) (xy 168.733452 -292.860912)
			(xy 168.686181 -292.874604) (xy 168.637326 -292.880536) (xy 168.588151 -292.878555) (xy 168.539932 -292.868711)
			(xy 168.493916 -292.851259) (xy 168.451295 -292.826652) (xy 168.413174 -292.795527) (xy 168.380539 -292.75869)
			(xy 168.354236 -292.717094) (xy 168.334945 -292.671818) (xy 168.323168 -292.624034) (xy 168.319208 -292.57498)
			(xy 167.98036 -292.57498) (xy 167.979865 -292.599587) (xy 167.97197 -292.648164) (xy 167.956386 -292.694845)
			(xy 167.933515 -292.738422) (xy 167.90395 -292.777766) (xy 167.868457 -292.811858) (xy 167.827954 -292.839814)
			(xy 167.783492 -292.860912) (xy 167.736221 -292.874604) (xy 167.687366 -292.880536) (xy 167.638191 -292.878555)
			(xy 167.589972 -292.868711) (xy 167.543956 -292.851259) (xy 167.501335 -292.826652) (xy 167.463214 -292.795527)
			(xy 167.430579 -292.75869) (xy 167.404276 -292.717094) (xy 167.384985 -292.671818) (xy 167.373208 -292.624034)
			(xy 167.369248 -292.57498) (xy 167.0304 -292.57498) (xy 167.029905 -292.599587) (xy 167.02201 -292.648164)
			(xy 167.006426 -292.694845) (xy 166.983555 -292.738422) (xy 166.95399 -292.777766) (xy 166.918497 -292.811858)
			(xy 166.877994 -292.839814) (xy 166.833532 -292.860912) (xy 166.786261 -292.874604) (xy 166.737406 -292.880536)
			(xy 166.688231 -292.878555) (xy 166.640012 -292.868711) (xy 166.593996 -292.851259) (xy 166.551375 -292.826652)
			(xy 166.513254 -292.795527) (xy 166.480619 -292.75869) (xy 166.454316 -292.717094) (xy 166.435025 -292.671818)
			(xy 166.423248 -292.624034) (xy 166.419288 -292.57498) (xy 166.080181 -292.57498) (xy 166.079691 -292.599333)
			(xy 166.071796 -292.64791) (xy 166.056212 -292.694591) (xy 166.033341 -292.738168) (xy 166.003776 -292.777512)
			(xy 165.968283 -292.811604) (xy 165.92778 -292.83956) (xy 165.883318 -292.860658) (xy 165.836047 -292.87435)
			(xy 165.787192 -292.880282) (xy 165.738017 -292.878301) (xy 165.689798 -292.868457) (xy 165.643782 -292.851005)
			(xy 165.601161 -292.826398) (xy 165.56304 -292.795273) (xy 165.530405 -292.758436) (xy 165.504102 -292.71684)
			(xy 165.484811 -292.671564) (xy 165.473034 -292.62378) (xy 165.469074 -292.574726) (xy 164.180261 -292.574726)
			(xy 164.180266 -292.57498) (xy 164.179771 -292.599587) (xy 164.171876 -292.648164) (xy 164.156292 -292.694845)
			(xy 164.133421 -292.738422) (xy 164.103856 -292.777766) (xy 164.068363 -292.811858) (xy 164.02786 -292.839814)
			(xy 163.983398 -292.860912) (xy 163.936127 -292.874604) (xy 163.887272 -292.880536) (xy 163.838097 -292.878555)
			(xy 163.789878 -292.868711) (xy 163.743862 -292.851259) (xy 163.701241 -292.826652) (xy 163.66312 -292.795527)
			(xy 163.630485 -292.75869) (xy 163.604182 -292.717094) (xy 163.584891 -292.671818) (xy 163.573114 -292.624034)
			(xy 163.569154 -292.57498) (xy 163.230306 -292.57498) (xy 163.229811 -292.599587) (xy 163.221916 -292.648164)
			(xy 163.206332 -292.694845) (xy 163.183461 -292.738422) (xy 163.153896 -292.777766) (xy 163.118403 -292.811858)
			(xy 163.0779 -292.839814) (xy 163.033438 -292.860912) (xy 162.986167 -292.874604) (xy 162.937312 -292.880536)
			(xy 162.888137 -292.878555) (xy 162.839918 -292.868711) (xy 162.793902 -292.851259) (xy 162.751281 -292.826652)
			(xy 162.71316 -292.795527) (xy 162.680525 -292.75869) (xy 162.654222 -292.717094) (xy 162.634931 -292.671818)
			(xy 162.623154 -292.624034) (xy 162.619194 -292.57498) (xy 162.280346 -292.57498) (xy 162.279851 -292.599587)
			(xy 162.271956 -292.648164) (xy 162.256372 -292.694845) (xy 162.233501 -292.738422) (xy 162.203936 -292.777766)
			(xy 162.168443 -292.811858) (xy 162.12794 -292.839814) (xy 162.083478 -292.860912) (xy 162.036207 -292.874604)
			(xy 161.987352 -292.880536) (xy 161.938177 -292.878555) (xy 161.889958 -292.868711) (xy 161.843942 -292.851259)
			(xy 161.801321 -292.826652) (xy 161.7632 -292.795527) (xy 161.730565 -292.75869) (xy 161.704262 -292.717094)
			(xy 161.684971 -292.671818) (xy 161.673194 -292.624034) (xy 161.669234 -292.57498) (xy 161.330386 -292.57498)
			(xy 161.329891 -292.599587) (xy 161.321996 -292.648164) (xy 161.306412 -292.694845) (xy 161.283541 -292.738422)
			(xy 161.253976 -292.777766) (xy 161.218483 -292.811858) (xy 161.17798 -292.839814) (xy 161.133518 -292.860912)
			(xy 161.086247 -292.874604) (xy 161.037392 -292.880536) (xy 160.988217 -292.878555) (xy 160.939998 -292.868711)
			(xy 160.893982 -292.851259) (xy 160.851361 -292.826652) (xy 160.81324 -292.795527) (xy 160.780605 -292.75869)
			(xy 160.754302 -292.717094) (xy 160.735011 -292.671818) (xy 160.723234 -292.624034) (xy 160.719274 -292.57498)
			(xy 160.380172 -292.57498) (xy 160.379677 -292.599587) (xy 160.371782 -292.648164) (xy 160.356198 -292.694845)
			(xy 160.333327 -292.738422) (xy 160.303762 -292.777766) (xy 160.268269 -292.811858) (xy 160.227766 -292.839814)
			(xy 160.183304 -292.860912) (xy 160.136033 -292.874604) (xy 160.087178 -292.880536) (xy 160.038003 -292.878555)
			(xy 159.989784 -292.868711) (xy 159.943768 -292.851259) (xy 159.901147 -292.826652) (xy 159.863026 -292.795527)
			(xy 159.830391 -292.75869) (xy 159.804088 -292.717094) (xy 159.784797 -292.671818) (xy 159.77302 -292.624034)
			(xy 159.76906 -292.57498) (xy 159.430212 -292.57498) (xy 159.429717 -292.599587) (xy 159.421822 -292.648164)
			(xy 159.406238 -292.694845) (xy 159.383367 -292.738422) (xy 159.353802 -292.777766) (xy 159.318309 -292.811858)
			(xy 159.277806 -292.839814) (xy 159.233344 -292.860912) (xy 159.186073 -292.874604) (xy 159.137218 -292.880536)
			(xy 159.088043 -292.878555) (xy 159.039824 -292.868711) (xy 158.993808 -292.851259) (xy 158.951187 -292.826652)
			(xy 158.913066 -292.795527) (xy 158.880431 -292.75869) (xy 158.854128 -292.717094) (xy 158.834837 -292.671818)
			(xy 158.82306 -292.624034) (xy 158.8191 -292.57498) (xy 158.531052 -292.57498) (xy 158.530554 -292.601629)
			(xy 158.522611 -292.654333) (xy 158.506901 -292.705263) (xy 158.483775 -292.753284) (xy 158.453751 -292.797321)
			(xy 158.417499 -292.836392) (xy 158.375828 -292.869623) (xy 158.32967 -292.896272) (xy 158.280056 -292.915744)
			(xy 158.228094 -292.927604) (xy 158.174944 -292.931588) (xy 158.121794 -292.927604) (xy 158.069832 -292.915744)
			(xy 158.020218 -292.896272) (xy 157.97406 -292.869623) (xy 157.932389 -292.836392) (xy 157.896137 -292.797321)
			(xy 157.866113 -292.753284) (xy 157.842987 -292.705263) (xy 157.827277 -292.654333) (xy 157.819334 -292.601629)
			(xy 157.529465 -292.601629) (xy 157.521902 -292.648164) (xy 157.506318 -292.694845) (xy 157.483447 -292.738422)
			(xy 157.453882 -292.777766) (xy 157.418389 -292.811858) (xy 157.377886 -292.839814) (xy 157.333424 -292.860912)
			(xy 157.286153 -292.874604) (xy 157.237298 -292.880536) (xy 157.188123 -292.878555) (xy 157.139904 -292.868711)
			(xy 157.093888 -292.851259) (xy 157.051267 -292.826652) (xy 157.013146 -292.795527) (xy 156.980511 -292.75869)
			(xy 156.954208 -292.717094) (xy 156.934917 -292.671818) (xy 156.92314 -292.624034) (xy 156.91918 -292.57498)
			(xy 156.580327 -292.57498) (xy 156.579837 -292.599333) (xy 156.571942 -292.64791) (xy 156.556358 -292.694591)
			(xy 156.533487 -292.738168) (xy 156.503922 -292.777512) (xy 156.468429 -292.811604) (xy 156.427926 -292.83956)
			(xy 156.383464 -292.860658) (xy 156.336193 -292.87435) (xy 156.287338 -292.880282) (xy 156.238163 -292.878301)
			(xy 156.189944 -292.868457) (xy 156.143928 -292.851005) (xy 156.101307 -292.826398) (xy 156.063186 -292.795273)
			(xy 156.030551 -292.758436) (xy 156.004248 -292.71684) (xy 155.984957 -292.671564) (xy 155.97318 -292.62378)
			(xy 155.96922 -292.574726) (xy 155.630372 -292.574726) (xy 155.629877 -292.599333) (xy 155.621982 -292.64791)
			(xy 155.606398 -292.694591) (xy 155.583527 -292.738168) (xy 155.553962 -292.777512) (xy 155.518469 -292.811604)
			(xy 155.477966 -292.83956) (xy 155.433504 -292.860658) (xy 155.386233 -292.87435) (xy 155.337378 -292.880282)
			(xy 155.288203 -292.878301) (xy 155.239984 -292.868457) (xy 155.193968 -292.851005) (xy 155.151347 -292.826398)
			(xy 155.113226 -292.795273) (xy 155.080591 -292.758436) (xy 155.054288 -292.71684) (xy 155.034997 -292.671564)
			(xy 155.02322 -292.62378) (xy 155.01926 -292.574726) (xy 154.680407 -292.574726) (xy 154.680412 -292.57498)
			(xy 154.679917 -292.599587) (xy 154.672022 -292.648164) (xy 154.656438 -292.694845) (xy 154.633567 -292.738422)
			(xy 154.604002 -292.777766) (xy 154.568509 -292.811858) (xy 154.528006 -292.839814) (xy 154.483544 -292.860912)
			(xy 154.436273 -292.874604) (xy 154.387418 -292.880536) (xy 154.338243 -292.878555) (xy 154.290024 -292.868711)
			(xy 154.244008 -292.851259) (xy 154.201387 -292.826652) (xy 154.163266 -292.795527) (xy 154.130631 -292.75869)
			(xy 154.104328 -292.717094) (xy 154.085037 -292.671818) (xy 154.07326 -292.624034) (xy 154.0693 -292.57498)
			(xy 153.730198 -292.57498) (xy 153.729703 -292.599587) (xy 153.721808 -292.648164) (xy 153.706224 -292.694845)
			(xy 153.683353 -292.738422) (xy 153.653788 -292.777766) (xy 153.618295 -292.811858) (xy 153.577792 -292.839814)
			(xy 153.53333 -292.860912) (xy 153.486059 -292.874604) (xy 153.437204 -292.880536) (xy 153.388029 -292.878555)
			(xy 153.33981 -292.868711) (xy 153.293794 -292.851259) (xy 153.251173 -292.826652) (xy 153.213052 -292.795527)
			(xy 153.180417 -292.75869) (xy 153.154114 -292.717094) (xy 153.134823 -292.671818) (xy 153.123046 -292.624034)
			(xy 153.119086 -292.57498) (xy 152.780238 -292.57498) (xy 152.779743 -292.599587) (xy 152.771848 -292.648164)
			(xy 152.756264 -292.694845) (xy 152.733393 -292.738422) (xy 152.703828 -292.777766) (xy 152.668335 -292.811858)
			(xy 152.627832 -292.839814) (xy 152.58337 -292.860912) (xy 152.536099 -292.874604) (xy 152.487244 -292.880536)
			(xy 152.438069 -292.878555) (xy 152.38985 -292.868711) (xy 152.343834 -292.851259) (xy 152.301213 -292.826652)
			(xy 152.263092 -292.795527) (xy 152.230457 -292.75869) (xy 152.204154 -292.717094) (xy 152.184863 -292.671818)
			(xy 152.173086 -292.624034) (xy 152.169126 -292.57498) (xy 148.177889 -292.57498) (xy 148.188959 -292.59922)
			(xy 148.204314 -292.651515) (xy 148.21207 -292.705463) (xy 148.212556 -292.732714) (xy 148.212006 -292.762096)
			(xy 148.202975 -292.820161) (xy 148.185143 -292.876154) (xy 148.158933 -292.928749) (xy 148.124966 -292.976701)
			(xy 148.084044 -293.018874) (xy 148.060918 -293.037006) (xy 148.051975 -293.044467) (xy 148.041527 -293.065256)
			(xy 148.040852 -293.076884) (xy 148.039582 -293.168832) (xy 148.049488 -293.189914) (xy 148.058632 -293.19728)
			(xy 148.080459 -293.215509) (xy 148.118999 -293.257324) (xy 148.150908 -293.304395) (xy 148.175478 -293.35568)
			(xy 148.192166 -293.410043) (xy 148.200603 -293.466281) (xy 148.201126 -293.494714) (xy 148.8346 -293.494714)
			(xy 148.838671 -293.439092) (xy 148.850797 -293.384655) (xy 148.87072 -293.332564) (xy 148.898016 -293.283929)
			(xy 148.932102 -293.239786) (xy 148.972251 -293.201077) (xy 149.017609 -293.168626) (xy 149.067209 -293.143125)
			(xy 149.119993 -293.125118) (xy 149.174836 -293.114988) (xy 149.23057 -293.112951) (xy 149.286007 -293.119051)
			(xy 149.339964 -293.133157) (xy 149.391293 -293.154969) (xy 149.438899 -293.184023) (xy 149.481767 -293.219698)
			(xy 149.518984 -293.261235) (xy 149.549757 -293.307748) (xy 149.573429 -293.358245) (xy 149.589497 -293.411652)
			(xy 149.597617 -293.466828) (xy 149.598126 -293.494714) (xy 149.72106 -293.494714) (xy 149.725131 -293.439092)
			(xy 149.737257 -293.384655) (xy 149.75718 -293.332564) (xy 149.784476 -293.283929) (xy 149.818562 -293.239786)
			(xy 149.858711 -293.201077) (xy 149.904069 -293.168626) (xy 149.953669 -293.143125) (xy 150.006453 -293.125118)
			(xy 150.061296 -293.114988) (xy 150.11703 -293.112951) (xy 150.172467 -293.119051) (xy 150.226424 -293.133157)
			(xy 150.277753 -293.154969) (xy 150.325359 -293.184023) (xy 150.368227 -293.219698) (xy 150.405444 -293.261235)
			(xy 150.436217 -293.307748) (xy 150.459889 -293.358245) (xy 150.475957 -293.411652) (xy 150.484077 -293.466828)
			(xy 150.484586 -293.494714) (xy 150.484077 -293.5226) (xy 150.483733 -293.52494) (xy 154.0693 -293.52494)
			(xy 154.07326 -293.475886) (xy 154.085037 -293.428102) (xy 154.104328 -293.382826) (xy 154.130631 -293.34123)
			(xy 154.163266 -293.304393) (xy 154.201387 -293.273268) (xy 154.244008 -293.248661) (xy 154.290024 -293.231209)
			(xy 154.338243 -293.221365) (xy 154.387418 -293.219384) (xy 154.436273 -293.225316) (xy 154.483544 -293.239008)
			(xy 154.528006 -293.260106) (xy 154.568509 -293.288062) (xy 154.604002 -293.322154) (xy 154.633567 -293.361498)
			(xy 154.656438 -293.405075) (xy 154.672022 -293.451756) (xy 154.679917 -293.500333) (xy 154.680412 -293.52494)
			(xy 155.01926 -293.52494) (xy 155.02322 -293.475886) (xy 155.034997 -293.428102) (xy 155.054288 -293.382826)
			(xy 155.080591 -293.34123) (xy 155.113226 -293.304393) (xy 155.151347 -293.273268) (xy 155.193968 -293.248661)
			(xy 155.239984 -293.231209) (xy 155.288203 -293.221365) (xy 155.337378 -293.219384) (xy 155.386233 -293.225316)
			(xy 155.433504 -293.239008) (xy 155.477966 -293.260106) (xy 155.518469 -293.288062) (xy 155.553962 -293.322154)
			(xy 155.583527 -293.361498) (xy 155.606398 -293.405075) (xy 155.621982 -293.451756) (xy 155.629877 -293.500333)
			(xy 155.630372 -293.52494) (xy 155.96922 -293.52494) (xy 155.97318 -293.475886) (xy 155.984957 -293.428102)
			(xy 156.004248 -293.382826) (xy 156.030551 -293.34123) (xy 156.063186 -293.304393) (xy 156.101307 -293.273268)
			(xy 156.143928 -293.248661) (xy 156.189944 -293.231209) (xy 156.238163 -293.221365) (xy 156.287338 -293.219384)
			(xy 156.336193 -293.225316) (xy 156.383464 -293.239008) (xy 156.427926 -293.260106) (xy 156.468429 -293.288062)
			(xy 156.503922 -293.322154) (xy 156.533487 -293.361498) (xy 156.556358 -293.405075) (xy 156.571942 -293.451756)
			(xy 156.579837 -293.500333) (xy 156.580332 -293.52494) (xy 156.91918 -293.52494) (xy 156.92314 -293.475886)
			(xy 156.934917 -293.428102) (xy 156.954208 -293.382826) (xy 156.980511 -293.34123) (xy 157.013146 -293.304393)
			(xy 157.051267 -293.273268) (xy 157.093888 -293.248661) (xy 157.139904 -293.231209) (xy 157.188123 -293.221365)
			(xy 157.237298 -293.219384) (xy 157.286153 -293.225316) (xy 157.333424 -293.239008) (xy 157.377886 -293.260106)
			(xy 157.418389 -293.288062) (xy 157.453882 -293.322154) (xy 157.483447 -293.361498) (xy 157.506318 -293.405075)
			(xy 157.521902 -293.451756) (xy 157.529797 -293.500333) (xy 157.530292 -293.52494) (xy 157.86914 -293.52494)
			(xy 157.8731 -293.475886) (xy 157.884877 -293.428102) (xy 157.904168 -293.382826) (xy 157.930471 -293.34123)
			(xy 157.963106 -293.304393) (xy 158.001227 -293.273268) (xy 158.043848 -293.248661) (xy 158.089864 -293.231209)
			(xy 158.138083 -293.221365) (xy 158.187258 -293.219384) (xy 158.236113 -293.225316) (xy 158.283384 -293.239008)
			(xy 158.327846 -293.260106) (xy 158.368349 -293.288062) (xy 158.403842 -293.322154) (xy 158.433407 -293.361498)
			(xy 158.456278 -293.405075) (xy 158.471862 -293.451756) (xy 158.479757 -293.500333) (xy 158.480252 -293.52494)
			(xy 158.479757 -293.549547) (xy 158.479425 -293.551589) (xy 158.769294 -293.551589) (xy 158.769294 -293.498291)
			(xy 158.777237 -293.445587) (xy 158.792947 -293.394657) (xy 158.816073 -293.346636) (xy 158.846097 -293.302599)
			(xy 158.882349 -293.263528) (xy 158.92402 -293.230297) (xy 158.970178 -293.203648) (xy 159.019792 -293.184176)
			(xy 159.071754 -293.172316) (xy 159.124904 -293.168333) (xy 159.178054 -293.172316) (xy 159.230016 -293.184176)
			(xy 159.27963 -293.203648) (xy 159.325788 -293.230297) (xy 159.367459 -293.263528) (xy 159.403711 -293.302599)
			(xy 159.433735 -293.346636) (xy 159.456861 -293.394657) (xy 159.472571 -293.445587) (xy 159.480514 -293.498291)
			(xy 159.481012 -293.52494) (xy 159.76906 -293.52494) (xy 159.77302 -293.475886) (xy 159.784797 -293.428102)
			(xy 159.804088 -293.382826) (xy 159.830391 -293.34123) (xy 159.863026 -293.304393) (xy 159.901147 -293.273268)
			(xy 159.943768 -293.248661) (xy 159.989784 -293.231209) (xy 160.038003 -293.221365) (xy 160.087178 -293.219384)
			(xy 160.136033 -293.225316) (xy 160.183304 -293.239008) (xy 160.227766 -293.260106) (xy 160.268269 -293.288062)
			(xy 160.303762 -293.322154) (xy 160.333327 -293.361498) (xy 160.356198 -293.405075) (xy 160.371782 -293.451756)
			(xy 160.379677 -293.500333) (xy 160.380172 -293.52494) (xy 161.669234 -293.52494) (xy 161.673194 -293.475886)
			(xy 161.684971 -293.428102) (xy 161.704262 -293.382826) (xy 161.730565 -293.34123) (xy 161.7632 -293.304393)
			(xy 161.801321 -293.273268) (xy 161.843942 -293.248661) (xy 161.889958 -293.231209) (xy 161.938177 -293.221365)
			(xy 161.987352 -293.219384) (xy 162.036207 -293.225316) (xy 162.083478 -293.239008) (xy 162.12794 -293.260106)
			(xy 162.168443 -293.288062) (xy 162.203936 -293.322154) (xy 162.233501 -293.361498) (xy 162.256372 -293.405075)
			(xy 162.271956 -293.451756) (xy 162.279851 -293.500333) (xy 162.280346 -293.52494) (xy 163.569154 -293.52494)
			(xy 163.573114 -293.475886) (xy 163.584891 -293.428102) (xy 163.604182 -293.382826) (xy 163.630485 -293.34123)
			(xy 163.66312 -293.304393) (xy 163.701241 -293.273268) (xy 163.743862 -293.248661) (xy 163.789878 -293.231209)
			(xy 163.838097 -293.221365) (xy 163.887272 -293.219384) (xy 163.936127 -293.225316) (xy 163.983398 -293.239008)
			(xy 164.02786 -293.260106) (xy 164.068363 -293.288062) (xy 164.103856 -293.322154) (xy 164.133421 -293.361498)
			(xy 164.156292 -293.405075) (xy 164.171876 -293.451756) (xy 164.179771 -293.500333) (xy 164.180266 -293.52494)
			(xy 164.519114 -293.52494) (xy 164.523074 -293.475886) (xy 164.534851 -293.428102) (xy 164.554142 -293.382826)
			(xy 164.580445 -293.34123) (xy 164.61308 -293.304393) (xy 164.651201 -293.273268) (xy 164.693822 -293.248661)
			(xy 164.739838 -293.231209) (xy 164.788057 -293.221365) (xy 164.837232 -293.219384) (xy 164.886087 -293.225316)
			(xy 164.933358 -293.239008) (xy 164.97782 -293.260106) (xy 165.018323 -293.288062) (xy 165.053816 -293.322154)
			(xy 165.083381 -293.361498) (xy 165.106252 -293.405075) (xy 165.121836 -293.451756) (xy 165.129731 -293.500333)
			(xy 165.130226 -293.52494) (xy 166.419288 -293.52494) (xy 166.423248 -293.475886) (xy 166.435025 -293.428102)
			(xy 166.454316 -293.382826) (xy 166.480619 -293.34123) (xy 166.513254 -293.304393) (xy 166.551375 -293.273268)
			(xy 166.593996 -293.248661) (xy 166.640012 -293.231209) (xy 166.688231 -293.221365) (xy 166.737406 -293.219384)
			(xy 166.786261 -293.225316) (xy 166.833532 -293.239008) (xy 166.877994 -293.260106) (xy 166.918497 -293.288062)
			(xy 166.95399 -293.322154) (xy 166.983555 -293.361498) (xy 167.006426 -293.405075) (xy 167.02201 -293.451756)
			(xy 167.029905 -293.500333) (xy 167.0304 -293.52494) (xy 168.319208 -293.52494) (xy 168.323168 -293.475886)
			(xy 168.334945 -293.428102) (xy 168.354236 -293.382826) (xy 168.380539 -293.34123) (xy 168.413174 -293.304393)
			(xy 168.451295 -293.273268) (xy 168.493916 -293.248661) (xy 168.539932 -293.231209) (xy 168.588151 -293.221365)
			(xy 168.637326 -293.219384) (xy 168.686181 -293.225316) (xy 168.733452 -293.239008) (xy 168.777914 -293.260106)
			(xy 168.818417 -293.288062) (xy 168.85391 -293.322154) (xy 168.883475 -293.361498) (xy 168.906346 -293.405075)
			(xy 168.92193 -293.451756) (xy 168.929825 -293.500333) (xy 168.93032 -293.52494) (xy 170.219128 -293.52494)
			(xy 170.223088 -293.475886) (xy 170.234865 -293.428102) (xy 170.254156 -293.382826) (xy 170.280459 -293.34123)
			(xy 170.313094 -293.304393) (xy 170.351215 -293.273268) (xy 170.393836 -293.248661) (xy 170.439852 -293.231209)
			(xy 170.488071 -293.221365) (xy 170.537246 -293.219384) (xy 170.586101 -293.225316) (xy 170.633372 -293.239008)
			(xy 170.677834 -293.260106) (xy 170.718337 -293.288062) (xy 170.75383 -293.322154) (xy 170.783395 -293.361498)
			(xy 170.806266 -293.405075) (xy 170.82185 -293.451756) (xy 170.829745 -293.500333) (xy 170.83024 -293.52494)
			(xy 172.119048 -293.52494) (xy 172.123008 -293.475886) (xy 172.134785 -293.428102) (xy 172.154076 -293.382826)
			(xy 172.180379 -293.34123) (xy 172.213014 -293.304393) (xy 172.251135 -293.273268) (xy 172.293756 -293.248661)
			(xy 172.339772 -293.231209) (xy 172.387991 -293.221365) (xy 172.437166 -293.219384) (xy 172.486021 -293.225316)
			(xy 172.533292 -293.239008) (xy 172.577754 -293.260106) (xy 172.618257 -293.288062) (xy 172.65375 -293.322154)
			(xy 172.683315 -293.361498) (xy 172.706186 -293.405075) (xy 172.72177 -293.451756) (xy 172.729665 -293.500333)
			(xy 172.73016 -293.52494) (xy 174.019222 -293.52494) (xy 174.023182 -293.475886) (xy 174.034959 -293.428102)
			(xy 174.05425 -293.382826) (xy 174.080553 -293.34123) (xy 174.113188 -293.304393) (xy 174.151309 -293.273268)
			(xy 174.19393 -293.248661) (xy 174.239946 -293.231209) (xy 174.288165 -293.221365) (xy 174.33734 -293.219384)
			(xy 174.386195 -293.225316) (xy 174.433466 -293.239008) (xy 174.477928 -293.260106) (xy 174.518431 -293.288062)
			(xy 174.553924 -293.322154) (xy 174.583489 -293.361498) (xy 174.60636 -293.405075) (xy 174.621944 -293.451756)
			(xy 174.629839 -293.500333) (xy 174.630334 -293.52494) (xy 176.869102 -293.52494) (xy 176.873062 -293.475886)
			(xy 176.884839 -293.428102) (xy 176.90413 -293.382826) (xy 176.930433 -293.34123) (xy 176.963068 -293.304393)
			(xy 177.001189 -293.273268) (xy 177.04381 -293.248661) (xy 177.089826 -293.231209) (xy 177.138045 -293.221365)
			(xy 177.18722 -293.219384) (xy 177.236075 -293.225316) (xy 177.283346 -293.239008) (xy 177.327808 -293.260106)
			(xy 177.368311 -293.288062) (xy 177.403804 -293.322154) (xy 177.433369 -293.361498) (xy 177.45624 -293.405075)
			(xy 177.471824 -293.451756) (xy 177.479719 -293.500333) (xy 177.480214 -293.52494) (xy 178.769276 -293.52494)
			(xy 178.773236 -293.475886) (xy 178.785013 -293.428102) (xy 178.804304 -293.382826) (xy 178.830607 -293.34123)
			(xy 178.863242 -293.304393) (xy 178.901363 -293.273268) (xy 178.943984 -293.248661) (xy 178.99 -293.231209)
			(xy 179.038219 -293.221365) (xy 179.087394 -293.219384) (xy 179.136249 -293.225316) (xy 179.18352 -293.239008)
			(xy 179.227982 -293.260106) (xy 179.268485 -293.288062) (xy 179.303978 -293.322154) (xy 179.333543 -293.361498)
			(xy 179.356414 -293.405075) (xy 179.371998 -293.451756) (xy 179.379893 -293.500333) (xy 179.380388 -293.52494)
			(xy 180.669196 -293.52494) (xy 180.673156 -293.475886) (xy 180.684933 -293.428102) (xy 180.704224 -293.382826)
			(xy 180.730527 -293.34123) (xy 180.763162 -293.304393) (xy 180.801283 -293.273268) (xy 180.843904 -293.248661)
			(xy 180.88992 -293.231209) (xy 180.938139 -293.221365) (xy 180.987314 -293.219384) (xy 181.036169 -293.225316)
			(xy 181.08344 -293.239008) (xy 181.127902 -293.260106) (xy 181.168405 -293.288062) (xy 181.203898 -293.322154)
			(xy 181.233463 -293.361498) (xy 181.256334 -293.405075) (xy 181.271918 -293.451756) (xy 181.279813 -293.500333)
			(xy 181.280308 -293.52494) (xy 182.569116 -293.52494) (xy 182.573076 -293.475886) (xy 182.584853 -293.428102)
			(xy 182.604144 -293.382826) (xy 182.630447 -293.34123) (xy 182.663082 -293.304393) (xy 182.701203 -293.273268)
			(xy 182.743824 -293.248661) (xy 182.78984 -293.231209) (xy 182.838059 -293.221365) (xy 182.887234 -293.219384)
			(xy 182.936089 -293.225316) (xy 182.98336 -293.239008) (xy 183.027822 -293.260106) (xy 183.068325 -293.288062)
			(xy 183.103818 -293.322154) (xy 183.133383 -293.361498) (xy 183.156254 -293.405075) (xy 183.171838 -293.451756)
			(xy 183.179733 -293.500333) (xy 183.180228 -293.52494) (xy 183.179733 -293.549547) (xy 183.171838 -293.598124)
			(xy 183.156254 -293.644805) (xy 183.133383 -293.688382) (xy 183.103818 -293.727726) (xy 183.068325 -293.761818)
			(xy 183.027822 -293.789774) (xy 182.98336 -293.810872) (xy 182.936089 -293.824564) (xy 182.887234 -293.830496)
			(xy 182.838059 -293.828515) (xy 182.78984 -293.818671) (xy 182.743824 -293.801219) (xy 182.701203 -293.776612)
			(xy 182.663082 -293.745487) (xy 182.630447 -293.70865) (xy 182.604144 -293.667054) (xy 182.584853 -293.621778)
			(xy 182.573076 -293.573994) (xy 182.569116 -293.52494) (xy 181.280308 -293.52494) (xy 181.279813 -293.549547)
			(xy 181.271918 -293.598124) (xy 181.256334 -293.644805) (xy 181.233463 -293.688382) (xy 181.203898 -293.727726)
			(xy 181.168405 -293.761818) (xy 181.127902 -293.789774) (xy 181.08344 -293.810872) (xy 181.036169 -293.824564)
			(xy 180.987314 -293.830496) (xy 180.938139 -293.828515) (xy 180.88992 -293.818671) (xy 180.843904 -293.801219)
			(xy 180.801283 -293.776612) (xy 180.763162 -293.745487) (xy 180.730527 -293.70865) (xy 180.704224 -293.667054)
			(xy 180.684933 -293.621778) (xy 180.673156 -293.573994) (xy 180.669196 -293.52494) (xy 179.380388 -293.52494)
			(xy 179.379893 -293.549547) (xy 179.371998 -293.598124) (xy 179.356414 -293.644805) (xy 179.333543 -293.688382)
			(xy 179.303978 -293.727726) (xy 179.268485 -293.761818) (xy 179.227982 -293.789774) (xy 179.18352 -293.810872)
			(xy 179.136249 -293.824564) (xy 179.087394 -293.830496) (xy 179.038219 -293.828515) (xy 178.99 -293.818671)
			(xy 178.943984 -293.801219) (xy 178.901363 -293.776612) (xy 178.863242 -293.745487) (xy 178.830607 -293.70865)
			(xy 178.804304 -293.667054) (xy 178.785013 -293.621778) (xy 178.773236 -293.573994) (xy 178.769276 -293.52494)
			(xy 177.480214 -293.52494) (xy 177.479719 -293.549547) (xy 177.471824 -293.598124) (xy 177.45624 -293.644805)
			(xy 177.433369 -293.688382) (xy 177.403804 -293.727726) (xy 177.368311 -293.761818) (xy 177.327808 -293.789774)
			(xy 177.283346 -293.810872) (xy 177.236075 -293.824564) (xy 177.18722 -293.830496) (xy 177.138045 -293.828515)
			(xy 177.089826 -293.818671) (xy 177.04381 -293.801219) (xy 177.001189 -293.776612) (xy 176.963068 -293.745487)
			(xy 176.930433 -293.70865) (xy 176.90413 -293.667054) (xy 176.884839 -293.621778) (xy 176.873062 -293.573994)
			(xy 176.869102 -293.52494) (xy 174.630334 -293.52494) (xy 174.629839 -293.549547) (xy 174.621944 -293.598124)
			(xy 174.60636 -293.644805) (xy 174.583489 -293.688382) (xy 174.553924 -293.727726) (xy 174.518431 -293.761818)
			(xy 174.477928 -293.789774) (xy 174.433466 -293.810872) (xy 174.386195 -293.824564) (xy 174.33734 -293.830496)
			(xy 174.288165 -293.828515) (xy 174.239946 -293.818671) (xy 174.19393 -293.801219) (xy 174.151309 -293.776612)
			(xy 174.113188 -293.745487) (xy 174.080553 -293.70865) (xy 174.05425 -293.667054) (xy 174.034959 -293.621778)
			(xy 174.023182 -293.573994) (xy 174.019222 -293.52494) (xy 172.73016 -293.52494) (xy 172.729665 -293.549547)
			(xy 172.72177 -293.598124) (xy 172.706186 -293.644805) (xy 172.683315 -293.688382) (xy 172.65375 -293.727726)
			(xy 172.618257 -293.761818) (xy 172.577754 -293.789774) (xy 172.533292 -293.810872) (xy 172.486021 -293.824564)
			(xy 172.437166 -293.830496) (xy 172.387991 -293.828515) (xy 172.339772 -293.818671) (xy 172.293756 -293.801219)
			(xy 172.251135 -293.776612) (xy 172.213014 -293.745487) (xy 172.180379 -293.70865) (xy 172.154076 -293.667054)
			(xy 172.134785 -293.621778) (xy 172.123008 -293.573994) (xy 172.119048 -293.52494) (xy 170.83024 -293.52494)
			(xy 170.829745 -293.549547) (xy 170.82185 -293.598124) (xy 170.806266 -293.644805) (xy 170.783395 -293.688382)
			(xy 170.75383 -293.727726) (xy 170.718337 -293.761818) (xy 170.677834 -293.789774) (xy 170.633372 -293.810872)
			(xy 170.586101 -293.824564) (xy 170.537246 -293.830496) (xy 170.488071 -293.828515) (xy 170.439852 -293.818671)
			(xy 170.393836 -293.801219) (xy 170.351215 -293.776612) (xy 170.313094 -293.745487) (xy 170.280459 -293.70865)
			(xy 170.254156 -293.667054) (xy 170.234865 -293.621778) (xy 170.223088 -293.573994) (xy 170.219128 -293.52494)
			(xy 168.93032 -293.52494) (xy 168.929825 -293.549547) (xy 168.92193 -293.598124) (xy 168.906346 -293.644805)
			(xy 168.883475 -293.688382) (xy 168.85391 -293.727726) (xy 168.818417 -293.761818) (xy 168.777914 -293.789774)
			(xy 168.733452 -293.810872) (xy 168.686181 -293.824564) (xy 168.637326 -293.830496) (xy 168.588151 -293.828515)
			(xy 168.539932 -293.818671) (xy 168.493916 -293.801219) (xy 168.451295 -293.776612) (xy 168.413174 -293.745487)
			(xy 168.380539 -293.70865) (xy 168.354236 -293.667054) (xy 168.334945 -293.621778) (xy 168.323168 -293.573994)
			(xy 168.319208 -293.52494) (xy 167.0304 -293.52494) (xy 167.029905 -293.549547) (xy 167.02201 -293.598124)
			(xy 167.006426 -293.644805) (xy 166.983555 -293.688382) (xy 166.95399 -293.727726) (xy 166.918497 -293.761818)
			(xy 166.877994 -293.789774) (xy 166.833532 -293.810872) (xy 166.786261 -293.824564) (xy 166.737406 -293.830496)
			(xy 166.688231 -293.828515) (xy 166.640012 -293.818671) (xy 166.593996 -293.801219) (xy 166.551375 -293.776612)
			(xy 166.513254 -293.745487) (xy 166.480619 -293.70865) (xy 166.454316 -293.667054) (xy 166.435025 -293.621778)
			(xy 166.423248 -293.573994) (xy 166.419288 -293.52494) (xy 165.130226 -293.52494) (xy 165.129731 -293.549547)
			(xy 165.121836 -293.598124) (xy 165.106252 -293.644805) (xy 165.083381 -293.688382) (xy 165.053816 -293.727726)
			(xy 165.018323 -293.761818) (xy 164.97782 -293.789774) (xy 164.933358 -293.810872) (xy 164.886087 -293.824564)
			(xy 164.837232 -293.830496) (xy 164.788057 -293.828515) (xy 164.739838 -293.818671) (xy 164.693822 -293.801219)
			(xy 164.651201 -293.776612) (xy 164.61308 -293.745487) (xy 164.580445 -293.70865) (xy 164.554142 -293.667054)
			(xy 164.534851 -293.621778) (xy 164.523074 -293.573994) (xy 164.519114 -293.52494) (xy 164.180266 -293.52494)
			(xy 164.179771 -293.549547) (xy 164.171876 -293.598124) (xy 164.156292 -293.644805) (xy 164.133421 -293.688382)
			(xy 164.103856 -293.727726) (xy 164.068363 -293.761818) (xy 164.02786 -293.789774) (xy 163.983398 -293.810872)
			(xy 163.936127 -293.824564) (xy 163.887272 -293.830496) (xy 163.838097 -293.828515) (xy 163.789878 -293.818671)
			(xy 163.743862 -293.801219) (xy 163.701241 -293.776612) (xy 163.66312 -293.745487) (xy 163.630485 -293.70865)
			(xy 163.604182 -293.667054) (xy 163.584891 -293.621778) (xy 163.573114 -293.573994) (xy 163.569154 -293.52494)
			(xy 162.280346 -293.52494) (xy 162.279851 -293.549547) (xy 162.271956 -293.598124) (xy 162.256372 -293.644805)
			(xy 162.233501 -293.688382) (xy 162.203936 -293.727726) (xy 162.168443 -293.761818) (xy 162.12794 -293.789774)
			(xy 162.083478 -293.810872) (xy 162.036207 -293.824564) (xy 161.987352 -293.830496) (xy 161.938177 -293.828515)
			(xy 161.889958 -293.818671) (xy 161.843942 -293.801219) (xy 161.801321 -293.776612) (xy 161.7632 -293.745487)
			(xy 161.730565 -293.70865) (xy 161.704262 -293.667054) (xy 161.684971 -293.621778) (xy 161.673194 -293.573994)
			(xy 161.669234 -293.52494) (xy 160.380172 -293.52494) (xy 160.379677 -293.549547) (xy 160.371782 -293.598124)
			(xy 160.356198 -293.644805) (xy 160.333327 -293.688382) (xy 160.303762 -293.727726) (xy 160.268269 -293.761818)
			(xy 160.227766 -293.789774) (xy 160.183304 -293.810872) (xy 160.136033 -293.824564) (xy 160.087178 -293.830496)
			(xy 160.038003 -293.828515) (xy 159.989784 -293.818671) (xy 159.943768 -293.801219) (xy 159.901147 -293.776612)
			(xy 159.863026 -293.745487) (xy 159.830391 -293.70865) (xy 159.804088 -293.667054) (xy 159.784797 -293.621778)
			(xy 159.77302 -293.573994) (xy 159.76906 -293.52494) (xy 159.481012 -293.52494) (xy 159.480514 -293.551589)
			(xy 159.472571 -293.604293) (xy 159.456861 -293.655223) (xy 159.433735 -293.703244) (xy 159.403711 -293.747281)
			(xy 159.367459 -293.786352) (xy 159.325788 -293.819583) (xy 159.27963 -293.846232) (xy 159.230016 -293.865704)
			(xy 159.178054 -293.877564) (xy 159.124904 -293.881548) (xy 159.071754 -293.877564) (xy 159.019792 -293.865704)
			(xy 158.970178 -293.846232) (xy 158.92402 -293.819583) (xy 158.882349 -293.786352) (xy 158.846097 -293.747281)
			(xy 158.816073 -293.703244) (xy 158.792947 -293.655223) (xy 158.777237 -293.604293) (xy 158.769294 -293.551589)
			(xy 158.479425 -293.551589) (xy 158.471862 -293.598124) (xy 158.456278 -293.644805) (xy 158.433407 -293.688382)
			(xy 158.403842 -293.727726) (xy 158.368349 -293.761818) (xy 158.327846 -293.789774) (xy 158.283384 -293.810872)
			(xy 158.236113 -293.824564) (xy 158.187258 -293.830496) (xy 158.138083 -293.828515) (xy 158.089864 -293.818671)
			(xy 158.043848 -293.801219) (xy 158.001227 -293.776612) (xy 157.963106 -293.745487) (xy 157.930471 -293.70865)
			(xy 157.904168 -293.667054) (xy 157.884877 -293.621778) (xy 157.8731 -293.573994) (xy 157.86914 -293.52494)
			(xy 157.530292 -293.52494) (xy 157.529797 -293.549547) (xy 157.521902 -293.598124) (xy 157.506318 -293.644805)
			(xy 157.483447 -293.688382) (xy 157.453882 -293.727726) (xy 157.418389 -293.761818) (xy 157.377886 -293.789774)
			(xy 157.333424 -293.810872) (xy 157.286153 -293.824564) (xy 157.237298 -293.830496) (xy 157.188123 -293.828515)
			(xy 157.139904 -293.818671) (xy 157.093888 -293.801219) (xy 157.051267 -293.776612) (xy 157.013146 -293.745487)
			(xy 156.980511 -293.70865) (xy 156.954208 -293.667054) (xy 156.934917 -293.621778) (xy 156.92314 -293.573994)
			(xy 156.91918 -293.52494) (xy 156.580332 -293.52494) (xy 156.579837 -293.549547) (xy 156.571942 -293.598124)
			(xy 156.556358 -293.644805) (xy 156.533487 -293.688382) (xy 156.503922 -293.727726) (xy 156.468429 -293.761818)
			(xy 156.427926 -293.789774) (xy 156.383464 -293.810872) (xy 156.336193 -293.824564) (xy 156.287338 -293.830496)
			(xy 156.238163 -293.828515) (xy 156.189944 -293.818671) (xy 156.143928 -293.801219) (xy 156.101307 -293.776612)
			(xy 156.063186 -293.745487) (xy 156.030551 -293.70865) (xy 156.004248 -293.667054) (xy 155.984957 -293.621778)
			(xy 155.97318 -293.573994) (xy 155.96922 -293.52494) (xy 155.630372 -293.52494) (xy 155.629877 -293.549547)
			(xy 155.621982 -293.598124) (xy 155.606398 -293.644805) (xy 155.583527 -293.688382) (xy 155.553962 -293.727726)
			(xy 155.518469 -293.761818) (xy 155.477966 -293.789774) (xy 155.433504 -293.810872) (xy 155.386233 -293.824564)
			(xy 155.337378 -293.830496) (xy 155.288203 -293.828515) (xy 155.239984 -293.818671) (xy 155.193968 -293.801219)
			(xy 155.151347 -293.776612) (xy 155.113226 -293.745487) (xy 155.080591 -293.70865) (xy 155.054288 -293.667054)
			(xy 155.034997 -293.621778) (xy 155.02322 -293.573994) (xy 155.01926 -293.52494) (xy 154.680412 -293.52494)
			(xy 154.679917 -293.549547) (xy 154.672022 -293.598124) (xy 154.656438 -293.644805) (xy 154.633567 -293.688382)
			(xy 154.604002 -293.727726) (xy 154.568509 -293.761818) (xy 154.528006 -293.789774) (xy 154.483544 -293.810872)
			(xy 154.436273 -293.824564) (xy 154.387418 -293.830496) (xy 154.338243 -293.828515) (xy 154.290024 -293.818671)
			(xy 154.244008 -293.801219) (xy 154.201387 -293.776612) (xy 154.163266 -293.745487) (xy 154.130631 -293.70865)
			(xy 154.104328 -293.667054) (xy 154.085037 -293.621778) (xy 154.07326 -293.573994) (xy 154.0693 -293.52494)
			(xy 150.483733 -293.52494) (xy 150.475957 -293.577776) (xy 150.459889 -293.631183) (xy 150.436217 -293.68168)
			(xy 150.405444 -293.728193) (xy 150.368227 -293.76973) (xy 150.325359 -293.805405) (xy 150.277753 -293.834459)
			(xy 150.226424 -293.856271) (xy 150.172467 -293.870377) (xy 150.11703 -293.876477) (xy 150.061296 -293.87444)
			(xy 150.006453 -293.86431) (xy 149.953669 -293.846303) (xy 149.904069 -293.820802) (xy 149.858711 -293.788351)
			(xy 149.818562 -293.749642) (xy 149.784476 -293.705499) (xy 149.75718 -293.656864) (xy 149.737257 -293.604773)
			(xy 149.725131 -293.550336) (xy 149.72106 -293.494714) (xy 149.598126 -293.494714) (xy 149.597617 -293.5226)
			(xy 149.589497 -293.577776) (xy 149.573429 -293.631183) (xy 149.549757 -293.68168) (xy 149.518984 -293.728193)
			(xy 149.481767 -293.76973) (xy 149.438899 -293.805405) (xy 149.391293 -293.834459) (xy 149.339964 -293.856271)
			(xy 149.286007 -293.870377) (xy 149.23057 -293.876477) (xy 149.174836 -293.87444) (xy 149.119993 -293.86431)
			(xy 149.067209 -293.846303) (xy 149.017609 -293.820802) (xy 148.972251 -293.788351) (xy 148.932102 -293.749642)
			(xy 148.898016 -293.705499) (xy 148.87072 -293.656864) (xy 148.850797 -293.604773) (xy 148.838671 -293.550336)
			(xy 148.8346 -293.494714) (xy 148.201126 -293.494714) (xy 148.20064 -293.521965) (xy 148.192884 -293.575913)
			(xy 148.177529 -293.628208) (xy 148.154887 -293.677785) (xy 148.125421 -293.723635) (xy 148.08973 -293.764826)
			(xy 148.048539 -293.800517) (xy 148.002689 -293.829983) (xy 147.953112 -293.852625) (xy 147.900817 -293.86798)
			(xy 147.846869 -293.875736) (xy 147.792367 -293.875736) (xy 147.738419 -293.86798) (xy 147.686124 -293.852625)
			(xy 147.636547 -293.829983) (xy 147.590697 -293.800517) (xy 147.549506 -293.764826) (xy 147.513815 -293.723635)
			(xy 147.484349 -293.677785) (xy 147.461707 -293.628208) (xy 147.446352 -293.575913) (xy 147.438596 -293.521965)
			(xy 147.43811 -293.494714) (xy 135.82015 -293.494714) (xy 135.191246 -294.123618) (xy 135.183849 -294.130465)
			(xy 135.165249 -294.138193) (xy 135.155178 -294.138604) (xy 119.489474 -294.138604) (xy 119.481194 -294.138926)
			(xy 119.465513 -294.144244) (xy 119.45874 -294.149018) (xy 119.455692 -294.151812) (xy 119.454422 -294.152828)
			(xy 119.452644 -294.154352) (xy 118.97614 -294.630856) (xy 141.911576 -294.630856) (xy 141.915647 -294.575234)
			(xy 141.927773 -294.520797) (xy 141.947696 -294.468706) (xy 141.974992 -294.420071) (xy 142.009078 -294.375928)
			(xy 142.049227 -294.337219) (xy 142.094585 -294.304768) (xy 142.144185 -294.279267) (xy 142.196969 -294.26126)
			(xy 142.251812 -294.25113) (xy 142.307546 -294.249093) (xy 142.362983 -294.255193) (xy 142.41694 -294.269299)
			(xy 142.468269 -294.291111) (xy 142.515875 -294.320165) (xy 142.558743 -294.35584) (xy 142.59596 -294.397377)
			(xy 142.626733 -294.44389) (xy 142.650405 -294.494387) (xy 142.666473 -294.547794) (xy 142.674593 -294.60297)
			(xy 142.675102 -294.630856) (xy 143.396714 -294.630856) (xy 143.400785 -294.575234) (xy 143.412911 -294.520797)
			(xy 143.432834 -294.468706) (xy 143.46013 -294.420071) (xy 143.494216 -294.375928) (xy 143.534365 -294.337219)
			(xy 143.579723 -294.304768) (xy 143.629323 -294.279267) (xy 143.682107 -294.26126) (xy 143.73695 -294.25113)
			(xy 143.792684 -294.249093) (xy 143.848121 -294.255193) (xy 143.902078 -294.269299) (xy 143.953407 -294.291111)
			(xy 144.001013 -294.320165) (xy 144.043881 -294.35584) (xy 144.081098 -294.397377) (xy 144.111871 -294.44389)
			(xy 144.126408 -294.4749) (xy 152.169126 -294.4749) (xy 152.173086 -294.425846) (xy 152.184863 -294.378062)
			(xy 152.204154 -294.332786) (xy 152.230457 -294.29119) (xy 152.263092 -294.254353) (xy 152.301213 -294.223228)
			(xy 152.343834 -294.198621) (xy 152.38985 -294.181169) (xy 152.438069 -294.171325) (xy 152.487244 -294.169344)
			(xy 152.536099 -294.175276) (xy 152.58337 -294.188968) (xy 152.627832 -294.210066) (xy 152.668335 -294.238022)
			(xy 152.703828 -294.272114) (xy 152.733393 -294.311458) (xy 152.756264 -294.355035) (xy 152.771848 -294.401716)
			(xy 152.779743 -294.450293) (xy 152.780238 -294.4749) (xy 153.119086 -294.4749) (xy 153.123046 -294.425846)
			(xy 153.134823 -294.378062) (xy 153.154114 -294.332786) (xy 153.180417 -294.29119) (xy 153.213052 -294.254353)
			(xy 153.251173 -294.223228) (xy 153.293794 -294.198621) (xy 153.33981 -294.181169) (xy 153.388029 -294.171325)
			(xy 153.437204 -294.169344) (xy 153.486059 -294.175276) (xy 153.53333 -294.188968) (xy 153.577792 -294.210066)
			(xy 153.618295 -294.238022) (xy 153.653788 -294.272114) (xy 153.683353 -294.311458) (xy 153.706224 -294.355035)
			(xy 153.721808 -294.401716) (xy 153.729703 -294.450293) (xy 153.730198 -294.4749) (xy 154.0693 -294.4749)
			(xy 154.07326 -294.425846) (xy 154.085037 -294.378062) (xy 154.104328 -294.332786) (xy 154.130631 -294.29119)
			(xy 154.163266 -294.254353) (xy 154.201387 -294.223228) (xy 154.244008 -294.198621) (xy 154.290024 -294.181169)
			(xy 154.338243 -294.171325) (xy 154.387418 -294.169344) (xy 154.436273 -294.175276) (xy 154.483544 -294.188968)
			(xy 154.528006 -294.210066) (xy 154.568509 -294.238022) (xy 154.604002 -294.272114) (xy 154.633567 -294.311458)
			(xy 154.656438 -294.355035) (xy 154.672022 -294.401716) (xy 154.679917 -294.450293) (xy 154.680412 -294.4749)
			(xy 156.91918 -294.4749) (xy 156.92314 -294.425846) (xy 156.934917 -294.378062) (xy 156.954208 -294.332786)
			(xy 156.980511 -294.29119) (xy 157.013146 -294.254353) (xy 157.051267 -294.223228) (xy 157.093888 -294.198621)
			(xy 157.139904 -294.181169) (xy 157.188123 -294.171325) (xy 157.237298 -294.169344) (xy 157.286153 -294.175276)
			(xy 157.333424 -294.188968) (xy 157.377886 -294.210066) (xy 157.418389 -294.238022) (xy 157.453882 -294.272114)
			(xy 157.483447 -294.311458) (xy 157.506318 -294.355035) (xy 157.521902 -294.401716) (xy 157.529797 -294.450293)
			(xy 157.530292 -294.4749) (xy 157.529797 -294.499507) (xy 157.529465 -294.501549) (xy 157.819334 -294.501549)
			(xy 157.819334 -294.448251) (xy 157.827277 -294.395547) (xy 157.842987 -294.344617) (xy 157.866113 -294.296596)
			(xy 157.896137 -294.252559) (xy 157.932389 -294.213488) (xy 157.97406 -294.180257) (xy 158.020218 -294.153608)
			(xy 158.069832 -294.134136) (xy 158.121794 -294.122276) (xy 158.174944 -294.118293) (xy 158.228094 -294.122276)
			(xy 158.280056 -294.134136) (xy 158.32967 -294.153608) (xy 158.375828 -294.180257) (xy 158.417499 -294.213488)
			(xy 158.453751 -294.252559) (xy 158.483775 -294.296596) (xy 158.506901 -294.344617) (xy 158.522611 -294.395547)
			(xy 158.530554 -294.448251) (xy 158.531052 -294.4749) (xy 158.8191 -294.4749) (xy 158.82306 -294.425846)
			(xy 158.834837 -294.378062) (xy 158.854128 -294.332786) (xy 158.880431 -294.29119) (xy 158.913066 -294.254353)
			(xy 158.951187 -294.223228) (xy 158.993808 -294.198621) (xy 159.039824 -294.181169) (xy 159.088043 -294.171325)
			(xy 159.137218 -294.169344) (xy 159.186073 -294.175276) (xy 159.233344 -294.188968) (xy 159.277806 -294.210066)
			(xy 159.318309 -294.238022) (xy 159.353802 -294.272114) (xy 159.383367 -294.311458) (xy 159.406238 -294.355035)
			(xy 159.421822 -294.401716) (xy 159.429717 -294.450293) (xy 159.430212 -294.4749) (xy 159.76906 -294.4749)
			(xy 159.77302 -294.425846) (xy 159.784797 -294.378062) (xy 159.804088 -294.332786) (xy 159.830391 -294.29119)
			(xy 159.863026 -294.254353) (xy 159.901147 -294.223228) (xy 159.943768 -294.198621) (xy 159.989784 -294.181169)
			(xy 160.038003 -294.171325) (xy 160.087178 -294.169344) (xy 160.136033 -294.175276) (xy 160.183304 -294.188968)
			(xy 160.227766 -294.210066) (xy 160.268269 -294.238022) (xy 160.303762 -294.272114) (xy 160.333327 -294.311458)
			(xy 160.356198 -294.355035) (xy 160.371782 -294.401716) (xy 160.379677 -294.450293) (xy 160.380172 -294.4749)
			(xy 160.719274 -294.4749) (xy 160.723234 -294.425846) (xy 160.735011 -294.378062) (xy 160.754302 -294.332786)
			(xy 160.780605 -294.29119) (xy 160.81324 -294.254353) (xy 160.851361 -294.223228) (xy 160.893982 -294.198621)
			(xy 160.939998 -294.181169) (xy 160.988217 -294.171325) (xy 161.037392 -294.169344) (xy 161.086247 -294.175276)
			(xy 161.133518 -294.188968) (xy 161.17798 -294.210066) (xy 161.218483 -294.238022) (xy 161.253976 -294.272114)
			(xy 161.283541 -294.311458) (xy 161.306412 -294.355035) (xy 161.321996 -294.401716) (xy 161.329891 -294.450293)
			(xy 161.330386 -294.4749) (xy 161.669234 -294.4749) (xy 161.673194 -294.425846) (xy 161.684971 -294.378062)
			(xy 161.704262 -294.332786) (xy 161.730565 -294.29119) (xy 161.7632 -294.254353) (xy 161.801321 -294.223228)
			(xy 161.843942 -294.198621) (xy 161.889958 -294.181169) (xy 161.938177 -294.171325) (xy 161.987352 -294.169344)
			(xy 162.036207 -294.175276) (xy 162.083478 -294.188968) (xy 162.12794 -294.210066) (xy 162.168443 -294.238022)
			(xy 162.203936 -294.272114) (xy 162.233501 -294.311458) (xy 162.256372 -294.355035) (xy 162.271956 -294.401716)
			(xy 162.279851 -294.450293) (xy 162.280346 -294.4749) (xy 162.619194 -294.4749) (xy 162.623154 -294.425846)
			(xy 162.634931 -294.378062) (xy 162.654222 -294.332786) (xy 162.680525 -294.29119) (xy 162.71316 -294.254353)
			(xy 162.751281 -294.223228) (xy 162.793902 -294.198621) (xy 162.839918 -294.181169) (xy 162.888137 -294.171325)
			(xy 162.937312 -294.169344) (xy 162.986167 -294.175276) (xy 163.033438 -294.188968) (xy 163.0779 -294.210066)
			(xy 163.118403 -294.238022) (xy 163.153896 -294.272114) (xy 163.183461 -294.311458) (xy 163.206332 -294.355035)
			(xy 163.221916 -294.401716) (xy 163.229811 -294.450293) (xy 163.230306 -294.4749) (xy 163.569154 -294.4749)
			(xy 163.573114 -294.425846) (xy 163.584891 -294.378062) (xy 163.604182 -294.332786) (xy 163.630485 -294.29119)
			(xy 163.66312 -294.254353) (xy 163.701241 -294.223228) (xy 163.743862 -294.198621) (xy 163.789878 -294.181169)
			(xy 163.838097 -294.171325) (xy 163.887272 -294.169344) (xy 163.936127 -294.175276) (xy 163.983398 -294.188968)
			(xy 164.02786 -294.210066) (xy 164.068363 -294.238022) (xy 164.103856 -294.272114) (xy 164.133421 -294.311458)
			(xy 164.156292 -294.355035) (xy 164.171876 -294.401716) (xy 164.179771 -294.450293) (xy 164.180266 -294.4749)
			(xy 165.469074 -294.4749) (xy 165.473034 -294.425846) (xy 165.484811 -294.378062) (xy 165.504102 -294.332786)
			(xy 165.530405 -294.29119) (xy 165.56304 -294.254353) (xy 165.601161 -294.223228) (xy 165.643782 -294.198621)
			(xy 165.689798 -294.181169) (xy 165.738017 -294.171325) (xy 165.787192 -294.169344) (xy 165.836047 -294.175276)
			(xy 165.883318 -294.188968) (xy 165.92778 -294.210066) (xy 165.968283 -294.238022) (xy 166.003776 -294.272114)
			(xy 166.033341 -294.311458) (xy 166.056212 -294.355035) (xy 166.071796 -294.401716) (xy 166.079691 -294.450293)
			(xy 166.080186 -294.4749) (xy 167.369248 -294.4749) (xy 167.373208 -294.425846) (xy 167.384985 -294.378062)
			(xy 167.404276 -294.332786) (xy 167.430579 -294.29119) (xy 167.463214 -294.254353) (xy 167.501335 -294.223228)
			(xy 167.543956 -294.198621) (xy 167.589972 -294.181169) (xy 167.638191 -294.171325) (xy 167.687366 -294.169344)
			(xy 167.736221 -294.175276) (xy 167.783492 -294.188968) (xy 167.827954 -294.210066) (xy 167.868457 -294.238022)
			(xy 167.90395 -294.272114) (xy 167.933515 -294.311458) (xy 167.956386 -294.355035) (xy 167.97197 -294.401716)
			(xy 167.979865 -294.450293) (xy 167.98036 -294.4749) (xy 169.269168 -294.4749) (xy 169.273128 -294.425846)
			(xy 169.284905 -294.378062) (xy 169.304196 -294.332786) (xy 169.330499 -294.29119) (xy 169.363134 -294.254353)
			(xy 169.401255 -294.223228) (xy 169.443876 -294.198621) (xy 169.489892 -294.181169) (xy 169.538111 -294.171325)
			(xy 169.587286 -294.169344) (xy 169.636141 -294.175276) (xy 169.683412 -294.188968) (xy 169.727874 -294.210066)
			(xy 169.768377 -294.238022) (xy 169.80387 -294.272114) (xy 169.833435 -294.311458) (xy 169.856306 -294.355035)
			(xy 169.87189 -294.401716) (xy 169.879785 -294.450293) (xy 169.88028 -294.4749) (xy 171.169088 -294.4749)
			(xy 171.173048 -294.425846) (xy 171.184825 -294.378062) (xy 171.204116 -294.332786) (xy 171.230419 -294.29119)
			(xy 171.263054 -294.254353) (xy 171.301175 -294.223228) (xy 171.343796 -294.198621) (xy 171.389812 -294.181169)
			(xy 171.438031 -294.171325) (xy 171.487206 -294.169344) (xy 171.536061 -294.175276) (xy 171.583332 -294.188968)
			(xy 171.627794 -294.210066) (xy 171.668297 -294.238022) (xy 171.70379 -294.272114) (xy 171.733355 -294.311458)
			(xy 171.756226 -294.355035) (xy 171.77181 -294.401716) (xy 171.779705 -294.450293) (xy 171.7802 -294.4749)
			(xy 173.069262 -294.4749) (xy 173.073222 -294.425846) (xy 173.084999 -294.378062) (xy 173.10429 -294.332786)
			(xy 173.130593 -294.29119) (xy 173.163228 -294.254353) (xy 173.201349 -294.223228) (xy 173.24397 -294.198621)
			(xy 173.289986 -294.181169) (xy 173.338205 -294.171325) (xy 173.38738 -294.169344) (xy 173.436235 -294.175276)
			(xy 173.483506 -294.188968) (xy 173.527968 -294.210066) (xy 173.568471 -294.238022) (xy 173.603964 -294.272114)
			(xy 173.633529 -294.311458) (xy 173.6564 -294.355035) (xy 173.671984 -294.401716) (xy 173.679879 -294.450293)
			(xy 173.680374 -294.4749) (xy 175.919142 -294.4749) (xy 175.923102 -294.425846) (xy 175.934879 -294.378062)
			(xy 175.95417 -294.332786) (xy 175.980473 -294.29119) (xy 176.013108 -294.254353) (xy 176.051229 -294.223228)
			(xy 176.09385 -294.198621) (xy 176.139866 -294.181169) (xy 176.188085 -294.171325) (xy 176.23726 -294.169344)
			(xy 176.286115 -294.175276) (xy 176.333386 -294.188968) (xy 176.377848 -294.210066) (xy 176.418351 -294.238022)
			(xy 176.453844 -294.272114) (xy 176.483409 -294.311458) (xy 176.50628 -294.355035) (xy 176.521864 -294.401716)
			(xy 176.529759 -294.450293) (xy 176.530254 -294.4749) (xy 177.819062 -294.4749) (xy 177.823022 -294.425846)
			(xy 177.834799 -294.378062) (xy 177.85409 -294.332786) (xy 177.880393 -294.29119) (xy 177.913028 -294.254353)
			(xy 177.951149 -294.223228) (xy 177.99377 -294.198621) (xy 178.039786 -294.181169) (xy 178.088005 -294.171325)
			(xy 178.13718 -294.169344) (xy 178.186035 -294.175276) (xy 178.233306 -294.188968) (xy 178.277768 -294.210066)
			(xy 178.318271 -294.238022) (xy 178.353764 -294.272114) (xy 178.383329 -294.311458) (xy 178.4062 -294.355035)
			(xy 178.421784 -294.401716) (xy 178.429679 -294.450293) (xy 178.430174 -294.4749) (xy 179.719236 -294.4749)
			(xy 179.723196 -294.425846) (xy 179.734973 -294.378062) (xy 179.754264 -294.332786) (xy 179.780567 -294.29119)
			(xy 179.813202 -294.254353) (xy 179.851323 -294.223228) (xy 179.893944 -294.198621) (xy 179.93996 -294.181169)
			(xy 179.988179 -294.171325) (xy 180.037354 -294.169344) (xy 180.086209 -294.175276) (xy 180.13348 -294.188968)
			(xy 180.177942 -294.210066) (xy 180.218445 -294.238022) (xy 180.253938 -294.272114) (xy 180.283503 -294.311458)
			(xy 180.306374 -294.355035) (xy 180.321958 -294.401716) (xy 180.329853 -294.450293) (xy 180.330348 -294.4749)
			(xy 181.619156 -294.4749) (xy 181.623116 -294.425846) (xy 181.634893 -294.378062) (xy 181.654184 -294.332786)
			(xy 181.680487 -294.29119) (xy 181.713122 -294.254353) (xy 181.751243 -294.223228) (xy 181.793864 -294.198621)
			(xy 181.83988 -294.181169) (xy 181.888099 -294.171325) (xy 181.937274 -294.169344) (xy 181.986129 -294.175276)
			(xy 182.0334 -294.188968) (xy 182.077862 -294.210066) (xy 182.118365 -294.238022) (xy 182.153858 -294.272114)
			(xy 182.183423 -294.311458) (xy 182.206294 -294.355035) (xy 182.221878 -294.401716) (xy 182.229773 -294.450293)
			(xy 182.230268 -294.4749) (xy 182.569116 -294.4749) (xy 182.573076 -294.425846) (xy 182.584853 -294.378062)
			(xy 182.604144 -294.332786) (xy 182.630447 -294.29119) (xy 182.663082 -294.254353) (xy 182.701203 -294.223228)
			(xy 182.743824 -294.198621) (xy 182.78984 -294.181169) (xy 182.838059 -294.171325) (xy 182.887234 -294.169344)
			(xy 182.936089 -294.175276) (xy 182.98336 -294.188968) (xy 183.027822 -294.210066) (xy 183.068325 -294.238022)
			(xy 183.103818 -294.272114) (xy 183.133383 -294.311458) (xy 183.156254 -294.355035) (xy 183.171838 -294.401716)
			(xy 183.179733 -294.450293) (xy 183.180228 -294.4749) (xy 183.519076 -294.4749) (xy 183.523036 -294.425846)
			(xy 183.534813 -294.378062) (xy 183.554104 -294.332786) (xy 183.580407 -294.29119) (xy 183.613042 -294.254353)
			(xy 183.651163 -294.223228) (xy 183.693784 -294.198621) (xy 183.7398 -294.181169) (xy 183.788019 -294.171325)
			(xy 183.837194 -294.169344) (xy 183.886049 -294.175276) (xy 183.93332 -294.188968) (xy 183.977782 -294.210066)
			(xy 184.018285 -294.238022) (xy 184.053778 -294.272114) (xy 184.083343 -294.311458) (xy 184.106214 -294.355035)
			(xy 184.121798 -294.401716) (xy 184.129693 -294.450293) (xy 184.130188 -294.4749) (xy 184.129693 -294.499507)
			(xy 184.121798 -294.548084) (xy 184.106214 -294.594765) (xy 184.083343 -294.638342) (xy 184.053778 -294.677686)
			(xy 184.018285 -294.711778) (xy 183.977782 -294.739734) (xy 183.93332 -294.760832) (xy 183.886049 -294.774524)
			(xy 183.837194 -294.780456) (xy 183.788019 -294.778475) (xy 183.7398 -294.768631) (xy 183.693784 -294.751179)
			(xy 183.651163 -294.726572) (xy 183.613042 -294.695447) (xy 183.580407 -294.65861) (xy 183.554104 -294.617014)
			(xy 183.534813 -294.571738) (xy 183.523036 -294.523954) (xy 183.519076 -294.4749) (xy 183.180228 -294.4749)
			(xy 183.179733 -294.499507) (xy 183.171838 -294.548084) (xy 183.156254 -294.594765) (xy 183.133383 -294.638342)
			(xy 183.103818 -294.677686) (xy 183.068325 -294.711778) (xy 183.027822 -294.739734) (xy 182.98336 -294.760832)
			(xy 182.936089 -294.774524) (xy 182.887234 -294.780456) (xy 182.838059 -294.778475) (xy 182.78984 -294.768631)
			(xy 182.743824 -294.751179) (xy 182.701203 -294.726572) (xy 182.663082 -294.695447) (xy 182.630447 -294.65861)
			(xy 182.604144 -294.617014) (xy 182.584853 -294.571738) (xy 182.573076 -294.523954) (xy 182.569116 -294.4749)
			(xy 182.230268 -294.4749) (xy 182.229773 -294.499507) (xy 182.221878 -294.548084) (xy 182.206294 -294.594765)
			(xy 182.183423 -294.638342) (xy 182.153858 -294.677686) (xy 182.118365 -294.711778) (xy 182.077862 -294.739734)
			(xy 182.0334 -294.760832) (xy 181.986129 -294.774524) (xy 181.937274 -294.780456) (xy 181.888099 -294.778475)
			(xy 181.83988 -294.768631) (xy 181.793864 -294.751179) (xy 181.751243 -294.726572) (xy 181.713122 -294.695447)
			(xy 181.680487 -294.65861) (xy 181.654184 -294.617014) (xy 181.634893 -294.571738) (xy 181.623116 -294.523954)
			(xy 181.619156 -294.4749) (xy 180.330348 -294.4749) (xy 180.329853 -294.499507) (xy 180.321958 -294.548084)
			(xy 180.306374 -294.594765) (xy 180.283503 -294.638342) (xy 180.253938 -294.677686) (xy 180.218445 -294.711778)
			(xy 180.177942 -294.739734) (xy 180.13348 -294.760832) (xy 180.086209 -294.774524) (xy 180.037354 -294.780456)
			(xy 179.988179 -294.778475) (xy 179.93996 -294.768631) (xy 179.893944 -294.751179) (xy 179.851323 -294.726572)
			(xy 179.813202 -294.695447) (xy 179.780567 -294.65861) (xy 179.754264 -294.617014) (xy 179.734973 -294.571738)
			(xy 179.723196 -294.523954) (xy 179.719236 -294.4749) (xy 178.430174 -294.4749) (xy 178.429679 -294.499507)
			(xy 178.421784 -294.548084) (xy 178.4062 -294.594765) (xy 178.383329 -294.638342) (xy 178.353764 -294.677686)
			(xy 178.318271 -294.711778) (xy 178.277768 -294.739734) (xy 178.233306 -294.760832) (xy 178.186035 -294.774524)
			(xy 178.13718 -294.780456) (xy 178.088005 -294.778475) (xy 178.039786 -294.768631) (xy 177.99377 -294.751179)
			(xy 177.951149 -294.726572) (xy 177.913028 -294.695447) (xy 177.880393 -294.65861) (xy 177.85409 -294.617014)
			(xy 177.834799 -294.571738) (xy 177.823022 -294.523954) (xy 177.819062 -294.4749) (xy 176.530254 -294.4749)
			(xy 176.529759 -294.499507) (xy 176.521864 -294.548084) (xy 176.50628 -294.594765) (xy 176.483409 -294.638342)
			(xy 176.453844 -294.677686) (xy 176.418351 -294.711778) (xy 176.377848 -294.739734) (xy 176.333386 -294.760832)
			(xy 176.286115 -294.774524) (xy 176.23726 -294.780456) (xy 176.188085 -294.778475) (xy 176.139866 -294.768631)
			(xy 176.09385 -294.751179) (xy 176.051229 -294.726572) (xy 176.013108 -294.695447) (xy 175.980473 -294.65861)
			(xy 175.95417 -294.617014) (xy 175.934879 -294.571738) (xy 175.923102 -294.523954) (xy 175.919142 -294.4749)
			(xy 173.680374 -294.4749) (xy 173.679879 -294.499507) (xy 173.671984 -294.548084) (xy 173.6564 -294.594765)
			(xy 173.633529 -294.638342) (xy 173.603964 -294.677686) (xy 173.568471 -294.711778) (xy 173.527968 -294.739734)
			(xy 173.483506 -294.760832) (xy 173.436235 -294.774524) (xy 173.38738 -294.780456) (xy 173.338205 -294.778475)
			(xy 173.289986 -294.768631) (xy 173.24397 -294.751179) (xy 173.201349 -294.726572) (xy 173.163228 -294.695447)
			(xy 173.130593 -294.65861) (xy 173.10429 -294.617014) (xy 173.084999 -294.571738) (xy 173.073222 -294.523954)
			(xy 173.069262 -294.4749) (xy 171.7802 -294.4749) (xy 171.779705 -294.499507) (xy 171.77181 -294.548084)
			(xy 171.756226 -294.594765) (xy 171.733355 -294.638342) (xy 171.70379 -294.677686) (xy 171.668297 -294.711778)
			(xy 171.627794 -294.739734) (xy 171.583332 -294.760832) (xy 171.536061 -294.774524) (xy 171.487206 -294.780456)
			(xy 171.438031 -294.778475) (xy 171.389812 -294.768631) (xy 171.343796 -294.751179) (xy 171.301175 -294.726572)
			(xy 171.263054 -294.695447) (xy 171.230419 -294.65861) (xy 171.204116 -294.617014) (xy 171.184825 -294.571738)
			(xy 171.173048 -294.523954) (xy 171.169088 -294.4749) (xy 169.88028 -294.4749) (xy 169.879785 -294.499507)
			(xy 169.87189 -294.548084) (xy 169.856306 -294.594765) (xy 169.833435 -294.638342) (xy 169.80387 -294.677686)
			(xy 169.768377 -294.711778) (xy 169.727874 -294.739734) (xy 169.683412 -294.760832) (xy 169.636141 -294.774524)
			(xy 169.587286 -294.780456) (xy 169.538111 -294.778475) (xy 169.489892 -294.768631) (xy 169.443876 -294.751179)
			(xy 169.401255 -294.726572) (xy 169.363134 -294.695447) (xy 169.330499 -294.65861) (xy 169.304196 -294.617014)
			(xy 169.284905 -294.571738) (xy 169.273128 -294.523954) (xy 169.269168 -294.4749) (xy 167.98036 -294.4749)
			(xy 167.979865 -294.499507) (xy 167.97197 -294.548084) (xy 167.956386 -294.594765) (xy 167.933515 -294.638342)
			(xy 167.90395 -294.677686) (xy 167.868457 -294.711778) (xy 167.827954 -294.739734) (xy 167.783492 -294.760832)
			(xy 167.736221 -294.774524) (xy 167.687366 -294.780456) (xy 167.638191 -294.778475) (xy 167.589972 -294.768631)
			(xy 167.543956 -294.751179) (xy 167.501335 -294.726572) (xy 167.463214 -294.695447) (xy 167.430579 -294.65861)
			(xy 167.404276 -294.617014) (xy 167.384985 -294.571738) (xy 167.373208 -294.523954) (xy 167.369248 -294.4749)
			(xy 166.080186 -294.4749) (xy 166.079691 -294.499507) (xy 166.071796 -294.548084) (xy 166.056212 -294.594765)
			(xy 166.033341 -294.638342) (xy 166.003776 -294.677686) (xy 165.968283 -294.711778) (xy 165.92778 -294.739734)
			(xy 165.883318 -294.760832) (xy 165.836047 -294.774524) (xy 165.787192 -294.780456) (xy 165.738017 -294.778475)
			(xy 165.689798 -294.768631) (xy 165.643782 -294.751179) (xy 165.601161 -294.726572) (xy 165.56304 -294.695447)
			(xy 165.530405 -294.65861) (xy 165.504102 -294.617014) (xy 165.484811 -294.571738) (xy 165.473034 -294.523954)
			(xy 165.469074 -294.4749) (xy 164.180266 -294.4749) (xy 164.179771 -294.499507) (xy 164.171876 -294.548084)
			(xy 164.156292 -294.594765) (xy 164.133421 -294.638342) (xy 164.103856 -294.677686) (xy 164.068363 -294.711778)
			(xy 164.02786 -294.739734) (xy 163.983398 -294.760832) (xy 163.936127 -294.774524) (xy 163.887272 -294.780456)
			(xy 163.838097 -294.778475) (xy 163.789878 -294.768631) (xy 163.743862 -294.751179) (xy 163.701241 -294.726572)
			(xy 163.66312 -294.695447) (xy 163.630485 -294.65861) (xy 163.604182 -294.617014) (xy 163.584891 -294.571738)
			(xy 163.573114 -294.523954) (xy 163.569154 -294.4749) (xy 163.230306 -294.4749) (xy 163.229811 -294.499507)
			(xy 163.221916 -294.548084) (xy 163.206332 -294.594765) (xy 163.183461 -294.638342) (xy 163.153896 -294.677686)
			(xy 163.118403 -294.711778) (xy 163.0779 -294.739734) (xy 163.033438 -294.760832) (xy 162.986167 -294.774524)
			(xy 162.937312 -294.780456) (xy 162.888137 -294.778475) (xy 162.839918 -294.768631) (xy 162.793902 -294.751179)
			(xy 162.751281 -294.726572) (xy 162.71316 -294.695447) (xy 162.680525 -294.65861) (xy 162.654222 -294.617014)
			(xy 162.634931 -294.571738) (xy 162.623154 -294.523954) (xy 162.619194 -294.4749) (xy 162.280346 -294.4749)
			(xy 162.279851 -294.499507) (xy 162.271956 -294.548084) (xy 162.256372 -294.594765) (xy 162.233501 -294.638342)
			(xy 162.203936 -294.677686) (xy 162.168443 -294.711778) (xy 162.12794 -294.739734) (xy 162.083478 -294.760832)
			(xy 162.036207 -294.774524) (xy 161.987352 -294.780456) (xy 161.938177 -294.778475) (xy 161.889958 -294.768631)
			(xy 161.843942 -294.751179) (xy 161.801321 -294.726572) (xy 161.7632 -294.695447) (xy 161.730565 -294.65861)
			(xy 161.704262 -294.617014) (xy 161.684971 -294.571738) (xy 161.673194 -294.523954) (xy 161.669234 -294.4749)
			(xy 161.330386 -294.4749) (xy 161.329891 -294.499507) (xy 161.321996 -294.548084) (xy 161.306412 -294.594765)
			(xy 161.283541 -294.638342) (xy 161.253976 -294.677686) (xy 161.218483 -294.711778) (xy 161.17798 -294.739734)
			(xy 161.133518 -294.760832) (xy 161.086247 -294.774524) (xy 161.037392 -294.780456) (xy 160.988217 -294.778475)
			(xy 160.939998 -294.768631) (xy 160.893982 -294.751179) (xy 160.851361 -294.726572) (xy 160.81324 -294.695447)
			(xy 160.780605 -294.65861) (xy 160.754302 -294.617014) (xy 160.735011 -294.571738) (xy 160.723234 -294.523954)
			(xy 160.719274 -294.4749) (xy 160.380172 -294.4749) (xy 160.379677 -294.499507) (xy 160.371782 -294.548084)
			(xy 160.356198 -294.594765) (xy 160.333327 -294.638342) (xy 160.303762 -294.677686) (xy 160.268269 -294.711778)
			(xy 160.227766 -294.739734) (xy 160.183304 -294.760832) (xy 160.136033 -294.774524) (xy 160.087178 -294.780456)
			(xy 160.038003 -294.778475) (xy 159.989784 -294.768631) (xy 159.943768 -294.751179) (xy 159.901147 -294.726572)
			(xy 159.863026 -294.695447) (xy 159.830391 -294.65861) (xy 159.804088 -294.617014) (xy 159.784797 -294.571738)
			(xy 159.77302 -294.523954) (xy 159.76906 -294.4749) (xy 159.430212 -294.4749) (xy 159.429717 -294.499507)
			(xy 159.421822 -294.548084) (xy 159.406238 -294.594765) (xy 159.383367 -294.638342) (xy 159.353802 -294.677686)
			(xy 159.318309 -294.711778) (xy 159.277806 -294.739734) (xy 159.233344 -294.760832) (xy 159.186073 -294.774524)
			(xy 159.137218 -294.780456) (xy 159.088043 -294.778475) (xy 159.039824 -294.768631) (xy 158.993808 -294.751179)
			(xy 158.951187 -294.726572) (xy 158.913066 -294.695447) (xy 158.880431 -294.65861) (xy 158.854128 -294.617014)
			(xy 158.834837 -294.571738) (xy 158.82306 -294.523954) (xy 158.8191 -294.4749) (xy 158.531052 -294.4749)
			(xy 158.530554 -294.501549) (xy 158.522611 -294.554253) (xy 158.506901 -294.605183) (xy 158.483775 -294.653204)
			(xy 158.453751 -294.697241) (xy 158.417499 -294.736312) (xy 158.375828 -294.769543) (xy 158.32967 -294.796192)
			(xy 158.280056 -294.815664) (xy 158.228094 -294.827524) (xy 158.174944 -294.831508) (xy 158.121794 -294.827524)
			(xy 158.069832 -294.815664) (xy 158.020218 -294.796192) (xy 157.97406 -294.769543) (xy 157.932389 -294.736312)
			(xy 157.896137 -294.697241) (xy 157.866113 -294.653204) (xy 157.842987 -294.605183) (xy 157.827277 -294.554253)
			(xy 157.819334 -294.501549) (xy 157.529465 -294.501549) (xy 157.521902 -294.548084) (xy 157.506318 -294.594765)
			(xy 157.483447 -294.638342) (xy 157.453882 -294.677686) (xy 157.418389 -294.711778) (xy 157.377886 -294.739734)
			(xy 157.333424 -294.760832) (xy 157.286153 -294.774524) (xy 157.237298 -294.780456) (xy 157.188123 -294.778475)
			(xy 157.139904 -294.768631) (xy 157.093888 -294.751179) (xy 157.051267 -294.726572) (xy 157.013146 -294.695447)
			(xy 156.980511 -294.65861) (xy 156.954208 -294.617014) (xy 156.934917 -294.571738) (xy 156.92314 -294.523954)
			(xy 156.91918 -294.4749) (xy 154.680412 -294.4749) (xy 154.679917 -294.499507) (xy 154.672022 -294.548084)
			(xy 154.656438 -294.594765) (xy 154.633567 -294.638342) (xy 154.604002 -294.677686) (xy 154.568509 -294.711778)
			(xy 154.528006 -294.739734) (xy 154.483544 -294.760832) (xy 154.436273 -294.774524) (xy 154.387418 -294.780456)
			(xy 154.338243 -294.778475) (xy 154.290024 -294.768631) (xy 154.244008 -294.751179) (xy 154.201387 -294.726572)
			(xy 154.163266 -294.695447) (xy 154.130631 -294.65861) (xy 154.104328 -294.617014) (xy 154.085037 -294.571738)
			(xy 154.07326 -294.523954) (xy 154.0693 -294.4749) (xy 153.730198 -294.4749) (xy 153.729703 -294.499507)
			(xy 153.721808 -294.548084) (xy 153.706224 -294.594765) (xy 153.683353 -294.638342) (xy 153.653788 -294.677686)
			(xy 153.618295 -294.711778) (xy 153.577792 -294.739734) (xy 153.53333 -294.760832) (xy 153.486059 -294.774524)
			(xy 153.437204 -294.780456) (xy 153.388029 -294.778475) (xy 153.33981 -294.768631) (xy 153.293794 -294.751179)
			(xy 153.251173 -294.726572) (xy 153.213052 -294.695447) (xy 153.180417 -294.65861) (xy 153.154114 -294.617014)
			(xy 153.134823 -294.571738) (xy 153.123046 -294.523954) (xy 153.119086 -294.4749) (xy 152.780238 -294.4749)
			(xy 152.779743 -294.499507) (xy 152.771848 -294.548084) (xy 152.756264 -294.594765) (xy 152.733393 -294.638342)
			(xy 152.703828 -294.677686) (xy 152.668335 -294.711778) (xy 152.627832 -294.739734) (xy 152.58337 -294.760832)
			(xy 152.536099 -294.774524) (xy 152.487244 -294.780456) (xy 152.438069 -294.778475) (xy 152.38985 -294.768631)
			(xy 152.343834 -294.751179) (xy 152.301213 -294.726572) (xy 152.263092 -294.695447) (xy 152.230457 -294.65861)
			(xy 152.204154 -294.617014) (xy 152.184863 -294.571738) (xy 152.173086 -294.523954) (xy 152.169126 -294.4749)
			(xy 144.126408 -294.4749) (xy 144.135543 -294.494387) (xy 144.151611 -294.547794) (xy 144.159731 -294.60297)
			(xy 144.16024 -294.630856) (xy 144.159731 -294.658742) (xy 144.151611 -294.713918) (xy 144.135543 -294.767325)
			(xy 144.111871 -294.817822) (xy 144.081098 -294.864335) (xy 144.043881 -294.905872) (xy 144.001013 -294.941547)
			(xy 143.953407 -294.970601) (xy 143.902078 -294.992413) (xy 143.848121 -295.006519) (xy 143.792684 -295.012619)
			(xy 143.73695 -295.010582) (xy 143.682107 -295.000452) (xy 143.629323 -294.982445) (xy 143.579723 -294.956944)
			(xy 143.534365 -294.924493) (xy 143.494216 -294.885784) (xy 143.46013 -294.841641) (xy 143.432834 -294.793006)
			(xy 143.412911 -294.740915) (xy 143.400785 -294.686478) (xy 143.396714 -294.630856) (xy 142.675102 -294.630856)
			(xy 142.674593 -294.658742) (xy 142.666473 -294.713918) (xy 142.650405 -294.767325) (xy 142.626733 -294.817822)
			(xy 142.59596 -294.864335) (xy 142.558743 -294.905872) (xy 142.515875 -294.941547) (xy 142.468269 -294.970601)
			(xy 142.41694 -294.992413) (xy 142.362983 -295.006519) (xy 142.307546 -295.012619) (xy 142.251812 -295.010582)
			(xy 142.196969 -295.000452) (xy 142.144185 -294.982445) (xy 142.094585 -294.956944) (xy 142.049227 -294.924493)
			(xy 142.009078 -294.885784) (xy 141.974992 -294.841641) (xy 141.947696 -294.793006) (xy 141.927773 -294.740915)
			(xy 141.915647 -294.686478) (xy 141.911576 -294.630856) (xy 118.97614 -294.630856) (xy 118.914164 -294.692832)
			(xy 118.909115 -294.697621) (xy 118.897 -294.704457) (xy 118.890288 -294.706294) (xy 118.890034 -294.706294)
			(xy 118.883176 -294.708072) (xy 118.877588 -294.71112) (xy 118.876318 -294.711882) (xy 118.866158 -294.719756)
			(xy 118.847616 -294.738298) (xy 118.844092 -294.742027) (xy 118.838457 -294.750599) (xy 118.83644 -294.755316)
			(xy 118.832884 -294.763952) (xy 118.832884 -295.933114) (xy 141.911576 -295.933114) (xy 141.915647 -295.877492)
			(xy 141.927773 -295.823055) (xy 141.947696 -295.770964) (xy 141.974992 -295.722329) (xy 142.009078 -295.678186)
			(xy 142.049227 -295.639477) (xy 142.094585 -295.607026) (xy 142.144185 -295.581525) (xy 142.196969 -295.563518)
			(xy 142.251812 -295.553388) (xy 142.307546 -295.551351) (xy 142.362983 -295.557451) (xy 142.41694 -295.571557)
			(xy 142.468269 -295.593369) (xy 142.515875 -295.622423) (xy 142.558743 -295.658098) (xy 142.59596 -295.699635)
			(xy 142.626733 -295.746148) (xy 142.650405 -295.796645) (xy 142.666473 -295.850052) (xy 142.674593 -295.905228)
			(xy 142.675102 -295.933114) (xy 143.387062 -295.933114) (xy 143.391133 -295.877492) (xy 143.403259 -295.823055)
			(xy 143.423182 -295.770964) (xy 143.450478 -295.722329) (xy 143.484564 -295.678186) (xy 143.524713 -295.639477)
			(xy 143.570071 -295.607026) (xy 143.619671 -295.581525) (xy 143.672455 -295.563518) (xy 143.727298 -295.553388)
			(xy 143.783032 -295.551351) (xy 143.838469 -295.557451) (xy 143.892426 -295.571557) (xy 143.943755 -295.593369)
			(xy 143.991361 -295.622423) (xy 144.034229 -295.658098) (xy 144.071446 -295.699635) (xy 144.102219 -295.746148)
			(xy 144.125891 -295.796645) (xy 144.141959 -295.850052) (xy 144.150079 -295.905228) (xy 144.150588 -295.933114)
			(xy 144.276062 -295.933114) (xy 144.280133 -295.877492) (xy 144.292259 -295.823055) (xy 144.312182 -295.770964)
			(xy 144.339478 -295.722329) (xy 144.373564 -295.678186) (xy 144.413713 -295.639477) (xy 144.459071 -295.607026)
			(xy 144.508671 -295.581525) (xy 144.561455 -295.563518) (xy 144.616298 -295.553388) (xy 144.672032 -295.551351)
			(xy 144.727469 -295.557451) (xy 144.781426 -295.571557) (xy 144.832755 -295.593369) (xy 144.880361 -295.622423)
			(xy 144.923229 -295.658098) (xy 144.960446 -295.699635) (xy 144.991219 -295.746148) (xy 145.014891 -295.796645)
			(xy 145.030959 -295.850052) (xy 145.039079 -295.905228) (xy 145.039588 -295.933114) (xy 145.039079 -295.961)
			(xy 145.030959 -296.016176) (xy 145.014891 -296.069583) (xy 144.991219 -296.12008) (xy 144.960446 -296.166593)
			(xy 144.923229 -296.20813) (xy 144.880361 -296.243805) (xy 144.832755 -296.272859) (xy 144.781426 -296.294671)
			(xy 144.727469 -296.308777) (xy 144.672032 -296.314877) (xy 144.616298 -296.31284) (xy 144.561455 -296.30271)
			(xy 144.508671 -296.284703) (xy 144.459071 -296.259202) (xy 144.413713 -296.226751) (xy 144.373564 -296.188042)
			(xy 144.339478 -296.143899) (xy 144.312182 -296.095264) (xy 144.292259 -296.043173) (xy 144.280133 -295.988736)
			(xy 144.276062 -295.933114) (xy 144.150588 -295.933114) (xy 144.150079 -295.961) (xy 144.141959 -296.016176)
			(xy 144.125891 -296.069583) (xy 144.102219 -296.12008) (xy 144.071446 -296.166593) (xy 144.034229 -296.20813)
			(xy 143.991361 -296.243805) (xy 143.943755 -296.272859) (xy 143.892426 -296.294671) (xy 143.838469 -296.308777)
			(xy 143.783032 -296.314877) (xy 143.727298 -296.31284) (xy 143.672455 -296.30271) (xy 143.619671 -296.284703)
			(xy 143.570071 -296.259202) (xy 143.524713 -296.226751) (xy 143.484564 -296.188042) (xy 143.450478 -296.143899)
			(xy 143.423182 -296.095264) (xy 143.403259 -296.043173) (xy 143.391133 -295.988736) (xy 143.387062 -295.933114)
			(xy 142.675102 -295.933114) (xy 142.674593 -295.961) (xy 142.666473 -296.016176) (xy 142.650405 -296.069583)
			(xy 142.626733 -296.12008) (xy 142.59596 -296.166593) (xy 142.558743 -296.20813) (xy 142.515875 -296.243805)
			(xy 142.468269 -296.272859) (xy 142.41694 -296.294671) (xy 142.362983 -296.308777) (xy 142.307546 -296.314877)
			(xy 142.251812 -296.31284) (xy 142.196969 -296.30271) (xy 142.144185 -296.284703) (xy 142.094585 -296.259202)
			(xy 142.049227 -296.226751) (xy 142.009078 -296.188042) (xy 141.974992 -296.143899) (xy 141.947696 -296.095264)
			(xy 141.927773 -296.043173) (xy 141.915647 -295.988736) (xy 141.911576 -295.933114) (xy 118.832884 -295.933114)
			(xy 118.832884 -296.695114) (xy 147.43811 -296.695114) (xy 147.438654 -296.665732) (xy 147.447683 -296.607665)
			(xy 147.465514 -296.551671) (xy 147.491725 -296.499075) (xy 147.525695 -296.451124) (xy 147.56662 -296.408952)
			(xy 147.589748 -296.390822) (xy 147.598672 -296.383342) (xy 147.609132 -296.362568) (xy 147.609814 -296.350944)
			(xy 147.611084 -296.258996) (xy 147.601178 -296.237914) (xy 147.592034 -296.230548) (xy 147.570186 -296.212342)
			(xy 147.531644 -296.170524) (xy 147.499736 -296.123449) (xy 147.475169 -296.072159) (xy 147.458486 -296.017791)
			(xy 147.450058 -295.961549) (xy 147.44954 -295.933114) (xy 147.450026 -295.905863) (xy 147.457782 -295.851915)
			(xy 147.473137 -295.79962) (xy 147.495779 -295.750043) (xy 147.525245 -295.704193) (xy 147.560936 -295.663002)
			(xy 147.602127 -295.627311) (xy 147.647977 -295.597845) (xy 147.697554 -295.575203) (xy 147.749849 -295.559848)
			(xy 147.803797 -295.552092) (xy 147.858299 -295.552092) (xy 147.912247 -295.559848) (xy 147.964542 -295.575203)
			(xy 148.014119 -295.597845) (xy 148.059969 -295.627311) (xy 148.10116 -295.663002) (xy 148.136851 -295.704193)
			(xy 148.166317 -295.750043) (xy 148.188959 -295.79962) (xy 148.204314 -295.851915) (xy 148.21207 -295.905863)
			(xy 148.212556 -295.933114) (xy 148.212006 -295.962496) (xy 148.202975 -296.020561) (xy 148.185143 -296.076554)
			(xy 148.158933 -296.129149) (xy 148.124966 -296.177101) (xy 148.084044 -296.219274) (xy 148.060918 -296.237406)
			(xy 148.051975 -296.244867) (xy 148.041527 -296.265656) (xy 148.040852 -296.277284) (xy 148.039582 -296.369232)
			(xy 148.049488 -296.390314) (xy 148.058632 -296.39768) (xy 148.080459 -296.415909) (xy 148.118999 -296.457724)
			(xy 148.150908 -296.504795) (xy 148.175478 -296.55608) (xy 148.192166 -296.610443) (xy 148.200603 -296.666681)
			(xy 148.201126 -296.695114) (xy 148.8346 -296.695114) (xy 148.838671 -296.639492) (xy 148.850797 -296.585055)
			(xy 148.87072 -296.532964) (xy 148.898016 -296.484329) (xy 148.932102 -296.440186) (xy 148.972251 -296.401477)
			(xy 149.017609 -296.369026) (xy 149.067209 -296.343525) (xy 149.119993 -296.325518) (xy 149.174836 -296.315388)
			(xy 149.23057 -296.313351) (xy 149.286007 -296.319451) (xy 149.339964 -296.333557) (xy 149.391293 -296.355369)
			(xy 149.438899 -296.384423) (xy 149.481767 -296.420098) (xy 149.518984 -296.461635) (xy 149.549757 -296.508148)
			(xy 149.573429 -296.558645) (xy 149.589497 -296.612052) (xy 149.597617 -296.667228) (xy 149.598126 -296.695114)
			(xy 149.72106 -296.695114) (xy 149.725131 -296.639492) (xy 149.737257 -296.585055) (xy 149.75718 -296.532964)
			(xy 149.784476 -296.484329) (xy 149.818562 -296.440186) (xy 149.858711 -296.401477) (xy 149.904069 -296.369026)
			(xy 149.953669 -296.343525) (xy 150.006453 -296.325518) (xy 150.061296 -296.315388) (xy 150.11703 -296.313351)
			(xy 150.172467 -296.319451) (xy 150.226424 -296.333557) (xy 150.277753 -296.355369) (xy 150.309624 -296.37482)
			(xy 153.11934 -296.37482) (xy 153.1233 -296.325766) (xy 153.135077 -296.277982) (xy 153.154368 -296.232706)
			(xy 153.180671 -296.19111) (xy 153.213306 -296.154273) (xy 153.251427 -296.123148) (xy 153.294048 -296.098541)
			(xy 153.340064 -296.081089) (xy 153.388283 -296.071245) (xy 153.437458 -296.069264) (xy 153.486313 -296.075196)
			(xy 153.533584 -296.088888) (xy 153.578046 -296.109986) (xy 153.618549 -296.137942) (xy 153.654042 -296.172034)
			(xy 153.683607 -296.211378) (xy 153.706478 -296.254955) (xy 153.722062 -296.301636) (xy 153.729957 -296.350213)
			(xy 153.730452 -296.37482) (xy 154.069046 -296.37482) (xy 154.073006 -296.325766) (xy 154.084783 -296.277982)
			(xy 154.104074 -296.232706) (xy 154.130377 -296.19111) (xy 154.163012 -296.154273) (xy 154.201133 -296.123148)
			(xy 154.243754 -296.098541) (xy 154.28977 -296.081089) (xy 154.337989 -296.071245) (xy 154.387164 -296.069264)
			(xy 154.436019 -296.075196) (xy 154.48329 -296.088888) (xy 154.527752 -296.109986) (xy 154.568255 -296.137942)
			(xy 154.603748 -296.172034) (xy 154.633313 -296.211378) (xy 154.656184 -296.254955) (xy 154.671768 -296.301636)
			(xy 154.679663 -296.350213) (xy 154.680158 -296.37482) (xy 155.01926 -296.37482) (xy 155.02322 -296.325766)
			(xy 155.034997 -296.277982) (xy 155.054288 -296.232706) (xy 155.080591 -296.19111) (xy 155.113226 -296.154273)
			(xy 155.151347 -296.123148) (xy 155.193968 -296.098541) (xy 155.239984 -296.081089) (xy 155.288203 -296.071245)
			(xy 155.337378 -296.069264) (xy 155.386233 -296.075196) (xy 155.433504 -296.088888) (xy 155.477966 -296.109986)
			(xy 155.518469 -296.137942) (xy 155.553962 -296.172034) (xy 155.583527 -296.211378) (xy 155.606398 -296.254955)
			(xy 155.621982 -296.301636) (xy 155.629877 -296.350213) (xy 155.630372 -296.37482) (xy 155.96922 -296.37482)
			(xy 155.97318 -296.325766) (xy 155.984957 -296.277982) (xy 156.004248 -296.232706) (xy 156.030551 -296.19111)
			(xy 156.063186 -296.154273) (xy 156.101307 -296.123148) (xy 156.143928 -296.098541) (xy 156.189944 -296.081089)
			(xy 156.238163 -296.071245) (xy 156.287338 -296.069264) (xy 156.336193 -296.075196) (xy 156.383464 -296.088888)
			(xy 156.427926 -296.109986) (xy 156.468429 -296.137942) (xy 156.503922 -296.172034) (xy 156.533487 -296.211378)
			(xy 156.556358 -296.254955) (xy 156.571942 -296.301636) (xy 156.579837 -296.350213) (xy 156.580332 -296.37482)
			(xy 157.86914 -296.37482) (xy 157.8731 -296.325766) (xy 157.884877 -296.277982) (xy 157.904168 -296.232706)
			(xy 157.930471 -296.19111) (xy 157.963106 -296.154273) (xy 158.001227 -296.123148) (xy 158.043848 -296.098541)
			(xy 158.089864 -296.081089) (xy 158.138083 -296.071245) (xy 158.187258 -296.069264) (xy 158.236113 -296.075196)
			(xy 158.283384 -296.088888) (xy 158.327846 -296.109986) (xy 158.368349 -296.137942) (xy 158.403842 -296.172034)
			(xy 158.433407 -296.211378) (xy 158.456278 -296.254955) (xy 158.471862 -296.301636) (xy 158.479757 -296.350213)
			(xy 158.480252 -296.37482) (xy 159.76906 -296.37482) (xy 159.77302 -296.325766) (xy 159.784797 -296.277982)
			(xy 159.804088 -296.232706) (xy 159.830391 -296.19111) (xy 159.863026 -296.154273) (xy 159.901147 -296.123148)
			(xy 159.943768 -296.098541) (xy 159.989784 -296.081089) (xy 160.038003 -296.071245) (xy 160.087178 -296.069264)
			(xy 160.136033 -296.075196) (xy 160.183304 -296.088888) (xy 160.227766 -296.109986) (xy 160.268269 -296.137942)
			(xy 160.303762 -296.172034) (xy 160.333327 -296.211378) (xy 160.356198 -296.254955) (xy 160.371782 -296.301636)
			(xy 160.379677 -296.350213) (xy 160.380172 -296.37482) (xy 160.719274 -296.37482) (xy 160.723234 -296.325766)
			(xy 160.735011 -296.277982) (xy 160.754302 -296.232706) (xy 160.780605 -296.19111) (xy 160.81324 -296.154273)
			(xy 160.851361 -296.123148) (xy 160.893982 -296.098541) (xy 160.939998 -296.081089) (xy 160.988217 -296.071245)
			(xy 161.037392 -296.069264) (xy 161.086247 -296.075196) (xy 161.133518 -296.088888) (xy 161.17798 -296.109986)
			(xy 161.218483 -296.137942) (xy 161.253976 -296.172034) (xy 161.283541 -296.211378) (xy 161.306412 -296.254955)
			(xy 161.321996 -296.301636) (xy 161.329891 -296.350213) (xy 161.330386 -296.37482) (xy 161.669234 -296.37482)
			(xy 161.673194 -296.325766) (xy 161.684971 -296.277982) (xy 161.704262 -296.232706) (xy 161.730565 -296.19111)
			(xy 161.7632 -296.154273) (xy 161.801321 -296.123148) (xy 161.843942 -296.098541) (xy 161.889958 -296.081089)
			(xy 161.938177 -296.071245) (xy 161.987352 -296.069264) (xy 162.036207 -296.075196) (xy 162.083478 -296.088888)
			(xy 162.12794 -296.109986) (xy 162.168443 -296.137942) (xy 162.203936 -296.172034) (xy 162.233501 -296.211378)
			(xy 162.256372 -296.254955) (xy 162.271956 -296.301636) (xy 162.279851 -296.350213) (xy 162.280346 -296.37482)
			(xy 163.569154 -296.37482) (xy 163.573114 -296.325766) (xy 163.584891 -296.277982) (xy 163.604182 -296.232706)
			(xy 163.630485 -296.19111) (xy 163.66312 -296.154273) (xy 163.701241 -296.123148) (xy 163.743862 -296.098541)
			(xy 163.789878 -296.081089) (xy 163.838097 -296.071245) (xy 163.887272 -296.069264) (xy 163.936127 -296.075196)
			(xy 163.983398 -296.088888) (xy 164.02786 -296.109986) (xy 164.068363 -296.137942) (xy 164.103856 -296.172034)
			(xy 164.133421 -296.211378) (xy 164.156292 -296.254955) (xy 164.171876 -296.301636) (xy 164.179771 -296.350213)
			(xy 164.180266 -296.37482) (xy 164.519114 -296.37482) (xy 164.523074 -296.325766) (xy 164.534851 -296.277982)
			(xy 164.554142 -296.232706) (xy 164.580445 -296.19111) (xy 164.61308 -296.154273) (xy 164.651201 -296.123148)
			(xy 164.693822 -296.098541) (xy 164.739838 -296.081089) (xy 164.788057 -296.071245) (xy 164.837232 -296.069264)
			(xy 164.886087 -296.075196) (xy 164.933358 -296.088888) (xy 164.97782 -296.109986) (xy 165.018323 -296.137942)
			(xy 165.053816 -296.172034) (xy 165.083381 -296.211378) (xy 165.106252 -296.254955) (xy 165.121836 -296.301636)
			(xy 165.129731 -296.350213) (xy 165.130226 -296.37482) (xy 166.419288 -296.37482) (xy 166.423248 -296.325766)
			(xy 166.435025 -296.277982) (xy 166.454316 -296.232706) (xy 166.480619 -296.19111) (xy 166.513254 -296.154273)
			(xy 166.551375 -296.123148) (xy 166.593996 -296.098541) (xy 166.640012 -296.081089) (xy 166.688231 -296.071245)
			(xy 166.737406 -296.069264) (xy 166.786261 -296.075196) (xy 166.833532 -296.088888) (xy 166.877994 -296.109986)
			(xy 166.918497 -296.137942) (xy 166.95399 -296.172034) (xy 166.983555 -296.211378) (xy 167.006426 -296.254955)
			(xy 167.02201 -296.301636) (xy 167.029905 -296.350213) (xy 167.0304 -296.37482) (xy 168.319208 -296.37482)
			(xy 168.323168 -296.325766) (xy 168.334945 -296.277982) (xy 168.354236 -296.232706) (xy 168.380539 -296.19111)
			(xy 168.413174 -296.154273) (xy 168.451295 -296.123148) (xy 168.493916 -296.098541) (xy 168.539932 -296.081089)
			(xy 168.588151 -296.071245) (xy 168.637326 -296.069264) (xy 168.686181 -296.075196) (xy 168.733452 -296.088888)
			(xy 168.777914 -296.109986) (xy 168.818417 -296.137942) (xy 168.85391 -296.172034) (xy 168.883475 -296.211378)
			(xy 168.906346 -296.254955) (xy 168.92193 -296.301636) (xy 168.929825 -296.350213) (xy 168.93032 -296.37482)
			(xy 170.219128 -296.37482) (xy 170.223088 -296.325766) (xy 170.234865 -296.277982) (xy 170.254156 -296.232706)
			(xy 170.280459 -296.19111) (xy 170.313094 -296.154273) (xy 170.351215 -296.123148) (xy 170.393836 -296.098541)
			(xy 170.439852 -296.081089) (xy 170.488071 -296.071245) (xy 170.537246 -296.069264) (xy 170.586101 -296.075196)
			(xy 170.633372 -296.088888) (xy 170.677834 -296.109986) (xy 170.718337 -296.137942) (xy 170.75383 -296.172034)
			(xy 170.783395 -296.211378) (xy 170.806266 -296.254955) (xy 170.82185 -296.301636) (xy 170.829745 -296.350213)
			(xy 170.83024 -296.37482) (xy 172.119302 -296.37482) (xy 172.123262 -296.325766) (xy 172.135039 -296.277982)
			(xy 172.15433 -296.232706) (xy 172.180633 -296.19111) (xy 172.213268 -296.154273) (xy 172.251389 -296.123148)
			(xy 172.29401 -296.098541) (xy 172.340026 -296.081089) (xy 172.388245 -296.071245) (xy 172.43742 -296.069264)
			(xy 172.486275 -296.075196) (xy 172.533546 -296.088888) (xy 172.578008 -296.109986) (xy 172.618511 -296.137942)
			(xy 172.654004 -296.172034) (xy 172.683569 -296.211378) (xy 172.70644 -296.254955) (xy 172.722024 -296.301636)
			(xy 172.729919 -296.350213) (xy 172.730414 -296.37482) (xy 174.019222 -296.37482) (xy 174.023182 -296.325766)
			(xy 174.034959 -296.277982) (xy 174.05425 -296.232706) (xy 174.080553 -296.19111) (xy 174.113188 -296.154273)
			(xy 174.151309 -296.123148) (xy 174.19393 -296.098541) (xy 174.239946 -296.081089) (xy 174.288165 -296.071245)
			(xy 174.33734 -296.069264) (xy 174.386195 -296.075196) (xy 174.433466 -296.088888) (xy 174.477928 -296.109986)
			(xy 174.518431 -296.137942) (xy 174.553924 -296.172034) (xy 174.583489 -296.211378) (xy 174.60636 -296.254955)
			(xy 174.621944 -296.301636) (xy 174.629839 -296.350213) (xy 174.630334 -296.37482) (xy 176.869102 -296.37482)
			(xy 176.873062 -296.325766) (xy 176.884839 -296.277982) (xy 176.90413 -296.232706) (xy 176.930433 -296.19111)
			(xy 176.963068 -296.154273) (xy 177.001189 -296.123148) (xy 177.04381 -296.098541) (xy 177.089826 -296.081089)
			(xy 177.138045 -296.071245) (xy 177.18722 -296.069264) (xy 177.236075 -296.075196) (xy 177.283346 -296.088888)
			(xy 177.327808 -296.109986) (xy 177.368311 -296.137942) (xy 177.403804 -296.172034) (xy 177.433369 -296.211378)
			(xy 177.45624 -296.254955) (xy 177.471824 -296.301636) (xy 177.479719 -296.350213) (xy 177.480214 -296.37482)
			(xy 178.769276 -296.37482) (xy 178.773236 -296.325766) (xy 178.785013 -296.277982) (xy 178.804304 -296.232706)
			(xy 178.830607 -296.19111) (xy 178.863242 -296.154273) (xy 178.901363 -296.123148) (xy 178.943984 -296.098541)
			(xy 178.99 -296.081089) (xy 179.038219 -296.071245) (xy 179.087394 -296.069264) (xy 179.136249 -296.075196)
			(xy 179.18352 -296.088888) (xy 179.227982 -296.109986) (xy 179.268485 -296.137942) (xy 179.303978 -296.172034)
			(xy 179.333543 -296.211378) (xy 179.356414 -296.254955) (xy 179.371998 -296.301636) (xy 179.379893 -296.350213)
			(xy 179.380388 -296.37482) (xy 180.669196 -296.37482) (xy 180.673156 -296.325766) (xy 180.684933 -296.277982)
			(xy 180.704224 -296.232706) (xy 180.730527 -296.19111) (xy 180.763162 -296.154273) (xy 180.801283 -296.123148)
			(xy 180.843904 -296.098541) (xy 180.88992 -296.081089) (xy 180.938139 -296.071245) (xy 180.987314 -296.069264)
			(xy 181.036169 -296.075196) (xy 181.08344 -296.088888) (xy 181.127902 -296.109986) (xy 181.168405 -296.137942)
			(xy 181.203898 -296.172034) (xy 181.233463 -296.211378) (xy 181.256334 -296.254955) (xy 181.271918 -296.301636)
			(xy 181.279813 -296.350213) (xy 181.280308 -296.37482) (xy 182.569116 -296.37482) (xy 182.573076 -296.325766)
			(xy 182.584853 -296.277982) (xy 182.604144 -296.232706) (xy 182.630447 -296.19111) (xy 182.663082 -296.154273)
			(xy 182.701203 -296.123148) (xy 182.743824 -296.098541) (xy 182.78984 -296.081089) (xy 182.838059 -296.071245)
			(xy 182.887234 -296.069264) (xy 182.936089 -296.075196) (xy 182.98336 -296.088888) (xy 183.027822 -296.109986)
			(xy 183.068325 -296.137942) (xy 183.103818 -296.172034) (xy 183.133383 -296.211378) (xy 183.156254 -296.254955)
			(xy 183.171838 -296.301636) (xy 183.179733 -296.350213) (xy 183.180228 -296.37482) (xy 183.519076 -296.37482)
			(xy 183.523036 -296.325766) (xy 183.534813 -296.277982) (xy 183.554104 -296.232706) (xy 183.580407 -296.19111)
			(xy 183.613042 -296.154273) (xy 183.651163 -296.123148) (xy 183.693784 -296.098541) (xy 183.7398 -296.081089)
			(xy 183.788019 -296.071245) (xy 183.837194 -296.069264) (xy 183.886049 -296.075196) (xy 183.93332 -296.088888)
			(xy 183.977782 -296.109986) (xy 184.018285 -296.137942) (xy 184.053778 -296.172034) (xy 184.083343 -296.211378)
			(xy 184.106214 -296.254955) (xy 184.121798 -296.301636) (xy 184.129693 -296.350213) (xy 184.130188 -296.37482)
			(xy 184.129693 -296.399427) (xy 184.121798 -296.448004) (xy 184.106214 -296.494685) (xy 184.083343 -296.538262)
			(xy 184.053778 -296.577606) (xy 184.018285 -296.611698) (xy 183.977782 -296.639654) (xy 183.93332 -296.660752)
			(xy 183.886049 -296.674444) (xy 183.837194 -296.680376) (xy 183.788019 -296.678395) (xy 183.7398 -296.668551)
			(xy 183.693784 -296.651099) (xy 183.651163 -296.626492) (xy 183.613042 -296.595367) (xy 183.580407 -296.55853)
			(xy 183.554104 -296.516934) (xy 183.534813 -296.471658) (xy 183.523036 -296.423874) (xy 183.519076 -296.37482)
			(xy 183.180228 -296.37482) (xy 183.179733 -296.399427) (xy 183.171838 -296.448004) (xy 183.156254 -296.494685)
			(xy 183.133383 -296.538262) (xy 183.103818 -296.577606) (xy 183.068325 -296.611698) (xy 183.027822 -296.639654)
			(xy 182.98336 -296.660752) (xy 182.936089 -296.674444) (xy 182.887234 -296.680376) (xy 182.838059 -296.678395)
			(xy 182.78984 -296.668551) (xy 182.743824 -296.651099) (xy 182.701203 -296.626492) (xy 182.663082 -296.595367)
			(xy 182.630447 -296.55853) (xy 182.604144 -296.516934) (xy 182.584853 -296.471658) (xy 182.573076 -296.423874)
			(xy 182.569116 -296.37482) (xy 181.280308 -296.37482) (xy 181.279813 -296.399427) (xy 181.271918 -296.448004)
			(xy 181.256334 -296.494685) (xy 181.233463 -296.538262) (xy 181.203898 -296.577606) (xy 181.168405 -296.611698)
			(xy 181.127902 -296.639654) (xy 181.08344 -296.660752) (xy 181.036169 -296.674444) (xy 180.987314 -296.680376)
			(xy 180.938139 -296.678395) (xy 180.88992 -296.668551) (xy 180.843904 -296.651099) (xy 180.801283 -296.626492)
			(xy 180.763162 -296.595367) (xy 180.730527 -296.55853) (xy 180.704224 -296.516934) (xy 180.684933 -296.471658)
			(xy 180.673156 -296.423874) (xy 180.669196 -296.37482) (xy 179.380388 -296.37482) (xy 179.379893 -296.399427)
			(xy 179.371998 -296.448004) (xy 179.356414 -296.494685) (xy 179.333543 -296.538262) (xy 179.303978 -296.577606)
			(xy 179.268485 -296.611698) (xy 179.227982 -296.639654) (xy 179.18352 -296.660752) (xy 179.136249 -296.674444)
			(xy 179.087394 -296.680376) (xy 179.038219 -296.678395) (xy 178.99 -296.668551) (xy 178.943984 -296.651099)
			(xy 178.901363 -296.626492) (xy 178.863242 -296.595367) (xy 178.830607 -296.55853) (xy 178.804304 -296.516934)
			(xy 178.785013 -296.471658) (xy 178.773236 -296.423874) (xy 178.769276 -296.37482) (xy 177.480214 -296.37482)
			(xy 177.479719 -296.399427) (xy 177.471824 -296.448004) (xy 177.45624 -296.494685) (xy 177.433369 -296.538262)
			(xy 177.403804 -296.577606) (xy 177.368311 -296.611698) (xy 177.327808 -296.639654) (xy 177.283346 -296.660752)
			(xy 177.236075 -296.674444) (xy 177.18722 -296.680376) (xy 177.138045 -296.678395) (xy 177.089826 -296.668551)
			(xy 177.04381 -296.651099) (xy 177.001189 -296.626492) (xy 176.963068 -296.595367) (xy 176.930433 -296.55853)
			(xy 176.90413 -296.516934) (xy 176.884839 -296.471658) (xy 176.873062 -296.423874) (xy 176.869102 -296.37482)
			(xy 174.630334 -296.37482) (xy 174.629839 -296.399427) (xy 174.621944 -296.448004) (xy 174.60636 -296.494685)
			(xy 174.583489 -296.538262) (xy 174.553924 -296.577606) (xy 174.518431 -296.611698) (xy 174.477928 -296.639654)
			(xy 174.433466 -296.660752) (xy 174.386195 -296.674444) (xy 174.33734 -296.680376) (xy 174.288165 -296.678395)
			(xy 174.239946 -296.668551) (xy 174.19393 -296.651099) (xy 174.151309 -296.626492) (xy 174.113188 -296.595367)
			(xy 174.080553 -296.55853) (xy 174.05425 -296.516934) (xy 174.034959 -296.471658) (xy 174.023182 -296.423874)
			(xy 174.019222 -296.37482) (xy 172.730414 -296.37482) (xy 172.729919 -296.399427) (xy 172.722024 -296.448004)
			(xy 172.70644 -296.494685) (xy 172.683569 -296.538262) (xy 172.654004 -296.577606) (xy 172.618511 -296.611698)
			(xy 172.578008 -296.639654) (xy 172.533546 -296.660752) (xy 172.486275 -296.674444) (xy 172.43742 -296.680376)
			(xy 172.388245 -296.678395) (xy 172.340026 -296.668551) (xy 172.29401 -296.651099) (xy 172.251389 -296.626492)
			(xy 172.213268 -296.595367) (xy 172.180633 -296.55853) (xy 172.15433 -296.516934) (xy 172.135039 -296.471658)
			(xy 172.123262 -296.423874) (xy 172.119302 -296.37482) (xy 170.83024 -296.37482) (xy 170.829745 -296.399427)
			(xy 170.82185 -296.448004) (xy 170.806266 -296.494685) (xy 170.783395 -296.538262) (xy 170.75383 -296.577606)
			(xy 170.718337 -296.611698) (xy 170.677834 -296.639654) (xy 170.633372 -296.660752) (xy 170.586101 -296.674444)
			(xy 170.537246 -296.680376) (xy 170.488071 -296.678395) (xy 170.439852 -296.668551) (xy 170.393836 -296.651099)
			(xy 170.351215 -296.626492) (xy 170.313094 -296.595367) (xy 170.280459 -296.55853) (xy 170.254156 -296.516934)
			(xy 170.234865 -296.471658) (xy 170.223088 -296.423874) (xy 170.219128 -296.37482) (xy 168.93032 -296.37482)
			(xy 168.929825 -296.399427) (xy 168.92193 -296.448004) (xy 168.906346 -296.494685) (xy 168.883475 -296.538262)
			(xy 168.85391 -296.577606) (xy 168.818417 -296.611698) (xy 168.777914 -296.639654) (xy 168.733452 -296.660752)
			(xy 168.686181 -296.674444) (xy 168.637326 -296.680376) (xy 168.588151 -296.678395) (xy 168.539932 -296.668551)
			(xy 168.493916 -296.651099) (xy 168.451295 -296.626492) (xy 168.413174 -296.595367) (xy 168.380539 -296.55853)
			(xy 168.354236 -296.516934) (xy 168.334945 -296.471658) (xy 168.323168 -296.423874) (xy 168.319208 -296.37482)
			(xy 167.0304 -296.37482) (xy 167.029905 -296.399427) (xy 167.02201 -296.448004) (xy 167.006426 -296.494685)
			(xy 166.983555 -296.538262) (xy 166.95399 -296.577606) (xy 166.918497 -296.611698) (xy 166.877994 -296.639654)
			(xy 166.833532 -296.660752) (xy 166.786261 -296.674444) (xy 166.737406 -296.680376) (xy 166.688231 -296.678395)
			(xy 166.640012 -296.668551) (xy 166.593996 -296.651099) (xy 166.551375 -296.626492) (xy 166.513254 -296.595367)
			(xy 166.480619 -296.55853) (xy 166.454316 -296.516934) (xy 166.435025 -296.471658) (xy 166.423248 -296.423874)
			(xy 166.419288 -296.37482) (xy 165.130226 -296.37482) (xy 165.129731 -296.399427) (xy 165.121836 -296.448004)
			(xy 165.106252 -296.494685) (xy 165.083381 -296.538262) (xy 165.053816 -296.577606) (xy 165.018323 -296.611698)
			(xy 164.97782 -296.639654) (xy 164.933358 -296.660752) (xy 164.886087 -296.674444) (xy 164.837232 -296.680376)
			(xy 164.788057 -296.678395) (xy 164.739838 -296.668551) (xy 164.693822 -296.651099) (xy 164.651201 -296.626492)
			(xy 164.61308 -296.595367) (xy 164.580445 -296.55853) (xy 164.554142 -296.516934) (xy 164.534851 -296.471658)
			(xy 164.523074 -296.423874) (xy 164.519114 -296.37482) (xy 164.180266 -296.37482) (xy 164.179771 -296.399427)
			(xy 164.171876 -296.448004) (xy 164.156292 -296.494685) (xy 164.133421 -296.538262) (xy 164.103856 -296.577606)
			(xy 164.068363 -296.611698) (xy 164.02786 -296.639654) (xy 163.983398 -296.660752) (xy 163.936127 -296.674444)
			(xy 163.887272 -296.680376) (xy 163.838097 -296.678395) (xy 163.789878 -296.668551) (xy 163.743862 -296.651099)
			(xy 163.701241 -296.626492) (xy 163.66312 -296.595367) (xy 163.630485 -296.55853) (xy 163.604182 -296.516934)
			(xy 163.584891 -296.471658) (xy 163.573114 -296.423874) (xy 163.569154 -296.37482) (xy 162.280346 -296.37482)
			(xy 162.279851 -296.399427) (xy 162.271956 -296.448004) (xy 162.256372 -296.494685) (xy 162.233501 -296.538262)
			(xy 162.203936 -296.577606) (xy 162.168443 -296.611698) (xy 162.12794 -296.639654) (xy 162.083478 -296.660752)
			(xy 162.036207 -296.674444) (xy 161.987352 -296.680376) (xy 161.938177 -296.678395) (xy 161.889958 -296.668551)
			(xy 161.843942 -296.651099) (xy 161.801321 -296.626492) (xy 161.7632 -296.595367) (xy 161.730565 -296.55853)
			(xy 161.704262 -296.516934) (xy 161.684971 -296.471658) (xy 161.673194 -296.423874) (xy 161.669234 -296.37482)
			(xy 161.330386 -296.37482) (xy 161.329891 -296.399427) (xy 161.321996 -296.448004) (xy 161.306412 -296.494685)
			(xy 161.283541 -296.538262) (xy 161.253976 -296.577606) (xy 161.218483 -296.611698) (xy 161.17798 -296.639654)
			(xy 161.133518 -296.660752) (xy 161.086247 -296.674444) (xy 161.037392 -296.680376) (xy 160.988217 -296.678395)
			(xy 160.939998 -296.668551) (xy 160.893982 -296.651099) (xy 160.851361 -296.626492) (xy 160.81324 -296.595367)
			(xy 160.780605 -296.55853) (xy 160.754302 -296.516934) (xy 160.735011 -296.471658) (xy 160.723234 -296.423874)
			(xy 160.719274 -296.37482) (xy 160.380172 -296.37482) (xy 160.379677 -296.399427) (xy 160.371782 -296.448004)
			(xy 160.356198 -296.494685) (xy 160.333327 -296.538262) (xy 160.303762 -296.577606) (xy 160.268269 -296.611698)
			(xy 160.227766 -296.639654) (xy 160.183304 -296.660752) (xy 160.136033 -296.674444) (xy 160.087178 -296.680376)
			(xy 160.038003 -296.678395) (xy 159.989784 -296.668551) (xy 159.943768 -296.651099) (xy 159.901147 -296.626492)
			(xy 159.863026 -296.595367) (xy 159.830391 -296.55853) (xy 159.804088 -296.516934) (xy 159.784797 -296.471658)
			(xy 159.77302 -296.423874) (xy 159.76906 -296.37482) (xy 158.480252 -296.37482) (xy 158.479757 -296.399427)
			(xy 158.471862 -296.448004) (xy 158.456278 -296.494685) (xy 158.433407 -296.538262) (xy 158.403842 -296.577606)
			(xy 158.368349 -296.611698) (xy 158.327846 -296.639654) (xy 158.283384 -296.660752) (xy 158.236113 -296.674444)
			(xy 158.187258 -296.680376) (xy 158.138083 -296.678395) (xy 158.089864 -296.668551) (xy 158.043848 -296.651099)
			(xy 158.001227 -296.626492) (xy 157.963106 -296.595367) (xy 157.930471 -296.55853) (xy 157.904168 -296.516934)
			(xy 157.884877 -296.471658) (xy 157.8731 -296.423874) (xy 157.86914 -296.37482) (xy 156.580332 -296.37482)
			(xy 156.579837 -296.399427) (xy 156.571942 -296.448004) (xy 156.556358 -296.494685) (xy 156.533487 -296.538262)
			(xy 156.503922 -296.577606) (xy 156.468429 -296.611698) (xy 156.427926 -296.639654) (xy 156.383464 -296.660752)
			(xy 156.336193 -296.674444) (xy 156.287338 -296.680376) (xy 156.238163 -296.678395) (xy 156.189944 -296.668551)
			(xy 156.143928 -296.651099) (xy 156.101307 -296.626492) (xy 156.063186 -296.595367) (xy 156.030551 -296.55853)
			(xy 156.004248 -296.516934) (xy 155.984957 -296.471658) (xy 155.97318 -296.423874) (xy 155.96922 -296.37482)
			(xy 155.630372 -296.37482) (xy 155.629877 -296.399427) (xy 155.621982 -296.448004) (xy 155.606398 -296.494685)
			(xy 155.583527 -296.538262) (xy 155.553962 -296.577606) (xy 155.518469 -296.611698) (xy 155.477966 -296.639654)
			(xy 155.433504 -296.660752) (xy 155.386233 -296.674444) (xy 155.337378 -296.680376) (xy 155.288203 -296.678395)
			(xy 155.239984 -296.668551) (xy 155.193968 -296.651099) (xy 155.151347 -296.626492) (xy 155.113226 -296.595367)
			(xy 155.080591 -296.55853) (xy 155.054288 -296.516934) (xy 155.034997 -296.471658) (xy 155.02322 -296.423874)
			(xy 155.01926 -296.37482) (xy 154.680158 -296.37482) (xy 154.679663 -296.399427) (xy 154.671768 -296.448004)
			(xy 154.656184 -296.494685) (xy 154.633313 -296.538262) (xy 154.603748 -296.577606) (xy 154.568255 -296.611698)
			(xy 154.527752 -296.639654) (xy 154.48329 -296.660752) (xy 154.436019 -296.674444) (xy 154.387164 -296.680376)
			(xy 154.337989 -296.678395) (xy 154.28977 -296.668551) (xy 154.243754 -296.651099) (xy 154.201133 -296.626492)
			(xy 154.163012 -296.595367) (xy 154.130377 -296.55853) (xy 154.104074 -296.516934) (xy 154.084783 -296.471658)
			(xy 154.073006 -296.423874) (xy 154.069046 -296.37482) (xy 153.730452 -296.37482) (xy 153.729957 -296.399427)
			(xy 153.722062 -296.448004) (xy 153.706478 -296.494685) (xy 153.683607 -296.538262) (xy 153.654042 -296.577606)
			(xy 153.618549 -296.611698) (xy 153.578046 -296.639654) (xy 153.533584 -296.660752) (xy 153.486313 -296.674444)
			(xy 153.437458 -296.680376) (xy 153.388283 -296.678395) (xy 153.340064 -296.668551) (xy 153.294048 -296.651099)
			(xy 153.251427 -296.626492) (xy 153.213306 -296.595367) (xy 153.180671 -296.55853) (xy 153.154368 -296.516934)
			(xy 153.135077 -296.471658) (xy 153.1233 -296.423874) (xy 153.11934 -296.37482) (xy 150.309624 -296.37482)
			(xy 150.325359 -296.384423) (xy 150.368227 -296.420098) (xy 150.405444 -296.461635) (xy 150.436217 -296.508148)
			(xy 150.459889 -296.558645) (xy 150.475957 -296.612052) (xy 150.484077 -296.667228) (xy 150.484586 -296.695114)
			(xy 150.484077 -296.723) (xy 150.475957 -296.778176) (xy 150.459889 -296.831583) (xy 150.436217 -296.88208)
			(xy 150.405444 -296.928593) (xy 150.368227 -296.97013) (xy 150.325359 -297.005805) (xy 150.277753 -297.034859)
			(xy 150.226424 -297.056671) (xy 150.172467 -297.070777) (xy 150.11703 -297.076877) (xy 150.061296 -297.07484)
			(xy 150.006453 -297.06471) (xy 149.953669 -297.046703) (xy 149.904069 -297.021202) (xy 149.858711 -296.988751)
			(xy 149.818562 -296.950042) (xy 149.784476 -296.905899) (xy 149.75718 -296.857264) (xy 149.737257 -296.805173)
			(xy 149.725131 -296.750736) (xy 149.72106 -296.695114) (xy 149.598126 -296.695114) (xy 149.597617 -296.723)
			(xy 149.589497 -296.778176) (xy 149.573429 -296.831583) (xy 149.549757 -296.88208) (xy 149.518984 -296.928593)
			(xy 149.481767 -296.97013) (xy 149.438899 -297.005805) (xy 149.391293 -297.034859) (xy 149.339964 -297.056671)
			(xy 149.286007 -297.070777) (xy 149.23057 -297.076877) (xy 149.174836 -297.07484) (xy 149.119993 -297.06471)
			(xy 149.067209 -297.046703) (xy 149.017609 -297.021202) (xy 148.972251 -296.988751) (xy 148.932102 -296.950042)
			(xy 148.898016 -296.905899) (xy 148.87072 -296.857264) (xy 148.850797 -296.805173) (xy 148.838671 -296.750736)
			(xy 148.8346 -296.695114) (xy 148.201126 -296.695114) (xy 148.20064 -296.722365) (xy 148.192884 -296.776313)
			(xy 148.177529 -296.828608) (xy 148.154887 -296.878185) (xy 148.125421 -296.924035) (xy 148.08973 -296.965226)
			(xy 148.048539 -297.000917) (xy 148.002689 -297.030383) (xy 147.953112 -297.053025) (xy 147.900817 -297.06838)
			(xy 147.846869 -297.076136) (xy 147.792367 -297.076136) (xy 147.738419 -297.06838) (xy 147.686124 -297.053025)
			(xy 147.636547 -297.030383) (xy 147.590697 -297.000917) (xy 147.549506 -296.965226) (xy 147.513815 -296.924035)
			(xy 147.484349 -296.878185) (xy 147.461707 -296.828608) (xy 147.446352 -296.776313) (xy 147.438596 -296.722365)
			(xy 147.43811 -296.695114) (xy 118.832884 -296.695114) (xy 118.832884 -297.3248) (xy 151.53402 -297.3248)
			(xy 151.538192 -297.274451) (xy 151.550595 -297.225475) (xy 151.570891 -297.179209) (xy 151.598525 -297.136915)
			(xy 151.632745 -297.099746) (xy 151.672615 -297.068717) (xy 151.71705 -297.044674) (xy 151.764835 -297.028274)
			(xy 151.814669 -297.019962) (xy 151.83993 -297.019472) (xy 151.865324 -297.020012) (xy 151.915412 -297.028419)
			(xy 151.963419 -297.044996) (xy 152.008022 -297.069287) (xy 152.047992 -297.100622) (xy 152.065482 -297.11904)
			(xy 152.072848 -297.127168) (xy 152.092914 -297.135804) (xy 152.192228 -297.13301) (xy 152.211786 -297.123612)
			(xy 152.218898 -297.114976) (xy 152.234711 -297.096425) (xy 152.270839 -297.063704) (xy 152.311375 -297.036635)
			(xy 152.355443 -297.015803) (xy 152.402088 -297.001658) (xy 152.450304 -296.994507) (xy 152.474676 -296.994072)
			(xy 153.424636 -296.994072) (xy 153.45062 -296.994624) (xy 153.501947 -297.002759) (xy 153.55137 -297.018822)
			(xy 153.597671 -297.042418) (xy 153.639712 -297.072967) (xy 153.676457 -297.109715) (xy 153.707001 -297.151759)
			(xy 153.730592 -297.198064) (xy 153.74665 -297.247488) (xy 153.754779 -297.298816) (xy 153.754779 -297.32478)
			(xy 154.069046 -297.32478) (xy 154.073006 -297.275726) (xy 154.084783 -297.227942) (xy 154.104074 -297.182666)
			(xy 154.130377 -297.14107) (xy 154.163012 -297.104233) (xy 154.201133 -297.073108) (xy 154.243754 -297.048501)
			(xy 154.28977 -297.031049) (xy 154.337989 -297.021205) (xy 154.387164 -297.019224) (xy 154.436019 -297.025156)
			(xy 154.48329 -297.038848) (xy 154.527752 -297.059946) (xy 154.568255 -297.087902) (xy 154.603748 -297.121994)
			(xy 154.633313 -297.161338) (xy 154.656184 -297.204915) (xy 154.671768 -297.251596) (xy 154.679663 -297.300173)
			(xy 154.680158 -297.32478) (xy 155.01926 -297.32478) (xy 155.02322 -297.275726) (xy 155.034997 -297.227942)
			(xy 155.054288 -297.182666) (xy 155.080591 -297.14107) (xy 155.113226 -297.104233) (xy 155.151347 -297.073108)
			(xy 155.193968 -297.048501) (xy 155.239984 -297.031049) (xy 155.288203 -297.021205) (xy 155.337378 -297.019224)
			(xy 155.386233 -297.025156) (xy 155.433504 -297.038848) (xy 155.477966 -297.059946) (xy 155.518469 -297.087902)
			(xy 155.553962 -297.121994) (xy 155.583527 -297.161338) (xy 155.606398 -297.204915) (xy 155.621982 -297.251596)
			(xy 155.629877 -297.300173) (xy 155.630372 -297.32478) (xy 157.86914 -297.32478) (xy 157.8731 -297.275726)
			(xy 157.884877 -297.227942) (xy 157.904168 -297.182666) (xy 157.930471 -297.14107) (xy 157.963106 -297.104233)
			(xy 158.001227 -297.073108) (xy 158.043848 -297.048501) (xy 158.089864 -297.031049) (xy 158.138083 -297.021205)
			(xy 158.187258 -297.019224) (xy 158.236113 -297.025156) (xy 158.283384 -297.038848) (xy 158.327846 -297.059946)
			(xy 158.368349 -297.087902) (xy 158.403842 -297.121994) (xy 158.433407 -297.161338) (xy 158.456278 -297.204915)
			(xy 158.471862 -297.251596) (xy 158.479757 -297.300173) (xy 158.480252 -297.32478) (xy 159.76906 -297.32478)
			(xy 159.77302 -297.275726) (xy 159.784797 -297.227942) (xy 159.804088 -297.182666) (xy 159.830391 -297.14107)
			(xy 159.863026 -297.104233) (xy 159.901147 -297.073108) (xy 159.943768 -297.048501) (xy 159.989784 -297.031049)
			(xy 160.038003 -297.021205) (xy 160.087178 -297.019224) (xy 160.136033 -297.025156) (xy 160.183304 -297.038848)
			(xy 160.227766 -297.059946) (xy 160.268269 -297.087902) (xy 160.303762 -297.121994) (xy 160.333327 -297.161338)
			(xy 160.356198 -297.204915) (xy 160.371782 -297.251596) (xy 160.379677 -297.300173) (xy 160.380172 -297.32478)
			(xy 160.719274 -297.32478) (xy 160.723234 -297.275726) (xy 160.735011 -297.227942) (xy 160.754302 -297.182666)
			(xy 160.780605 -297.14107) (xy 160.81324 -297.104233) (xy 160.851361 -297.073108) (xy 160.893982 -297.048501)
			(xy 160.939998 -297.031049) (xy 160.988217 -297.021205) (xy 161.037392 -297.019224) (xy 161.086247 -297.025156)
			(xy 161.133518 -297.038848) (xy 161.17798 -297.059946) (xy 161.218483 -297.087902) (xy 161.253976 -297.121994)
			(xy 161.283541 -297.161338) (xy 161.306412 -297.204915) (xy 161.321996 -297.251596) (xy 161.329891 -297.300173)
			(xy 161.330386 -297.32478) (xy 161.669234 -297.32478) (xy 161.673194 -297.275726) (xy 161.684971 -297.227942)
			(xy 161.704262 -297.182666) (xy 161.730565 -297.14107) (xy 161.7632 -297.104233) (xy 161.801321 -297.073108)
			(xy 161.843942 -297.048501) (xy 161.889958 -297.031049) (xy 161.938177 -297.021205) (xy 161.987352 -297.019224)
			(xy 162.036207 -297.025156) (xy 162.083478 -297.038848) (xy 162.12794 -297.059946) (xy 162.168443 -297.087902)
			(xy 162.203936 -297.121994) (xy 162.233501 -297.161338) (xy 162.256372 -297.204915) (xy 162.271956 -297.251596)
			(xy 162.279851 -297.300173) (xy 162.280346 -297.32478) (xy 162.619194 -297.32478) (xy 162.623154 -297.275726)
			(xy 162.634931 -297.227942) (xy 162.654222 -297.182666) (xy 162.680525 -297.14107) (xy 162.71316 -297.104233)
			(xy 162.751281 -297.073108) (xy 162.793902 -297.048501) (xy 162.839918 -297.031049) (xy 162.888137 -297.021205)
			(xy 162.937312 -297.019224) (xy 162.986167 -297.025156) (xy 163.033438 -297.038848) (xy 163.0779 -297.059946)
			(xy 163.118403 -297.087902) (xy 163.153896 -297.121994) (xy 163.183461 -297.161338) (xy 163.206332 -297.204915)
			(xy 163.221916 -297.251596) (xy 163.229811 -297.300173) (xy 163.230306 -297.32478) (xy 163.569154 -297.32478)
			(xy 163.573114 -297.275726) (xy 163.584891 -297.227942) (xy 163.604182 -297.182666) (xy 163.630485 -297.14107)
			(xy 163.66312 -297.104233) (xy 163.701241 -297.073108) (xy 163.743862 -297.048501) (xy 163.789878 -297.031049)
			(xy 163.838097 -297.021205) (xy 163.887272 -297.019224) (xy 163.936127 -297.025156) (xy 163.983398 -297.038848)
			(xy 164.02786 -297.059946) (xy 164.068363 -297.087902) (xy 164.103856 -297.121994) (xy 164.133421 -297.161338)
			(xy 164.156292 -297.204915) (xy 164.171876 -297.251596) (xy 164.179771 -297.300173) (xy 164.180266 -297.32478)
			(xy 165.469074 -297.32478) (xy 165.473034 -297.275726) (xy 165.484811 -297.227942) (xy 165.504102 -297.182666)
			(xy 165.530405 -297.14107) (xy 165.56304 -297.104233) (xy 165.601161 -297.073108) (xy 165.643782 -297.048501)
			(xy 165.689798 -297.031049) (xy 165.738017 -297.021205) (xy 165.787192 -297.019224) (xy 165.836047 -297.025156)
			(xy 165.883318 -297.038848) (xy 165.92778 -297.059946) (xy 165.968283 -297.087902) (xy 166.003776 -297.121994)
			(xy 166.033341 -297.161338) (xy 166.056212 -297.204915) (xy 166.071796 -297.251596) (xy 166.079691 -297.300173)
			(xy 166.080186 -297.32478) (xy 167.369248 -297.32478) (xy 167.373208 -297.275726) (xy 167.384985 -297.227942)
			(xy 167.404276 -297.182666) (xy 167.430579 -297.14107) (xy 167.463214 -297.104233) (xy 167.501335 -297.073108)
			(xy 167.543956 -297.048501) (xy 167.589972 -297.031049) (xy 167.638191 -297.021205) (xy 167.687366 -297.019224)
			(xy 167.736221 -297.025156) (xy 167.783492 -297.038848) (xy 167.827954 -297.059946) (xy 167.868457 -297.087902)
			(xy 167.90395 -297.121994) (xy 167.933515 -297.161338) (xy 167.956386 -297.204915) (xy 167.97197 -297.251596)
			(xy 167.979865 -297.300173) (xy 167.98036 -297.32478) (xy 169.269168 -297.32478) (xy 169.273128 -297.275726)
			(xy 169.284905 -297.227942) (xy 169.304196 -297.182666) (xy 169.330499 -297.14107) (xy 169.363134 -297.104233)
			(xy 169.401255 -297.073108) (xy 169.443876 -297.048501) (xy 169.489892 -297.031049) (xy 169.538111 -297.021205)
			(xy 169.587286 -297.019224) (xy 169.636141 -297.025156) (xy 169.683412 -297.038848) (xy 169.727874 -297.059946)
			(xy 169.768377 -297.087902) (xy 169.80387 -297.121994) (xy 169.833435 -297.161338) (xy 169.856306 -297.204915)
			(xy 169.87189 -297.251596) (xy 169.879785 -297.300173) (xy 169.88028 -297.32478) (xy 171.169088 -297.32478)
			(xy 171.173048 -297.275726) (xy 171.184825 -297.227942) (xy 171.204116 -297.182666) (xy 171.230419 -297.14107)
			(xy 171.263054 -297.104233) (xy 171.301175 -297.073108) (xy 171.343796 -297.048501) (xy 171.389812 -297.031049)
			(xy 171.438031 -297.021205) (xy 171.487206 -297.019224) (xy 171.536061 -297.025156) (xy 171.583332 -297.038848)
			(xy 171.627794 -297.059946) (xy 171.668297 -297.087902) (xy 171.70379 -297.121994) (xy 171.733355 -297.161338)
			(xy 171.756226 -297.204915) (xy 171.77181 -297.251596) (xy 171.779705 -297.300173) (xy 171.7802 -297.32478)
			(xy 173.069262 -297.32478) (xy 173.073222 -297.275726) (xy 173.084999 -297.227942) (xy 173.10429 -297.182666)
			(xy 173.130593 -297.14107) (xy 173.163228 -297.104233) (xy 173.201349 -297.073108) (xy 173.24397 -297.048501)
			(xy 173.289986 -297.031049) (xy 173.338205 -297.021205) (xy 173.38738 -297.019224) (xy 173.436235 -297.025156)
			(xy 173.483506 -297.038848) (xy 173.527968 -297.059946) (xy 173.568471 -297.087902) (xy 173.603964 -297.121994)
			(xy 173.633529 -297.161338) (xy 173.6564 -297.204915) (xy 173.671984 -297.251596) (xy 173.679879 -297.300173)
			(xy 173.680374 -297.32478) (xy 175.919142 -297.32478) (xy 175.923102 -297.275726) (xy 175.934879 -297.227942)
			(xy 175.95417 -297.182666) (xy 175.980473 -297.14107) (xy 176.013108 -297.104233) (xy 176.051229 -297.073108)
			(xy 176.09385 -297.048501) (xy 176.139866 -297.031049) (xy 176.188085 -297.021205) (xy 176.23726 -297.019224)
			(xy 176.286115 -297.025156) (xy 176.333386 -297.038848) (xy 176.377848 -297.059946) (xy 176.418351 -297.087902)
			(xy 176.453844 -297.121994) (xy 176.483409 -297.161338) (xy 176.50628 -297.204915) (xy 176.521864 -297.251596)
			(xy 176.529759 -297.300173) (xy 176.530254 -297.32478) (xy 177.819062 -297.32478) (xy 177.823022 -297.275726)
			(xy 177.834799 -297.227942) (xy 177.85409 -297.182666) (xy 177.880393 -297.14107) (xy 177.913028 -297.104233)
			(xy 177.951149 -297.073108) (xy 177.99377 -297.048501) (xy 178.039786 -297.031049) (xy 178.088005 -297.021205)
			(xy 178.13718 -297.019224) (xy 178.186035 -297.025156) (xy 178.233306 -297.038848) (xy 178.277768 -297.059946)
			(xy 178.318271 -297.087902) (xy 178.353764 -297.121994) (xy 178.383329 -297.161338) (xy 178.4062 -297.204915)
			(xy 178.421784 -297.251596) (xy 178.429679 -297.300173) (xy 178.430174 -297.32478) (xy 179.719236 -297.32478)
			(xy 179.723196 -297.275726) (xy 179.734973 -297.227942) (xy 179.754264 -297.182666) (xy 179.780567 -297.14107)
			(xy 179.813202 -297.104233) (xy 179.851323 -297.073108) (xy 179.893944 -297.048501) (xy 179.93996 -297.031049)
			(xy 179.988179 -297.021205) (xy 180.037354 -297.019224) (xy 180.086209 -297.025156) (xy 180.13348 -297.038848)
			(xy 180.177942 -297.059946) (xy 180.218445 -297.087902) (xy 180.253938 -297.121994) (xy 180.283503 -297.161338)
			(xy 180.306374 -297.204915) (xy 180.321958 -297.251596) (xy 180.329853 -297.300173) (xy 180.330348 -297.32478)
			(xy 181.619156 -297.32478) (xy 181.623116 -297.275726) (xy 181.634893 -297.227942) (xy 181.654184 -297.182666)
			(xy 181.680487 -297.14107) (xy 181.713122 -297.104233) (xy 181.751243 -297.073108) (xy 181.793864 -297.048501)
			(xy 181.83988 -297.031049) (xy 181.888099 -297.021205) (xy 181.937274 -297.019224) (xy 181.986129 -297.025156)
			(xy 182.0334 -297.038848) (xy 182.077862 -297.059946) (xy 182.118365 -297.087902) (xy 182.153858 -297.121994)
			(xy 182.183423 -297.161338) (xy 182.206294 -297.204915) (xy 182.221878 -297.251596) (xy 182.229773 -297.300173)
			(xy 182.230268 -297.32478) (xy 182.569116 -297.32478) (xy 182.573076 -297.275726) (xy 182.584853 -297.227942)
			(xy 182.604144 -297.182666) (xy 182.630447 -297.14107) (xy 182.663082 -297.104233) (xy 182.701203 -297.073108)
			(xy 182.743824 -297.048501) (xy 182.78984 -297.031049) (xy 182.838059 -297.021205) (xy 182.887234 -297.019224)
			(xy 182.936089 -297.025156) (xy 182.98336 -297.038848) (xy 183.027822 -297.059946) (xy 183.068325 -297.087902)
			(xy 183.103818 -297.121994) (xy 183.133383 -297.161338) (xy 183.156254 -297.204915) (xy 183.171838 -297.251596)
			(xy 183.179733 -297.300173) (xy 183.180228 -297.32478) (xy 183.519076 -297.32478) (xy 183.523036 -297.275726)
			(xy 183.534813 -297.227942) (xy 183.554104 -297.182666) (xy 183.580407 -297.14107) (xy 183.613042 -297.104233)
			(xy 183.651163 -297.073108) (xy 183.693784 -297.048501) (xy 183.7398 -297.031049) (xy 183.788019 -297.021205)
			(xy 183.837194 -297.019224) (xy 183.886049 -297.025156) (xy 183.93332 -297.038848) (xy 183.977782 -297.059946)
			(xy 184.018285 -297.087902) (xy 184.053778 -297.121994) (xy 184.083343 -297.161338) (xy 184.106214 -297.204915)
			(xy 184.121798 -297.251596) (xy 184.129693 -297.300173) (xy 184.130188 -297.32478) (xy 184.129693 -297.349387)
			(xy 184.121798 -297.397964) (xy 184.106214 -297.444645) (xy 184.083343 -297.488222) (xy 184.053778 -297.527566)
			(xy 184.018285 -297.561658) (xy 183.977782 -297.589614) (xy 183.93332 -297.610712) (xy 183.886049 -297.624404)
			(xy 183.837194 -297.630336) (xy 183.788019 -297.628355) (xy 183.7398 -297.618511) (xy 183.693784 -297.601059)
			(xy 183.651163 -297.576452) (xy 183.613042 -297.545327) (xy 183.580407 -297.50849) (xy 183.554104 -297.466894)
			(xy 183.534813 -297.421618) (xy 183.523036 -297.373834) (xy 183.519076 -297.32478) (xy 183.180228 -297.32478)
			(xy 183.179733 -297.349387) (xy 183.171838 -297.397964) (xy 183.156254 -297.444645) (xy 183.133383 -297.488222)
			(xy 183.103818 -297.527566) (xy 183.068325 -297.561658) (xy 183.027822 -297.589614) (xy 182.98336 -297.610712)
			(xy 182.936089 -297.624404) (xy 182.887234 -297.630336) (xy 182.838059 -297.628355) (xy 182.78984 -297.618511)
			(xy 182.743824 -297.601059) (xy 182.701203 -297.576452) (xy 182.663082 -297.545327) (xy 182.630447 -297.50849)
			(xy 182.604144 -297.466894) (xy 182.584853 -297.421618) (xy 182.573076 -297.373834) (xy 182.569116 -297.32478)
			(xy 182.230268 -297.32478) (xy 182.229773 -297.349387) (xy 182.221878 -297.397964) (xy 182.206294 -297.444645)
			(xy 182.183423 -297.488222) (xy 182.153858 -297.527566) (xy 182.118365 -297.561658) (xy 182.077862 -297.589614)
			(xy 182.0334 -297.610712) (xy 181.986129 -297.624404) (xy 181.937274 -297.630336) (xy 181.888099 -297.628355)
			(xy 181.83988 -297.618511) (xy 181.793864 -297.601059) (xy 181.751243 -297.576452) (xy 181.713122 -297.545327)
			(xy 181.680487 -297.50849) (xy 181.654184 -297.466894) (xy 181.634893 -297.421618) (xy 181.623116 -297.373834)
			(xy 181.619156 -297.32478) (xy 180.330348 -297.32478) (xy 180.329853 -297.349387) (xy 180.321958 -297.397964)
			(xy 180.306374 -297.444645) (xy 180.283503 -297.488222) (xy 180.253938 -297.527566) (xy 180.218445 -297.561658)
			(xy 180.177942 -297.589614) (xy 180.13348 -297.610712) (xy 180.086209 -297.624404) (xy 180.037354 -297.630336)
			(xy 179.988179 -297.628355) (xy 179.93996 -297.618511) (xy 179.893944 -297.601059) (xy 179.851323 -297.576452)
			(xy 179.813202 -297.545327) (xy 179.780567 -297.50849) (xy 179.754264 -297.466894) (xy 179.734973 -297.421618)
			(xy 179.723196 -297.373834) (xy 179.719236 -297.32478) (xy 178.430174 -297.32478) (xy 178.429679 -297.349387)
			(xy 178.421784 -297.397964) (xy 178.4062 -297.444645) (xy 178.383329 -297.488222) (xy 178.353764 -297.527566)
			(xy 178.318271 -297.561658) (xy 178.277768 -297.589614) (xy 178.233306 -297.610712) (xy 178.186035 -297.624404)
			(xy 178.13718 -297.630336) (xy 178.088005 -297.628355) (xy 178.039786 -297.618511) (xy 177.99377 -297.601059)
			(xy 177.951149 -297.576452) (xy 177.913028 -297.545327) (xy 177.880393 -297.50849) (xy 177.85409 -297.466894)
			(xy 177.834799 -297.421618) (xy 177.823022 -297.373834) (xy 177.819062 -297.32478) (xy 176.530254 -297.32478)
			(xy 176.529759 -297.349387) (xy 176.521864 -297.397964) (xy 176.50628 -297.444645) (xy 176.483409 -297.488222)
			(xy 176.453844 -297.527566) (xy 176.418351 -297.561658) (xy 176.377848 -297.589614) (xy 176.333386 -297.610712)
			(xy 176.286115 -297.624404) (xy 176.23726 -297.630336) (xy 176.188085 -297.628355) (xy 176.139866 -297.618511)
			(xy 176.09385 -297.601059) (xy 176.051229 -297.576452) (xy 176.013108 -297.545327) (xy 175.980473 -297.50849)
			(xy 175.95417 -297.466894) (xy 175.934879 -297.421618) (xy 175.923102 -297.373834) (xy 175.919142 -297.32478)
			(xy 173.680374 -297.32478) (xy 173.679879 -297.349387) (xy 173.671984 -297.397964) (xy 173.6564 -297.444645)
			(xy 173.633529 -297.488222) (xy 173.603964 -297.527566) (xy 173.568471 -297.561658) (xy 173.527968 -297.589614)
			(xy 173.483506 -297.610712) (xy 173.436235 -297.624404) (xy 173.38738 -297.630336) (xy 173.338205 -297.628355)
			(xy 173.289986 -297.618511) (xy 173.24397 -297.601059) (xy 173.201349 -297.576452) (xy 173.163228 -297.545327)
			(xy 173.130593 -297.50849) (xy 173.10429 -297.466894) (xy 173.084999 -297.421618) (xy 173.073222 -297.373834)
			(xy 173.069262 -297.32478) (xy 171.7802 -297.32478) (xy 171.779705 -297.349387) (xy 171.77181 -297.397964)
			(xy 171.756226 -297.444645) (xy 171.733355 -297.488222) (xy 171.70379 -297.527566) (xy 171.668297 -297.561658)
			(xy 171.627794 -297.589614) (xy 171.583332 -297.610712) (xy 171.536061 -297.624404) (xy 171.487206 -297.630336)
			(xy 171.438031 -297.628355) (xy 171.389812 -297.618511) (xy 171.343796 -297.601059) (xy 171.301175 -297.576452)
			(xy 171.263054 -297.545327) (xy 171.230419 -297.50849) (xy 171.204116 -297.466894) (xy 171.184825 -297.421618)
			(xy 171.173048 -297.373834) (xy 171.169088 -297.32478) (xy 169.88028 -297.32478) (xy 169.879785 -297.349387)
			(xy 169.87189 -297.397964) (xy 169.856306 -297.444645) (xy 169.833435 -297.488222) (xy 169.80387 -297.527566)
			(xy 169.768377 -297.561658) (xy 169.727874 -297.589614) (xy 169.683412 -297.610712) (xy 169.636141 -297.624404)
			(xy 169.587286 -297.630336) (xy 169.538111 -297.628355) (xy 169.489892 -297.618511) (xy 169.443876 -297.601059)
			(xy 169.401255 -297.576452) (xy 169.363134 -297.545327) (xy 169.330499 -297.50849) (xy 169.304196 -297.466894)
			(xy 169.284905 -297.421618) (xy 169.273128 -297.373834) (xy 169.269168 -297.32478) (xy 167.98036 -297.32478)
			(xy 167.979865 -297.349387) (xy 167.97197 -297.397964) (xy 167.956386 -297.444645) (xy 167.933515 -297.488222)
			(xy 167.90395 -297.527566) (xy 167.868457 -297.561658) (xy 167.827954 -297.589614) (xy 167.783492 -297.610712)
			(xy 167.736221 -297.624404) (xy 167.687366 -297.630336) (xy 167.638191 -297.628355) (xy 167.589972 -297.618511)
			(xy 167.543956 -297.601059) (xy 167.501335 -297.576452) (xy 167.463214 -297.545327) (xy 167.430579 -297.50849)
			(xy 167.404276 -297.466894) (xy 167.384985 -297.421618) (xy 167.373208 -297.373834) (xy 167.369248 -297.32478)
			(xy 166.080186 -297.32478) (xy 166.079691 -297.349387) (xy 166.071796 -297.397964) (xy 166.056212 -297.444645)
			(xy 166.033341 -297.488222) (xy 166.003776 -297.527566) (xy 165.968283 -297.561658) (xy 165.92778 -297.589614)
			(xy 165.883318 -297.610712) (xy 165.836047 -297.624404) (xy 165.787192 -297.630336) (xy 165.738017 -297.628355)
			(xy 165.689798 -297.618511) (xy 165.643782 -297.601059) (xy 165.601161 -297.576452) (xy 165.56304 -297.545327)
			(xy 165.530405 -297.50849) (xy 165.504102 -297.466894) (xy 165.484811 -297.421618) (xy 165.473034 -297.373834)
			(xy 165.469074 -297.32478) (xy 164.180266 -297.32478) (xy 164.179771 -297.349387) (xy 164.171876 -297.397964)
			(xy 164.156292 -297.444645) (xy 164.133421 -297.488222) (xy 164.103856 -297.527566) (xy 164.068363 -297.561658)
			(xy 164.02786 -297.589614) (xy 163.983398 -297.610712) (xy 163.936127 -297.624404) (xy 163.887272 -297.630336)
			(xy 163.838097 -297.628355) (xy 163.789878 -297.618511) (xy 163.743862 -297.601059) (xy 163.701241 -297.576452)
			(xy 163.66312 -297.545327) (xy 163.630485 -297.50849) (xy 163.604182 -297.466894) (xy 163.584891 -297.421618)
			(xy 163.573114 -297.373834) (xy 163.569154 -297.32478) (xy 163.230306 -297.32478) (xy 163.229811 -297.349387)
			(xy 163.221916 -297.397964) (xy 163.206332 -297.444645) (xy 163.183461 -297.488222) (xy 163.153896 -297.527566)
			(xy 163.118403 -297.561658) (xy 163.0779 -297.589614) (xy 163.033438 -297.610712) (xy 162.986167 -297.624404)
			(xy 162.937312 -297.630336) (xy 162.888137 -297.628355) (xy 162.839918 -297.618511) (xy 162.793902 -297.601059)
			(xy 162.751281 -297.576452) (xy 162.71316 -297.545327) (xy 162.680525 -297.50849) (xy 162.654222 -297.466894)
			(xy 162.634931 -297.421618) (xy 162.623154 -297.373834) (xy 162.619194 -297.32478) (xy 162.280346 -297.32478)
			(xy 162.279851 -297.349387) (xy 162.271956 -297.397964) (xy 162.256372 -297.444645) (xy 162.233501 -297.488222)
			(xy 162.203936 -297.527566) (xy 162.168443 -297.561658) (xy 162.12794 -297.589614) (xy 162.083478 -297.610712)
			(xy 162.036207 -297.624404) (xy 161.987352 -297.630336) (xy 161.938177 -297.628355) (xy 161.889958 -297.618511)
			(xy 161.843942 -297.601059) (xy 161.801321 -297.576452) (xy 161.7632 -297.545327) (xy 161.730565 -297.50849)
			(xy 161.704262 -297.466894) (xy 161.684971 -297.421618) (xy 161.673194 -297.373834) (xy 161.669234 -297.32478)
			(xy 161.330386 -297.32478) (xy 161.329891 -297.349387) (xy 161.321996 -297.397964) (xy 161.306412 -297.444645)
			(xy 161.283541 -297.488222) (xy 161.253976 -297.527566) (xy 161.218483 -297.561658) (xy 161.17798 -297.589614)
			(xy 161.133518 -297.610712) (xy 161.086247 -297.624404) (xy 161.037392 -297.630336) (xy 160.988217 -297.628355)
			(xy 160.939998 -297.618511) (xy 160.893982 -297.601059) (xy 160.851361 -297.576452) (xy 160.81324 -297.545327)
			(xy 160.780605 -297.50849) (xy 160.754302 -297.466894) (xy 160.735011 -297.421618) (xy 160.723234 -297.373834)
			(xy 160.719274 -297.32478) (xy 160.380172 -297.32478) (xy 160.379677 -297.349387) (xy 160.371782 -297.397964)
			(xy 160.356198 -297.444645) (xy 160.333327 -297.488222) (xy 160.303762 -297.527566) (xy 160.268269 -297.561658)
			(xy 160.227766 -297.589614) (xy 160.183304 -297.610712) (xy 160.136033 -297.624404) (xy 160.087178 -297.630336)
			(xy 160.038003 -297.628355) (xy 159.989784 -297.618511) (xy 159.943768 -297.601059) (xy 159.901147 -297.576452)
			(xy 159.863026 -297.545327) (xy 159.830391 -297.50849) (xy 159.804088 -297.466894) (xy 159.784797 -297.421618)
			(xy 159.77302 -297.373834) (xy 159.76906 -297.32478) (xy 158.480252 -297.32478) (xy 158.479757 -297.349387)
			(xy 158.471862 -297.397964) (xy 158.456278 -297.444645) (xy 158.433407 -297.488222) (xy 158.403842 -297.527566)
			(xy 158.368349 -297.561658) (xy 158.327846 -297.589614) (xy 158.283384 -297.610712) (xy 158.236113 -297.624404)
			(xy 158.187258 -297.630336) (xy 158.138083 -297.628355) (xy 158.089864 -297.618511) (xy 158.043848 -297.601059)
			(xy 158.001227 -297.576452) (xy 157.963106 -297.545327) (xy 157.930471 -297.50849) (xy 157.904168 -297.466894)
			(xy 157.884877 -297.421618) (xy 157.8731 -297.373834) (xy 157.86914 -297.32478) (xy 155.630372 -297.32478)
			(xy 155.629877 -297.349387) (xy 155.621982 -297.397964) (xy 155.606398 -297.444645) (xy 155.583527 -297.488222)
			(xy 155.553962 -297.527566) (xy 155.518469 -297.561658) (xy 155.477966 -297.589614) (xy 155.433504 -297.610712)
			(xy 155.386233 -297.624404) (xy 155.337378 -297.630336) (xy 155.288203 -297.628355) (xy 155.239984 -297.618511)
			(xy 155.193968 -297.601059) (xy 155.151347 -297.576452) (xy 155.113226 -297.545327) (xy 155.080591 -297.50849)
			(xy 155.054288 -297.466894) (xy 155.034997 -297.421618) (xy 155.02322 -297.373834) (xy 155.01926 -297.32478)
			(xy 154.680158 -297.32478) (xy 154.679663 -297.349387) (xy 154.671768 -297.397964) (xy 154.656184 -297.444645)
			(xy 154.633313 -297.488222) (xy 154.603748 -297.527566) (xy 154.568255 -297.561658) (xy 154.527752 -297.589614)
			(xy 154.48329 -297.610712) (xy 154.436019 -297.624404) (xy 154.387164 -297.630336) (xy 154.337989 -297.628355)
			(xy 154.28977 -297.618511) (xy 154.243754 -297.601059) (xy 154.201133 -297.576452) (xy 154.163012 -297.545327)
			(xy 154.130377 -297.50849) (xy 154.104074 -297.466894) (xy 154.084783 -297.421618) (xy 154.073006 -297.373834)
			(xy 154.069046 -297.32478) (xy 153.754779 -297.32478) (xy 153.754779 -297.350784) (xy 153.74665 -297.402112)
			(xy 153.730592 -297.451536) (xy 153.707001 -297.497841) (xy 153.676457 -297.539885) (xy 153.639712 -297.576633)
			(xy 153.597671 -297.607182) (xy 153.55137 -297.630778) (xy 153.501947 -297.646841) (xy 153.45062 -297.654976)
			(xy 153.424636 -297.655488) (xy 152.474676 -297.655488) (xy 152.450304 -297.655045) (xy 152.402085 -297.647904)
			(xy 152.355436 -297.633766) (xy 152.311365 -297.612937) (xy 152.270828 -297.585868) (xy 152.234701 -297.553144)
			(xy 152.218898 -297.534584) (xy 152.211527 -297.526557) (xy 152.191922 -297.517084) (xy 152.181052 -297.516296)
			(xy 152.092914 -297.513756) (xy 152.072848 -297.522392) (xy 152.065482 -297.53052) (xy 152.048017 -297.548966)
			(xy 152.008048 -297.580314) (xy 151.96344 -297.604613) (xy 151.915425 -297.62119) (xy 151.865328 -297.629589)
			(xy 151.83993 -297.630088) (xy 151.814669 -297.629638) (xy 151.764835 -297.621326) (xy 151.71705 -297.604926)
			(xy 151.672615 -297.580883) (xy 151.632745 -297.549854) (xy 151.598525 -297.512685) (xy 151.570891 -297.470391)
			(xy 151.550595 -297.424125) (xy 151.538192 -297.375149) (xy 151.53402 -297.3248) (xy 118.832884 -297.3248)
			(xy 118.832884 -297.831256) (xy 141.911576 -297.831256) (xy 141.915647 -297.775634) (xy 141.927773 -297.721197)
			(xy 141.947696 -297.669106) (xy 141.974992 -297.620471) (xy 142.009078 -297.576328) (xy 142.049227 -297.537619)
			(xy 142.094585 -297.505168) (xy 142.144185 -297.479667) (xy 142.196969 -297.46166) (xy 142.251812 -297.45153)
			(xy 142.307546 -297.449493) (xy 142.362983 -297.455593) (xy 142.41694 -297.469699) (xy 142.468269 -297.491511)
			(xy 142.515875 -297.520565) (xy 142.558743 -297.55624) (xy 142.59596 -297.597777) (xy 142.626733 -297.64429)
			(xy 142.650405 -297.694787) (xy 142.666473 -297.748194) (xy 142.674593 -297.80337) (xy 142.675102 -297.831256)
			(xy 143.396714 -297.831256) (xy 143.400785 -297.775634) (xy 143.412911 -297.721197) (xy 143.432834 -297.669106)
			(xy 143.46013 -297.620471) (xy 143.494216 -297.576328) (xy 143.534365 -297.537619) (xy 143.579723 -297.505168)
			(xy 143.629323 -297.479667) (xy 143.682107 -297.46166) (xy 143.73695 -297.45153) (xy 143.792684 -297.449493)
			(xy 143.848121 -297.455593) (xy 143.902078 -297.469699) (xy 143.953407 -297.491511) (xy 144.001013 -297.520565)
			(xy 144.043881 -297.55624) (xy 144.081098 -297.597777) (xy 144.111871 -297.64429) (xy 144.135543 -297.694787)
			(xy 144.151611 -297.748194) (xy 144.159731 -297.80337) (xy 144.16024 -297.831256) (xy 144.159731 -297.859142)
			(xy 144.151611 -297.914318) (xy 144.135543 -297.967725) (xy 144.111871 -298.018222) (xy 144.081098 -298.064735)
			(xy 144.043881 -298.106272) (xy 144.001013 -298.141947) (xy 143.953407 -298.171001) (xy 143.902078 -298.192813)
			(xy 143.848121 -298.206919) (xy 143.792684 -298.213019) (xy 143.73695 -298.210982) (xy 143.682107 -298.200852)
			(xy 143.629323 -298.182845) (xy 143.579723 -298.157344) (xy 143.534365 -298.124893) (xy 143.494216 -298.086184)
			(xy 143.46013 -298.042041) (xy 143.432834 -297.993406) (xy 143.412911 -297.941315) (xy 143.400785 -297.886878)
			(xy 143.396714 -297.831256) (xy 142.675102 -297.831256) (xy 142.674593 -297.859142) (xy 142.666473 -297.914318)
			(xy 142.650405 -297.967725) (xy 142.626733 -298.018222) (xy 142.59596 -298.064735) (xy 142.558743 -298.106272)
			(xy 142.515875 -298.141947) (xy 142.468269 -298.171001) (xy 142.41694 -298.192813) (xy 142.362983 -298.206919)
			(xy 142.307546 -298.213019) (xy 142.251812 -298.210982) (xy 142.196969 -298.200852) (xy 142.144185 -298.182845)
			(xy 142.094585 -298.157344) (xy 142.049227 -298.124893) (xy 142.009078 -298.086184) (xy 141.974992 -298.042041)
			(xy 141.947696 -297.993406) (xy 141.927773 -297.941315) (xy 141.915647 -297.886878) (xy 141.911576 -297.831256)
			(xy 118.832884 -297.831256) (xy 118.832884 -298.27474) (xy 153.118832 -298.27474) (xy 153.122792 -298.225686)
			(xy 153.134569 -298.177902) (xy 153.15386 -298.132626) (xy 153.180163 -298.09103) (xy 153.212798 -298.054193)
			(xy 153.250919 -298.023068) (xy 153.29354 -297.998461) (xy 153.339556 -297.981009) (xy 153.387775 -297.971165)
			(xy 153.43695 -297.969184) (xy 153.485805 -297.975116) (xy 153.533076 -297.988808) (xy 153.577538 -298.009906)
			(xy 153.618041 -298.037862) (xy 153.653534 -298.071954) (xy 153.683099 -298.111298) (xy 153.70597 -298.154875)
			(xy 153.721554 -298.201556) (xy 153.729449 -298.250133) (xy 153.729944 -298.27474) (xy 154.069046 -298.27474)
			(xy 154.073006 -298.225686) (xy 154.084783 -298.177902) (xy 154.104074 -298.132626) (xy 154.130377 -298.09103)
			(xy 154.163012 -298.054193) (xy 154.201133 -298.023068) (xy 154.243754 -297.998461) (xy 154.28977 -297.981009)
			(xy 154.337989 -297.971165) (xy 154.387164 -297.969184) (xy 154.436019 -297.975116) (xy 154.48329 -297.988808)
			(xy 154.527752 -298.009906) (xy 154.568255 -298.037862) (xy 154.603748 -298.071954) (xy 154.633313 -298.111298)
			(xy 154.656184 -298.154875) (xy 154.671768 -298.201556) (xy 154.679663 -298.250133) (xy 154.680158 -298.27474)
			(xy 155.01926 -298.27474) (xy 155.02322 -298.225686) (xy 155.034997 -298.177902) (xy 155.054288 -298.132626)
			(xy 155.080591 -298.09103) (xy 155.113226 -298.054193) (xy 155.151347 -298.023068) (xy 155.193968 -297.998461)
			(xy 155.239984 -297.981009) (xy 155.288203 -297.971165) (xy 155.337378 -297.969184) (xy 155.386233 -297.975116)
			(xy 155.433504 -297.988808) (xy 155.477966 -298.009906) (xy 155.518469 -298.037862) (xy 155.553962 -298.071954)
			(xy 155.583527 -298.111298) (xy 155.606398 -298.154875) (xy 155.621982 -298.201556) (xy 155.629877 -298.250133)
			(xy 155.630372 -298.27474) (xy 155.96922 -298.27474) (xy 155.97318 -298.225686) (xy 155.984957 -298.177902)
			(xy 156.004248 -298.132626) (xy 156.030551 -298.09103) (xy 156.063186 -298.054193) (xy 156.101307 -298.023068)
			(xy 156.143928 -297.998461) (xy 156.189944 -297.981009) (xy 156.238163 -297.971165) (xy 156.287338 -297.969184)
			(xy 156.336193 -297.975116) (xy 156.383464 -297.988808) (xy 156.427926 -298.009906) (xy 156.468429 -298.037862)
			(xy 156.503922 -298.071954) (xy 156.533487 -298.111298) (xy 156.556358 -298.154875) (xy 156.571942 -298.201556)
			(xy 156.579837 -298.250133) (xy 156.580332 -298.27474) (xy 156.91918 -298.27474) (xy 156.92314 -298.225686)
			(xy 156.934917 -298.177902) (xy 156.954208 -298.132626) (xy 156.980511 -298.09103) (xy 157.013146 -298.054193)
			(xy 157.051267 -298.023068) (xy 157.093888 -297.998461) (xy 157.139904 -297.981009) (xy 157.188123 -297.971165)
			(xy 157.237298 -297.969184) (xy 157.286153 -297.975116) (xy 157.333424 -297.988808) (xy 157.377886 -298.009906)
			(xy 157.418389 -298.037862) (xy 157.453882 -298.071954) (xy 157.483447 -298.111298) (xy 157.506318 -298.154875)
			(xy 157.521902 -298.201556) (xy 157.529797 -298.250133) (xy 157.530292 -298.27474) (xy 157.86914 -298.27474)
			(xy 157.8731 -298.225686) (xy 157.884877 -298.177902) (xy 157.904168 -298.132626) (xy 157.930471 -298.09103)
			(xy 157.963106 -298.054193) (xy 158.001227 -298.023068) (xy 158.043848 -297.998461) (xy 158.089864 -297.981009)
			(xy 158.138083 -297.971165) (xy 158.187258 -297.969184) (xy 158.236113 -297.975116) (xy 158.283384 -297.988808)
			(xy 158.327846 -298.009906) (xy 158.368349 -298.037862) (xy 158.403842 -298.071954) (xy 158.433407 -298.111298)
			(xy 158.456278 -298.154875) (xy 158.471862 -298.201556) (xy 158.479757 -298.250133) (xy 158.480252 -298.27474)
			(xy 159.76906 -298.27474) (xy 159.77302 -298.225686) (xy 159.784797 -298.177902) (xy 159.804088 -298.132626)
			(xy 159.830391 -298.09103) (xy 159.863026 -298.054193) (xy 159.901147 -298.023068) (xy 159.943768 -297.998461)
			(xy 159.989784 -297.981009) (xy 160.038003 -297.971165) (xy 160.087178 -297.969184) (xy 160.136033 -297.975116)
			(xy 160.183304 -297.988808) (xy 160.227766 -298.009906) (xy 160.268269 -298.037862) (xy 160.303762 -298.071954)
			(xy 160.333327 -298.111298) (xy 160.356198 -298.154875) (xy 160.371782 -298.201556) (xy 160.379677 -298.250133)
			(xy 160.380172 -298.27474) (xy 160.719274 -298.27474) (xy 160.723234 -298.225686) (xy 160.735011 -298.177902)
			(xy 160.754302 -298.132626) (xy 160.780605 -298.09103) (xy 160.81324 -298.054193) (xy 160.851361 -298.023068)
			(xy 160.893982 -297.998461) (xy 160.939998 -297.981009) (xy 160.988217 -297.971165) (xy 161.037392 -297.969184)
			(xy 161.086247 -297.975116) (xy 161.133518 -297.988808) (xy 161.17798 -298.009906) (xy 161.218483 -298.037862)
			(xy 161.253976 -298.071954) (xy 161.283541 -298.111298) (xy 161.306412 -298.154875) (xy 161.321996 -298.201556)
			(xy 161.329891 -298.250133) (xy 161.330386 -298.27474) (xy 161.669234 -298.27474) (xy 161.673194 -298.225686)
			(xy 161.684971 -298.177902) (xy 161.704262 -298.132626) (xy 161.730565 -298.09103) (xy 161.7632 -298.054193)
			(xy 161.801321 -298.023068) (xy 161.843942 -297.998461) (xy 161.889958 -297.981009) (xy 161.938177 -297.971165)
			(xy 161.987352 -297.969184) (xy 162.036207 -297.975116) (xy 162.083478 -297.988808) (xy 162.12794 -298.009906)
			(xy 162.168443 -298.037862) (xy 162.203936 -298.071954) (xy 162.233501 -298.111298) (xy 162.256372 -298.154875)
			(xy 162.271956 -298.201556) (xy 162.279851 -298.250133) (xy 162.280346 -298.27474) (xy 163.569154 -298.27474)
			(xy 163.573114 -298.225686) (xy 163.584891 -298.177902) (xy 163.604182 -298.132626) (xy 163.630485 -298.09103)
			(xy 163.66312 -298.054193) (xy 163.701241 -298.023068) (xy 163.743862 -297.998461) (xy 163.789878 -297.981009)
			(xy 163.838097 -297.971165) (xy 163.887272 -297.969184) (xy 163.936127 -297.975116) (xy 163.983398 -297.988808)
			(xy 164.02786 -298.009906) (xy 164.068363 -298.037862) (xy 164.103856 -298.071954) (xy 164.133421 -298.111298)
			(xy 164.156292 -298.154875) (xy 164.171876 -298.201556) (xy 164.179771 -298.250133) (xy 164.180266 -298.27474)
			(xy 164.519114 -298.27474) (xy 164.523074 -298.225686) (xy 164.534851 -298.177902) (xy 164.554142 -298.132626)
			(xy 164.580445 -298.09103) (xy 164.61308 -298.054193) (xy 164.651201 -298.023068) (xy 164.693822 -297.998461)
			(xy 164.739838 -297.981009) (xy 164.788057 -297.971165) (xy 164.837232 -297.969184) (xy 164.886087 -297.975116)
			(xy 164.933358 -297.988808) (xy 164.97782 -298.009906) (xy 165.018323 -298.037862) (xy 165.053816 -298.071954)
			(xy 165.083381 -298.111298) (xy 165.106252 -298.154875) (xy 165.121836 -298.201556) (xy 165.129731 -298.250133)
			(xy 165.130226 -298.27474) (xy 166.419288 -298.27474) (xy 166.423248 -298.225686) (xy 166.435025 -298.177902)
			(xy 166.454316 -298.132626) (xy 166.480619 -298.09103) (xy 166.513254 -298.054193) (xy 166.551375 -298.023068)
			(xy 166.593996 -297.998461) (xy 166.640012 -297.981009) (xy 166.688231 -297.971165) (xy 166.737406 -297.969184)
			(xy 166.786261 -297.975116) (xy 166.833532 -297.988808) (xy 166.877994 -298.009906) (xy 166.918497 -298.037862)
			(xy 166.95399 -298.071954) (xy 166.983555 -298.111298) (xy 167.006426 -298.154875) (xy 167.02201 -298.201556)
			(xy 167.029905 -298.250133) (xy 167.0304 -298.27474) (xy 168.319208 -298.27474) (xy 168.323168 -298.225686)
			(xy 168.334945 -298.177902) (xy 168.354236 -298.132626) (xy 168.380539 -298.09103) (xy 168.413174 -298.054193)
			(xy 168.451295 -298.023068) (xy 168.493916 -297.998461) (xy 168.539932 -297.981009) (xy 168.588151 -297.971165)
			(xy 168.637326 -297.969184) (xy 168.686181 -297.975116) (xy 168.733452 -297.988808) (xy 168.777914 -298.009906)
			(xy 168.818417 -298.037862) (xy 168.85391 -298.071954) (xy 168.883475 -298.111298) (xy 168.906346 -298.154875)
			(xy 168.92193 -298.201556) (xy 168.929825 -298.250133) (xy 168.93032 -298.27474) (xy 170.219128 -298.27474)
			(xy 170.223088 -298.225686) (xy 170.234865 -298.177902) (xy 170.254156 -298.132626) (xy 170.280459 -298.09103)
			(xy 170.313094 -298.054193) (xy 170.351215 -298.023068) (xy 170.393836 -297.998461) (xy 170.439852 -297.981009)
			(xy 170.488071 -297.971165) (xy 170.537246 -297.969184) (xy 170.586101 -297.975116) (xy 170.633372 -297.988808)
			(xy 170.677834 -298.009906) (xy 170.718337 -298.037862) (xy 170.75383 -298.071954) (xy 170.783395 -298.111298)
			(xy 170.806266 -298.154875) (xy 170.82185 -298.201556) (xy 170.829745 -298.250133) (xy 170.83024 -298.27474)
			(xy 172.119048 -298.27474) (xy 172.123008 -298.225686) (xy 172.134785 -298.177902) (xy 172.154076 -298.132626)
			(xy 172.180379 -298.09103) (xy 172.213014 -298.054193) (xy 172.251135 -298.023068) (xy 172.293756 -297.998461)
			(xy 172.339772 -297.981009) (xy 172.387991 -297.971165) (xy 172.437166 -297.969184) (xy 172.486021 -297.975116)
			(xy 172.533292 -297.988808) (xy 172.577754 -298.009906) (xy 172.618257 -298.037862) (xy 172.65375 -298.071954)
			(xy 172.683315 -298.111298) (xy 172.706186 -298.154875) (xy 172.72177 -298.201556) (xy 172.729665 -298.250133)
			(xy 172.73016 -298.27474) (xy 174.019222 -298.27474) (xy 174.023182 -298.225686) (xy 174.034959 -298.177902)
			(xy 174.05425 -298.132626) (xy 174.080553 -298.09103) (xy 174.113188 -298.054193) (xy 174.151309 -298.023068)
			(xy 174.19393 -297.998461) (xy 174.239946 -297.981009) (xy 174.288165 -297.971165) (xy 174.33734 -297.969184)
			(xy 174.386195 -297.975116) (xy 174.433466 -297.988808) (xy 174.477928 -298.009906) (xy 174.518431 -298.037862)
			(xy 174.553924 -298.071954) (xy 174.583489 -298.111298) (xy 174.60636 -298.154875) (xy 174.621944 -298.201556)
			(xy 174.629839 -298.250133) (xy 174.630334 -298.27474) (xy 176.869102 -298.27474) (xy 176.873062 -298.225686)
			(xy 176.884839 -298.177902) (xy 176.90413 -298.132626) (xy 176.930433 -298.09103) (xy 176.963068 -298.054193)
			(xy 177.001189 -298.023068) (xy 177.04381 -297.998461) (xy 177.089826 -297.981009) (xy 177.138045 -297.971165)
			(xy 177.18722 -297.969184) (xy 177.236075 -297.975116) (xy 177.283346 -297.988808) (xy 177.327808 -298.009906)
			(xy 177.368311 -298.037862) (xy 177.403804 -298.071954) (xy 177.433369 -298.111298) (xy 177.45624 -298.154875)
			(xy 177.471824 -298.201556) (xy 177.479719 -298.250133) (xy 177.480214 -298.27474) (xy 178.769276 -298.27474)
			(xy 178.773236 -298.225686) (xy 178.785013 -298.177902) (xy 178.804304 -298.132626) (xy 178.830607 -298.09103)
			(xy 178.863242 -298.054193) (xy 178.901363 -298.023068) (xy 178.943984 -297.998461) (xy 178.99 -297.981009)
			(xy 179.038219 -297.971165) (xy 179.087394 -297.969184) (xy 179.136249 -297.975116) (xy 179.18352 -297.988808)
			(xy 179.227982 -298.009906) (xy 179.268485 -298.037862) (xy 179.303978 -298.071954) (xy 179.333543 -298.111298)
			(xy 179.356414 -298.154875) (xy 179.371998 -298.201556) (xy 179.379893 -298.250133) (xy 179.380388 -298.27474)
			(xy 180.669196 -298.27474) (xy 180.673156 -298.225686) (xy 180.684933 -298.177902) (xy 180.704224 -298.132626)
			(xy 180.730527 -298.09103) (xy 180.763162 -298.054193) (xy 180.801283 -298.023068) (xy 180.843904 -297.998461)
			(xy 180.88992 -297.981009) (xy 180.938139 -297.971165) (xy 180.987314 -297.969184) (xy 181.036169 -297.975116)
			(xy 181.08344 -297.988808) (xy 181.127902 -298.009906) (xy 181.168405 -298.037862) (xy 181.203898 -298.071954)
			(xy 181.233463 -298.111298) (xy 181.256334 -298.154875) (xy 181.271918 -298.201556) (xy 181.279813 -298.250133)
			(xy 181.280308 -298.27474) (xy 182.569116 -298.27474) (xy 182.573076 -298.225686) (xy 182.584853 -298.177902)
			(xy 182.604144 -298.132626) (xy 182.630447 -298.09103) (xy 182.663082 -298.054193) (xy 182.701203 -298.023068)
			(xy 182.743824 -297.998461) (xy 182.78984 -297.981009) (xy 182.838059 -297.971165) (xy 182.887234 -297.969184)
			(xy 182.936089 -297.975116) (xy 182.98336 -297.988808) (xy 183.027822 -298.009906) (xy 183.068325 -298.037862)
			(xy 183.103818 -298.071954) (xy 183.133383 -298.111298) (xy 183.156254 -298.154875) (xy 183.171838 -298.201556)
			(xy 183.179733 -298.250133) (xy 183.180228 -298.27474) (xy 183.179733 -298.299347) (xy 183.171838 -298.347924)
			(xy 183.156254 -298.394605) (xy 183.133383 -298.438182) (xy 183.103818 -298.477526) (xy 183.068325 -298.511618)
			(xy 183.027822 -298.539574) (xy 182.98336 -298.560672) (xy 182.936089 -298.574364) (xy 182.887234 -298.580296)
			(xy 182.838059 -298.578315) (xy 182.78984 -298.568471) (xy 182.743824 -298.551019) (xy 182.701203 -298.526412)
			(xy 182.663082 -298.495287) (xy 182.630447 -298.45845) (xy 182.604144 -298.416854) (xy 182.584853 -298.371578)
			(xy 182.573076 -298.323794) (xy 182.569116 -298.27474) (xy 181.280308 -298.27474) (xy 181.279813 -298.299347)
			(xy 181.271918 -298.347924) (xy 181.256334 -298.394605) (xy 181.233463 -298.438182) (xy 181.203898 -298.477526)
			(xy 181.168405 -298.511618) (xy 181.127902 -298.539574) (xy 181.08344 -298.560672) (xy 181.036169 -298.574364)
			(xy 180.987314 -298.580296) (xy 180.938139 -298.578315) (xy 180.88992 -298.568471) (xy 180.843904 -298.551019)
			(xy 180.801283 -298.526412) (xy 180.763162 -298.495287) (xy 180.730527 -298.45845) (xy 180.704224 -298.416854)
			(xy 180.684933 -298.371578) (xy 180.673156 -298.323794) (xy 180.669196 -298.27474) (xy 179.380388 -298.27474)
			(xy 179.379893 -298.299347) (xy 179.371998 -298.347924) (xy 179.356414 -298.394605) (xy 179.333543 -298.438182)
			(xy 179.303978 -298.477526) (xy 179.268485 -298.511618) (xy 179.227982 -298.539574) (xy 179.18352 -298.560672)
			(xy 179.136249 -298.574364) (xy 179.087394 -298.580296) (xy 179.038219 -298.578315) (xy 178.99 -298.568471)
			(xy 178.943984 -298.551019) (xy 178.901363 -298.526412) (xy 178.863242 -298.495287) (xy 178.830607 -298.45845)
			(xy 178.804304 -298.416854) (xy 178.785013 -298.371578) (xy 178.773236 -298.323794) (xy 178.769276 -298.27474)
			(xy 177.480214 -298.27474) (xy 177.479719 -298.299347) (xy 177.471824 -298.347924) (xy 177.45624 -298.394605)
			(xy 177.433369 -298.438182) (xy 177.403804 -298.477526) (xy 177.368311 -298.511618) (xy 177.327808 -298.539574)
			(xy 177.283346 -298.560672) (xy 177.236075 -298.574364) (xy 177.18722 -298.580296) (xy 177.138045 -298.578315)
			(xy 177.089826 -298.568471) (xy 177.04381 -298.551019) (xy 177.001189 -298.526412) (xy 176.963068 -298.495287)
			(xy 176.930433 -298.45845) (xy 176.90413 -298.416854) (xy 176.884839 -298.371578) (xy 176.873062 -298.323794)
			(xy 176.869102 -298.27474) (xy 174.630334 -298.27474) (xy 174.629839 -298.299347) (xy 174.621944 -298.347924)
			(xy 174.60636 -298.394605) (xy 174.583489 -298.438182) (xy 174.553924 -298.477526) (xy 174.518431 -298.511618)
			(xy 174.477928 -298.539574) (xy 174.433466 -298.560672) (xy 174.386195 -298.574364) (xy 174.33734 -298.580296)
			(xy 174.288165 -298.578315) (xy 174.239946 -298.568471) (xy 174.19393 -298.551019) (xy 174.151309 -298.526412)
			(xy 174.113188 -298.495287) (xy 174.080553 -298.45845) (xy 174.05425 -298.416854) (xy 174.034959 -298.371578)
			(xy 174.023182 -298.323794) (xy 174.019222 -298.27474) (xy 172.73016 -298.27474) (xy 172.729665 -298.299347)
			(xy 172.72177 -298.347924) (xy 172.706186 -298.394605) (xy 172.683315 -298.438182) (xy 172.65375 -298.477526)
			(xy 172.618257 -298.511618) (xy 172.577754 -298.539574) (xy 172.533292 -298.560672) (xy 172.486021 -298.574364)
			(xy 172.437166 -298.580296) (xy 172.387991 -298.578315) (xy 172.339772 -298.568471) (xy 172.293756 -298.551019)
			(xy 172.251135 -298.526412) (xy 172.213014 -298.495287) (xy 172.180379 -298.45845) (xy 172.154076 -298.416854)
			(xy 172.134785 -298.371578) (xy 172.123008 -298.323794) (xy 172.119048 -298.27474) (xy 170.83024 -298.27474)
			(xy 170.829745 -298.299347) (xy 170.82185 -298.347924) (xy 170.806266 -298.394605) (xy 170.783395 -298.438182)
			(xy 170.75383 -298.477526) (xy 170.718337 -298.511618) (xy 170.677834 -298.539574) (xy 170.633372 -298.560672)
			(xy 170.586101 -298.574364) (xy 170.537246 -298.580296) (xy 170.488071 -298.578315) (xy 170.439852 -298.568471)
			(xy 170.393836 -298.551019) (xy 170.351215 -298.526412) (xy 170.313094 -298.495287) (xy 170.280459 -298.45845)
			(xy 170.254156 -298.416854) (xy 170.234865 -298.371578) (xy 170.223088 -298.323794) (xy 170.219128 -298.27474)
			(xy 168.93032 -298.27474) (xy 168.929825 -298.299347) (xy 168.92193 -298.347924) (xy 168.906346 -298.394605)
			(xy 168.883475 -298.438182) (xy 168.85391 -298.477526) (xy 168.818417 -298.511618) (xy 168.777914 -298.539574)
			(xy 168.733452 -298.560672) (xy 168.686181 -298.574364) (xy 168.637326 -298.580296) (xy 168.588151 -298.578315)
			(xy 168.539932 -298.568471) (xy 168.493916 -298.551019) (xy 168.451295 -298.526412) (xy 168.413174 -298.495287)
			(xy 168.380539 -298.45845) (xy 168.354236 -298.416854) (xy 168.334945 -298.371578) (xy 168.323168 -298.323794)
			(xy 168.319208 -298.27474) (xy 167.0304 -298.27474) (xy 167.029905 -298.299347) (xy 167.02201 -298.347924)
			(xy 167.006426 -298.394605) (xy 166.983555 -298.438182) (xy 166.95399 -298.477526) (xy 166.918497 -298.511618)
			(xy 166.877994 -298.539574) (xy 166.833532 -298.560672) (xy 166.786261 -298.574364) (xy 166.737406 -298.580296)
			(xy 166.688231 -298.578315) (xy 166.640012 -298.568471) (xy 166.593996 -298.551019) (xy 166.551375 -298.526412)
			(xy 166.513254 -298.495287) (xy 166.480619 -298.45845) (xy 166.454316 -298.416854) (xy 166.435025 -298.371578)
			(xy 166.423248 -298.323794) (xy 166.419288 -298.27474) (xy 165.130226 -298.27474) (xy 165.129731 -298.299347)
			(xy 165.121836 -298.347924) (xy 165.106252 -298.394605) (xy 165.083381 -298.438182) (xy 165.053816 -298.477526)
			(xy 165.018323 -298.511618) (xy 164.97782 -298.539574) (xy 164.933358 -298.560672) (xy 164.886087 -298.574364)
			(xy 164.837232 -298.580296) (xy 164.788057 -298.578315) (xy 164.739838 -298.568471) (xy 164.693822 -298.551019)
			(xy 164.651201 -298.526412) (xy 164.61308 -298.495287) (xy 164.580445 -298.45845) (xy 164.554142 -298.416854)
			(xy 164.534851 -298.371578) (xy 164.523074 -298.323794) (xy 164.519114 -298.27474) (xy 164.180266 -298.27474)
			(xy 164.179771 -298.299347) (xy 164.171876 -298.347924) (xy 164.156292 -298.394605) (xy 164.133421 -298.438182)
			(xy 164.103856 -298.477526) (xy 164.068363 -298.511618) (xy 164.02786 -298.539574) (xy 163.983398 -298.560672)
			(xy 163.936127 -298.574364) (xy 163.887272 -298.580296) (xy 163.838097 -298.578315) (xy 163.789878 -298.568471)
			(xy 163.743862 -298.551019) (xy 163.701241 -298.526412) (xy 163.66312 -298.495287) (xy 163.630485 -298.45845)
			(xy 163.604182 -298.416854) (xy 163.584891 -298.371578) (xy 163.573114 -298.323794) (xy 163.569154 -298.27474)
			(xy 162.280346 -298.27474) (xy 162.279851 -298.299347) (xy 162.271956 -298.347924) (xy 162.256372 -298.394605)
			(xy 162.233501 -298.438182) (xy 162.203936 -298.477526) (xy 162.168443 -298.511618) (xy 162.12794 -298.539574)
			(xy 162.083478 -298.560672) (xy 162.036207 -298.574364) (xy 161.987352 -298.580296) (xy 161.938177 -298.578315)
			(xy 161.889958 -298.568471) (xy 161.843942 -298.551019) (xy 161.801321 -298.526412) (xy 161.7632 -298.495287)
			(xy 161.730565 -298.45845) (xy 161.704262 -298.416854) (xy 161.684971 -298.371578) (xy 161.673194 -298.323794)
			(xy 161.669234 -298.27474) (xy 161.330386 -298.27474) (xy 161.329891 -298.299347) (xy 161.321996 -298.347924)
			(xy 161.306412 -298.394605) (xy 161.283541 -298.438182) (xy 161.253976 -298.477526) (xy 161.218483 -298.511618)
			(xy 161.17798 -298.539574) (xy 161.133518 -298.560672) (xy 161.086247 -298.574364) (xy 161.037392 -298.580296)
			(xy 160.988217 -298.578315) (xy 160.939998 -298.568471) (xy 160.893982 -298.551019) (xy 160.851361 -298.526412)
			(xy 160.81324 -298.495287) (xy 160.780605 -298.45845) (xy 160.754302 -298.416854) (xy 160.735011 -298.371578)
			(xy 160.723234 -298.323794) (xy 160.719274 -298.27474) (xy 160.380172 -298.27474) (xy 160.379677 -298.299347)
			(xy 160.371782 -298.347924) (xy 160.356198 -298.394605) (xy 160.333327 -298.438182) (xy 160.303762 -298.477526)
			(xy 160.268269 -298.511618) (xy 160.227766 -298.539574) (xy 160.183304 -298.560672) (xy 160.136033 -298.574364)
			(xy 160.087178 -298.580296) (xy 160.038003 -298.578315) (xy 159.989784 -298.568471) (xy 159.943768 -298.551019)
			(xy 159.901147 -298.526412) (xy 159.863026 -298.495287) (xy 159.830391 -298.45845) (xy 159.804088 -298.416854)
			(xy 159.784797 -298.371578) (xy 159.77302 -298.323794) (xy 159.76906 -298.27474) (xy 158.480252 -298.27474)
			(xy 158.479757 -298.299347) (xy 158.471862 -298.347924) (xy 158.456278 -298.394605) (xy 158.433407 -298.438182)
			(xy 158.403842 -298.477526) (xy 158.368349 -298.511618) (xy 158.327846 -298.539574) (xy 158.283384 -298.560672)
			(xy 158.236113 -298.574364) (xy 158.187258 -298.580296) (xy 158.138083 -298.578315) (xy 158.089864 -298.568471)
			(xy 158.043848 -298.551019) (xy 158.001227 -298.526412) (xy 157.963106 -298.495287) (xy 157.930471 -298.45845)
			(xy 157.904168 -298.416854) (xy 157.884877 -298.371578) (xy 157.8731 -298.323794) (xy 157.86914 -298.27474)
			(xy 157.530292 -298.27474) (xy 157.529797 -298.299347) (xy 157.521902 -298.347924) (xy 157.506318 -298.394605)
			(xy 157.483447 -298.438182) (xy 157.453882 -298.477526) (xy 157.418389 -298.511618) (xy 157.377886 -298.539574)
			(xy 157.333424 -298.560672) (xy 157.286153 -298.574364) (xy 157.237298 -298.580296) (xy 157.188123 -298.578315)
			(xy 157.139904 -298.568471) (xy 157.093888 -298.551019) (xy 157.051267 -298.526412) (xy 157.013146 -298.495287)
			(xy 156.980511 -298.45845) (xy 156.954208 -298.416854) (xy 156.934917 -298.371578) (xy 156.92314 -298.323794)
			(xy 156.91918 -298.27474) (xy 156.580332 -298.27474) (xy 156.579837 -298.299347) (xy 156.571942 -298.347924)
			(xy 156.556358 -298.394605) (xy 156.533487 -298.438182) (xy 156.503922 -298.477526) (xy 156.468429 -298.511618)
			(xy 156.427926 -298.539574) (xy 156.383464 -298.560672) (xy 156.336193 -298.574364) (xy 156.287338 -298.580296)
			(xy 156.238163 -298.578315) (xy 156.189944 -298.568471) (xy 156.143928 -298.551019) (xy 156.101307 -298.526412)
			(xy 156.063186 -298.495287) (xy 156.030551 -298.45845) (xy 156.004248 -298.416854) (xy 155.984957 -298.371578)
			(xy 155.97318 -298.323794) (xy 155.96922 -298.27474) (xy 155.630372 -298.27474) (xy 155.629877 -298.299347)
			(xy 155.621982 -298.347924) (xy 155.606398 -298.394605) (xy 155.583527 -298.438182) (xy 155.553962 -298.477526)
			(xy 155.518469 -298.511618) (xy 155.477966 -298.539574) (xy 155.433504 -298.560672) (xy 155.386233 -298.574364)
			(xy 155.337378 -298.580296) (xy 155.288203 -298.578315) (xy 155.239984 -298.568471) (xy 155.193968 -298.551019)
			(xy 155.151347 -298.526412) (xy 155.113226 -298.495287) (xy 155.080591 -298.45845) (xy 155.054288 -298.416854)
			(xy 155.034997 -298.371578) (xy 155.02322 -298.323794) (xy 155.01926 -298.27474) (xy 154.680158 -298.27474)
			(xy 154.679663 -298.299347) (xy 154.671768 -298.347924) (xy 154.656184 -298.394605) (xy 154.633313 -298.438182)
			(xy 154.603748 -298.477526) (xy 154.568255 -298.511618) (xy 154.527752 -298.539574) (xy 154.48329 -298.560672)
			(xy 154.436019 -298.574364) (xy 154.387164 -298.580296) (xy 154.337989 -298.578315) (xy 154.28977 -298.568471)
			(xy 154.243754 -298.551019) (xy 154.201133 -298.526412) (xy 154.163012 -298.495287) (xy 154.130377 -298.45845)
			(xy 154.104074 -298.416854) (xy 154.084783 -298.371578) (xy 154.073006 -298.323794) (xy 154.069046 -298.27474)
			(xy 153.729944 -298.27474) (xy 153.729449 -298.299347) (xy 153.721554 -298.347924) (xy 153.70597 -298.394605)
			(xy 153.683099 -298.438182) (xy 153.653534 -298.477526) (xy 153.618041 -298.511618) (xy 153.577538 -298.539574)
			(xy 153.533076 -298.560672) (xy 153.485805 -298.574364) (xy 153.43695 -298.580296) (xy 153.387775 -298.578315)
			(xy 153.339556 -298.568471) (xy 153.29354 -298.551019) (xy 153.250919 -298.526412) (xy 153.212798 -298.495287)
			(xy 153.180163 -298.45845) (xy 153.15386 -298.416854) (xy 153.134569 -298.371578) (xy 153.122792 -298.323794)
			(xy 153.118832 -298.27474) (xy 118.832884 -298.27474) (xy 118.832884 -299.133514) (xy 141.911576 -299.133514)
			(xy 141.915647 -299.077892) (xy 141.927773 -299.023455) (xy 141.947696 -298.971364) (xy 141.974992 -298.922729)
			(xy 142.009078 -298.878586) (xy 142.049227 -298.839877) (xy 142.094585 -298.807426) (xy 142.144185 -298.781925)
			(xy 142.196969 -298.763918) (xy 142.251812 -298.753788) (xy 142.307546 -298.751751) (xy 142.362983 -298.757851)
			(xy 142.41694 -298.771957) (xy 142.468269 -298.793769) (xy 142.515875 -298.822823) (xy 142.558743 -298.858498)
			(xy 142.59596 -298.900035) (xy 142.626733 -298.946548) (xy 142.650405 -298.997045) (xy 142.666473 -299.050452)
			(xy 142.674593 -299.105628) (xy 142.675102 -299.133514) (xy 143.387062 -299.133514) (xy 143.391133 -299.077892)
			(xy 143.403259 -299.023455) (xy 143.423182 -298.971364) (xy 143.450478 -298.922729) (xy 143.484564 -298.878586)
			(xy 143.524713 -298.839877) (xy 143.570071 -298.807426) (xy 143.619671 -298.781925) (xy 143.672455 -298.763918)
			(xy 143.727298 -298.753788) (xy 143.783032 -298.751751) (xy 143.838469 -298.757851) (xy 143.892426 -298.771957)
			(xy 143.943755 -298.793769) (xy 143.991361 -298.822823) (xy 144.034229 -298.858498) (xy 144.071446 -298.900035)
			(xy 144.102219 -298.946548) (xy 144.125891 -298.997045) (xy 144.141959 -299.050452) (xy 144.150079 -299.105628)
			(xy 144.150588 -299.133514) (xy 144.276062 -299.133514) (xy 144.280133 -299.077892) (xy 144.292259 -299.023455)
			(xy 144.312182 -298.971364) (xy 144.339478 -298.922729) (xy 144.373564 -298.878586) (xy 144.413713 -298.839877)
			(xy 144.459071 -298.807426) (xy 144.508671 -298.781925) (xy 144.561455 -298.763918) (xy 144.616298 -298.753788)
			(xy 144.672032 -298.751751) (xy 144.727469 -298.757851) (xy 144.781426 -298.771957) (xy 144.832755 -298.793769)
			(xy 144.880361 -298.822823) (xy 144.923229 -298.858498) (xy 144.960446 -298.900035) (xy 144.991219 -298.946548)
			(xy 145.014891 -298.997045) (xy 145.030959 -299.050452) (xy 145.039079 -299.105628) (xy 145.039588 -299.133514)
			(xy 145.039079 -299.1614) (xy 145.030959 -299.216576) (xy 145.014891 -299.269983) (xy 144.991219 -299.32048)
			(xy 144.960446 -299.366993) (xy 144.923229 -299.40853) (xy 144.880361 -299.444205) (xy 144.832755 -299.473259)
			(xy 144.781426 -299.495071) (xy 144.727469 -299.509177) (xy 144.672032 -299.515277) (xy 144.616298 -299.51324)
			(xy 144.561455 -299.50311) (xy 144.508671 -299.485103) (xy 144.459071 -299.459602) (xy 144.413713 -299.427151)
			(xy 144.373564 -299.388442) (xy 144.339478 -299.344299) (xy 144.312182 -299.295664) (xy 144.292259 -299.243573)
			(xy 144.280133 -299.189136) (xy 144.276062 -299.133514) (xy 144.150588 -299.133514) (xy 144.150079 -299.1614)
			(xy 144.141959 -299.216576) (xy 144.125891 -299.269983) (xy 144.102219 -299.32048) (xy 144.071446 -299.366993)
			(xy 144.034229 -299.40853) (xy 143.991361 -299.444205) (xy 143.943755 -299.473259) (xy 143.892426 -299.495071)
			(xy 143.838469 -299.509177) (xy 143.783032 -299.515277) (xy 143.727298 -299.51324) (xy 143.672455 -299.50311)
			(xy 143.619671 -299.485103) (xy 143.570071 -299.459602) (xy 143.524713 -299.427151) (xy 143.484564 -299.388442)
			(xy 143.450478 -299.344299) (xy 143.423182 -299.295664) (xy 143.403259 -299.243573) (xy 143.391133 -299.189136)
			(xy 143.387062 -299.133514) (xy 142.675102 -299.133514) (xy 142.674593 -299.1614) (xy 142.666473 -299.216576)
			(xy 142.650405 -299.269983) (xy 142.626733 -299.32048) (xy 142.59596 -299.366993) (xy 142.558743 -299.40853)
			(xy 142.515875 -299.444205) (xy 142.468269 -299.473259) (xy 142.41694 -299.495071) (xy 142.362983 -299.509177)
			(xy 142.307546 -299.515277) (xy 142.251812 -299.51324) (xy 142.196969 -299.50311) (xy 142.144185 -299.485103)
			(xy 142.094585 -299.459602) (xy 142.049227 -299.427151) (xy 142.009078 -299.388442) (xy 141.974992 -299.344299)
			(xy 141.947696 -299.295664) (xy 141.927773 -299.243573) (xy 141.915647 -299.189136) (xy 141.911576 -299.133514)
			(xy 118.832884 -299.133514) (xy 118.832884 -299.895514) (xy 147.43811 -299.895514) (xy 147.438654 -299.866132)
			(xy 147.447683 -299.808065) (xy 147.465514 -299.752071) (xy 147.491725 -299.699475) (xy 147.525695 -299.651524)
			(xy 147.56662 -299.609352) (xy 147.589748 -299.591222) (xy 147.598672 -299.583742) (xy 147.609132 -299.562968)
			(xy 147.609814 -299.551344) (xy 147.611084 -299.459396) (xy 147.601178 -299.438314) (xy 147.592034 -299.430948)
			(xy 147.570186 -299.412742) (xy 147.531644 -299.370924) (xy 147.499736 -299.323849) (xy 147.475169 -299.272559)
			(xy 147.458486 -299.218191) (xy 147.450058 -299.161949) (xy 147.44954 -299.133514) (xy 147.450026 -299.106263)
			(xy 147.457782 -299.052315) (xy 147.473137 -299.00002) (xy 147.495779 -298.950443) (xy 147.525245 -298.904593)
			(xy 147.560936 -298.863402) (xy 147.602127 -298.827711) (xy 147.647977 -298.798245) (xy 147.697554 -298.775603)
			(xy 147.749849 -298.760248) (xy 147.803797 -298.752492) (xy 147.858299 -298.752492) (xy 147.912247 -298.760248)
			(xy 147.964542 -298.775603) (xy 148.014119 -298.798245) (xy 148.059969 -298.827711) (xy 148.10116 -298.863402)
			(xy 148.136851 -298.904593) (xy 148.166317 -298.950443) (xy 148.188959 -299.00002) (xy 148.204314 -299.052315)
			(xy 148.21207 -299.106263) (xy 148.212556 -299.133514) (xy 148.212006 -299.162896) (xy 148.202975 -299.220961)
			(xy 148.201784 -299.2247) (xy 151.53404 -299.2247) (xy 151.538212 -299.174354) (xy 151.550614 -299.125381)
			(xy 151.570909 -299.079118) (xy 151.598541 -299.036827) (xy 151.632758 -298.999661) (xy 151.672626 -298.968634)
			(xy 151.717058 -298.944593) (xy 151.76484 -298.928193) (xy 151.814671 -298.919882) (xy 151.83993 -298.919392)
			(xy 151.865325 -298.919926) (xy 151.915413 -298.928333) (xy 151.96342 -298.944912) (xy 152.008023 -298.969204)
			(xy 152.047993 -299.000541) (xy 152.065482 -299.01896) (xy 152.065736 -299.019214) (xy 152.07342 -299.0268)
			(xy 152.093294 -299.035202) (xy 152.10409 -299.03547) (xy 152.192228 -299.033184) (xy 152.21204 -299.023532)
			(xy 152.219152 -299.014896) (xy 152.234926 -298.996339) (xy 152.271023 -298.963642) (xy 152.311522 -298.936588)
			(xy 152.355548 -298.915761) (xy 152.402151 -298.90161) (xy 152.450324 -298.89444) (xy 152.474676 -298.893992)
			(xy 153.424636 -298.893992) (xy 153.450638 -298.894597) (xy 153.502 -298.902737) (xy 153.551457 -298.918811)
			(xy 153.59779 -298.942424) (xy 153.63986 -298.972993) (xy 153.67663 -299.009767) (xy 153.707195 -299.05184)
			(xy 153.730803 -299.098177) (xy 153.746871 -299.147635) (xy 153.755006 -299.198998) (xy 153.755006 -299.224954)
			(xy 154.069046 -299.224954) (xy 154.073006 -299.1759) (xy 154.084783 -299.128116) (xy 154.104074 -299.08284)
			(xy 154.130377 -299.041244) (xy 154.163012 -299.004407) (xy 154.201133 -298.973282) (xy 154.243754 -298.948675)
			(xy 154.28977 -298.931223) (xy 154.337989 -298.921379) (xy 154.387164 -298.919398) (xy 154.436019 -298.92533)
			(xy 154.48329 -298.939022) (xy 154.527752 -298.96012) (xy 154.568255 -298.988076) (xy 154.603748 -299.022168)
			(xy 154.633313 -299.061512) (xy 154.656184 -299.105089) (xy 154.671768 -299.15177) (xy 154.679663 -299.200347)
			(xy 154.680158 -299.224954) (xy 154.679663 -299.249561) (xy 154.679428 -299.251009) (xy 154.994602 -299.251009)
			(xy 154.994602 -299.198991) (xy 155.002739 -299.147613) (xy 155.018812 -299.098141) (xy 155.042426 -299.051792)
			(xy 155.073 -299.009707) (xy 155.10978 -298.972923) (xy 155.151861 -298.942345) (xy 155.198208 -298.918726)
			(xy 155.247678 -298.902647) (xy 155.299055 -298.894505) (xy 155.325064 -298.893992) (xy 156.275024 -298.893992)
			(xy 156.301026 -298.894596) (xy 156.35239 -298.902735) (xy 156.401848 -298.918808) (xy 156.448184 -298.94242)
			(xy 156.490255 -298.972989) (xy 156.527026 -299.009763) (xy 156.557593 -299.051837) (xy 156.581201 -299.098174)
			(xy 156.597271 -299.147633) (xy 156.605406 -299.198998) (xy 156.605406 -299.224954) (xy 156.91918 -299.224954)
			(xy 156.92314 -299.1759) (xy 156.934917 -299.128116) (xy 156.954208 -299.08284) (xy 156.980511 -299.041244)
			(xy 157.013146 -299.004407) (xy 157.051267 -298.973282) (xy 157.093888 -298.948675) (xy 157.139904 -298.931223)
			(xy 157.188123 -298.921379) (xy 157.237298 -298.919398) (xy 157.286153 -298.92533) (xy 157.333424 -298.939022)
			(xy 157.377886 -298.96012) (xy 157.418389 -298.988076) (xy 157.453882 -299.022168) (xy 157.483447 -299.061512)
			(xy 157.506318 -299.105089) (xy 157.521902 -299.15177) (xy 157.529797 -299.200347) (xy 157.530287 -299.2247)
			(xy 157.86914 -299.2247) (xy 157.8731 -299.175646) (xy 157.884877 -299.127862) (xy 157.904168 -299.082586)
			(xy 157.930471 -299.04099) (xy 157.963106 -299.004153) (xy 158.001227 -298.973028) (xy 158.043848 -298.948421)
			(xy 158.089864 -298.930969) (xy 158.138083 -298.921125) (xy 158.187258 -298.919144) (xy 158.236113 -298.925076)
			(xy 158.283384 -298.938768) (xy 158.327846 -298.959866) (xy 158.368349 -298.987822) (xy 158.403842 -299.021914)
			(xy 158.433407 -299.061258) (xy 158.456278 -299.104835) (xy 158.471862 -299.151516) (xy 158.479757 -299.200093)
			(xy 158.480252 -299.2247) (xy 158.480247 -299.224954) (xy 159.76906 -299.224954) (xy 159.77302 -299.1759)
			(xy 159.784797 -299.128116) (xy 159.804088 -299.08284) (xy 159.830391 -299.041244) (xy 159.863026 -299.004407)
			(xy 159.901147 -298.973282) (xy 159.943768 -298.948675) (xy 159.989784 -298.931223) (xy 160.038003 -298.921379)
			(xy 160.087178 -298.919398) (xy 160.136033 -298.92533) (xy 160.183304 -298.939022) (xy 160.227766 -298.96012)
			(xy 160.268269 -298.988076) (xy 160.303762 -299.022168) (xy 160.333327 -299.061512) (xy 160.356198 -299.105089)
			(xy 160.371782 -299.15177) (xy 160.379677 -299.200347) (xy 160.380172 -299.224954) (xy 160.719274 -299.224954)
			(xy 160.723234 -299.1759) (xy 160.735011 -299.128116) (xy 160.754302 -299.08284) (xy 160.780605 -299.041244)
			(xy 160.81324 -299.004407) (xy 160.851361 -298.973282) (xy 160.893982 -298.948675) (xy 160.939998 -298.931223)
			(xy 160.988217 -298.921379) (xy 161.037392 -298.919398) (xy 161.086247 -298.92533) (xy 161.133518 -298.939022)
			(xy 161.17798 -298.96012) (xy 161.218483 -298.988076) (xy 161.253976 -299.022168) (xy 161.283541 -299.061512)
			(xy 161.306412 -299.105089) (xy 161.321996 -299.15177) (xy 161.329891 -299.200347) (xy 161.330386 -299.224954)
			(xy 161.669234 -299.224954) (xy 161.673194 -299.1759) (xy 161.684971 -299.128116) (xy 161.704262 -299.08284)
			(xy 161.730565 -299.041244) (xy 161.7632 -299.004407) (xy 161.801321 -298.973282) (xy 161.843942 -298.948675)
			(xy 161.889958 -298.931223) (xy 161.938177 -298.921379) (xy 161.987352 -298.919398) (xy 162.036207 -298.92533)
			(xy 162.083478 -298.939022) (xy 162.12794 -298.96012) (xy 162.168443 -298.988076) (xy 162.203936 -299.022168)
			(xy 162.233501 -299.061512) (xy 162.256372 -299.105089) (xy 162.271956 -299.15177) (xy 162.279851 -299.200347)
			(xy 162.280346 -299.224954) (xy 162.619194 -299.224954) (xy 162.623154 -299.1759) (xy 162.634931 -299.128116)
			(xy 162.654222 -299.08284) (xy 162.680525 -299.041244) (xy 162.71316 -299.004407) (xy 162.751281 -298.973282)
			(xy 162.793902 -298.948675) (xy 162.839918 -298.931223) (xy 162.888137 -298.921379) (xy 162.937312 -298.919398)
			(xy 162.986167 -298.92533) (xy 163.033438 -298.939022) (xy 163.0779 -298.96012) (xy 163.118403 -298.988076)
			(xy 163.153896 -299.022168) (xy 163.183461 -299.061512) (xy 163.206332 -299.105089) (xy 163.221916 -299.15177)
			(xy 163.229811 -299.200347) (xy 163.230306 -299.224954) (xy 163.569154 -299.224954) (xy 163.573114 -299.1759)
			(xy 163.584891 -299.128116) (xy 163.604182 -299.08284) (xy 163.630485 -299.041244) (xy 163.66312 -299.004407)
			(xy 163.701241 -298.973282) (xy 163.743862 -298.948675) (xy 163.789878 -298.931223) (xy 163.838097 -298.921379)
			(xy 163.887272 -298.919398) (xy 163.936127 -298.92533) (xy 163.983398 -298.939022) (xy 164.02786 -298.96012)
			(xy 164.068363 -298.988076) (xy 164.103856 -299.022168) (xy 164.133421 -299.061512) (xy 164.156292 -299.105089)
			(xy 164.171876 -299.15177) (xy 164.179771 -299.200347) (xy 164.180266 -299.224954) (xy 165.469074 -299.224954)
			(xy 165.473034 -299.1759) (xy 165.484811 -299.128116) (xy 165.504102 -299.08284) (xy 165.530405 -299.041244)
			(xy 165.56304 -299.004407) (xy 165.601161 -298.973282) (xy 165.643782 -298.948675) (xy 165.689798 -298.931223)
			(xy 165.738017 -298.921379) (xy 165.787192 -298.919398) (xy 165.836047 -298.92533) (xy 165.883318 -298.939022)
			(xy 165.92778 -298.96012) (xy 165.968283 -298.988076) (xy 166.003776 -299.022168) (xy 166.033341 -299.061512)
			(xy 166.056212 -299.105089) (xy 166.071796 -299.15177) (xy 166.079691 -299.200347) (xy 166.080186 -299.224954)
			(xy 166.419288 -299.224954) (xy 166.423248 -299.1759) (xy 166.435025 -299.128116) (xy 166.454316 -299.08284)
			(xy 166.480619 -299.041244) (xy 166.513254 -299.004407) (xy 166.551375 -298.973282) (xy 166.593996 -298.948675)
			(xy 166.640012 -298.931223) (xy 166.688231 -298.921379) (xy 166.737406 -298.919398) (xy 166.786261 -298.92533)
			(xy 166.833532 -298.939022) (xy 166.877994 -298.96012) (xy 166.918497 -298.988076) (xy 166.95399 -299.022168)
			(xy 166.983555 -299.061512) (xy 167.006426 -299.105089) (xy 167.02201 -299.15177) (xy 167.029905 -299.200347)
			(xy 167.0304 -299.224954) (xy 167.369248 -299.224954) (xy 167.373208 -299.1759) (xy 167.384985 -299.128116)
			(xy 167.404276 -299.08284) (xy 167.430579 -299.041244) (xy 167.463214 -299.004407) (xy 167.501335 -298.973282)
			(xy 167.543956 -298.948675) (xy 167.589972 -298.931223) (xy 167.638191 -298.921379) (xy 167.687366 -298.919398)
			(xy 167.736221 -298.92533) (xy 167.783492 -298.939022) (xy 167.827954 -298.96012) (xy 167.868457 -298.988076)
			(xy 167.90395 -299.022168) (xy 167.933515 -299.061512) (xy 167.956386 -299.105089) (xy 167.97197 -299.15177)
			(xy 167.979865 -299.200347) (xy 167.98036 -299.224954) (xy 168.319208 -299.224954) (xy 168.323168 -299.1759)
			(xy 168.334945 -299.128116) (xy 168.354236 -299.08284) (xy 168.380539 -299.041244) (xy 168.413174 -299.004407)
			(xy 168.451295 -298.973282) (xy 168.493916 -298.948675) (xy 168.539932 -298.931223) (xy 168.588151 -298.921379)
			(xy 168.637326 -298.919398) (xy 168.686181 -298.92533) (xy 168.733452 -298.939022) (xy 168.777914 -298.96012)
			(xy 168.818417 -298.988076) (xy 168.85391 -299.022168) (xy 168.883475 -299.061512) (xy 168.906346 -299.105089)
			(xy 168.92193 -299.15177) (xy 168.929825 -299.200347) (xy 168.93032 -299.224954) (xy 169.269168 -299.224954)
			(xy 169.273128 -299.1759) (xy 169.284905 -299.128116) (xy 169.304196 -299.08284) (xy 169.330499 -299.041244)
			(xy 169.363134 -299.004407) (xy 169.401255 -298.973282) (xy 169.443876 -298.948675) (xy 169.489892 -298.931223)
			(xy 169.538111 -298.921379) (xy 169.587286 -298.919398) (xy 169.636141 -298.92533) (xy 169.683412 -298.939022)
			(xy 169.727874 -298.96012) (xy 169.768377 -298.988076) (xy 169.80387 -299.022168) (xy 169.833435 -299.061512)
			(xy 169.856306 -299.105089) (xy 169.87189 -299.15177) (xy 169.879785 -299.200347) (xy 169.88028 -299.224954)
			(xy 170.219128 -299.224954) (xy 170.223088 -299.1759) (xy 170.234865 -299.128116) (xy 170.254156 -299.08284)
			(xy 170.280459 -299.041244) (xy 170.313094 -299.004407) (xy 170.351215 -298.973282) (xy 170.393836 -298.948675)
			(xy 170.439852 -298.931223) (xy 170.488071 -298.921379) (xy 170.537246 -298.919398) (xy 170.586101 -298.92533)
			(xy 170.633372 -298.939022) (xy 170.677834 -298.96012) (xy 170.718337 -298.988076) (xy 170.75383 -299.022168)
			(xy 170.783395 -299.061512) (xy 170.806266 -299.105089) (xy 170.82185 -299.15177) (xy 170.829745 -299.200347)
			(xy 170.83024 -299.224954) (xy 171.169088 -299.224954) (xy 171.173048 -299.1759) (xy 171.184825 -299.128116)
			(xy 171.204116 -299.08284) (xy 171.230419 -299.041244) (xy 171.263054 -299.004407) (xy 171.301175 -298.973282)
			(xy 171.343796 -298.948675) (xy 171.389812 -298.931223) (xy 171.438031 -298.921379) (xy 171.487206 -298.919398)
			(xy 171.536061 -298.92533) (xy 171.583332 -298.939022) (xy 171.627794 -298.96012) (xy 171.668297 -298.988076)
			(xy 171.70379 -299.022168) (xy 171.733355 -299.061512) (xy 171.756226 -299.105089) (xy 171.77181 -299.15177)
			(xy 171.779705 -299.200347) (xy 171.7802 -299.224954) (xy 172.119048 -299.224954) (xy 172.123008 -299.1759)
			(xy 172.134785 -299.128116) (xy 172.154076 -299.08284) (xy 172.180379 -299.041244) (xy 172.213014 -299.004407)
			(xy 172.251135 -298.973282) (xy 172.293756 -298.948675) (xy 172.339772 -298.931223) (xy 172.387991 -298.921379)
			(xy 172.437166 -298.919398) (xy 172.486021 -298.92533) (xy 172.533292 -298.939022) (xy 172.577754 -298.96012)
			(xy 172.618257 -298.988076) (xy 172.65375 -299.022168) (xy 172.683315 -299.061512) (xy 172.706186 -299.105089)
			(xy 172.72177 -299.15177) (xy 172.729665 -299.200347) (xy 172.73016 -299.224954) (xy 173.069262 -299.224954)
			(xy 173.073222 -299.1759) (xy 173.084999 -299.128116) (xy 173.10429 -299.08284) (xy 173.130593 -299.041244)
			(xy 173.163228 -299.004407) (xy 173.201349 -298.973282) (xy 173.24397 -298.948675) (xy 173.289986 -298.931223)
			(xy 173.338205 -298.921379) (xy 173.38738 -298.919398) (xy 173.436235 -298.92533) (xy 173.483506 -298.939022)
			(xy 173.527968 -298.96012) (xy 173.568471 -298.988076) (xy 173.603964 -299.022168) (xy 173.633529 -299.061512)
			(xy 173.6564 -299.105089) (xy 173.671984 -299.15177) (xy 173.679879 -299.200347) (xy 173.680374 -299.224954)
			(xy 174.019222 -299.224954) (xy 174.023182 -299.1759) (xy 174.034959 -299.128116) (xy 174.05425 -299.08284)
			(xy 174.080553 -299.041244) (xy 174.113188 -299.004407) (xy 174.151309 -298.973282) (xy 174.19393 -298.948675)
			(xy 174.239946 -298.931223) (xy 174.288165 -298.921379) (xy 174.33734 -298.919398) (xy 174.386195 -298.92533)
			(xy 174.433466 -298.939022) (xy 174.477928 -298.96012) (xy 174.518431 -298.988076) (xy 174.553924 -299.022168)
			(xy 174.583489 -299.061512) (xy 174.60636 -299.105089) (xy 174.621944 -299.15177) (xy 174.629839 -299.200347)
			(xy 174.630334 -299.224954) (xy 175.919142 -299.224954) (xy 175.923102 -299.1759) (xy 175.934879 -299.128116)
			(xy 175.95417 -299.08284) (xy 175.980473 -299.041244) (xy 176.013108 -299.004407) (xy 176.051229 -298.973282)
			(xy 176.09385 -298.948675) (xy 176.139866 -298.931223) (xy 176.188085 -298.921379) (xy 176.23726 -298.919398)
			(xy 176.286115 -298.92533) (xy 176.333386 -298.939022) (xy 176.377848 -298.96012) (xy 176.418351 -298.988076)
			(xy 176.453844 -299.022168) (xy 176.483409 -299.061512) (xy 176.50628 -299.105089) (xy 176.521864 -299.15177)
			(xy 176.529759 -299.200347) (xy 176.530254 -299.224954) (xy 176.869102 -299.224954) (xy 176.873062 -299.1759)
			(xy 176.884839 -299.128116) (xy 176.90413 -299.08284) (xy 176.930433 -299.041244) (xy 176.963068 -299.004407)
			(xy 177.001189 -298.973282) (xy 177.04381 -298.948675) (xy 177.089826 -298.931223) (xy 177.138045 -298.921379)
			(xy 177.18722 -298.919398) (xy 177.236075 -298.92533) (xy 177.283346 -298.939022) (xy 177.327808 -298.96012)
			(xy 177.368311 -298.988076) (xy 177.403804 -299.022168) (xy 177.433369 -299.061512) (xy 177.45624 -299.105089)
			(xy 177.471824 -299.15177) (xy 177.479719 -299.200347) (xy 177.480214 -299.224954) (xy 177.819062 -299.224954)
			(xy 177.823022 -299.1759) (xy 177.834799 -299.128116) (xy 177.85409 -299.08284) (xy 177.880393 -299.041244)
			(xy 177.913028 -299.004407) (xy 177.951149 -298.973282) (xy 177.99377 -298.948675) (xy 178.039786 -298.931223)
			(xy 178.088005 -298.921379) (xy 178.13718 -298.919398) (xy 178.186035 -298.92533) (xy 178.233306 -298.939022)
			(xy 178.277768 -298.96012) (xy 178.318271 -298.988076) (xy 178.353764 -299.022168) (xy 178.383329 -299.061512)
			(xy 178.4062 -299.105089) (xy 178.421784 -299.15177) (xy 178.429679 -299.200347) (xy 178.430174 -299.224954)
			(xy 178.769276 -299.224954) (xy 178.773236 -299.1759) (xy 178.785013 -299.128116) (xy 178.804304 -299.08284)
			(xy 178.830607 -299.041244) (xy 178.863242 -299.004407) (xy 178.901363 -298.973282) (xy 178.943984 -298.948675)
			(xy 178.99 -298.931223) (xy 179.038219 -298.921379) (xy 179.087394 -298.919398) (xy 179.136249 -298.92533)
			(xy 179.18352 -298.939022) (xy 179.227982 -298.96012) (xy 179.268485 -298.988076) (xy 179.303978 -299.022168)
			(xy 179.333543 -299.061512) (xy 179.356414 -299.105089) (xy 179.371998 -299.15177) (xy 179.379893 -299.200347)
			(xy 179.380388 -299.224954) (xy 179.719236 -299.224954) (xy 179.723196 -299.1759) (xy 179.734973 -299.128116)
			(xy 179.754264 -299.08284) (xy 179.780567 -299.041244) (xy 179.813202 -299.004407) (xy 179.851323 -298.973282)
			(xy 179.893944 -298.948675) (xy 179.93996 -298.931223) (xy 179.988179 -298.921379) (xy 180.037354 -298.919398)
			(xy 180.086209 -298.92533) (xy 180.13348 -298.939022) (xy 180.177942 -298.96012) (xy 180.218445 -298.988076)
			(xy 180.253938 -299.022168) (xy 180.283503 -299.061512) (xy 180.306374 -299.105089) (xy 180.321958 -299.15177)
			(xy 180.329853 -299.200347) (xy 180.330348 -299.224954) (xy 180.669196 -299.224954) (xy 180.673156 -299.1759)
			(xy 180.684933 -299.128116) (xy 180.704224 -299.08284) (xy 180.730527 -299.041244) (xy 180.763162 -299.004407)
			(xy 180.801283 -298.973282) (xy 180.843904 -298.948675) (xy 180.88992 -298.931223) (xy 180.938139 -298.921379)
			(xy 180.987314 -298.919398) (xy 181.036169 -298.92533) (xy 181.08344 -298.939022) (xy 181.127902 -298.96012)
			(xy 181.168405 -298.988076) (xy 181.203898 -299.022168) (xy 181.233463 -299.061512) (xy 181.256334 -299.105089)
			(xy 181.271918 -299.15177) (xy 181.279813 -299.200347) (xy 181.280308 -299.224954) (xy 181.619156 -299.224954)
			(xy 181.623116 -299.1759) (xy 181.634893 -299.128116) (xy 181.654184 -299.08284) (xy 181.680487 -299.041244)
			(xy 181.713122 -299.004407) (xy 181.751243 -298.973282) (xy 181.793864 -298.948675) (xy 181.83988 -298.931223)
			(xy 181.888099 -298.921379) (xy 181.937274 -298.919398) (xy 181.986129 -298.92533) (xy 182.0334 -298.939022)
			(xy 182.077862 -298.96012) (xy 182.118365 -298.988076) (xy 182.153858 -299.022168) (xy 182.183423 -299.061512)
			(xy 182.206294 -299.105089) (xy 182.221878 -299.15177) (xy 182.229773 -299.200347) (xy 182.230268 -299.224954)
			(xy 182.569116 -299.224954) (xy 182.573076 -299.1759) (xy 182.584853 -299.128116) (xy 182.604144 -299.08284)
			(xy 182.630447 -299.041244) (xy 182.663082 -299.004407) (xy 182.701203 -298.973282) (xy 182.743824 -298.948675)
			(xy 182.78984 -298.931223) (xy 182.838059 -298.921379) (xy 182.887234 -298.919398) (xy 182.936089 -298.92533)
			(xy 182.98336 -298.939022) (xy 183.027822 -298.96012) (xy 183.068325 -298.988076) (xy 183.103818 -299.022168)
			(xy 183.133383 -299.061512) (xy 183.156254 -299.105089) (xy 183.171838 -299.15177) (xy 183.179733 -299.200347)
			(xy 183.180228 -299.224954) (xy 183.519076 -299.224954) (xy 183.523036 -299.1759) (xy 183.534813 -299.128116)
			(xy 183.554104 -299.08284) (xy 183.580407 -299.041244) (xy 183.613042 -299.004407) (xy 183.651163 -298.973282)
			(xy 183.693784 -298.948675) (xy 183.7398 -298.931223) (xy 183.788019 -298.921379) (xy 183.837194 -298.919398)
			(xy 183.886049 -298.92533) (xy 183.93332 -298.939022) (xy 183.977782 -298.96012) (xy 184.018285 -298.988076)
			(xy 184.053778 -299.022168) (xy 184.083343 -299.061512) (xy 184.106214 -299.105089) (xy 184.121798 -299.15177)
			(xy 184.129693 -299.200347) (xy 184.130188 -299.224954) (xy 184.129693 -299.249561) (xy 184.121798 -299.298138)
			(xy 184.106214 -299.344819) (xy 184.083343 -299.388396) (xy 184.053778 -299.42774) (xy 184.018285 -299.461832)
			(xy 183.977782 -299.489788) (xy 183.93332 -299.510886) (xy 183.886049 -299.524578) (xy 183.837194 -299.53051)
			(xy 183.788019 -299.528529) (xy 183.7398 -299.518685) (xy 183.693784 -299.501233) (xy 183.651163 -299.476626)
			(xy 183.613042 -299.445501) (xy 183.580407 -299.408664) (xy 183.554104 -299.367068) (xy 183.534813 -299.321792)
			(xy 183.523036 -299.274008) (xy 183.519076 -299.224954) (xy 183.180228 -299.224954) (xy 183.179733 -299.249561)
			(xy 183.171838 -299.298138) (xy 183.156254 -299.344819) (xy 183.133383 -299.388396) (xy 183.103818 -299.42774)
			(xy 183.068325 -299.461832) (xy 183.027822 -299.489788) (xy 182.98336 -299.510886) (xy 182.936089 -299.524578)
			(xy 182.887234 -299.53051) (xy 182.838059 -299.528529) (xy 182.78984 -299.518685) (xy 182.743824 -299.501233)
			(xy 182.701203 -299.476626) (xy 182.663082 -299.445501) (xy 182.630447 -299.408664) (xy 182.604144 -299.367068)
			(xy 182.584853 -299.321792) (xy 182.573076 -299.274008) (xy 182.569116 -299.224954) (xy 182.230268 -299.224954)
			(xy 182.229773 -299.249561) (xy 182.221878 -299.298138) (xy 182.206294 -299.344819) (xy 182.183423 -299.388396)
			(xy 182.153858 -299.42774) (xy 182.118365 -299.461832) (xy 182.077862 -299.489788) (xy 182.0334 -299.510886)
			(xy 181.986129 -299.524578) (xy 181.937274 -299.53051) (xy 181.888099 -299.528529) (xy 181.83988 -299.518685)
			(xy 181.793864 -299.501233) (xy 181.751243 -299.476626) (xy 181.713122 -299.445501) (xy 181.680487 -299.408664)
			(xy 181.654184 -299.367068) (xy 181.634893 -299.321792) (xy 181.623116 -299.274008) (xy 181.619156 -299.224954)
			(xy 181.280308 -299.224954) (xy 181.279813 -299.249561) (xy 181.271918 -299.298138) (xy 181.256334 -299.344819)
			(xy 181.233463 -299.388396) (xy 181.203898 -299.42774) (xy 181.168405 -299.461832) (xy 181.127902 -299.489788)
			(xy 181.08344 -299.510886) (xy 181.036169 -299.524578) (xy 180.987314 -299.53051) (xy 180.938139 -299.528529)
			(xy 180.88992 -299.518685) (xy 180.843904 -299.501233) (xy 180.801283 -299.476626) (xy 180.763162 -299.445501)
			(xy 180.730527 -299.408664) (xy 180.704224 -299.367068) (xy 180.684933 -299.321792) (xy 180.673156 -299.274008)
			(xy 180.669196 -299.224954) (xy 180.330348 -299.224954) (xy 180.329853 -299.249561) (xy 180.321958 -299.298138)
			(xy 180.306374 -299.344819) (xy 180.283503 -299.388396) (xy 180.253938 -299.42774) (xy 180.218445 -299.461832)
			(xy 180.177942 -299.489788) (xy 180.13348 -299.510886) (xy 180.086209 -299.524578) (xy 180.037354 -299.53051)
			(xy 179.988179 -299.528529) (xy 179.93996 -299.518685) (xy 179.893944 -299.501233) (xy 179.851323 -299.476626)
			(xy 179.813202 -299.445501) (xy 179.780567 -299.408664) (xy 179.754264 -299.367068) (xy 179.734973 -299.321792)
			(xy 179.723196 -299.274008) (xy 179.719236 -299.224954) (xy 179.380388 -299.224954) (xy 179.379893 -299.249561)
			(xy 179.371998 -299.298138) (xy 179.356414 -299.344819) (xy 179.333543 -299.388396) (xy 179.303978 -299.42774)
			(xy 179.268485 -299.461832) (xy 179.227982 -299.489788) (xy 179.18352 -299.510886) (xy 179.136249 -299.524578)
			(xy 179.087394 -299.53051) (xy 179.038219 -299.528529) (xy 178.99 -299.518685) (xy 178.943984 -299.501233)
			(xy 178.901363 -299.476626) (xy 178.863242 -299.445501) (xy 178.830607 -299.408664) (xy 178.804304 -299.367068)
			(xy 178.785013 -299.321792) (xy 178.773236 -299.274008) (xy 178.769276 -299.224954) (xy 178.430174 -299.224954)
			(xy 178.429679 -299.249561) (xy 178.421784 -299.298138) (xy 178.4062 -299.344819) (xy 178.383329 -299.388396)
			(xy 178.353764 -299.42774) (xy 178.318271 -299.461832) (xy 178.277768 -299.489788) (xy 178.233306 -299.510886)
			(xy 178.186035 -299.524578) (xy 178.13718 -299.53051) (xy 178.088005 -299.528529) (xy 178.039786 -299.518685)
			(xy 177.99377 -299.501233) (xy 177.951149 -299.476626) (xy 177.913028 -299.445501) (xy 177.880393 -299.408664)
			(xy 177.85409 -299.367068) (xy 177.834799 -299.321792) (xy 177.823022 -299.274008) (xy 177.819062 -299.224954)
			(xy 177.480214 -299.224954) (xy 177.479719 -299.249561) (xy 177.471824 -299.298138) (xy 177.45624 -299.344819)
			(xy 177.433369 -299.388396) (xy 177.403804 -299.42774) (xy 177.368311 -299.461832) (xy 177.327808 -299.489788)
			(xy 177.283346 -299.510886) (xy 177.236075 -299.524578) (xy 177.18722 -299.53051) (xy 177.138045 -299.528529)
			(xy 177.089826 -299.518685) (xy 177.04381 -299.501233) (xy 177.001189 -299.476626) (xy 176.963068 -299.445501)
			(xy 176.930433 -299.408664) (xy 176.90413 -299.367068) (xy 176.884839 -299.321792) (xy 176.873062 -299.274008)
			(xy 176.869102 -299.224954) (xy 176.530254 -299.224954) (xy 176.529759 -299.249561) (xy 176.521864 -299.298138)
			(xy 176.50628 -299.344819) (xy 176.483409 -299.388396) (xy 176.453844 -299.42774) (xy 176.418351 -299.461832)
			(xy 176.377848 -299.489788) (xy 176.333386 -299.510886) (xy 176.286115 -299.524578) (xy 176.23726 -299.53051)
			(xy 176.188085 -299.528529) (xy 176.139866 -299.518685) (xy 176.09385 -299.501233) (xy 176.051229 -299.476626)
			(xy 176.013108 -299.445501) (xy 175.980473 -299.408664) (xy 175.95417 -299.367068) (xy 175.934879 -299.321792)
			(xy 175.923102 -299.274008) (xy 175.919142 -299.224954) (xy 174.630334 -299.224954) (xy 174.629839 -299.249561)
			(xy 174.621944 -299.298138) (xy 174.60636 -299.344819) (xy 174.583489 -299.388396) (xy 174.553924 -299.42774)
			(xy 174.518431 -299.461832) (xy 174.477928 -299.489788) (xy 174.433466 -299.510886) (xy 174.386195 -299.524578)
			(xy 174.33734 -299.53051) (xy 174.288165 -299.528529) (xy 174.239946 -299.518685) (xy 174.19393 -299.501233)
			(xy 174.151309 -299.476626) (xy 174.113188 -299.445501) (xy 174.080553 -299.408664) (xy 174.05425 -299.367068)
			(xy 174.034959 -299.321792) (xy 174.023182 -299.274008) (xy 174.019222 -299.224954) (xy 173.680374 -299.224954)
			(xy 173.679879 -299.249561) (xy 173.671984 -299.298138) (xy 173.6564 -299.344819) (xy 173.633529 -299.388396)
			(xy 173.603964 -299.42774) (xy 173.568471 -299.461832) (xy 173.527968 -299.489788) (xy 173.483506 -299.510886)
			(xy 173.436235 -299.524578) (xy 173.38738 -299.53051) (xy 173.338205 -299.528529) (xy 173.289986 -299.518685)
			(xy 173.24397 -299.501233) (xy 173.201349 -299.476626) (xy 173.163228 -299.445501) (xy 173.130593 -299.408664)
			(xy 173.10429 -299.367068) (xy 173.084999 -299.321792) (xy 173.073222 -299.274008) (xy 173.069262 -299.224954)
			(xy 172.73016 -299.224954) (xy 172.729665 -299.249561) (xy 172.72177 -299.298138) (xy 172.706186 -299.344819)
			(xy 172.683315 -299.388396) (xy 172.65375 -299.42774) (xy 172.618257 -299.461832) (xy 172.577754 -299.489788)
			(xy 172.533292 -299.510886) (xy 172.486021 -299.524578) (xy 172.437166 -299.53051) (xy 172.387991 -299.528529)
			(xy 172.339772 -299.518685) (xy 172.293756 -299.501233) (xy 172.251135 -299.476626) (xy 172.213014 -299.445501)
			(xy 172.180379 -299.408664) (xy 172.154076 -299.367068) (xy 172.134785 -299.321792) (xy 172.123008 -299.274008)
			(xy 172.119048 -299.224954) (xy 171.7802 -299.224954) (xy 171.779705 -299.249561) (xy 171.77181 -299.298138)
			(xy 171.756226 -299.344819) (xy 171.733355 -299.388396) (xy 171.70379 -299.42774) (xy 171.668297 -299.461832)
			(xy 171.627794 -299.489788) (xy 171.583332 -299.510886) (xy 171.536061 -299.524578) (xy 171.487206 -299.53051)
			(xy 171.438031 -299.528529) (xy 171.389812 -299.518685) (xy 171.343796 -299.501233) (xy 171.301175 -299.476626)
			(xy 171.263054 -299.445501) (xy 171.230419 -299.408664) (xy 171.204116 -299.367068) (xy 171.184825 -299.321792)
			(xy 171.173048 -299.274008) (xy 171.169088 -299.224954) (xy 170.83024 -299.224954) (xy 170.829745 -299.249561)
			(xy 170.82185 -299.298138) (xy 170.806266 -299.344819) (xy 170.783395 -299.388396) (xy 170.75383 -299.42774)
			(xy 170.718337 -299.461832) (xy 170.677834 -299.489788) (xy 170.633372 -299.510886) (xy 170.586101 -299.524578)
			(xy 170.537246 -299.53051) (xy 170.488071 -299.528529) (xy 170.439852 -299.518685) (xy 170.393836 -299.501233)
			(xy 170.351215 -299.476626) (xy 170.313094 -299.445501) (xy 170.280459 -299.408664) (xy 170.254156 -299.367068)
			(xy 170.234865 -299.321792) (xy 170.223088 -299.274008) (xy 170.219128 -299.224954) (xy 169.88028 -299.224954)
			(xy 169.879785 -299.249561) (xy 169.87189 -299.298138) (xy 169.856306 -299.344819) (xy 169.833435 -299.388396)
			(xy 169.80387 -299.42774) (xy 169.768377 -299.461832) (xy 169.727874 -299.489788) (xy 169.683412 -299.510886)
			(xy 169.636141 -299.524578) (xy 169.587286 -299.53051) (xy 169.538111 -299.528529) (xy 169.489892 -299.518685)
			(xy 169.443876 -299.501233) (xy 169.401255 -299.476626) (xy 169.363134 -299.445501) (xy 169.330499 -299.408664)
			(xy 169.304196 -299.367068) (xy 169.284905 -299.321792) (xy 169.273128 -299.274008) (xy 169.269168 -299.224954)
			(xy 168.93032 -299.224954) (xy 168.929825 -299.249561) (xy 168.92193 -299.298138) (xy 168.906346 -299.344819)
			(xy 168.883475 -299.388396) (xy 168.85391 -299.42774) (xy 168.818417 -299.461832) (xy 168.777914 -299.489788)
			(xy 168.733452 -299.510886) (xy 168.686181 -299.524578) (xy 168.637326 -299.53051) (xy 168.588151 -299.528529)
			(xy 168.539932 -299.518685) (xy 168.493916 -299.501233) (xy 168.451295 -299.476626) (xy 168.413174 -299.445501)
			(xy 168.380539 -299.408664) (xy 168.354236 -299.367068) (xy 168.334945 -299.321792) (xy 168.323168 -299.274008)
			(xy 168.319208 -299.224954) (xy 167.98036 -299.224954) (xy 167.979865 -299.249561) (xy 167.97197 -299.298138)
			(xy 167.956386 -299.344819) (xy 167.933515 -299.388396) (xy 167.90395 -299.42774) (xy 167.868457 -299.461832)
			(xy 167.827954 -299.489788) (xy 167.783492 -299.510886) (xy 167.736221 -299.524578) (xy 167.687366 -299.53051)
			(xy 167.638191 -299.528529) (xy 167.589972 -299.518685) (xy 167.543956 -299.501233) (xy 167.501335 -299.476626)
			(xy 167.463214 -299.445501) (xy 167.430579 -299.408664) (xy 167.404276 -299.367068) (xy 167.384985 -299.321792)
			(xy 167.373208 -299.274008) (xy 167.369248 -299.224954) (xy 167.0304 -299.224954) (xy 167.029905 -299.249561)
			(xy 167.02201 -299.298138) (xy 167.006426 -299.344819) (xy 166.983555 -299.388396) (xy 166.95399 -299.42774)
			(xy 166.918497 -299.461832) (xy 166.877994 -299.489788) (xy 166.833532 -299.510886) (xy 166.786261 -299.524578)
			(xy 166.737406 -299.53051) (xy 166.688231 -299.528529) (xy 166.640012 -299.518685) (xy 166.593996 -299.501233)
			(xy 166.551375 -299.476626) (xy 166.513254 -299.445501) (xy 166.480619 -299.408664) (xy 166.454316 -299.367068)
			(xy 166.435025 -299.321792) (xy 166.423248 -299.274008) (xy 166.419288 -299.224954) (xy 166.080186 -299.224954)
			(xy 166.079691 -299.249561) (xy 166.071796 -299.298138) (xy 166.056212 -299.344819) (xy 166.033341 -299.388396)
			(xy 166.003776 -299.42774) (xy 165.968283 -299.461832) (xy 165.92778 -299.489788) (xy 165.883318 -299.510886)
			(xy 165.836047 -299.524578) (xy 165.787192 -299.53051) (xy 165.738017 -299.528529) (xy 165.689798 -299.518685)
			(xy 165.643782 -299.501233) (xy 165.601161 -299.476626) (xy 165.56304 -299.445501) (xy 165.530405 -299.408664)
			(xy 165.504102 -299.367068) (xy 165.484811 -299.321792) (xy 165.473034 -299.274008) (xy 165.469074 -299.224954)
			(xy 164.180266 -299.224954) (xy 164.179771 -299.249561) (xy 164.171876 -299.298138) (xy 164.156292 -299.344819)
			(xy 164.133421 -299.388396) (xy 164.103856 -299.42774) (xy 164.068363 -299.461832) (xy 164.02786 -299.489788)
			(xy 163.983398 -299.510886) (xy 163.936127 -299.524578) (xy 163.887272 -299.53051) (xy 163.838097 -299.528529)
			(xy 163.789878 -299.518685) (xy 163.743862 -299.501233) (xy 163.701241 -299.476626) (xy 163.66312 -299.445501)
			(xy 163.630485 -299.408664) (xy 163.604182 -299.367068) (xy 163.584891 -299.321792) (xy 163.573114 -299.274008)
			(xy 163.569154 -299.224954) (xy 163.230306 -299.224954) (xy 163.229811 -299.249561) (xy 163.221916 -299.298138)
			(xy 163.206332 -299.344819) (xy 163.183461 -299.388396) (xy 163.153896 -299.42774) (xy 163.118403 -299.461832)
			(xy 163.0779 -299.489788) (xy 163.033438 -299.510886) (xy 162.986167 -299.524578) (xy 162.937312 -299.53051)
			(xy 162.888137 -299.528529) (xy 162.839918 -299.518685) (xy 162.793902 -299.501233) (xy 162.751281 -299.476626)
			(xy 162.71316 -299.445501) (xy 162.680525 -299.408664) (xy 162.654222 -299.367068) (xy 162.634931 -299.321792)
			(xy 162.623154 -299.274008) (xy 162.619194 -299.224954) (xy 162.280346 -299.224954) (xy 162.279851 -299.249561)
			(xy 162.271956 -299.298138) (xy 162.256372 -299.344819) (xy 162.233501 -299.388396) (xy 162.203936 -299.42774)
			(xy 162.168443 -299.461832) (xy 162.12794 -299.489788) (xy 162.083478 -299.510886) (xy 162.036207 -299.524578)
			(xy 161.987352 -299.53051) (xy 161.938177 -299.528529) (xy 161.889958 -299.518685) (xy 161.843942 -299.501233)
			(xy 161.801321 -299.476626) (xy 161.7632 -299.445501) (xy 161.730565 -299.408664) (xy 161.704262 -299.367068)
			(xy 161.684971 -299.321792) (xy 161.673194 -299.274008) (xy 161.669234 -299.224954) (xy 161.330386 -299.224954)
			(xy 161.329891 -299.249561) (xy 161.321996 -299.298138) (xy 161.306412 -299.344819) (xy 161.283541 -299.388396)
			(xy 161.253976 -299.42774) (xy 161.218483 -299.461832) (xy 161.17798 -299.489788) (xy 161.133518 -299.510886)
			(xy 161.086247 -299.524578) (xy 161.037392 -299.53051) (xy 160.988217 -299.528529) (xy 160.939998 -299.518685)
			(xy 160.893982 -299.501233) (xy 160.851361 -299.476626) (xy 160.81324 -299.445501) (xy 160.780605 -299.408664)
			(xy 160.754302 -299.367068) (xy 160.735011 -299.321792) (xy 160.723234 -299.274008) (xy 160.719274 -299.224954)
			(xy 160.380172 -299.224954) (xy 160.379677 -299.249561) (xy 160.371782 -299.298138) (xy 160.356198 -299.344819)
			(xy 160.333327 -299.388396) (xy 160.303762 -299.42774) (xy 160.268269 -299.461832) (xy 160.227766 -299.489788)
			(xy 160.183304 -299.510886) (xy 160.136033 -299.524578) (xy 160.087178 -299.53051) (xy 160.038003 -299.528529)
			(xy 159.989784 -299.518685) (xy 159.943768 -299.501233) (xy 159.901147 -299.476626) (xy 159.863026 -299.445501)
			(xy 159.830391 -299.408664) (xy 159.804088 -299.367068) (xy 159.784797 -299.321792) (xy 159.77302 -299.274008)
			(xy 159.76906 -299.224954) (xy 158.480247 -299.224954) (xy 158.479757 -299.249307) (xy 158.471862 -299.297884)
			(xy 158.456278 -299.344565) (xy 158.433407 -299.388142) (xy 158.403842 -299.427486) (xy 158.368349 -299.461578)
			(xy 158.327846 -299.489534) (xy 158.283384 -299.510632) (xy 158.236113 -299.524324) (xy 158.187258 -299.530256)
			(xy 158.138083 -299.528275) (xy 158.089864 -299.518431) (xy 158.043848 -299.500979) (xy 158.001227 -299.476372)
			(xy 157.963106 -299.445247) (xy 157.930471 -299.40841) (xy 157.904168 -299.366814) (xy 157.884877 -299.321538)
			(xy 157.8731 -299.273754) (xy 157.86914 -299.2247) (xy 157.530287 -299.2247) (xy 157.530292 -299.224954)
			(xy 157.529797 -299.249561) (xy 157.521902 -299.298138) (xy 157.506318 -299.344819) (xy 157.483447 -299.388396)
			(xy 157.453882 -299.42774) (xy 157.418389 -299.461832) (xy 157.377886 -299.489788) (xy 157.333424 -299.510886)
			(xy 157.286153 -299.524578) (xy 157.237298 -299.53051) (xy 157.188123 -299.528529) (xy 157.139904 -299.518685)
			(xy 157.093888 -299.501233) (xy 157.051267 -299.476626) (xy 157.013146 -299.445501) (xy 156.980511 -299.408664)
			(xy 156.954208 -299.367068) (xy 156.934917 -299.321792) (xy 156.92314 -299.274008) (xy 156.91918 -299.224954)
			(xy 156.605406 -299.224954) (xy 156.605406 -299.251002) (xy 156.597271 -299.302367) (xy 156.581201 -299.351826)
			(xy 156.557593 -299.398163) (xy 156.527026 -299.440237) (xy 156.490255 -299.477011) (xy 156.448184 -299.50758)
			(xy 156.401848 -299.531192) (xy 156.35239 -299.547265) (xy 156.301026 -299.555404) (xy 156.275024 -299.555916)
			(xy 156.204666 -299.555916) (xy 156.193941 -299.556335) (xy 156.174336 -299.565018) (xy 156.16682 -299.57268)
			(xy 156.109162 -299.636942) (xy 156.102558 -299.657262) (xy 156.103574 -299.667676) (xy 156.103574 -299.668184)
			(xy 156.105352 -299.699934) (xy 156.10483 -299.725189) (xy 156.096517 -299.775011) (xy 156.080116 -299.822785)
			(xy 156.056075 -299.867208) (xy 156.025051 -299.907068) (xy 155.987889 -299.941278) (xy 155.945603 -299.968904)
			(xy 155.899347 -299.989194) (xy 155.850382 -300.001594) (xy 155.800044 -300.005765) (xy 155.749706 -300.001594)
			(xy 155.700741 -299.989194) (xy 155.654485 -299.968904) (xy 155.612199 -299.941278) (xy 155.575037 -299.907068)
			(xy 155.544013 -299.867208) (xy 155.519972 -299.822785) (xy 155.503571 -299.775011) (xy 155.495258 -299.725189)
			(xy 155.494736 -299.699934) (xy 155.496514 -299.66793) (xy 155.49753 -299.657262) (xy 155.490926 -299.636942)
			(xy 155.433268 -299.57268) (xy 155.425667 -299.56514) (xy 155.406114 -299.55648) (xy 155.395422 -299.555916)
			(xy 155.325064 -299.555916) (xy 155.299055 -299.555495) (xy 155.247678 -299.547353) (xy 155.198208 -299.531274)
			(xy 155.151861 -299.507655) (xy 155.10978 -299.477077) (xy 155.073 -299.440293) (xy 155.042426 -299.398208)
			(xy 155.018812 -299.351859) (xy 155.002739 -299.302387) (xy 154.994602 -299.251009) (xy 154.679428 -299.251009)
			(xy 154.671768 -299.298138) (xy 154.656184 -299.344819) (xy 154.633313 -299.388396) (xy 154.603748 -299.42774)
			(xy 154.568255 -299.461832) (xy 154.527752 -299.489788) (xy 154.48329 -299.510886) (xy 154.436019 -299.524578)
			(xy 154.387164 -299.53051) (xy 154.337989 -299.528529) (xy 154.28977 -299.518685) (xy 154.243754 -299.501233)
			(xy 154.201133 -299.476626) (xy 154.163012 -299.445501) (xy 154.130377 -299.408664) (xy 154.104074 -299.367068)
			(xy 154.084783 -299.321792) (xy 154.073006 -299.274008) (xy 154.069046 -299.224954) (xy 153.755006 -299.224954)
			(xy 153.755006 -299.251002) (xy 153.746871 -299.302365) (xy 153.730803 -299.351823) (xy 153.707195 -299.39816)
			(xy 153.67663 -299.440233) (xy 153.63986 -299.477007) (xy 153.59779 -299.507576) (xy 153.551457 -299.531189)
			(xy 153.502 -299.547263) (xy 153.450638 -299.555403) (xy 153.424636 -299.555916) (xy 152.474676 -299.555916)
			(xy 152.450291 -299.555513) (xy 152.402052 -299.548333) (xy 152.355391 -299.534148) (xy 152.311318 -299.513264)
			(xy 152.27079 -299.486135) (xy 152.234684 -299.453349) (xy 152.218898 -299.434758) (xy 152.211523 -299.426595)
			(xy 152.191772 -299.416968) (xy 152.180798 -299.416216) (xy 152.10409 -299.41393) (xy 152.093104 -299.414173)
			(xy 152.072952 -299.422877) (xy 152.065228 -299.430694) (xy 152.047764 -299.449091) (xy 152.007828 -299.480363)
			(xy 151.96327 -299.5046) (xy 151.915318 -299.521135) (xy 151.865292 -299.529511) (xy 151.83993 -299.530008)
			(xy 151.814671 -299.529518) (xy 151.76484 -299.521207) (xy 151.717058 -299.504807) (xy 151.672626 -299.480766)
			(xy 151.632758 -299.449739) (xy 151.598541 -299.412573) (xy 151.570909 -299.370282) (xy 151.550614 -299.324019)
			(xy 151.538212 -299.275046) (xy 151.53404 -299.2247) (xy 148.201784 -299.2247) (xy 148.185143 -299.276954)
			(xy 148.158933 -299.329549) (xy 148.124966 -299.377501) (xy 148.084044 -299.419674) (xy 148.060918 -299.437806)
			(xy 148.051975 -299.445267) (xy 148.041527 -299.466056) (xy 148.040852 -299.477684) (xy 148.039582 -299.569632)
			(xy 148.049488 -299.590714) (xy 148.058632 -299.59808) (xy 148.080459 -299.616309) (xy 148.118999 -299.658124)
			(xy 148.150908 -299.705195) (xy 148.175478 -299.75648) (xy 148.192166 -299.810843) (xy 148.200603 -299.867081)
			(xy 148.201126 -299.895514) (xy 148.8346 -299.895514) (xy 148.838671 -299.839892) (xy 148.850797 -299.785455)
			(xy 148.87072 -299.733364) (xy 148.898016 -299.684729) (xy 148.932102 -299.640586) (xy 148.972251 -299.601877)
			(xy 149.017609 -299.569426) (xy 149.067209 -299.543925) (xy 149.119993 -299.525918) (xy 149.174836 -299.515788)
			(xy 149.23057 -299.513751) (xy 149.286007 -299.519851) (xy 149.339964 -299.533957) (xy 149.391293 -299.555769)
			(xy 149.438899 -299.584823) (xy 149.481767 -299.620498) (xy 149.518984 -299.662035) (xy 149.549757 -299.708548)
			(xy 149.573429 -299.759045) (xy 149.589497 -299.812452) (xy 149.597617 -299.867628) (xy 149.598126 -299.895514)
			(xy 149.72106 -299.895514) (xy 149.725131 -299.839892) (xy 149.737257 -299.785455) (xy 149.75718 -299.733364)
			(xy 149.784476 -299.684729) (xy 149.818562 -299.640586) (xy 149.858711 -299.601877) (xy 149.904069 -299.569426)
			(xy 149.953669 -299.543925) (xy 150.006453 -299.525918) (xy 150.061296 -299.515788) (xy 150.11703 -299.513751)
			(xy 150.172467 -299.519851) (xy 150.226424 -299.533957) (xy 150.277753 -299.555769) (xy 150.325359 -299.584823)
			(xy 150.368227 -299.620498) (xy 150.405444 -299.662035) (xy 150.436217 -299.708548) (xy 150.459889 -299.759045)
			(xy 150.475957 -299.812452) (xy 150.484077 -299.867628) (xy 150.484586 -299.895514) (xy 150.484077 -299.9234)
			(xy 150.475957 -299.978576) (xy 150.459889 -300.031983) (xy 150.436217 -300.08248) (xy 150.405444 -300.128993)
			(xy 150.368227 -300.17053) (xy 150.325359 -300.206205) (xy 150.277753 -300.235259) (xy 150.226424 -300.257071)
			(xy 150.172467 -300.271177) (xy 150.11703 -300.277277) (xy 150.061296 -300.27524) (xy 150.006453 -300.26511)
			(xy 149.953669 -300.247103) (xy 149.904069 -300.221602) (xy 149.858711 -300.189151) (xy 149.818562 -300.150442)
			(xy 149.784476 -300.106299) (xy 149.75718 -300.057664) (xy 149.737257 -300.005573) (xy 149.725131 -299.951136)
			(xy 149.72106 -299.895514) (xy 149.598126 -299.895514) (xy 149.597617 -299.9234) (xy 149.589497 -299.978576)
			(xy 149.573429 -300.031983) (xy 149.549757 -300.08248) (xy 149.518984 -300.128993) (xy 149.481767 -300.17053)
			(xy 149.438899 -300.206205) (xy 149.391293 -300.235259) (xy 149.339964 -300.257071) (xy 149.286007 -300.271177)
			(xy 149.23057 -300.277277) (xy 149.174836 -300.27524) (xy 149.119993 -300.26511) (xy 149.067209 -300.247103)
			(xy 149.017609 -300.221602) (xy 148.972251 -300.189151) (xy 148.932102 -300.150442) (xy 148.898016 -300.106299)
			(xy 148.87072 -300.057664) (xy 148.850797 -300.005573) (xy 148.838671 -299.951136) (xy 148.8346 -299.895514)
			(xy 148.201126 -299.895514) (xy 148.20064 -299.922765) (xy 148.192884 -299.976713) (xy 148.177529 -300.029008)
			(xy 148.154887 -300.078585) (xy 148.125421 -300.124435) (xy 148.08973 -300.165626) (xy 148.048539 -300.201317)
			(xy 148.002689 -300.230783) (xy 147.953112 -300.253425) (xy 147.900817 -300.26878) (xy 147.846869 -300.276536)
			(xy 147.792367 -300.276536) (xy 147.738419 -300.26878) (xy 147.686124 -300.253425) (xy 147.636547 -300.230783)
			(xy 147.590697 -300.201317) (xy 147.549506 -300.165626) (xy 147.513815 -300.124435) (xy 147.484349 -300.078585)
			(xy 147.461707 -300.029008) (xy 147.446352 -299.976713) (xy 147.438596 -299.922765) (xy 147.43811 -299.895514)
			(xy 118.832884 -299.895514) (xy 118.832884 -301.031656) (xy 141.911576 -301.031656) (xy 141.915647 -300.976034)
			(xy 141.927773 -300.921597) (xy 141.947696 -300.869506) (xy 141.974992 -300.820871) (xy 142.009078 -300.776728)
			(xy 142.049227 -300.738019) (xy 142.094585 -300.705568) (xy 142.144185 -300.680067) (xy 142.196969 -300.66206)
			(xy 142.251812 -300.65193) (xy 142.307546 -300.649893) (xy 142.362983 -300.655993) (xy 142.41694 -300.670099)
			(xy 142.468269 -300.691911) (xy 142.515875 -300.720965) (xy 142.558743 -300.75664) (xy 142.59596 -300.798177)
			(xy 142.626733 -300.84469) (xy 142.650405 -300.895187) (xy 142.666473 -300.948594) (xy 142.674593 -301.00377)
			(xy 142.675102 -301.031656) (xy 143.396714 -301.031656) (xy 143.400785 -300.976034) (xy 143.412911 -300.921597)
			(xy 143.432834 -300.869506) (xy 143.46013 -300.820871) (xy 143.494216 -300.776728) (xy 143.534365 -300.738019)
			(xy 143.579723 -300.705568) (xy 143.629323 -300.680067) (xy 143.682107 -300.66206) (xy 143.73695 -300.65193)
			(xy 143.792684 -300.649893) (xy 143.792693 -300.649894) (xy 152.644106 -300.649894) (xy 152.648066 -300.60084)
			(xy 152.659843 -300.553056) (xy 152.679134 -300.50778) (xy 152.705437 -300.466184) (xy 152.738072 -300.429347)
			(xy 152.776193 -300.398222) (xy 152.818814 -300.373615) (xy 152.86483 -300.356163) (xy 152.913049 -300.346319)
			(xy 152.962224 -300.344338) (xy 153.011079 -300.35027) (xy 153.05835 -300.363962) (xy 153.102812 -300.38506)
			(xy 153.143315 -300.413016) (xy 153.178808 -300.447108) (xy 153.208373 -300.486452) (xy 153.231244 -300.530029)
			(xy 153.246828 -300.57671) (xy 153.254723 -300.625287) (xy 153.255218 -300.649894) (xy 153.594066 -300.649894)
			(xy 153.598026 -300.60084) (xy 153.609803 -300.553056) (xy 153.629094 -300.50778) (xy 153.655397 -300.466184)
			(xy 153.688032 -300.429347) (xy 153.726153 -300.398222) (xy 153.768774 -300.373615) (xy 153.81479 -300.356163)
			(xy 153.863009 -300.346319) (xy 153.912184 -300.344338) (xy 153.961039 -300.35027) (xy 154.00831 -300.363962)
			(xy 154.052772 -300.38506) (xy 154.093275 -300.413016) (xy 154.128768 -300.447108) (xy 154.158333 -300.486452)
			(xy 154.181204 -300.530029) (xy 154.196788 -300.57671) (xy 154.204683 -300.625287) (xy 154.205178 -300.649894)
			(xy 154.54428 -300.649894) (xy 154.54824 -300.60084) (xy 154.560017 -300.553056) (xy 154.579308 -300.50778)
			(xy 154.605611 -300.466184) (xy 154.638246 -300.429347) (xy 154.676367 -300.398222) (xy 154.718988 -300.373615)
			(xy 154.765004 -300.356163) (xy 154.813223 -300.346319) (xy 154.862398 -300.344338) (xy 154.911253 -300.35027)
			(xy 154.958524 -300.363962) (xy 155.002986 -300.38506) (xy 155.043489 -300.413016) (xy 155.078982 -300.447108)
			(xy 155.108547 -300.486452) (xy 155.131418 -300.530029) (xy 155.147002 -300.57671) (xy 155.154897 -300.625287)
			(xy 155.155392 -300.649894) (xy 155.49424 -300.649894) (xy 155.4982 -300.60084) (xy 155.509977 -300.553056)
			(xy 155.529268 -300.50778) (xy 155.555571 -300.466184) (xy 155.588206 -300.429347) (xy 155.626327 -300.398222)
			(xy 155.668948 -300.373615) (xy 155.714964 -300.356163) (xy 155.763183 -300.346319) (xy 155.812358 -300.344338)
			(xy 155.861213 -300.35027) (xy 155.908484 -300.363962) (xy 155.952946 -300.38506) (xy 155.993449 -300.413016)
			(xy 156.028942 -300.447108) (xy 156.058507 -300.486452) (xy 156.081378 -300.530029) (xy 156.096962 -300.57671)
			(xy 156.104857 -300.625287) (xy 156.105352 -300.649894) (xy 156.4442 -300.649894) (xy 156.44816 -300.60084)
			(xy 156.459937 -300.553056) (xy 156.479228 -300.50778) (xy 156.505531 -300.466184) (xy 156.538166 -300.429347)
			(xy 156.576287 -300.398222) (xy 156.618908 -300.373615) (xy 156.664924 -300.356163) (xy 156.713143 -300.346319)
			(xy 156.762318 -300.344338) (xy 156.811173 -300.35027) (xy 156.858444 -300.363962) (xy 156.902906 -300.38506)
			(xy 156.943409 -300.413016) (xy 156.978902 -300.447108) (xy 157.008467 -300.486452) (xy 157.031338 -300.530029)
			(xy 157.046922 -300.57671) (xy 157.054817 -300.625287) (xy 157.055312 -300.649894) (xy 157.39416 -300.649894)
			(xy 157.39812 -300.60084) (xy 157.409897 -300.553056) (xy 157.429188 -300.50778) (xy 157.455491 -300.466184)
			(xy 157.488126 -300.429347) (xy 157.526247 -300.398222) (xy 157.568868 -300.373615) (xy 157.614884 -300.356163)
			(xy 157.663103 -300.346319) (xy 157.712278 -300.344338) (xy 157.761133 -300.35027) (xy 157.808404 -300.363962)
			(xy 157.852866 -300.38506) (xy 157.893369 -300.413016) (xy 157.928862 -300.447108) (xy 157.958427 -300.486452)
			(xy 157.981298 -300.530029) (xy 157.996882 -300.57671) (xy 158.004777 -300.625287) (xy 158.005272 -300.649894)
			(xy 158.34412 -300.649894) (xy 158.34808 -300.60084) (xy 158.359857 -300.553056) (xy 158.379148 -300.50778)
			(xy 158.405451 -300.466184) (xy 158.438086 -300.429347) (xy 158.476207 -300.398222) (xy 158.518828 -300.373615)
			(xy 158.564844 -300.356163) (xy 158.613063 -300.346319) (xy 158.662238 -300.344338) (xy 158.711093 -300.35027)
			(xy 158.758364 -300.363962) (xy 158.802826 -300.38506) (xy 158.843329 -300.413016) (xy 158.878822 -300.447108)
			(xy 158.908387 -300.486452) (xy 158.931258 -300.530029) (xy 158.946842 -300.57671) (xy 158.954737 -300.625287)
			(xy 158.955066 -300.641631) (xy 159.294175 -300.641631) (xy 159.29954 -300.592279) (xy 159.312819 -300.544446)
			(xy 159.333661 -300.499391) (xy 159.361518 -300.458301) (xy 159.395655 -300.422259) (xy 159.435174 -300.392215)
			(xy 159.479032 -300.36896) (xy 159.526075 -300.353107) (xy 159.575063 -300.345073) (xy 159.599884 -300.344586)
			(xy 159.614067 -300.344765) (xy 159.642307 -300.347436) (xy 159.656272 -300.34992) (xy 159.670242 -300.352051)
			(xy 159.698371 -300.349479) (xy 159.724717 -300.339295) (xy 159.747264 -300.322281) (xy 159.764284 -300.299738)
			(xy 159.774473 -300.273394) (xy 159.777053 -300.245266) (xy 159.77489 -300.231302) (xy 159.772418 -300.217335)
			(xy 159.769743 -300.189096) (xy 159.769556 -300.174914) (xy 159.770063 -300.150091) (xy 159.778093 -300.101099)
			(xy 159.793943 -300.054052) (xy 159.817196 -300.010188) (xy 159.84724 -299.970665) (xy 159.883282 -299.936523)
			(xy 159.924372 -299.908662) (xy 159.969429 -299.887816) (xy 160.017266 -299.874534) (xy 160.06662 -299.869167)
			(xy 160.116193 -299.871855) (xy 160.164678 -299.882529) (xy 160.210797 -299.900905) (xy 160.253336 -299.926502)
			(xy 160.291173 -299.958643) (xy 160.323311 -299.996482) (xy 160.348904 -300.039022) (xy 160.367278 -300.085143)
			(xy 160.377948 -300.133629) (xy 160.380183 -300.174914) (xy 160.719274 -300.174914) (xy 160.723234 -300.12586)
			(xy 160.735011 -300.078076) (xy 160.754302 -300.0328) (xy 160.780605 -299.991204) (xy 160.81324 -299.954367)
			(xy 160.851361 -299.923242) (xy 160.893982 -299.898635) (xy 160.939998 -299.881183) (xy 160.988217 -299.871339)
			(xy 161.037392 -299.869358) (xy 161.086247 -299.87529) (xy 161.133518 -299.888982) (xy 161.17798 -299.91008)
			(xy 161.218483 -299.938036) (xy 161.253976 -299.972128) (xy 161.283541 -300.011472) (xy 161.306412 -300.055049)
			(xy 161.321996 -300.10173) (xy 161.329891 -300.150307) (xy 161.330386 -300.174914) (xy 161.669234 -300.174914)
			(xy 161.673194 -300.12586) (xy 161.684971 -300.078076) (xy 161.704262 -300.0328) (xy 161.730565 -299.991204)
			(xy 161.7632 -299.954367) (xy 161.801321 -299.923242) (xy 161.843942 -299.898635) (xy 161.889958 -299.881183)
			(xy 161.938177 -299.871339) (xy 161.987352 -299.869358) (xy 162.036207 -299.87529) (xy 162.083478 -299.888982)
			(xy 162.12794 -299.91008) (xy 162.168443 -299.938036) (xy 162.203936 -299.972128) (xy 162.233501 -300.011472)
			(xy 162.256372 -300.055049) (xy 162.271956 -300.10173) (xy 162.279851 -300.150307) (xy 162.280346 -300.174914)
			(xy 163.569154 -300.174914) (xy 163.573114 -300.12586) (xy 163.584891 -300.078076) (xy 163.604182 -300.0328)
			(xy 163.630485 -299.991204) (xy 163.66312 -299.954367) (xy 163.701241 -299.923242) (xy 163.743862 -299.898635)
			(xy 163.789878 -299.881183) (xy 163.838097 -299.871339) (xy 163.887272 -299.869358) (xy 163.936127 -299.87529)
			(xy 163.983398 -299.888982) (xy 164.02786 -299.91008) (xy 164.068363 -299.938036) (xy 164.103856 -299.972128)
			(xy 164.133421 -300.011472) (xy 164.156292 -300.055049) (xy 164.171876 -300.10173) (xy 164.179771 -300.150307)
			(xy 164.180266 -300.174914) (xy 164.519114 -300.174914) (xy 164.523074 -300.12586) (xy 164.534851 -300.078076)
			(xy 164.554142 -300.0328) (xy 164.580445 -299.991204) (xy 164.61308 -299.954367) (xy 164.651201 -299.923242)
			(xy 164.693822 -299.898635) (xy 164.739838 -299.881183) (xy 164.788057 -299.871339) (xy 164.837232 -299.869358)
			(xy 164.886087 -299.87529) (xy 164.933358 -299.888982) (xy 164.97782 -299.91008) (xy 165.018323 -299.938036)
			(xy 165.053816 -299.972128) (xy 165.083381 -300.011472) (xy 165.106252 -300.055049) (xy 165.121836 -300.10173)
			(xy 165.129731 -300.150307) (xy 165.130226 -300.174914) (xy 166.419288 -300.174914) (xy 166.423248 -300.12586)
			(xy 166.435025 -300.078076) (xy 166.454316 -300.0328) (xy 166.480619 -299.991204) (xy 166.513254 -299.954367)
			(xy 166.551375 -299.923242) (xy 166.593996 -299.898635) (xy 166.640012 -299.881183) (xy 166.688231 -299.871339)
			(xy 166.737406 -299.869358) (xy 166.786261 -299.87529) (xy 166.833532 -299.888982) (xy 166.877994 -299.91008)
			(xy 166.918497 -299.938036) (xy 166.95399 -299.972128) (xy 166.983555 -300.011472) (xy 167.006426 -300.055049)
			(xy 167.02201 -300.10173) (xy 167.029905 -300.150307) (xy 167.0304 -300.174914) (xy 167.369248 -300.174914)
			(xy 167.373208 -300.12586) (xy 167.384985 -300.078076) (xy 167.404276 -300.0328) (xy 167.430579 -299.991204)
			(xy 167.463214 -299.954367) (xy 167.501335 -299.923242) (xy 167.543956 -299.898635) (xy 167.589972 -299.881183)
			(xy 167.638191 -299.871339) (xy 167.687366 -299.869358) (xy 167.736221 -299.87529) (xy 167.783492 -299.888982)
			(xy 167.827954 -299.91008) (xy 167.868457 -299.938036) (xy 167.90395 -299.972128) (xy 167.933515 -300.011472)
			(xy 167.956386 -300.055049) (xy 167.97197 -300.10173) (xy 167.979865 -300.150307) (xy 167.98036 -300.174914)
			(xy 168.319208 -300.174914) (xy 168.323168 -300.12586) (xy 168.334945 -300.078076) (xy 168.354236 -300.0328)
			(xy 168.380539 -299.991204) (xy 168.413174 -299.954367) (xy 168.451295 -299.923242) (xy 168.493916 -299.898635)
			(xy 168.539932 -299.881183) (xy 168.588151 -299.871339) (xy 168.637326 -299.869358) (xy 168.686181 -299.87529)
			(xy 168.733452 -299.888982) (xy 168.777914 -299.91008) (xy 168.818417 -299.938036) (xy 168.85391 -299.972128)
			(xy 168.883475 -300.011472) (xy 168.906346 -300.055049) (xy 168.92193 -300.10173) (xy 168.929825 -300.150307)
			(xy 168.93032 -300.174914) (xy 169.269168 -300.174914) (xy 169.273128 -300.12586) (xy 169.284905 -300.078076)
			(xy 169.304196 -300.0328) (xy 169.330499 -299.991204) (xy 169.363134 -299.954367) (xy 169.401255 -299.923242)
			(xy 169.443876 -299.898635) (xy 169.489892 -299.881183) (xy 169.538111 -299.871339) (xy 169.587286 -299.869358)
			(xy 169.636141 -299.87529) (xy 169.683412 -299.888982) (xy 169.727874 -299.91008) (xy 169.768377 -299.938036)
			(xy 169.80387 -299.972128) (xy 169.833435 -300.011472) (xy 169.856306 -300.055049) (xy 169.87189 -300.10173)
			(xy 169.879785 -300.150307) (xy 169.88028 -300.174914) (xy 170.219128 -300.174914) (xy 170.223088 -300.12586)
			(xy 170.234865 -300.078076) (xy 170.254156 -300.0328) (xy 170.280459 -299.991204) (xy 170.313094 -299.954367)
			(xy 170.351215 -299.923242) (xy 170.393836 -299.898635) (xy 170.439852 -299.881183) (xy 170.488071 -299.871339)
			(xy 170.537246 -299.869358) (xy 170.586101 -299.87529) (xy 170.633372 -299.888982) (xy 170.677834 -299.91008)
			(xy 170.718337 -299.938036) (xy 170.75383 -299.972128) (xy 170.783395 -300.011472) (xy 170.806266 -300.055049)
			(xy 170.82185 -300.10173) (xy 170.829745 -300.150307) (xy 170.83024 -300.174914) (xy 171.169088 -300.174914)
			(xy 171.173048 -300.12586) (xy 171.184825 -300.078076) (xy 171.204116 -300.0328) (xy 171.230419 -299.991204)
			(xy 171.263054 -299.954367) (xy 171.301175 -299.923242) (xy 171.343796 -299.898635) (xy 171.389812 -299.881183)
			(xy 171.438031 -299.871339) (xy 171.487206 -299.869358) (xy 171.536061 -299.87529) (xy 171.583332 -299.888982)
			(xy 171.627794 -299.91008) (xy 171.668297 -299.938036) (xy 171.70379 -299.972128) (xy 171.733355 -300.011472)
			(xy 171.756226 -300.055049) (xy 171.77181 -300.10173) (xy 171.779705 -300.150307) (xy 171.7802 -300.174914)
			(xy 172.119048 -300.174914) (xy 172.123008 -300.12586) (xy 172.134785 -300.078076) (xy 172.154076 -300.0328)
			(xy 172.180379 -299.991204) (xy 172.213014 -299.954367) (xy 172.251135 -299.923242) (xy 172.293756 -299.898635)
			(xy 172.339772 -299.881183) (xy 172.387991 -299.871339) (xy 172.437166 -299.869358) (xy 172.486021 -299.87529)
			(xy 172.533292 -299.888982) (xy 172.577754 -299.91008) (xy 172.618257 -299.938036) (xy 172.65375 -299.972128)
			(xy 172.683315 -300.011472) (xy 172.706186 -300.055049) (xy 172.72177 -300.10173) (xy 172.729665 -300.150307)
			(xy 172.73016 -300.174914) (xy 173.069262 -300.174914) (xy 173.073222 -300.12586) (xy 173.084999 -300.078076)
			(xy 173.10429 -300.0328) (xy 173.130593 -299.991204) (xy 173.163228 -299.954367) (xy 173.201349 -299.923242)
			(xy 173.24397 -299.898635) (xy 173.289986 -299.881183) (xy 173.338205 -299.871339) (xy 173.38738 -299.869358)
			(xy 173.436235 -299.87529) (xy 173.483506 -299.888982) (xy 173.527968 -299.91008) (xy 173.568471 -299.938036)
			(xy 173.603964 -299.972128) (xy 173.633529 -300.011472) (xy 173.6564 -300.055049) (xy 173.671984 -300.10173)
			(xy 173.679879 -300.150307) (xy 173.680374 -300.174914) (xy 174.019222 -300.174914) (xy 174.023182 -300.12586)
			(xy 174.034959 -300.078076) (xy 174.05425 -300.0328) (xy 174.080553 -299.991204) (xy 174.113188 -299.954367)
			(xy 174.151309 -299.923242) (xy 174.19393 -299.898635) (xy 174.239946 -299.881183) (xy 174.288165 -299.871339)
			(xy 174.33734 -299.869358) (xy 174.386195 -299.87529) (xy 174.433466 -299.888982) (xy 174.477928 -299.91008)
			(xy 174.518431 -299.938036) (xy 174.553924 -299.972128) (xy 174.583489 -300.011472) (xy 174.60636 -300.055049)
			(xy 174.621944 -300.10173) (xy 174.629839 -300.150307) (xy 174.630334 -300.174914) (xy 175.919142 -300.174914)
			(xy 175.923102 -300.12586) (xy 175.934879 -300.078076) (xy 175.95417 -300.0328) (xy 175.980473 -299.991204)
			(xy 176.013108 -299.954367) (xy 176.051229 -299.923242) (xy 176.09385 -299.898635) (xy 176.139866 -299.881183)
			(xy 176.188085 -299.871339) (xy 176.23726 -299.869358) (xy 176.286115 -299.87529) (xy 176.333386 -299.888982)
			(xy 176.377848 -299.91008) (xy 176.418351 -299.938036) (xy 176.453844 -299.972128) (xy 176.483409 -300.011472)
			(xy 176.50628 -300.055049) (xy 176.521864 -300.10173) (xy 176.529759 -300.150307) (xy 176.530254 -300.174914)
			(xy 176.869102 -300.174914) (xy 176.873062 -300.12586) (xy 176.884839 -300.078076) (xy 176.90413 -300.0328)
			(xy 176.930433 -299.991204) (xy 176.963068 -299.954367) (xy 177.001189 -299.923242) (xy 177.04381 -299.898635)
			(xy 177.089826 -299.881183) (xy 177.138045 -299.871339) (xy 177.18722 -299.869358) (xy 177.236075 -299.87529)
			(xy 177.283346 -299.888982) (xy 177.327808 -299.91008) (xy 177.368311 -299.938036) (xy 177.403804 -299.972128)
			(xy 177.433369 -300.011472) (xy 177.45624 -300.055049) (xy 177.471824 -300.10173) (xy 177.479719 -300.150307)
			(xy 177.480214 -300.174914) (xy 177.819062 -300.174914) (xy 177.823022 -300.12586) (xy 177.834799 -300.078076)
			(xy 177.85409 -300.0328) (xy 177.880393 -299.991204) (xy 177.913028 -299.954367) (xy 177.951149 -299.923242)
			(xy 177.99377 -299.898635) (xy 178.039786 -299.881183) (xy 178.088005 -299.871339) (xy 178.13718 -299.869358)
			(xy 178.186035 -299.87529) (xy 178.233306 -299.888982) (xy 178.277768 -299.91008) (xy 178.318271 -299.938036)
			(xy 178.353764 -299.972128) (xy 178.383329 -300.011472) (xy 178.4062 -300.055049) (xy 178.421784 -300.10173)
			(xy 178.429679 -300.150307) (xy 178.430174 -300.174914) (xy 178.769276 -300.174914) (xy 178.773236 -300.12586)
			(xy 178.785013 -300.078076) (xy 178.804304 -300.0328) (xy 178.830607 -299.991204) (xy 178.863242 -299.954367)
			(xy 178.901363 -299.923242) (xy 178.943984 -299.898635) (xy 178.99 -299.881183) (xy 179.038219 -299.871339)
			(xy 179.087394 -299.869358) (xy 179.136249 -299.87529) (xy 179.18352 -299.888982) (xy 179.227982 -299.91008)
			(xy 179.268485 -299.938036) (xy 179.303978 -299.972128) (xy 179.333543 -300.011472) (xy 179.356414 -300.055049)
			(xy 179.371998 -300.10173) (xy 179.379893 -300.150307) (xy 179.380388 -300.174914) (xy 179.719236 -300.174914)
			(xy 179.723196 -300.12586) (xy 179.734973 -300.078076) (xy 179.754264 -300.0328) (xy 179.780567 -299.991204)
			(xy 179.813202 -299.954367) (xy 179.851323 -299.923242) (xy 179.893944 -299.898635) (xy 179.93996 -299.881183)
			(xy 179.988179 -299.871339) (xy 180.037354 -299.869358) (xy 180.086209 -299.87529) (xy 180.13348 -299.888982)
			(xy 180.177942 -299.91008) (xy 180.218445 -299.938036) (xy 180.253938 -299.972128) (xy 180.283503 -300.011472)
			(xy 180.306374 -300.055049) (xy 180.321958 -300.10173) (xy 180.329853 -300.150307) (xy 180.330348 -300.174914)
			(xy 180.669196 -300.174914) (xy 180.673156 -300.12586) (xy 180.684933 -300.078076) (xy 180.704224 -300.0328)
			(xy 180.730527 -299.991204) (xy 180.763162 -299.954367) (xy 180.801283 -299.923242) (xy 180.843904 -299.898635)
			(xy 180.88992 -299.881183) (xy 180.938139 -299.871339) (xy 180.987314 -299.869358) (xy 181.036169 -299.87529)
			(xy 181.08344 -299.888982) (xy 181.127902 -299.91008) (xy 181.168405 -299.938036) (xy 181.203898 -299.972128)
			(xy 181.233463 -300.011472) (xy 181.256334 -300.055049) (xy 181.271918 -300.10173) (xy 181.279813 -300.150307)
			(xy 181.280308 -300.174914) (xy 181.619156 -300.174914) (xy 181.623116 -300.12586) (xy 181.634893 -300.078076)
			(xy 181.654184 -300.0328) (xy 181.680487 -299.991204) (xy 181.713122 -299.954367) (xy 181.751243 -299.923242)
			(xy 181.793864 -299.898635) (xy 181.83988 -299.881183) (xy 181.888099 -299.871339) (xy 181.937274 -299.869358)
			(xy 181.986129 -299.87529) (xy 182.0334 -299.888982) (xy 182.077862 -299.91008) (xy 182.118365 -299.938036)
			(xy 182.153858 -299.972128) (xy 182.183423 -300.011472) (xy 182.206294 -300.055049) (xy 182.221878 -300.10173)
			(xy 182.229773 -300.150307) (xy 182.230268 -300.174914) (xy 182.569116 -300.174914) (xy 182.573076 -300.12586)
			(xy 182.584853 -300.078076) (xy 182.604144 -300.0328) (xy 182.630447 -299.991204) (xy 182.663082 -299.954367)
			(xy 182.701203 -299.923242) (xy 182.743824 -299.898635) (xy 182.78984 -299.881183) (xy 182.838059 -299.871339)
			(xy 182.887234 -299.869358) (xy 182.936089 -299.87529) (xy 182.98336 -299.888982) (xy 183.027822 -299.91008)
			(xy 183.068325 -299.938036) (xy 183.103818 -299.972128) (xy 183.133383 -300.011472) (xy 183.156254 -300.055049)
			(xy 183.171838 -300.10173) (xy 183.179733 -300.150307) (xy 183.180228 -300.174914) (xy 183.519076 -300.174914)
			(xy 183.523036 -300.12586) (xy 183.534813 -300.078076) (xy 183.554104 -300.0328) (xy 183.580407 -299.991204)
			(xy 183.613042 -299.954367) (xy 183.651163 -299.923242) (xy 183.693784 -299.898635) (xy 183.7398 -299.881183)
			(xy 183.788019 -299.871339) (xy 183.837194 -299.869358) (xy 183.886049 -299.87529) (xy 183.93332 -299.888982)
			(xy 183.977782 -299.91008) (xy 184.018285 -299.938036) (xy 184.053778 -299.972128) (xy 184.083343 -300.011472)
			(xy 184.106214 -300.055049) (xy 184.121798 -300.10173) (xy 184.129693 -300.150307) (xy 184.130188 -300.174914)
			(xy 184.129693 -300.199521) (xy 184.121798 -300.248098) (xy 184.106214 -300.294779) (xy 184.083343 -300.338356)
			(xy 184.053778 -300.3777) (xy 184.018285 -300.411792) (xy 183.977782 -300.439748) (xy 183.93332 -300.460846)
			(xy 183.886049 -300.474538) (xy 183.837194 -300.48047) (xy 183.788019 -300.478489) (xy 183.7398 -300.468645)
			(xy 183.693784 -300.451193) (xy 183.651163 -300.426586) (xy 183.613042 -300.395461) (xy 183.580407 -300.358624)
			(xy 183.554104 -300.317028) (xy 183.534813 -300.271752) (xy 183.523036 -300.223968) (xy 183.519076 -300.174914)
			(xy 183.180228 -300.174914) (xy 183.179733 -300.199521) (xy 183.171838 -300.248098) (xy 183.156254 -300.294779)
			(xy 183.133383 -300.338356) (xy 183.103818 -300.3777) (xy 183.068325 -300.411792) (xy 183.027822 -300.439748)
			(xy 182.98336 -300.460846) (xy 182.936089 -300.474538) (xy 182.887234 -300.48047) (xy 182.838059 -300.478489)
			(xy 182.78984 -300.468645) (xy 182.743824 -300.451193) (xy 182.701203 -300.426586) (xy 182.663082 -300.395461)
			(xy 182.630447 -300.358624) (xy 182.604144 -300.317028) (xy 182.584853 -300.271752) (xy 182.573076 -300.223968)
			(xy 182.569116 -300.174914) (xy 182.230268 -300.174914) (xy 182.229773 -300.199521) (xy 182.221878 -300.248098)
			(xy 182.206294 -300.294779) (xy 182.183423 -300.338356) (xy 182.153858 -300.3777) (xy 182.118365 -300.411792)
			(xy 182.077862 -300.439748) (xy 182.0334 -300.460846) (xy 181.986129 -300.474538) (xy 181.937274 -300.48047)
			(xy 181.888099 -300.478489) (xy 181.83988 -300.468645) (xy 181.793864 -300.451193) (xy 181.751243 -300.426586)
			(xy 181.713122 -300.395461) (xy 181.680487 -300.358624) (xy 181.654184 -300.317028) (xy 181.634893 -300.271752)
			(xy 181.623116 -300.223968) (xy 181.619156 -300.174914) (xy 181.280308 -300.174914) (xy 181.279813 -300.199521)
			(xy 181.271918 -300.248098) (xy 181.256334 -300.294779) (xy 181.233463 -300.338356) (xy 181.203898 -300.3777)
			(xy 181.168405 -300.411792) (xy 181.127902 -300.439748) (xy 181.08344 -300.460846) (xy 181.036169 -300.474538)
			(xy 180.987314 -300.48047) (xy 180.938139 -300.478489) (xy 180.88992 -300.468645) (xy 180.843904 -300.451193)
			(xy 180.801283 -300.426586) (xy 180.763162 -300.395461) (xy 180.730527 -300.358624) (xy 180.704224 -300.317028)
			(xy 180.684933 -300.271752) (xy 180.673156 -300.223968) (xy 180.669196 -300.174914) (xy 180.330348 -300.174914)
			(xy 180.329853 -300.199521) (xy 180.321958 -300.248098) (xy 180.306374 -300.294779) (xy 180.283503 -300.338356)
			(xy 180.253938 -300.3777) (xy 180.218445 -300.411792) (xy 180.177942 -300.439748) (xy 180.13348 -300.460846)
			(xy 180.086209 -300.474538) (xy 180.037354 -300.48047) (xy 179.988179 -300.478489) (xy 179.93996 -300.468645)
			(xy 179.893944 -300.451193) (xy 179.851323 -300.426586) (xy 179.813202 -300.395461) (xy 179.780567 -300.358624)
			(xy 179.754264 -300.317028) (xy 179.734973 -300.271752) (xy 179.723196 -300.223968) (xy 179.719236 -300.174914)
			(xy 179.380388 -300.174914) (xy 179.379893 -300.199521) (xy 179.371998 -300.248098) (xy 179.356414 -300.294779)
			(xy 179.333543 -300.338356) (xy 179.303978 -300.3777) (xy 179.268485 -300.411792) (xy 179.227982 -300.439748)
			(xy 179.18352 -300.460846) (xy 179.136249 -300.474538) (xy 179.087394 -300.48047) (xy 179.038219 -300.478489)
			(xy 178.99 -300.468645) (xy 178.943984 -300.451193) (xy 178.901363 -300.426586) (xy 178.863242 -300.395461)
			(xy 178.830607 -300.358624) (xy 178.804304 -300.317028) (xy 178.785013 -300.271752) (xy 178.773236 -300.223968)
			(xy 178.769276 -300.174914) (xy 178.430174 -300.174914) (xy 178.429679 -300.199521) (xy 178.421784 -300.248098)
			(xy 178.4062 -300.294779) (xy 178.383329 -300.338356) (xy 178.353764 -300.3777) (xy 178.318271 -300.411792)
			(xy 178.277768 -300.439748) (xy 178.233306 -300.460846) (xy 178.186035 -300.474538) (xy 178.13718 -300.48047)
			(xy 178.088005 -300.478489) (xy 178.039786 -300.468645) (xy 177.99377 -300.451193) (xy 177.951149 -300.426586)
			(xy 177.913028 -300.395461) (xy 177.880393 -300.358624) (xy 177.85409 -300.317028) (xy 177.834799 -300.271752)
			(xy 177.823022 -300.223968) (xy 177.819062 -300.174914) (xy 177.480214 -300.174914) (xy 177.479719 -300.199521)
			(xy 177.471824 -300.248098) (xy 177.45624 -300.294779) (xy 177.433369 -300.338356) (xy 177.403804 -300.3777)
			(xy 177.368311 -300.411792) (xy 177.327808 -300.439748) (xy 177.283346 -300.460846) (xy 177.236075 -300.474538)
			(xy 177.18722 -300.48047) (xy 177.138045 -300.478489) (xy 177.089826 -300.468645) (xy 177.04381 -300.451193)
			(xy 177.001189 -300.426586) (xy 176.963068 -300.395461) (xy 176.930433 -300.358624) (xy 176.90413 -300.317028)
			(xy 176.884839 -300.271752) (xy 176.873062 -300.223968) (xy 176.869102 -300.174914) (xy 176.530254 -300.174914)
			(xy 176.529759 -300.199521) (xy 176.521864 -300.248098) (xy 176.50628 -300.294779) (xy 176.483409 -300.338356)
			(xy 176.453844 -300.3777) (xy 176.418351 -300.411792) (xy 176.377848 -300.439748) (xy 176.333386 -300.460846)
			(xy 176.286115 -300.474538) (xy 176.23726 -300.48047) (xy 176.188085 -300.478489) (xy 176.139866 -300.468645)
			(xy 176.09385 -300.451193) (xy 176.051229 -300.426586) (xy 176.013108 -300.395461) (xy 175.980473 -300.358624)
			(xy 175.95417 -300.317028) (xy 175.934879 -300.271752) (xy 175.923102 -300.223968) (xy 175.919142 -300.174914)
			(xy 174.630334 -300.174914) (xy 174.629839 -300.199521) (xy 174.621944 -300.248098) (xy 174.60636 -300.294779)
			(xy 174.583489 -300.338356) (xy 174.553924 -300.3777) (xy 174.518431 -300.411792) (xy 174.477928 -300.439748)
			(xy 174.433466 -300.460846) (xy 174.386195 -300.474538) (xy 174.33734 -300.48047) (xy 174.288165 -300.478489)
			(xy 174.239946 -300.468645) (xy 174.19393 -300.451193) (xy 174.151309 -300.426586) (xy 174.113188 -300.395461)
			(xy 174.080553 -300.358624) (xy 174.05425 -300.317028) (xy 174.034959 -300.271752) (xy 174.023182 -300.223968)
			(xy 174.019222 -300.174914) (xy 173.680374 -300.174914) (xy 173.679879 -300.199521) (xy 173.671984 -300.248098)
			(xy 173.6564 -300.294779) (xy 173.633529 -300.338356) (xy 173.603964 -300.3777) (xy 173.568471 -300.411792)
			(xy 173.527968 -300.439748) (xy 173.483506 -300.460846) (xy 173.436235 -300.474538) (xy 173.38738 -300.48047)
			(xy 173.338205 -300.478489) (xy 173.289986 -300.468645) (xy 173.24397 -300.451193) (xy 173.201349 -300.426586)
			(xy 173.163228 -300.395461) (xy 173.130593 -300.358624) (xy 173.10429 -300.317028) (xy 173.084999 -300.271752)
			(xy 173.073222 -300.223968) (xy 173.069262 -300.174914) (xy 172.73016 -300.174914) (xy 172.729665 -300.199521)
			(xy 172.72177 -300.248098) (xy 172.706186 -300.294779) (xy 172.683315 -300.338356) (xy 172.65375 -300.3777)
			(xy 172.618257 -300.411792) (xy 172.577754 -300.439748) (xy 172.533292 -300.460846) (xy 172.486021 -300.474538)
			(xy 172.437166 -300.48047) (xy 172.387991 -300.478489) (xy 172.339772 -300.468645) (xy 172.293756 -300.451193)
			(xy 172.251135 -300.426586) (xy 172.213014 -300.395461) (xy 172.180379 -300.358624) (xy 172.154076 -300.317028)
			(xy 172.134785 -300.271752) (xy 172.123008 -300.223968) (xy 172.119048 -300.174914) (xy 171.7802 -300.174914)
			(xy 171.779705 -300.199521) (xy 171.77181 -300.248098) (xy 171.756226 -300.294779) (xy 171.733355 -300.338356)
			(xy 171.70379 -300.3777) (xy 171.668297 -300.411792) (xy 171.627794 -300.439748) (xy 171.583332 -300.460846)
			(xy 171.536061 -300.474538) (xy 171.487206 -300.48047) (xy 171.438031 -300.478489) (xy 171.389812 -300.468645)
			(xy 171.343796 -300.451193) (xy 171.301175 -300.426586) (xy 171.263054 -300.395461) (xy 171.230419 -300.358624)
			(xy 171.204116 -300.317028) (xy 171.184825 -300.271752) (xy 171.173048 -300.223968) (xy 171.169088 -300.174914)
			(xy 170.83024 -300.174914) (xy 170.829745 -300.199521) (xy 170.82185 -300.248098) (xy 170.806266 -300.294779)
			(xy 170.783395 -300.338356) (xy 170.75383 -300.3777) (xy 170.718337 -300.411792) (xy 170.677834 -300.439748)
			(xy 170.633372 -300.460846) (xy 170.586101 -300.474538) (xy 170.537246 -300.48047) (xy 170.488071 -300.478489)
			(xy 170.439852 -300.468645) (xy 170.393836 -300.451193) (xy 170.351215 -300.426586) (xy 170.313094 -300.395461)
			(xy 170.280459 -300.358624) (xy 170.254156 -300.317028) (xy 170.234865 -300.271752) (xy 170.223088 -300.223968)
			(xy 170.219128 -300.174914) (xy 169.88028 -300.174914) (xy 169.879785 -300.199521) (xy 169.87189 -300.248098)
			(xy 169.856306 -300.294779) (xy 169.833435 -300.338356) (xy 169.80387 -300.3777) (xy 169.768377 -300.411792)
			(xy 169.727874 -300.439748) (xy 169.683412 -300.460846) (xy 169.636141 -300.474538) (xy 169.587286 -300.48047)
			(xy 169.538111 -300.478489) (xy 169.489892 -300.468645) (xy 169.443876 -300.451193) (xy 169.401255 -300.426586)
			(xy 169.363134 -300.395461) (xy 169.330499 -300.358624) (xy 169.304196 -300.317028) (xy 169.284905 -300.271752)
			(xy 169.273128 -300.223968) (xy 169.269168 -300.174914) (xy 168.93032 -300.174914) (xy 168.929825 -300.199521)
			(xy 168.92193 -300.248098) (xy 168.906346 -300.294779) (xy 168.883475 -300.338356) (xy 168.85391 -300.3777)
			(xy 168.818417 -300.411792) (xy 168.777914 -300.439748) (xy 168.733452 -300.460846) (xy 168.686181 -300.474538)
			(xy 168.637326 -300.48047) (xy 168.588151 -300.478489) (xy 168.539932 -300.468645) (xy 168.493916 -300.451193)
			(xy 168.451295 -300.426586) (xy 168.413174 -300.395461) (xy 168.380539 -300.358624) (xy 168.354236 -300.317028)
			(xy 168.334945 -300.271752) (xy 168.323168 -300.223968) (xy 168.319208 -300.174914) (xy 167.98036 -300.174914)
			(xy 167.979865 -300.199521) (xy 167.97197 -300.248098) (xy 167.956386 -300.294779) (xy 167.933515 -300.338356)
			(xy 167.90395 -300.3777) (xy 167.868457 -300.411792) (xy 167.827954 -300.439748) (xy 167.783492 -300.460846)
			(xy 167.736221 -300.474538) (xy 167.687366 -300.48047) (xy 167.638191 -300.478489) (xy 167.589972 -300.468645)
			(xy 167.543956 -300.451193) (xy 167.501335 -300.426586) (xy 167.463214 -300.395461) (xy 167.430579 -300.358624)
			(xy 167.404276 -300.317028) (xy 167.384985 -300.271752) (xy 167.373208 -300.223968) (xy 167.369248 -300.174914)
			(xy 167.0304 -300.174914) (xy 167.029905 -300.199521) (xy 167.02201 -300.248098) (xy 167.006426 -300.294779)
			(xy 166.983555 -300.338356) (xy 166.95399 -300.3777) (xy 166.918497 -300.411792) (xy 166.877994 -300.439748)
			(xy 166.833532 -300.460846) (xy 166.786261 -300.474538) (xy 166.737406 -300.48047) (xy 166.688231 -300.478489)
			(xy 166.640012 -300.468645) (xy 166.593996 -300.451193) (xy 166.551375 -300.426586) (xy 166.513254 -300.395461)
			(xy 166.480619 -300.358624) (xy 166.454316 -300.317028) (xy 166.435025 -300.271752) (xy 166.423248 -300.223968)
			(xy 166.419288 -300.174914) (xy 165.130226 -300.174914) (xy 165.129731 -300.199521) (xy 165.121836 -300.248098)
			(xy 165.106252 -300.294779) (xy 165.083381 -300.338356) (xy 165.053816 -300.3777) (xy 165.018323 -300.411792)
			(xy 164.97782 -300.439748) (xy 164.933358 -300.460846) (xy 164.886087 -300.474538) (xy 164.837232 -300.48047)
			(xy 164.788057 -300.478489) (xy 164.739838 -300.468645) (xy 164.693822 -300.451193) (xy 164.651201 -300.426586)
			(xy 164.61308 -300.395461) (xy 164.580445 -300.358624) (xy 164.554142 -300.317028) (xy 164.534851 -300.271752)
			(xy 164.523074 -300.223968) (xy 164.519114 -300.174914) (xy 164.180266 -300.174914) (xy 164.179771 -300.199521)
			(xy 164.171876 -300.248098) (xy 164.156292 -300.294779) (xy 164.133421 -300.338356) (xy 164.103856 -300.3777)
			(xy 164.068363 -300.411792) (xy 164.02786 -300.439748) (xy 163.983398 -300.460846) (xy 163.936127 -300.474538)
			(xy 163.887272 -300.48047) (xy 163.838097 -300.478489) (xy 163.789878 -300.468645) (xy 163.743862 -300.451193)
			(xy 163.701241 -300.426586) (xy 163.66312 -300.395461) (xy 163.630485 -300.358624) (xy 163.604182 -300.317028)
			(xy 163.584891 -300.271752) (xy 163.573114 -300.223968) (xy 163.569154 -300.174914) (xy 162.280346 -300.174914)
			(xy 162.279851 -300.199521) (xy 162.271956 -300.248098) (xy 162.256372 -300.294779) (xy 162.233501 -300.338356)
			(xy 162.203936 -300.3777) (xy 162.168443 -300.411792) (xy 162.12794 -300.439748) (xy 162.083478 -300.460846)
			(xy 162.036207 -300.474538) (xy 161.987352 -300.48047) (xy 161.938177 -300.478489) (xy 161.889958 -300.468645)
			(xy 161.843942 -300.451193) (xy 161.801321 -300.426586) (xy 161.7632 -300.395461) (xy 161.730565 -300.358624)
			(xy 161.704262 -300.317028) (xy 161.684971 -300.271752) (xy 161.673194 -300.223968) (xy 161.669234 -300.174914)
			(xy 161.330386 -300.174914) (xy 161.329891 -300.199521) (xy 161.321996 -300.248098) (xy 161.306412 -300.294779)
			(xy 161.283541 -300.338356) (xy 161.253976 -300.3777) (xy 161.218483 -300.411792) (xy 161.17798 -300.439748)
			(xy 161.133518 -300.460846) (xy 161.086247 -300.474538) (xy 161.037392 -300.48047) (xy 160.988217 -300.478489)
			(xy 160.939998 -300.468645) (xy 160.893982 -300.451193) (xy 160.851361 -300.426586) (xy 160.81324 -300.395461)
			(xy 160.780605 -300.358624) (xy 160.754302 -300.317028) (xy 160.735011 -300.271752) (xy 160.723234 -300.223968)
			(xy 160.719274 -300.174914) (xy 160.380183 -300.174914) (xy 160.380632 -300.183202) (xy 160.375261 -300.232556)
			(xy 160.361976 -300.280391) (xy 160.341127 -300.325447) (xy 160.313263 -300.366536) (xy 160.279118 -300.402575)
			(xy 160.239593 -300.432616) (xy 160.195728 -300.455866) (xy 160.14868 -300.471713) (xy 160.099687 -300.479739)
			(xy 160.074864 -300.480222) (xy 160.060681 -300.48005) (xy 160.032441 -300.477375) (xy 160.018476 -300.474888)
			(xy 160.004514 -300.472693) (xy 159.976379 -300.475278) (xy 159.950029 -300.485473) (xy 159.927482 -300.502499)
			(xy 159.910462 -300.52505) (xy 159.900273 -300.551403) (xy 159.897694 -300.579538) (xy 159.899858 -300.593506)
			(xy 159.902331 -300.607472) (xy 159.905005 -300.635712) (xy 159.905192 -300.649894) (xy 159.904729 -300.674715)
			(xy 159.896698 -300.723704) (xy 159.880849 -300.770748) (xy 159.857597 -300.814608) (xy 159.827555 -300.854129)
			(xy 159.791516 -300.888268) (xy 159.750428 -300.916128) (xy 159.705375 -300.936974) (xy 159.657542 -300.950256)
			(xy 159.608191 -300.955625) (xy 159.558622 -300.952939) (xy 159.510139 -300.942268) (xy 159.464022 -300.923895)
			(xy 159.421485 -300.898304) (xy 159.383648 -300.866167) (xy 159.351509 -300.828333) (xy 159.325914 -300.785797)
			(xy 159.307538 -300.739682) (xy 159.296864 -300.6912) (xy 159.294175 -300.641631) (xy 158.955066 -300.641631)
			(xy 158.955232 -300.649894) (xy 158.954737 -300.674501) (xy 158.946842 -300.723078) (xy 158.931258 -300.769759)
			(xy 158.908387 -300.813336) (xy 158.878822 -300.85268) (xy 158.843329 -300.886772) (xy 158.802826 -300.914728)
			(xy 158.758364 -300.935826) (xy 158.711093 -300.949518) (xy 158.662238 -300.95545) (xy 158.613063 -300.953469)
			(xy 158.564844 -300.943625) (xy 158.518828 -300.926173) (xy 158.476207 -300.901566) (xy 158.438086 -300.870441)
			(xy 158.405451 -300.833604) (xy 158.379148 -300.792008) (xy 158.359857 -300.746732) (xy 158.34808 -300.698948)
			(xy 158.34412 -300.649894) (xy 158.005272 -300.649894) (xy 158.004777 -300.674501) (xy 157.996882 -300.723078)
			(xy 157.981298 -300.769759) (xy 157.958427 -300.813336) (xy 157.928862 -300.85268) (xy 157.893369 -300.886772)
			(xy 157.852866 -300.914728) (xy 157.808404 -300.935826) (xy 157.761133 -300.949518) (xy 157.712278 -300.95545)
			(xy 157.663103 -300.953469) (xy 157.614884 -300.943625) (xy 157.568868 -300.926173) (xy 157.526247 -300.901566)
			(xy 157.488126 -300.870441) (xy 157.455491 -300.833604) (xy 157.429188 -300.792008) (xy 157.409897 -300.746732)
			(xy 157.39812 -300.698948) (xy 157.39416 -300.649894) (xy 157.055312 -300.649894) (xy 157.054817 -300.674501)
			(xy 157.046922 -300.723078) (xy 157.031338 -300.769759) (xy 157.008467 -300.813336) (xy 156.978902 -300.85268)
			(xy 156.943409 -300.886772) (xy 156.902906 -300.914728) (xy 156.858444 -300.935826) (xy 156.811173 -300.949518)
			(xy 156.762318 -300.95545) (xy 156.713143 -300.953469) (xy 156.664924 -300.943625) (xy 156.618908 -300.926173)
			(xy 156.576287 -300.901566) (xy 156.538166 -300.870441) (xy 156.505531 -300.833604) (xy 156.479228 -300.792008)
			(xy 156.459937 -300.746732) (xy 156.44816 -300.698948) (xy 156.4442 -300.649894) (xy 156.105352 -300.649894)
			(xy 156.104857 -300.674501) (xy 156.096962 -300.723078) (xy 156.081378 -300.769759) (xy 156.058507 -300.813336)
			(xy 156.028942 -300.85268) (xy 155.993449 -300.886772) (xy 155.952946 -300.914728) (xy 155.908484 -300.935826)
			(xy 155.861213 -300.949518) (xy 155.812358 -300.95545) (xy 155.763183 -300.953469) (xy 155.714964 -300.943625)
			(xy 155.668948 -300.926173) (xy 155.626327 -300.901566) (xy 155.588206 -300.870441) (xy 155.555571 -300.833604)
			(xy 155.529268 -300.792008) (xy 155.509977 -300.746732) (xy 155.4982 -300.698948) (xy 155.49424 -300.649894)
			(xy 155.155392 -300.649894) (xy 155.154897 -300.674501) (xy 155.147002 -300.723078) (xy 155.131418 -300.769759)
			(xy 155.108547 -300.813336) (xy 155.078982 -300.85268) (xy 155.043489 -300.886772) (xy 155.002986 -300.914728)
			(xy 154.958524 -300.935826) (xy 154.911253 -300.949518) (xy 154.862398 -300.95545) (xy 154.813223 -300.953469)
			(xy 154.765004 -300.943625) (xy 154.718988 -300.926173) (xy 154.676367 -300.901566) (xy 154.638246 -300.870441)
			(xy 154.605611 -300.833604) (xy 154.579308 -300.792008) (xy 154.560017 -300.746732) (xy 154.54824 -300.698948)
			(xy 154.54428 -300.649894) (xy 154.205178 -300.649894) (xy 154.204683 -300.674501) (xy 154.196788 -300.723078)
			(xy 154.181204 -300.769759) (xy 154.158333 -300.813336) (xy 154.128768 -300.85268) (xy 154.093275 -300.886772)
			(xy 154.052772 -300.914728) (xy 154.00831 -300.935826) (xy 153.961039 -300.949518) (xy 153.912184 -300.95545)
			(xy 153.863009 -300.953469) (xy 153.81479 -300.943625) (xy 153.768774 -300.926173) (xy 153.726153 -300.901566)
			(xy 153.688032 -300.870441) (xy 153.655397 -300.833604) (xy 153.629094 -300.792008) (xy 153.609803 -300.746732)
			(xy 153.598026 -300.698948) (xy 153.594066 -300.649894) (xy 153.255218 -300.649894) (xy 153.254723 -300.674501)
			(xy 153.246828 -300.723078) (xy 153.231244 -300.769759) (xy 153.208373 -300.813336) (xy 153.178808 -300.85268)
			(xy 153.143315 -300.886772) (xy 153.102812 -300.914728) (xy 153.05835 -300.935826) (xy 153.011079 -300.949518)
			(xy 152.962224 -300.95545) (xy 152.913049 -300.953469) (xy 152.86483 -300.943625) (xy 152.818814 -300.926173)
			(xy 152.776193 -300.901566) (xy 152.738072 -300.870441) (xy 152.705437 -300.833604) (xy 152.679134 -300.792008)
			(xy 152.659843 -300.746732) (xy 152.648066 -300.698948) (xy 152.644106 -300.649894) (xy 143.792693 -300.649894)
			(xy 143.848121 -300.655993) (xy 143.902078 -300.670099) (xy 143.953407 -300.691911) (xy 144.001013 -300.720965)
			(xy 144.043881 -300.75664) (xy 144.081098 -300.798177) (xy 144.111871 -300.84469) (xy 144.135543 -300.895187)
			(xy 144.151611 -300.948594) (xy 144.159731 -301.00377) (xy 144.16024 -301.031656) (xy 144.159731 -301.059542)
			(xy 144.151611 -301.114718) (xy 144.135543 -301.168125) (xy 144.111871 -301.218622) (xy 144.081098 -301.265135)
			(xy 144.043881 -301.306672) (xy 144.001013 -301.342347) (xy 143.953407 -301.371401) (xy 143.902078 -301.393213)
			(xy 143.848121 -301.407319) (xy 143.792684 -301.413419) (xy 143.73695 -301.411382) (xy 143.682107 -301.401252)
			(xy 143.629323 -301.383245) (xy 143.579723 -301.357744) (xy 143.534365 -301.325293) (xy 143.494216 -301.286584)
			(xy 143.46013 -301.242441) (xy 143.432834 -301.193806) (xy 143.412911 -301.141715) (xy 143.400785 -301.087278)
			(xy 143.396714 -301.031656) (xy 142.675102 -301.031656) (xy 142.674593 -301.059542) (xy 142.666473 -301.114718)
			(xy 142.650405 -301.168125) (xy 142.626733 -301.218622) (xy 142.59596 -301.265135) (xy 142.558743 -301.306672)
			(xy 142.515875 -301.342347) (xy 142.468269 -301.371401) (xy 142.41694 -301.393213) (xy 142.362983 -301.407319)
			(xy 142.307546 -301.413419) (xy 142.251812 -301.411382) (xy 142.196969 -301.401252) (xy 142.144185 -301.383245)
			(xy 142.094585 -301.357744) (xy 142.049227 -301.325293) (xy 142.009078 -301.286584) (xy 141.974992 -301.242441)
			(xy 141.947696 -301.193806) (xy 141.927773 -301.141715) (xy 141.915647 -301.087278) (xy 141.911576 -301.031656)
			(xy 118.832884 -301.031656) (xy 118.832884 -301.599854) (xy 152.644106 -301.599854) (xy 152.648066 -301.5508)
			(xy 152.659843 -301.503016) (xy 152.679134 -301.45774) (xy 152.705437 -301.416144) (xy 152.738072 -301.379307)
			(xy 152.776193 -301.348182) (xy 152.818814 -301.323575) (xy 152.86483 -301.306123) (xy 152.913049 -301.296279)
			(xy 152.962224 -301.294298) (xy 153.011079 -301.30023) (xy 153.05835 -301.313922) (xy 153.102812 -301.33502)
			(xy 153.143315 -301.362976) (xy 153.178808 -301.397068) (xy 153.208373 -301.436412) (xy 153.231244 -301.479989)
			(xy 153.246828 -301.52667) (xy 153.254723 -301.575247) (xy 153.255218 -301.599854) (xy 153.594066 -301.599854)
			(xy 153.598026 -301.5508) (xy 153.609803 -301.503016) (xy 153.629094 -301.45774) (xy 153.655397 -301.416144)
			(xy 153.688032 -301.379307) (xy 153.726153 -301.348182) (xy 153.768774 -301.323575) (xy 153.81479 -301.306123)
			(xy 153.863009 -301.296279) (xy 153.912184 -301.294298) (xy 153.961039 -301.30023) (xy 154.00831 -301.313922)
			(xy 154.052772 -301.33502) (xy 154.093275 -301.362976) (xy 154.128768 -301.397068) (xy 154.158333 -301.436412)
			(xy 154.181204 -301.479989) (xy 154.196788 -301.52667) (xy 154.204683 -301.575247) (xy 154.205178 -301.599854)
			(xy 154.54428 -301.599854) (xy 154.54824 -301.5508) (xy 154.560017 -301.503016) (xy 154.579308 -301.45774)
			(xy 154.605611 -301.416144) (xy 154.638246 -301.379307) (xy 154.676367 -301.348182) (xy 154.718988 -301.323575)
			(xy 154.765004 -301.306123) (xy 154.813223 -301.296279) (xy 154.862398 -301.294298) (xy 154.911253 -301.30023)
			(xy 154.958524 -301.313922) (xy 155.002986 -301.33502) (xy 155.043489 -301.362976) (xy 155.078982 -301.397068)
			(xy 155.108547 -301.436412) (xy 155.131418 -301.479989) (xy 155.147002 -301.52667) (xy 155.154897 -301.575247)
			(xy 155.155392 -301.599854) (xy 155.49424 -301.599854) (xy 155.4982 -301.5508) (xy 155.509977 -301.503016)
			(xy 155.529268 -301.45774) (xy 155.555571 -301.416144) (xy 155.588206 -301.379307) (xy 155.626327 -301.348182)
			(xy 155.668948 -301.323575) (xy 155.714964 -301.306123) (xy 155.763183 -301.296279) (xy 155.812358 -301.294298)
			(xy 155.861213 -301.30023) (xy 155.908484 -301.313922) (xy 155.952946 -301.33502) (xy 155.993449 -301.362976)
			(xy 156.028942 -301.397068) (xy 156.058507 -301.436412) (xy 156.081378 -301.479989) (xy 156.096962 -301.52667)
			(xy 156.104857 -301.575247) (xy 156.105352 -301.599854) (xy 156.4442 -301.599854) (xy 156.44816 -301.5508)
			(xy 156.459937 -301.503016) (xy 156.479228 -301.45774) (xy 156.505531 -301.416144) (xy 156.538166 -301.379307)
			(xy 156.576287 -301.348182) (xy 156.618908 -301.323575) (xy 156.664924 -301.306123) (xy 156.713143 -301.296279)
			(xy 156.762318 -301.294298) (xy 156.811173 -301.30023) (xy 156.858444 -301.313922) (xy 156.902906 -301.33502)
			(xy 156.943409 -301.362976) (xy 156.978902 -301.397068) (xy 157.008467 -301.436412) (xy 157.031338 -301.479989)
			(xy 157.046922 -301.52667) (xy 157.054817 -301.575247) (xy 157.055312 -301.599854) (xy 157.39416 -301.599854)
			(xy 157.39812 -301.5508) (xy 157.409897 -301.503016) (xy 157.429188 -301.45774) (xy 157.455491 -301.416144)
			(xy 157.488126 -301.379307) (xy 157.526247 -301.348182) (xy 157.568868 -301.323575) (xy 157.614884 -301.306123)
			(xy 157.663103 -301.296279) (xy 157.712278 -301.294298) (xy 157.761133 -301.30023) (xy 157.808404 -301.313922)
			(xy 157.852866 -301.33502) (xy 157.893369 -301.362976) (xy 157.928862 -301.397068) (xy 157.958427 -301.436412)
			(xy 157.981298 -301.479989) (xy 157.996882 -301.52667) (xy 158.004777 -301.575247) (xy 158.005272 -301.599854)
			(xy 158.34412 -301.599854) (xy 158.34808 -301.5508) (xy 158.359857 -301.503016) (xy 158.379148 -301.45774)
			(xy 158.405451 -301.416144) (xy 158.438086 -301.379307) (xy 158.476207 -301.348182) (xy 158.518828 -301.323575)
			(xy 158.564844 -301.306123) (xy 158.613063 -301.296279) (xy 158.662238 -301.294298) (xy 158.711093 -301.30023)
			(xy 158.758364 -301.313922) (xy 158.802826 -301.33502) (xy 158.843329 -301.362976) (xy 158.878822 -301.397068)
			(xy 158.908387 -301.436412) (xy 158.931258 -301.479989) (xy 158.946842 -301.52667) (xy 158.954737 -301.575247)
			(xy 158.955232 -301.599854) (xy 159.29408 -301.599854) (xy 159.29804 -301.5508) (xy 159.309817 -301.503016)
			(xy 159.329108 -301.45774) (xy 159.355411 -301.416144) (xy 159.388046 -301.379307) (xy 159.426167 -301.348182)
			(xy 159.468788 -301.323575) (xy 159.514804 -301.306123) (xy 159.563023 -301.296279) (xy 159.612198 -301.294298)
			(xy 159.661053 -301.30023) (xy 159.708324 -301.313922) (xy 159.752786 -301.33502) (xy 159.793289 -301.362976)
			(xy 159.828782 -301.397068) (xy 159.858347 -301.436412) (xy 159.881218 -301.479989) (xy 159.896802 -301.52667)
			(xy 159.904697 -301.575247) (xy 159.905026 -301.591602) (xy 160.244035 -301.591602) (xy 160.249406 -301.542241)
			(xy 160.262692 -301.4944) (xy 160.283544 -301.449338) (xy 160.311412 -301.408244) (xy 160.345561 -301.372199)
			(xy 160.385092 -301.342155) (xy 160.428963 -301.318903) (xy 160.476018 -301.303054) (xy 160.525018 -301.295028)
			(xy 160.549844 -301.294546) (xy 160.564091 -301.294708) (xy 160.592459 -301.297381) (xy 160.606486 -301.29988)
			(xy 160.618932 -301.302166) (xy 160.642554 -301.2948) (xy 160.711134 -301.226474) (xy 160.719324 -301.217262)
			(xy 160.726611 -301.193752) (xy 160.725104 -301.181516) (xy 160.725104 -301.181008) (xy 160.722645 -301.167104)
			(xy 160.719971 -301.138993) (xy 160.71977 -301.124874) (xy 160.720292 -301.099619) (xy 160.728605 -301.049797)
			(xy 160.745006 -301.002023) (xy 160.769047 -300.9576) (xy 160.800071 -300.91774) (xy 160.837233 -300.88353)
			(xy 160.879519 -300.855904) (xy 160.925775 -300.835614) (xy 160.97474 -300.823214) (xy 161.025078 -300.819043)
			(xy 161.075416 -300.823214) (xy 161.124381 -300.835614) (xy 161.170637 -300.855904) (xy 161.212923 -300.88353)
			(xy 161.250085 -300.91774) (xy 161.281109 -300.9576) (xy 161.30515 -301.002023) (xy 161.321551 -301.049797)
			(xy 161.329864 -301.099619) (xy 161.330386 -301.124874) (xy 161.330206 -301.139057) (xy 161.327536 -301.167297)
			(xy 161.325052 -301.181262) (xy 161.322766 -301.193708) (xy 161.330132 -301.21733) (xy 161.407602 -301.2948)
			(xy 161.431224 -301.302166) (xy 161.44367 -301.29988) (xy 161.457635 -301.297398) (xy 161.485875 -301.29473)
			(xy 161.500058 -301.294546) (xy 161.514241 -301.294729) (xy 161.542481 -301.297397) (xy 161.556446 -301.29988)
			(xy 161.568892 -301.302166) (xy 161.592514 -301.2948) (xy 161.669984 -301.21733) (xy 161.67735 -301.193708)
			(xy 161.675064 -301.181262) (xy 161.672587 -301.167296) (xy 161.669915 -301.139057) (xy 161.66973 -301.124874)
			(xy 161.670206 -301.100056) (xy 161.67824 -301.051076) (xy 161.694092 -301.00404) (xy 161.717344 -300.960188)
			(xy 161.747384 -300.920675) (xy 161.783421 -300.886543) (xy 161.824505 -300.85869) (xy 161.869553 -300.83785)
			(xy 161.91738 -300.824573) (xy 161.966724 -300.819207) (xy 162.016286 -300.821895) (xy 162.064761 -300.832565)
			(xy 162.110871 -300.850937) (xy 162.153402 -300.876526) (xy 162.191233 -300.908659) (xy 162.223367 -300.946488)
			(xy 162.248958 -300.989018) (xy 162.267331 -301.035127) (xy 162.278004 -301.083602) (xy 162.280243 -301.124874)
			(xy 162.619194 -301.124874) (xy 162.623154 -301.07582) (xy 162.634931 -301.028036) (xy 162.654222 -300.98276)
			(xy 162.680525 -300.941164) (xy 162.71316 -300.904327) (xy 162.751281 -300.873202) (xy 162.793902 -300.848595)
			(xy 162.839918 -300.831143) (xy 162.888137 -300.821299) (xy 162.937312 -300.819318) (xy 162.986167 -300.82525)
			(xy 163.033438 -300.838942) (xy 163.0779 -300.86004) (xy 163.118403 -300.887996) (xy 163.153896 -300.922088)
			(xy 163.183461 -300.961432) (xy 163.206332 -301.005009) (xy 163.221916 -301.05169) (xy 163.229811 -301.100267)
			(xy 163.230306 -301.124874) (xy 163.569154 -301.124874) (xy 163.573114 -301.07582) (xy 163.584891 -301.028036)
			(xy 163.604182 -300.98276) (xy 163.630485 -300.941164) (xy 163.66312 -300.904327) (xy 163.701241 -300.873202)
			(xy 163.743862 -300.848595) (xy 163.789878 -300.831143) (xy 163.838097 -300.821299) (xy 163.887272 -300.819318)
			(xy 163.936127 -300.82525) (xy 163.983398 -300.838942) (xy 164.02786 -300.86004) (xy 164.068363 -300.887996)
			(xy 164.103856 -300.922088) (xy 164.133421 -300.961432) (xy 164.156292 -301.005009) (xy 164.171876 -301.05169)
			(xy 164.179771 -301.100267) (xy 164.180266 -301.124874) (xy 165.469074 -301.124874) (xy 165.473034 -301.07582)
			(xy 165.484811 -301.028036) (xy 165.504102 -300.98276) (xy 165.530405 -300.941164) (xy 165.56304 -300.904327)
			(xy 165.601161 -300.873202) (xy 165.643782 -300.848595) (xy 165.689798 -300.831143) (xy 165.738017 -300.821299)
			(xy 165.787192 -300.819318) (xy 165.836047 -300.82525) (xy 165.883318 -300.838942) (xy 165.92778 -300.86004)
			(xy 165.968283 -300.887996) (xy 166.003776 -300.922088) (xy 166.033341 -300.961432) (xy 166.056212 -301.005009)
			(xy 166.071796 -301.05169) (xy 166.079691 -301.100267) (xy 166.080186 -301.124874) (xy 166.419288 -301.124874)
			(xy 166.423248 -301.07582) (xy 166.435025 -301.028036) (xy 166.454316 -300.98276) (xy 166.480619 -300.941164)
			(xy 166.513254 -300.904327) (xy 166.551375 -300.873202) (xy 166.593996 -300.848595) (xy 166.640012 -300.831143)
			(xy 166.688231 -300.821299) (xy 166.737406 -300.819318) (xy 166.786261 -300.82525) (xy 166.833532 -300.838942)
			(xy 166.877994 -300.86004) (xy 166.918497 -300.887996) (xy 166.95399 -300.922088) (xy 166.983555 -300.961432)
			(xy 167.006426 -301.005009) (xy 167.02201 -301.05169) (xy 167.029905 -301.100267) (xy 167.0304 -301.124874)
			(xy 167.369248 -301.124874) (xy 167.373208 -301.07582) (xy 167.384985 -301.028036) (xy 167.404276 -300.98276)
			(xy 167.430579 -300.941164) (xy 167.463214 -300.904327) (xy 167.501335 -300.873202) (xy 167.543956 -300.848595)
			(xy 167.589972 -300.831143) (xy 167.638191 -300.821299) (xy 167.687366 -300.819318) (xy 167.736221 -300.82525)
			(xy 167.783492 -300.838942) (xy 167.827954 -300.86004) (xy 167.868457 -300.887996) (xy 167.90395 -300.922088)
			(xy 167.933515 -300.961432) (xy 167.956386 -301.005009) (xy 167.97197 -301.05169) (xy 167.979865 -301.100267)
			(xy 167.98036 -301.124874) (xy 168.319208 -301.124874) (xy 168.323168 -301.07582) (xy 168.334945 -301.028036)
			(xy 168.354236 -300.98276) (xy 168.380539 -300.941164) (xy 168.413174 -300.904327) (xy 168.451295 -300.873202)
			(xy 168.493916 -300.848595) (xy 168.539932 -300.831143) (xy 168.588151 -300.821299) (xy 168.637326 -300.819318)
			(xy 168.686181 -300.82525) (xy 168.733452 -300.838942) (xy 168.777914 -300.86004) (xy 168.818417 -300.887996)
			(xy 168.85391 -300.922088) (xy 168.883475 -300.961432) (xy 168.906346 -301.005009) (xy 168.92193 -301.05169)
			(xy 168.929825 -301.100267) (xy 168.93032 -301.124874) (xy 169.269168 -301.124874) (xy 169.273128 -301.07582)
			(xy 169.284905 -301.028036) (xy 169.304196 -300.98276) (xy 169.330499 -300.941164) (xy 169.363134 -300.904327)
			(xy 169.401255 -300.873202) (xy 169.443876 -300.848595) (xy 169.489892 -300.831143) (xy 169.538111 -300.821299)
			(xy 169.587286 -300.819318) (xy 169.636141 -300.82525) (xy 169.683412 -300.838942) (xy 169.727874 -300.86004)
			(xy 169.768377 -300.887996) (xy 169.80387 -300.922088) (xy 169.833435 -300.961432) (xy 169.856306 -301.005009)
			(xy 169.87189 -301.05169) (xy 169.879785 -301.100267) (xy 169.88028 -301.124874) (xy 170.219128 -301.124874)
			(xy 170.223088 -301.07582) (xy 170.234865 -301.028036) (xy 170.254156 -300.98276) (xy 170.280459 -300.941164)
			(xy 170.313094 -300.904327) (xy 170.351215 -300.873202) (xy 170.393836 -300.848595) (xy 170.439852 -300.831143)
			(xy 170.488071 -300.821299) (xy 170.537246 -300.819318) (xy 170.586101 -300.82525) (xy 170.633372 -300.838942)
			(xy 170.677834 -300.86004) (xy 170.718337 -300.887996) (xy 170.75383 -300.922088) (xy 170.783395 -300.961432)
			(xy 170.806266 -301.005009) (xy 170.82185 -301.05169) (xy 170.829745 -301.100267) (xy 170.83024 -301.124874)
			(xy 171.169088 -301.124874) (xy 171.173048 -301.07582) (xy 171.184825 -301.028036) (xy 171.204116 -300.98276)
			(xy 171.230419 -300.941164) (xy 171.263054 -300.904327) (xy 171.301175 -300.873202) (xy 171.343796 -300.848595)
			(xy 171.389812 -300.831143) (xy 171.438031 -300.821299) (xy 171.487206 -300.819318) (xy 171.536061 -300.82525)
			(xy 171.583332 -300.838942) (xy 171.627794 -300.86004) (xy 171.668297 -300.887996) (xy 171.70379 -300.922088)
			(xy 171.733355 -300.961432) (xy 171.756226 -301.005009) (xy 171.77181 -301.05169) (xy 171.779705 -301.100267)
			(xy 171.7802 -301.124874) (xy 172.119048 -301.124874) (xy 172.123008 -301.07582) (xy 172.134785 -301.028036)
			(xy 172.154076 -300.98276) (xy 172.180379 -300.941164) (xy 172.213014 -300.904327) (xy 172.251135 -300.873202)
			(xy 172.293756 -300.848595) (xy 172.339772 -300.831143) (xy 172.387991 -300.821299) (xy 172.437166 -300.819318)
			(xy 172.486021 -300.82525) (xy 172.533292 -300.838942) (xy 172.577754 -300.86004) (xy 172.618257 -300.887996)
			(xy 172.65375 -300.922088) (xy 172.683315 -300.961432) (xy 172.706186 -301.005009) (xy 172.72177 -301.05169)
			(xy 172.729665 -301.100267) (xy 172.73016 -301.124874) (xy 173.069262 -301.124874) (xy 173.073222 -301.07582)
			(xy 173.084999 -301.028036) (xy 173.10429 -300.98276) (xy 173.130593 -300.941164) (xy 173.163228 -300.904327)
			(xy 173.201349 -300.873202) (xy 173.24397 -300.848595) (xy 173.289986 -300.831143) (xy 173.338205 -300.821299)
			(xy 173.38738 -300.819318) (xy 173.436235 -300.82525) (xy 173.483506 -300.838942) (xy 173.527968 -300.86004)
			(xy 173.568471 -300.887996) (xy 173.603964 -300.922088) (xy 173.633529 -300.961432) (xy 173.6564 -301.005009)
			(xy 173.671984 -301.05169) (xy 173.679879 -301.100267) (xy 173.680374 -301.124874) (xy 174.019222 -301.124874)
			(xy 174.023182 -301.07582) (xy 174.034959 -301.028036) (xy 174.05425 -300.98276) (xy 174.080553 -300.941164)
			(xy 174.113188 -300.904327) (xy 174.151309 -300.873202) (xy 174.19393 -300.848595) (xy 174.239946 -300.831143)
			(xy 174.288165 -300.821299) (xy 174.33734 -300.819318) (xy 174.386195 -300.82525) (xy 174.433466 -300.838942)
			(xy 174.477928 -300.86004) (xy 174.518431 -300.887996) (xy 174.553924 -300.922088) (xy 174.583489 -300.961432)
			(xy 174.60636 -301.005009) (xy 174.621944 -301.05169) (xy 174.629839 -301.100267) (xy 174.630334 -301.124874)
			(xy 175.919142 -301.124874) (xy 175.923102 -301.07582) (xy 175.934879 -301.028036) (xy 175.95417 -300.98276)
			(xy 175.980473 -300.941164) (xy 176.013108 -300.904327) (xy 176.051229 -300.873202) (xy 176.09385 -300.848595)
			(xy 176.139866 -300.831143) (xy 176.188085 -300.821299) (xy 176.23726 -300.819318) (xy 176.286115 -300.82525)
			(xy 176.333386 -300.838942) (xy 176.377848 -300.86004) (xy 176.418351 -300.887996) (xy 176.453844 -300.922088)
			(xy 176.483409 -300.961432) (xy 176.50628 -301.005009) (xy 176.521864 -301.05169) (xy 176.529759 -301.100267)
			(xy 176.530254 -301.124874) (xy 176.869102 -301.124874) (xy 176.873062 -301.07582) (xy 176.884839 -301.028036)
			(xy 176.90413 -300.98276) (xy 176.930433 -300.941164) (xy 176.963068 -300.904327) (xy 177.001189 -300.873202)
			(xy 177.04381 -300.848595) (xy 177.089826 -300.831143) (xy 177.138045 -300.821299) (xy 177.18722 -300.819318)
			(xy 177.236075 -300.82525) (xy 177.283346 -300.838942) (xy 177.327808 -300.86004) (xy 177.368311 -300.887996)
			(xy 177.403804 -300.922088) (xy 177.433369 -300.961432) (xy 177.45624 -301.005009) (xy 177.471824 -301.05169)
			(xy 177.479719 -301.100267) (xy 177.480214 -301.124874) (xy 177.819062 -301.124874) (xy 177.823022 -301.07582)
			(xy 177.834799 -301.028036) (xy 177.85409 -300.98276) (xy 177.880393 -300.941164) (xy 177.913028 -300.904327)
			(xy 177.951149 -300.873202) (xy 177.99377 -300.848595) (xy 178.039786 -300.831143) (xy 178.088005 -300.821299)
			(xy 178.13718 -300.819318) (xy 178.186035 -300.82525) (xy 178.233306 -300.838942) (xy 178.277768 -300.86004)
			(xy 178.318271 -300.887996) (xy 178.353764 -300.922088) (xy 178.383329 -300.961432) (xy 178.4062 -301.005009)
			(xy 178.421784 -301.05169) (xy 178.429679 -301.100267) (xy 178.430174 -301.124874) (xy 178.769276 -301.124874)
			(xy 178.773236 -301.07582) (xy 178.785013 -301.028036) (xy 178.804304 -300.98276) (xy 178.830607 -300.941164)
			(xy 178.863242 -300.904327) (xy 178.901363 -300.873202) (xy 178.943984 -300.848595) (xy 178.99 -300.831143)
			(xy 179.038219 -300.821299) (xy 179.087394 -300.819318) (xy 179.136249 -300.82525) (xy 179.18352 -300.838942)
			(xy 179.227982 -300.86004) (xy 179.268485 -300.887996) (xy 179.303978 -300.922088) (xy 179.333543 -300.961432)
			(xy 179.356414 -301.005009) (xy 179.371998 -301.05169) (xy 179.379893 -301.100267) (xy 179.380388 -301.124874)
			(xy 179.719236 -301.124874) (xy 179.723196 -301.07582) (xy 179.734973 -301.028036) (xy 179.754264 -300.98276)
			(xy 179.780567 -300.941164) (xy 179.813202 -300.904327) (xy 179.851323 -300.873202) (xy 179.893944 -300.848595)
			(xy 179.93996 -300.831143) (xy 179.988179 -300.821299) (xy 180.037354 -300.819318) (xy 180.086209 -300.82525)
			(xy 180.13348 -300.838942) (xy 180.177942 -300.86004) (xy 180.218445 -300.887996) (xy 180.253938 -300.922088)
			(xy 180.283503 -300.961432) (xy 180.306374 -301.005009) (xy 180.321958 -301.05169) (xy 180.329853 -301.100267)
			(xy 180.330348 -301.124874) (xy 180.669196 -301.124874) (xy 180.673156 -301.07582) (xy 180.684933 -301.028036)
			(xy 180.704224 -300.98276) (xy 180.730527 -300.941164) (xy 180.763162 -300.904327) (xy 180.801283 -300.873202)
			(xy 180.843904 -300.848595) (xy 180.88992 -300.831143) (xy 180.938139 -300.821299) (xy 180.987314 -300.819318)
			(xy 181.036169 -300.82525) (xy 181.08344 -300.838942) (xy 181.127902 -300.86004) (xy 181.168405 -300.887996)
			(xy 181.203898 -300.922088) (xy 181.233463 -300.961432) (xy 181.256334 -301.005009) (xy 181.271918 -301.05169)
			(xy 181.279813 -301.100267) (xy 181.280308 -301.124874) (xy 181.619156 -301.124874) (xy 181.623116 -301.07582)
			(xy 181.634893 -301.028036) (xy 181.654184 -300.98276) (xy 181.680487 -300.941164) (xy 181.713122 -300.904327)
			(xy 181.751243 -300.873202) (xy 181.793864 -300.848595) (xy 181.83988 -300.831143) (xy 181.888099 -300.821299)
			(xy 181.937274 -300.819318) (xy 181.986129 -300.82525) (xy 182.0334 -300.838942) (xy 182.077862 -300.86004)
			(xy 182.118365 -300.887996) (xy 182.153858 -300.922088) (xy 182.183423 -300.961432) (xy 182.206294 -301.005009)
			(xy 182.221878 -301.05169) (xy 182.229773 -301.100267) (xy 182.230268 -301.124874) (xy 182.569116 -301.124874)
			(xy 182.573076 -301.07582) (xy 182.584853 -301.028036) (xy 182.604144 -300.98276) (xy 182.630447 -300.941164)
			(xy 182.663082 -300.904327) (xy 182.701203 -300.873202) (xy 182.743824 -300.848595) (xy 182.78984 -300.831143)
			(xy 182.838059 -300.821299) (xy 182.887234 -300.819318) (xy 182.936089 -300.82525) (xy 182.98336 -300.838942)
			(xy 183.027822 -300.86004) (xy 183.068325 -300.887996) (xy 183.103818 -300.922088) (xy 183.133383 -300.961432)
			(xy 183.156254 -301.005009) (xy 183.171838 -301.05169) (xy 183.179733 -301.100267) (xy 183.180228 -301.124874)
			(xy 183.519076 -301.124874) (xy 183.523036 -301.07582) (xy 183.534813 -301.028036) (xy 183.554104 -300.98276)
			(xy 183.580407 -300.941164) (xy 183.613042 -300.904327) (xy 183.651163 -300.873202) (xy 183.693784 -300.848595)
			(xy 183.7398 -300.831143) (xy 183.788019 -300.821299) (xy 183.837194 -300.819318) (xy 183.886049 -300.82525)
			(xy 183.93332 -300.838942) (xy 183.977782 -300.86004) (xy 184.018285 -300.887996) (xy 184.053778 -300.922088)
			(xy 184.083343 -300.961432) (xy 184.106214 -301.005009) (xy 184.121798 -301.05169) (xy 184.129693 -301.100267)
			(xy 184.130188 -301.124874) (xy 184.129693 -301.149481) (xy 184.121798 -301.198058) (xy 184.106214 -301.244739)
			(xy 184.083343 -301.288316) (xy 184.053778 -301.32766) (xy 184.018285 -301.361752) (xy 183.977782 -301.389708)
			(xy 183.93332 -301.410806) (xy 183.886049 -301.424498) (xy 183.837194 -301.43043) (xy 183.788019 -301.428449)
			(xy 183.7398 -301.418605) (xy 183.693784 -301.401153) (xy 183.651163 -301.376546) (xy 183.613042 -301.345421)
			(xy 183.580407 -301.308584) (xy 183.554104 -301.266988) (xy 183.534813 -301.221712) (xy 183.523036 -301.173928)
			(xy 183.519076 -301.124874) (xy 183.180228 -301.124874) (xy 183.179733 -301.149481) (xy 183.171838 -301.198058)
			(xy 183.156254 -301.244739) (xy 183.133383 -301.288316) (xy 183.103818 -301.32766) (xy 183.068325 -301.361752)
			(xy 183.027822 -301.389708) (xy 182.98336 -301.410806) (xy 182.936089 -301.424498) (xy 182.887234 -301.43043)
			(xy 182.838059 -301.428449) (xy 182.78984 -301.418605) (xy 182.743824 -301.401153) (xy 182.701203 -301.376546)
			(xy 182.663082 -301.345421) (xy 182.630447 -301.308584) (xy 182.604144 -301.266988) (xy 182.584853 -301.221712)
			(xy 182.573076 -301.173928) (xy 182.569116 -301.124874) (xy 182.230268 -301.124874) (xy 182.229773 -301.149481)
			(xy 182.221878 -301.198058) (xy 182.206294 -301.244739) (xy 182.183423 -301.288316) (xy 182.153858 -301.32766)
			(xy 182.118365 -301.361752) (xy 182.077862 -301.389708) (xy 182.0334 -301.410806) (xy 181.986129 -301.424498)
			(xy 181.937274 -301.43043) (xy 181.888099 -301.428449) (xy 181.83988 -301.418605) (xy 181.793864 -301.401153)
			(xy 181.751243 -301.376546) (xy 181.713122 -301.345421) (xy 181.680487 -301.308584) (xy 181.654184 -301.266988)
			(xy 181.634893 -301.221712) (xy 181.623116 -301.173928) (xy 181.619156 -301.124874) (xy 181.280308 -301.124874)
			(xy 181.279813 -301.149481) (xy 181.271918 -301.198058) (xy 181.256334 -301.244739) (xy 181.233463 -301.288316)
			(xy 181.203898 -301.32766) (xy 181.168405 -301.361752) (xy 181.127902 -301.389708) (xy 181.08344 -301.410806)
			(xy 181.036169 -301.424498) (xy 180.987314 -301.43043) (xy 180.938139 -301.428449) (xy 180.88992 -301.418605)
			(xy 180.843904 -301.401153) (xy 180.801283 -301.376546) (xy 180.763162 -301.345421) (xy 180.730527 -301.308584)
			(xy 180.704224 -301.266988) (xy 180.684933 -301.221712) (xy 180.673156 -301.173928) (xy 180.669196 -301.124874)
			(xy 180.330348 -301.124874) (xy 180.329853 -301.149481) (xy 180.321958 -301.198058) (xy 180.306374 -301.244739)
			(xy 180.283503 -301.288316) (xy 180.253938 -301.32766) (xy 180.218445 -301.361752) (xy 180.177942 -301.389708)
			(xy 180.13348 -301.410806) (xy 180.086209 -301.424498) (xy 180.037354 -301.43043) (xy 179.988179 -301.428449)
			(xy 179.93996 -301.418605) (xy 179.893944 -301.401153) (xy 179.851323 -301.376546) (xy 179.813202 -301.345421)
			(xy 179.780567 -301.308584) (xy 179.754264 -301.266988) (xy 179.734973 -301.221712) (xy 179.723196 -301.173928)
			(xy 179.719236 -301.124874) (xy 179.380388 -301.124874) (xy 179.379893 -301.149481) (xy 179.371998 -301.198058)
			(xy 179.356414 -301.244739) (xy 179.333543 -301.288316) (xy 179.303978 -301.32766) (xy 179.268485 -301.361752)
			(xy 179.227982 -301.389708) (xy 179.18352 -301.410806) (xy 179.136249 -301.424498) (xy 179.087394 -301.43043)
			(xy 179.038219 -301.428449) (xy 178.99 -301.418605) (xy 178.943984 -301.401153) (xy 178.901363 -301.376546)
			(xy 178.863242 -301.345421) (xy 178.830607 -301.308584) (xy 178.804304 -301.266988) (xy 178.785013 -301.221712)
			(xy 178.773236 -301.173928) (xy 178.769276 -301.124874) (xy 178.430174 -301.124874) (xy 178.429679 -301.149481)
			(xy 178.421784 -301.198058) (xy 178.4062 -301.244739) (xy 178.383329 -301.288316) (xy 178.353764 -301.32766)
			(xy 178.318271 -301.361752) (xy 178.277768 -301.389708) (xy 178.233306 -301.410806) (xy 178.186035 -301.424498)
			(xy 178.13718 -301.43043) (xy 178.088005 -301.428449) (xy 178.039786 -301.418605) (xy 177.99377 -301.401153)
			(xy 177.951149 -301.376546) (xy 177.913028 -301.345421) (xy 177.880393 -301.308584) (xy 177.85409 -301.266988)
			(xy 177.834799 -301.221712) (xy 177.823022 -301.173928) (xy 177.819062 -301.124874) (xy 177.480214 -301.124874)
			(xy 177.479719 -301.149481) (xy 177.471824 -301.198058) (xy 177.45624 -301.244739) (xy 177.433369 -301.288316)
			(xy 177.403804 -301.32766) (xy 177.368311 -301.361752) (xy 177.327808 -301.389708) (xy 177.283346 -301.410806)
			(xy 177.236075 -301.424498) (xy 177.18722 -301.43043) (xy 177.138045 -301.428449) (xy 177.089826 -301.418605)
			(xy 177.04381 -301.401153) (xy 177.001189 -301.376546) (xy 176.963068 -301.345421) (xy 176.930433 -301.308584)
			(xy 176.90413 -301.266988) (xy 176.884839 -301.221712) (xy 176.873062 -301.173928) (xy 176.869102 -301.124874)
			(xy 176.530254 -301.124874) (xy 176.529759 -301.149481) (xy 176.521864 -301.198058) (xy 176.50628 -301.244739)
			(xy 176.483409 -301.288316) (xy 176.453844 -301.32766) (xy 176.418351 -301.361752) (xy 176.377848 -301.389708)
			(xy 176.333386 -301.410806) (xy 176.286115 -301.424498) (xy 176.23726 -301.43043) (xy 176.188085 -301.428449)
			(xy 176.139866 -301.418605) (xy 176.09385 -301.401153) (xy 176.051229 -301.376546) (xy 176.013108 -301.345421)
			(xy 175.980473 -301.308584) (xy 175.95417 -301.266988) (xy 175.934879 -301.221712) (xy 175.923102 -301.173928)
			(xy 175.919142 -301.124874) (xy 174.630334 -301.124874) (xy 174.629839 -301.149481) (xy 174.621944 -301.198058)
			(xy 174.60636 -301.244739) (xy 174.583489 -301.288316) (xy 174.553924 -301.32766) (xy 174.518431 -301.361752)
			(xy 174.477928 -301.389708) (xy 174.433466 -301.410806) (xy 174.386195 -301.424498) (xy 174.33734 -301.43043)
			(xy 174.288165 -301.428449) (xy 174.239946 -301.418605) (xy 174.19393 -301.401153) (xy 174.151309 -301.376546)
			(xy 174.113188 -301.345421) (xy 174.080553 -301.308584) (xy 174.05425 -301.266988) (xy 174.034959 -301.221712)
			(xy 174.023182 -301.173928) (xy 174.019222 -301.124874) (xy 173.680374 -301.124874) (xy 173.679879 -301.149481)
			(xy 173.671984 -301.198058) (xy 173.6564 -301.244739) (xy 173.633529 -301.288316) (xy 173.603964 -301.32766)
			(xy 173.568471 -301.361752) (xy 173.527968 -301.389708) (xy 173.483506 -301.410806) (xy 173.436235 -301.424498)
			(xy 173.38738 -301.43043) (xy 173.338205 -301.428449) (xy 173.289986 -301.418605) (xy 173.24397 -301.401153)
			(xy 173.201349 -301.376546) (xy 173.163228 -301.345421) (xy 173.130593 -301.308584) (xy 173.10429 -301.266988)
			(xy 173.084999 -301.221712) (xy 173.073222 -301.173928) (xy 173.069262 -301.124874) (xy 172.73016 -301.124874)
			(xy 172.729665 -301.149481) (xy 172.72177 -301.198058) (xy 172.706186 -301.244739) (xy 172.683315 -301.288316)
			(xy 172.65375 -301.32766) (xy 172.618257 -301.361752) (xy 172.577754 -301.389708) (xy 172.533292 -301.410806)
			(xy 172.486021 -301.424498) (xy 172.437166 -301.43043) (xy 172.387991 -301.428449) (xy 172.339772 -301.418605)
			(xy 172.293756 -301.401153) (xy 172.251135 -301.376546) (xy 172.213014 -301.345421) (xy 172.180379 -301.308584)
			(xy 172.154076 -301.266988) (xy 172.134785 -301.221712) (xy 172.123008 -301.173928) (xy 172.119048 -301.124874)
			(xy 171.7802 -301.124874) (xy 171.779705 -301.149481) (xy 171.77181 -301.198058) (xy 171.756226 -301.244739)
			(xy 171.733355 -301.288316) (xy 171.70379 -301.32766) (xy 171.668297 -301.361752) (xy 171.627794 -301.389708)
			(xy 171.583332 -301.410806) (xy 171.536061 -301.424498) (xy 171.487206 -301.43043) (xy 171.438031 -301.428449)
			(xy 171.389812 -301.418605) (xy 171.343796 -301.401153) (xy 171.301175 -301.376546) (xy 171.263054 -301.345421)
			(xy 171.230419 -301.308584) (xy 171.204116 -301.266988) (xy 171.184825 -301.221712) (xy 171.173048 -301.173928)
			(xy 171.169088 -301.124874) (xy 170.83024 -301.124874) (xy 170.829745 -301.149481) (xy 170.82185 -301.198058)
			(xy 170.806266 -301.244739) (xy 170.783395 -301.288316) (xy 170.75383 -301.32766) (xy 170.718337 -301.361752)
			(xy 170.677834 -301.389708) (xy 170.633372 -301.410806) (xy 170.586101 -301.424498) (xy 170.537246 -301.43043)
			(xy 170.488071 -301.428449) (xy 170.439852 -301.418605) (xy 170.393836 -301.401153) (xy 170.351215 -301.376546)
			(xy 170.313094 -301.345421) (xy 170.280459 -301.308584) (xy 170.254156 -301.266988) (xy 170.234865 -301.221712)
			(xy 170.223088 -301.173928) (xy 170.219128 -301.124874) (xy 169.88028 -301.124874) (xy 169.879785 -301.149481)
			(xy 169.87189 -301.198058) (xy 169.856306 -301.244739) (xy 169.833435 -301.288316) (xy 169.80387 -301.32766)
			(xy 169.768377 -301.361752) (xy 169.727874 -301.389708) (xy 169.683412 -301.410806) (xy 169.636141 -301.424498)
			(xy 169.587286 -301.43043) (xy 169.538111 -301.428449) (xy 169.489892 -301.418605) (xy 169.443876 -301.401153)
			(xy 169.401255 -301.376546) (xy 169.363134 -301.345421) (xy 169.330499 -301.308584) (xy 169.304196 -301.266988)
			(xy 169.284905 -301.221712) (xy 169.273128 -301.173928) (xy 169.269168 -301.124874) (xy 168.93032 -301.124874)
			(xy 168.929825 -301.149481) (xy 168.92193 -301.198058) (xy 168.906346 -301.244739) (xy 168.883475 -301.288316)
			(xy 168.85391 -301.32766) (xy 168.818417 -301.361752) (xy 168.777914 -301.389708) (xy 168.733452 -301.410806)
			(xy 168.686181 -301.424498) (xy 168.637326 -301.43043) (xy 168.588151 -301.428449) (xy 168.539932 -301.418605)
			(xy 168.493916 -301.401153) (xy 168.451295 -301.376546) (xy 168.413174 -301.345421) (xy 168.380539 -301.308584)
			(xy 168.354236 -301.266988) (xy 168.334945 -301.221712) (xy 168.323168 -301.173928) (xy 168.319208 -301.124874)
			(xy 167.98036 -301.124874) (xy 167.979865 -301.149481) (xy 167.97197 -301.198058) (xy 167.956386 -301.244739)
			(xy 167.933515 -301.288316) (xy 167.90395 -301.32766) (xy 167.868457 -301.361752) (xy 167.827954 -301.389708)
			(xy 167.783492 -301.410806) (xy 167.736221 -301.424498) (xy 167.687366 -301.43043) (xy 167.638191 -301.428449)
			(xy 167.589972 -301.418605) (xy 167.543956 -301.401153) (xy 167.501335 -301.376546) (xy 167.463214 -301.345421)
			(xy 167.430579 -301.308584) (xy 167.404276 -301.266988) (xy 167.384985 -301.221712) (xy 167.373208 -301.173928)
			(xy 167.369248 -301.124874) (xy 167.0304 -301.124874) (xy 167.029905 -301.149481) (xy 167.02201 -301.198058)
			(xy 167.006426 -301.244739) (xy 166.983555 -301.288316) (xy 166.95399 -301.32766) (xy 166.918497 -301.361752)
			(xy 166.877994 -301.389708) (xy 166.833532 -301.410806) (xy 166.786261 -301.424498) (xy 166.737406 -301.43043)
			(xy 166.688231 -301.428449) (xy 166.640012 -301.418605) (xy 166.593996 -301.401153) (xy 166.551375 -301.376546)
			(xy 166.513254 -301.345421) (xy 166.480619 -301.308584) (xy 166.454316 -301.266988) (xy 166.435025 -301.221712)
			(xy 166.423248 -301.173928) (xy 166.419288 -301.124874) (xy 166.080186 -301.124874) (xy 166.079691 -301.149481)
			(xy 166.071796 -301.198058) (xy 166.056212 -301.244739) (xy 166.033341 -301.288316) (xy 166.003776 -301.32766)
			(xy 165.968283 -301.361752) (xy 165.92778 -301.389708) (xy 165.883318 -301.410806) (xy 165.836047 -301.424498)
			(xy 165.787192 -301.43043) (xy 165.738017 -301.428449) (xy 165.689798 -301.418605) (xy 165.643782 -301.401153)
			(xy 165.601161 -301.376546) (xy 165.56304 -301.345421) (xy 165.530405 -301.308584) (xy 165.504102 -301.266988)
			(xy 165.484811 -301.221712) (xy 165.473034 -301.173928) (xy 165.469074 -301.124874) (xy 164.180266 -301.124874)
			(xy 164.179771 -301.149481) (xy 164.171876 -301.198058) (xy 164.156292 -301.244739) (xy 164.133421 -301.288316)
			(xy 164.103856 -301.32766) (xy 164.068363 -301.361752) (xy 164.02786 -301.389708) (xy 163.983398 -301.410806)
			(xy 163.936127 -301.424498) (xy 163.887272 -301.43043) (xy 163.838097 -301.428449) (xy 163.789878 -301.418605)
			(xy 163.743862 -301.401153) (xy 163.701241 -301.376546) (xy 163.66312 -301.345421) (xy 163.630485 -301.308584)
			(xy 163.604182 -301.266988) (xy 163.584891 -301.221712) (xy 163.573114 -301.173928) (xy 163.569154 -301.124874)
			(xy 163.230306 -301.124874) (xy 163.229811 -301.149481) (xy 163.221916 -301.198058) (xy 163.206332 -301.244739)
			(xy 163.183461 -301.288316) (xy 163.153896 -301.32766) (xy 163.118403 -301.361752) (xy 163.0779 -301.389708)
			(xy 163.033438 -301.410806) (xy 162.986167 -301.424498) (xy 162.937312 -301.43043) (xy 162.888137 -301.428449)
			(xy 162.839918 -301.418605) (xy 162.793902 -301.401153) (xy 162.751281 -301.376546) (xy 162.71316 -301.345421)
			(xy 162.680525 -301.308584) (xy 162.654222 -301.266988) (xy 162.634931 -301.221712) (xy 162.623154 -301.173928)
			(xy 162.619194 -301.124874) (xy 162.280243 -301.124874) (xy 162.280693 -301.133164) (xy 162.27533 -301.182509)
			(xy 162.262054 -301.230336) (xy 162.241216 -301.275385) (xy 162.213365 -301.31647) (xy 162.179234 -301.352508)
			(xy 162.139722 -301.382549) (xy 162.095871 -301.405804) (xy 162.048836 -301.421657) (xy 161.999856 -301.429693)
			(xy 161.975038 -301.430182) (xy 161.960855 -301.430001) (xy 161.932615 -301.427332) (xy 161.91865 -301.424848)
			(xy 161.906204 -301.422562) (xy 161.882582 -301.429928) (xy 161.805112 -301.507398) (xy 161.797746 -301.53102)
			(xy 161.800032 -301.543466) (xy 161.802514 -301.557431) (xy 161.805182 -301.585671) (xy 161.805366 -301.599854)
			(xy 161.805184 -301.614037) (xy 161.802515 -301.642277) (xy 161.800032 -301.656242) (xy 161.797746 -301.668688)
			(xy 161.805112 -301.69231) (xy 161.882582 -301.76978) (xy 161.906204 -301.777146) (xy 161.91865 -301.77486)
			(xy 161.932616 -301.772381) (xy 161.960855 -301.769711) (xy 161.975038 -301.769526) (xy 162.000294 -301.769983)
			(xy 162.050117 -301.778302) (xy 162.09789 -301.794708) (xy 162.142312 -301.818753) (xy 162.182171 -301.849781)
			(xy 162.21638 -301.886946) (xy 162.244006 -301.929235) (xy 162.264295 -301.975493) (xy 162.276694 -302.02446)
			(xy 162.280865 -302.0748) (xy 162.280862 -302.074834) (xy 165.469074 -302.074834) (xy 165.473034 -302.02578)
			(xy 165.484811 -301.977996) (xy 165.504102 -301.93272) (xy 165.530405 -301.891124) (xy 165.56304 -301.854287)
			(xy 165.601161 -301.823162) (xy 165.643782 -301.798555) (xy 165.689798 -301.781103) (xy 165.738017 -301.771259)
			(xy 165.787192 -301.769278) (xy 165.836047 -301.77521) (xy 165.883318 -301.788902) (xy 165.92778 -301.81)
			(xy 165.968283 -301.837956) (xy 166.003776 -301.872048) (xy 166.033341 -301.911392) (xy 166.056212 -301.954969)
			(xy 166.071796 -302.00165) (xy 166.079691 -302.050227) (xy 166.080186 -302.074834) (xy 166.419288 -302.074834)
			(xy 166.423248 -302.02578) (xy 166.435025 -301.977996) (xy 166.454316 -301.93272) (xy 166.480619 -301.891124)
			(xy 166.513254 -301.854287) (xy 166.551375 -301.823162) (xy 166.593996 -301.798555) (xy 166.640012 -301.781103)
			(xy 166.688231 -301.771259) (xy 166.737406 -301.769278) (xy 166.786261 -301.77521) (xy 166.833532 -301.788902)
			(xy 166.877994 -301.81) (xy 166.918497 -301.837956) (xy 166.95399 -301.872048) (xy 166.983555 -301.911392)
			(xy 167.006426 -301.954969) (xy 167.02201 -302.00165) (xy 167.029905 -302.050227) (xy 167.0304 -302.074834)
			(xy 167.369248 -302.074834) (xy 167.373208 -302.02578) (xy 167.384985 -301.977996) (xy 167.404276 -301.93272)
			(xy 167.430579 -301.891124) (xy 167.463214 -301.854287) (xy 167.501335 -301.823162) (xy 167.543956 -301.798555)
			(xy 167.589972 -301.781103) (xy 167.638191 -301.771259) (xy 167.687366 -301.769278) (xy 167.736221 -301.77521)
			(xy 167.783492 -301.788902) (xy 167.827954 -301.81) (xy 167.868457 -301.837956) (xy 167.90395 -301.872048)
			(xy 167.933515 -301.911392) (xy 167.956386 -301.954969) (xy 167.97197 -302.00165) (xy 167.979865 -302.050227)
			(xy 167.98036 -302.074834) (xy 168.319208 -302.074834) (xy 168.323168 -302.02578) (xy 168.334945 -301.977996)
			(xy 168.354236 -301.93272) (xy 168.380539 -301.891124) (xy 168.413174 -301.854287) (xy 168.451295 -301.823162)
			(xy 168.493916 -301.798555) (xy 168.539932 -301.781103) (xy 168.588151 -301.771259) (xy 168.637326 -301.769278)
			(xy 168.686181 -301.77521) (xy 168.733452 -301.788902) (xy 168.777914 -301.81) (xy 168.818417 -301.837956)
			(xy 168.85391 -301.872048) (xy 168.883475 -301.911392) (xy 168.906346 -301.954969) (xy 168.92193 -302.00165)
			(xy 168.929825 -302.050227) (xy 168.93032 -302.074834) (xy 169.269168 -302.074834) (xy 169.273128 -302.02578)
			(xy 169.284905 -301.977996) (xy 169.304196 -301.93272) (xy 169.330499 -301.891124) (xy 169.363134 -301.854287)
			(xy 169.401255 -301.823162) (xy 169.443876 -301.798555) (xy 169.489892 -301.781103) (xy 169.538111 -301.771259)
			(xy 169.587286 -301.769278) (xy 169.636141 -301.77521) (xy 169.683412 -301.788902) (xy 169.727874 -301.81)
			(xy 169.768377 -301.837956) (xy 169.80387 -301.872048) (xy 169.833435 -301.911392) (xy 169.856306 -301.954969)
			(xy 169.87189 -302.00165) (xy 169.879785 -302.050227) (xy 169.88028 -302.074834) (xy 170.219128 -302.074834)
			(xy 170.223088 -302.02578) (xy 170.234865 -301.977996) (xy 170.254156 -301.93272) (xy 170.280459 -301.891124)
			(xy 170.313094 -301.854287) (xy 170.351215 -301.823162) (xy 170.393836 -301.798555) (xy 170.439852 -301.781103)
			(xy 170.488071 -301.771259) (xy 170.537246 -301.769278) (xy 170.586101 -301.77521) (xy 170.633372 -301.788902)
			(xy 170.677834 -301.81) (xy 170.718337 -301.837956) (xy 170.75383 -301.872048) (xy 170.783395 -301.911392)
			(xy 170.806266 -301.954969) (xy 170.82185 -302.00165) (xy 170.829745 -302.050227) (xy 170.83024 -302.074834)
			(xy 171.169088 -302.074834) (xy 171.173048 -302.02578) (xy 171.184825 -301.977996) (xy 171.204116 -301.93272)
			(xy 171.230419 -301.891124) (xy 171.263054 -301.854287) (xy 171.301175 -301.823162) (xy 171.343796 -301.798555)
			(xy 171.389812 -301.781103) (xy 171.438031 -301.771259) (xy 171.487206 -301.769278) (xy 171.536061 -301.77521)
			(xy 171.583332 -301.788902) (xy 171.627794 -301.81) (xy 171.668297 -301.837956) (xy 171.70379 -301.872048)
			(xy 171.733355 -301.911392) (xy 171.756226 -301.954969) (xy 171.77181 -302.00165) (xy 171.779705 -302.050227)
			(xy 171.7802 -302.074834) (xy 172.119048 -302.074834) (xy 172.123008 -302.02578) (xy 172.134785 -301.977996)
			(xy 172.154076 -301.93272) (xy 172.180379 -301.891124) (xy 172.213014 -301.854287) (xy 172.251135 -301.823162)
			(xy 172.293756 -301.798555) (xy 172.339772 -301.781103) (xy 172.387991 -301.771259) (xy 172.437166 -301.769278)
			(xy 172.486021 -301.77521) (xy 172.533292 -301.788902) (xy 172.577754 -301.81) (xy 172.618257 -301.837956)
			(xy 172.65375 -301.872048) (xy 172.683315 -301.911392) (xy 172.706186 -301.954969) (xy 172.72177 -302.00165)
			(xy 172.729665 -302.050227) (xy 172.73016 -302.074834) (xy 173.069262 -302.074834) (xy 173.073222 -302.02578)
			(xy 173.084999 -301.977996) (xy 173.10429 -301.93272) (xy 173.130593 -301.891124) (xy 173.163228 -301.854287)
			(xy 173.201349 -301.823162) (xy 173.24397 -301.798555) (xy 173.289986 -301.781103) (xy 173.338205 -301.771259)
			(xy 173.38738 -301.769278) (xy 173.436235 -301.77521) (xy 173.483506 -301.788902) (xy 173.527968 -301.81)
			(xy 173.568471 -301.837956) (xy 173.603964 -301.872048) (xy 173.633529 -301.911392) (xy 173.6564 -301.954969)
			(xy 173.671984 -302.00165) (xy 173.679879 -302.050227) (xy 173.680374 -302.074834) (xy 174.019222 -302.074834)
			(xy 174.023182 -302.02578) (xy 174.034959 -301.977996) (xy 174.05425 -301.93272) (xy 174.080553 -301.891124)
			(xy 174.113188 -301.854287) (xy 174.151309 -301.823162) (xy 174.19393 -301.798555) (xy 174.239946 -301.781103)
			(xy 174.288165 -301.771259) (xy 174.33734 -301.769278) (xy 174.386195 -301.77521) (xy 174.433466 -301.788902)
			(xy 174.477928 -301.81) (xy 174.518431 -301.837956) (xy 174.553924 -301.872048) (xy 174.583489 -301.911392)
			(xy 174.60636 -301.954969) (xy 174.621944 -302.00165) (xy 174.629839 -302.050227) (xy 174.630334 -302.074834)
			(xy 175.919142 -302.074834) (xy 175.923102 -302.02578) (xy 175.934879 -301.977996) (xy 175.95417 -301.93272)
			(xy 175.980473 -301.891124) (xy 176.013108 -301.854287) (xy 176.051229 -301.823162) (xy 176.09385 -301.798555)
			(xy 176.139866 -301.781103) (xy 176.188085 -301.771259) (xy 176.23726 -301.769278) (xy 176.286115 -301.77521)
			(xy 176.333386 -301.788902) (xy 176.377848 -301.81) (xy 176.418351 -301.837956) (xy 176.453844 -301.872048)
			(xy 176.483409 -301.911392) (xy 176.50628 -301.954969) (xy 176.521864 -302.00165) (xy 176.529759 -302.050227)
			(xy 176.530254 -302.074834) (xy 176.869102 -302.074834) (xy 176.873062 -302.02578) (xy 176.884839 -301.977996)
			(xy 176.90413 -301.93272) (xy 176.930433 -301.891124) (xy 176.963068 -301.854287) (xy 177.001189 -301.823162)
			(xy 177.04381 -301.798555) (xy 177.089826 -301.781103) (xy 177.138045 -301.771259) (xy 177.18722 -301.769278)
			(xy 177.236075 -301.77521) (xy 177.283346 -301.788902) (xy 177.327808 -301.81) (xy 177.368311 -301.837956)
			(xy 177.403804 -301.872048) (xy 177.433369 -301.911392) (xy 177.45624 -301.954969) (xy 177.471824 -302.00165)
			(xy 177.479719 -302.050227) (xy 177.480214 -302.074834) (xy 177.819062 -302.074834) (xy 177.823022 -302.02578)
			(xy 177.834799 -301.977996) (xy 177.85409 -301.93272) (xy 177.880393 -301.891124) (xy 177.913028 -301.854287)
			(xy 177.951149 -301.823162) (xy 177.99377 -301.798555) (xy 178.039786 -301.781103) (xy 178.088005 -301.771259)
			(xy 178.13718 -301.769278) (xy 178.186035 -301.77521) (xy 178.233306 -301.788902) (xy 178.277768 -301.81)
			(xy 178.318271 -301.837956) (xy 178.353764 -301.872048) (xy 178.383329 -301.911392) (xy 178.4062 -301.954969)
			(xy 178.421784 -302.00165) (xy 178.429679 -302.050227) (xy 178.430174 -302.074834) (xy 178.769276 -302.074834)
			(xy 178.773236 -302.02578) (xy 178.785013 -301.977996) (xy 178.804304 -301.93272) (xy 178.830607 -301.891124)
			(xy 178.863242 -301.854287) (xy 178.901363 -301.823162) (xy 178.943984 -301.798555) (xy 178.99 -301.781103)
			(xy 179.038219 -301.771259) (xy 179.087394 -301.769278) (xy 179.136249 -301.77521) (xy 179.18352 -301.788902)
			(xy 179.227982 -301.81) (xy 179.268485 -301.837956) (xy 179.303978 -301.872048) (xy 179.333543 -301.911392)
			(xy 179.356414 -301.954969) (xy 179.371998 -302.00165) (xy 179.379893 -302.050227) (xy 179.380388 -302.074834)
			(xy 179.719236 -302.074834) (xy 179.723196 -302.02578) (xy 179.734973 -301.977996) (xy 179.754264 -301.93272)
			(xy 179.780567 -301.891124) (xy 179.813202 -301.854287) (xy 179.851323 -301.823162) (xy 179.893944 -301.798555)
			(xy 179.93996 -301.781103) (xy 179.988179 -301.771259) (xy 180.037354 -301.769278) (xy 180.086209 -301.77521)
			(xy 180.13348 -301.788902) (xy 180.177942 -301.81) (xy 180.218445 -301.837956) (xy 180.253938 -301.872048)
			(xy 180.283503 -301.911392) (xy 180.306374 -301.954969) (xy 180.321958 -302.00165) (xy 180.329853 -302.050227)
			(xy 180.330348 -302.074834) (xy 180.669196 -302.074834) (xy 180.673156 -302.02578) (xy 180.684933 -301.977996)
			(xy 180.704224 -301.93272) (xy 180.730527 -301.891124) (xy 180.763162 -301.854287) (xy 180.801283 -301.823162)
			(xy 180.843904 -301.798555) (xy 180.88992 -301.781103) (xy 180.938139 -301.771259) (xy 180.987314 -301.769278)
			(xy 181.036169 -301.77521) (xy 181.08344 -301.788902) (xy 181.127902 -301.81) (xy 181.168405 -301.837956)
			(xy 181.203898 -301.872048) (xy 181.233463 -301.911392) (xy 181.256334 -301.954969) (xy 181.271918 -302.00165)
			(xy 181.279813 -302.050227) (xy 181.280308 -302.074834) (xy 181.619156 -302.074834) (xy 181.623116 -302.02578)
			(xy 181.634893 -301.977996) (xy 181.654184 -301.93272) (xy 181.680487 -301.891124) (xy 181.713122 -301.854287)
			(xy 181.751243 -301.823162) (xy 181.793864 -301.798555) (xy 181.83988 -301.781103) (xy 181.888099 -301.771259)
			(xy 181.937274 -301.769278) (xy 181.986129 -301.77521) (xy 182.0334 -301.788902) (xy 182.077862 -301.81)
			(xy 182.118365 -301.837956) (xy 182.153858 -301.872048) (xy 182.183423 -301.911392) (xy 182.206294 -301.954969)
			(xy 182.221878 -302.00165) (xy 182.229773 -302.050227) (xy 182.230268 -302.074834) (xy 182.569116 -302.074834)
			(xy 182.573076 -302.02578) (xy 182.584853 -301.977996) (xy 182.604144 -301.93272) (xy 182.630447 -301.891124)
			(xy 182.663082 -301.854287) (xy 182.701203 -301.823162) (xy 182.743824 -301.798555) (xy 182.78984 -301.781103)
			(xy 182.838059 -301.771259) (xy 182.887234 -301.769278) (xy 182.936089 -301.77521) (xy 182.98336 -301.788902)
			(xy 183.027822 -301.81) (xy 183.068325 -301.837956) (xy 183.103818 -301.872048) (xy 183.133383 -301.911392)
			(xy 183.156254 -301.954969) (xy 183.171838 -302.00165) (xy 183.179733 -302.050227) (xy 183.180228 -302.074834)
			(xy 183.519076 -302.074834) (xy 183.523036 -302.02578) (xy 183.534813 -301.977996) (xy 183.554104 -301.93272)
			(xy 183.580407 -301.891124) (xy 183.613042 -301.854287) (xy 183.651163 -301.823162) (xy 183.693784 -301.798555)
			(xy 183.7398 -301.781103) (xy 183.788019 -301.771259) (xy 183.837194 -301.769278) (xy 183.886049 -301.77521)
			(xy 183.93332 -301.788902) (xy 183.977782 -301.81) (xy 184.018285 -301.837956) (xy 184.053778 -301.872048)
			(xy 184.083343 -301.911392) (xy 184.106214 -301.954969) (xy 184.121798 -302.00165) (xy 184.129693 -302.050227)
			(xy 184.130188 -302.074834) (xy 184.129693 -302.099441) (xy 184.121798 -302.148018) (xy 184.106214 -302.194699)
			(xy 184.083343 -302.238276) (xy 184.053778 -302.27762) (xy 184.018285 -302.311712) (xy 183.977782 -302.339668)
			(xy 183.93332 -302.360766) (xy 183.886049 -302.374458) (xy 183.837194 -302.38039) (xy 183.788019 -302.378409)
			(xy 183.7398 -302.368565) (xy 183.693784 -302.351113) (xy 183.651163 -302.326506) (xy 183.613042 -302.295381)
			(xy 183.580407 -302.258544) (xy 183.554104 -302.216948) (xy 183.534813 -302.171672) (xy 183.523036 -302.123888)
			(xy 183.519076 -302.074834) (xy 183.180228 -302.074834) (xy 183.179733 -302.099441) (xy 183.171838 -302.148018)
			(xy 183.156254 -302.194699) (xy 183.133383 -302.238276) (xy 183.103818 -302.27762) (xy 183.068325 -302.311712)
			(xy 183.027822 -302.339668) (xy 182.98336 -302.360766) (xy 182.936089 -302.374458) (xy 182.887234 -302.38039)
			(xy 182.838059 -302.378409) (xy 182.78984 -302.368565) (xy 182.743824 -302.351113) (xy 182.701203 -302.326506)
			(xy 182.663082 -302.295381) (xy 182.630447 -302.258544) (xy 182.604144 -302.216948) (xy 182.584853 -302.171672)
			(xy 182.573076 -302.123888) (xy 182.569116 -302.074834) (xy 182.230268 -302.074834) (xy 182.229773 -302.099441)
			(xy 182.221878 -302.148018) (xy 182.206294 -302.194699) (xy 182.183423 -302.238276) (xy 182.153858 -302.27762)
			(xy 182.118365 -302.311712) (xy 182.077862 -302.339668) (xy 182.0334 -302.360766) (xy 181.986129 -302.374458)
			(xy 181.937274 -302.38039) (xy 181.888099 -302.378409) (xy 181.83988 -302.368565) (xy 181.793864 -302.351113)
			(xy 181.751243 -302.326506) (xy 181.713122 -302.295381) (xy 181.680487 -302.258544) (xy 181.654184 -302.216948)
			(xy 181.634893 -302.171672) (xy 181.623116 -302.123888) (xy 181.619156 -302.074834) (xy 181.280308 -302.074834)
			(xy 181.279813 -302.099441) (xy 181.271918 -302.148018) (xy 181.256334 -302.194699) (xy 181.233463 -302.238276)
			(xy 181.203898 -302.27762) (xy 181.168405 -302.311712) (xy 181.127902 -302.339668) (xy 181.08344 -302.360766)
			(xy 181.036169 -302.374458) (xy 180.987314 -302.38039) (xy 180.938139 -302.378409) (xy 180.88992 -302.368565)
			(xy 180.843904 -302.351113) (xy 180.801283 -302.326506) (xy 180.763162 -302.295381) (xy 180.730527 -302.258544)
			(xy 180.704224 -302.216948) (xy 180.684933 -302.171672) (xy 180.673156 -302.123888) (xy 180.669196 -302.074834)
			(xy 180.330348 -302.074834) (xy 180.329853 -302.099441) (xy 180.321958 -302.148018) (xy 180.306374 -302.194699)
			(xy 180.283503 -302.238276) (xy 180.253938 -302.27762) (xy 180.218445 -302.311712) (xy 180.177942 -302.339668)
			(xy 180.13348 -302.360766) (xy 180.086209 -302.374458) (xy 180.037354 -302.38039) (xy 179.988179 -302.378409)
			(xy 179.93996 -302.368565) (xy 179.893944 -302.351113) (xy 179.851323 -302.326506) (xy 179.813202 -302.295381)
			(xy 179.780567 -302.258544) (xy 179.754264 -302.216948) (xy 179.734973 -302.171672) (xy 179.723196 -302.123888)
			(xy 179.719236 -302.074834) (xy 179.380388 -302.074834) (xy 179.379893 -302.099441) (xy 179.371998 -302.148018)
			(xy 179.356414 -302.194699) (xy 179.333543 -302.238276) (xy 179.303978 -302.27762) (xy 179.268485 -302.311712)
			(xy 179.227982 -302.339668) (xy 179.18352 -302.360766) (xy 179.136249 -302.374458) (xy 179.087394 -302.38039)
			(xy 179.038219 -302.378409) (xy 178.99 -302.368565) (xy 178.943984 -302.351113) (xy 178.901363 -302.326506)
			(xy 178.863242 -302.295381) (xy 178.830607 -302.258544) (xy 178.804304 -302.216948) (xy 178.785013 -302.171672)
			(xy 178.773236 -302.123888) (xy 178.769276 -302.074834) (xy 178.430174 -302.074834) (xy 178.429679 -302.099441)
			(xy 178.421784 -302.148018) (xy 178.4062 -302.194699) (xy 178.383329 -302.238276) (xy 178.353764 -302.27762)
			(xy 178.318271 -302.311712) (xy 178.277768 -302.339668) (xy 178.233306 -302.360766) (xy 178.186035 -302.374458)
			(xy 178.13718 -302.38039) (xy 178.088005 -302.378409) (xy 178.039786 -302.368565) (xy 177.99377 -302.351113)
			(xy 177.951149 -302.326506) (xy 177.913028 -302.295381) (xy 177.880393 -302.258544) (xy 177.85409 -302.216948)
			(xy 177.834799 -302.171672) (xy 177.823022 -302.123888) (xy 177.819062 -302.074834) (xy 177.480214 -302.074834)
			(xy 177.479719 -302.099441) (xy 177.471824 -302.148018) (xy 177.45624 -302.194699) (xy 177.433369 -302.238276)
			(xy 177.403804 -302.27762) (xy 177.368311 -302.311712) (xy 177.327808 -302.339668) (xy 177.283346 -302.360766)
			(xy 177.236075 -302.374458) (xy 177.18722 -302.38039) (xy 177.138045 -302.378409) (xy 177.089826 -302.368565)
			(xy 177.04381 -302.351113) (xy 177.001189 -302.326506) (xy 176.963068 -302.295381) (xy 176.930433 -302.258544)
			(xy 176.90413 -302.216948) (xy 176.884839 -302.171672) (xy 176.873062 -302.123888) (xy 176.869102 -302.074834)
			(xy 176.530254 -302.074834) (xy 176.529759 -302.099441) (xy 176.521864 -302.148018) (xy 176.50628 -302.194699)
			(xy 176.483409 -302.238276) (xy 176.453844 -302.27762) (xy 176.418351 -302.311712) (xy 176.377848 -302.339668)
			(xy 176.333386 -302.360766) (xy 176.286115 -302.374458) (xy 176.23726 -302.38039) (xy 176.188085 -302.378409)
			(xy 176.139866 -302.368565) (xy 176.09385 -302.351113) (xy 176.051229 -302.326506) (xy 176.013108 -302.295381)
			(xy 175.980473 -302.258544) (xy 175.95417 -302.216948) (xy 175.934879 -302.171672) (xy 175.923102 -302.123888)
			(xy 175.919142 -302.074834) (xy 174.630334 -302.074834) (xy 174.629839 -302.099441) (xy 174.621944 -302.148018)
			(xy 174.60636 -302.194699) (xy 174.583489 -302.238276) (xy 174.553924 -302.27762) (xy 174.518431 -302.311712)
			(xy 174.477928 -302.339668) (xy 174.433466 -302.360766) (xy 174.386195 -302.374458) (xy 174.33734 -302.38039)
			(xy 174.288165 -302.378409) (xy 174.239946 -302.368565) (xy 174.19393 -302.351113) (xy 174.151309 -302.326506)
			(xy 174.113188 -302.295381) (xy 174.080553 -302.258544) (xy 174.05425 -302.216948) (xy 174.034959 -302.171672)
			(xy 174.023182 -302.123888) (xy 174.019222 -302.074834) (xy 173.680374 -302.074834) (xy 173.679879 -302.099441)
			(xy 173.671984 -302.148018) (xy 173.6564 -302.194699) (xy 173.633529 -302.238276) (xy 173.603964 -302.27762)
			(xy 173.568471 -302.311712) (xy 173.527968 -302.339668) (xy 173.483506 -302.360766) (xy 173.436235 -302.374458)
			(xy 173.38738 -302.38039) (xy 173.338205 -302.378409) (xy 173.289986 -302.368565) (xy 173.24397 -302.351113)
			(xy 173.201349 -302.326506) (xy 173.163228 -302.295381) (xy 173.130593 -302.258544) (xy 173.10429 -302.216948)
			(xy 173.084999 -302.171672) (xy 173.073222 -302.123888) (xy 173.069262 -302.074834) (xy 172.73016 -302.074834)
			(xy 172.729665 -302.099441) (xy 172.72177 -302.148018) (xy 172.706186 -302.194699) (xy 172.683315 -302.238276)
			(xy 172.65375 -302.27762) (xy 172.618257 -302.311712) (xy 172.577754 -302.339668) (xy 172.533292 -302.360766)
			(xy 172.486021 -302.374458) (xy 172.437166 -302.38039) (xy 172.387991 -302.378409) (xy 172.339772 -302.368565)
			(xy 172.293756 -302.351113) (xy 172.251135 -302.326506) (xy 172.213014 -302.295381) (xy 172.180379 -302.258544)
			(xy 172.154076 -302.216948) (xy 172.134785 -302.171672) (xy 172.123008 -302.123888) (xy 172.119048 -302.074834)
			(xy 171.7802 -302.074834) (xy 171.779705 -302.099441) (xy 171.77181 -302.148018) (xy 171.756226 -302.194699)
			(xy 171.733355 -302.238276) (xy 171.70379 -302.27762) (xy 171.668297 -302.311712) (xy 171.627794 -302.339668)
			(xy 171.583332 -302.360766) (xy 171.536061 -302.374458) (xy 171.487206 -302.38039) (xy 171.438031 -302.378409)
			(xy 171.389812 -302.368565) (xy 171.343796 -302.351113) (xy 171.301175 -302.326506) (xy 171.263054 -302.295381)
			(xy 171.230419 -302.258544) (xy 171.204116 -302.216948) (xy 171.184825 -302.171672) (xy 171.173048 -302.123888)
			(xy 171.169088 -302.074834) (xy 170.83024 -302.074834) (xy 170.829745 -302.099441) (xy 170.82185 -302.148018)
			(xy 170.806266 -302.194699) (xy 170.783395 -302.238276) (xy 170.75383 -302.27762) (xy 170.718337 -302.311712)
			(xy 170.677834 -302.339668) (xy 170.633372 -302.360766) (xy 170.586101 -302.374458) (xy 170.537246 -302.38039)
			(xy 170.488071 -302.378409) (xy 170.439852 -302.368565) (xy 170.393836 -302.351113) (xy 170.351215 -302.326506)
			(xy 170.313094 -302.295381) (xy 170.280459 -302.258544) (xy 170.254156 -302.216948) (xy 170.234865 -302.171672)
			(xy 170.223088 -302.123888) (xy 170.219128 -302.074834) (xy 169.88028 -302.074834) (xy 169.879785 -302.099441)
			(xy 169.87189 -302.148018) (xy 169.856306 -302.194699) (xy 169.833435 -302.238276) (xy 169.80387 -302.27762)
			(xy 169.768377 -302.311712) (xy 169.727874 -302.339668) (xy 169.683412 -302.360766) (xy 169.636141 -302.374458)
			(xy 169.587286 -302.38039) (xy 169.538111 -302.378409) (xy 169.489892 -302.368565) (xy 169.443876 -302.351113)
			(xy 169.401255 -302.326506) (xy 169.363134 -302.295381) (xy 169.330499 -302.258544) (xy 169.304196 -302.216948)
			(xy 169.284905 -302.171672) (xy 169.273128 -302.123888) (xy 169.269168 -302.074834) (xy 168.93032 -302.074834)
			(xy 168.929825 -302.099441) (xy 168.92193 -302.148018) (xy 168.906346 -302.194699) (xy 168.883475 -302.238276)
			(xy 168.85391 -302.27762) (xy 168.818417 -302.311712) (xy 168.777914 -302.339668) (xy 168.733452 -302.360766)
			(xy 168.686181 -302.374458) (xy 168.637326 -302.38039) (xy 168.588151 -302.378409) (xy 168.539932 -302.368565)
			(xy 168.493916 -302.351113) (xy 168.451295 -302.326506) (xy 168.413174 -302.295381) (xy 168.380539 -302.258544)
			(xy 168.354236 -302.216948) (xy 168.334945 -302.171672) (xy 168.323168 -302.123888) (xy 168.319208 -302.074834)
			(xy 167.98036 -302.074834) (xy 167.979865 -302.099441) (xy 167.97197 -302.148018) (xy 167.956386 -302.194699)
			(xy 167.933515 -302.238276) (xy 167.90395 -302.27762) (xy 167.868457 -302.311712) (xy 167.827954 -302.339668)
			(xy 167.783492 -302.360766) (xy 167.736221 -302.374458) (xy 167.687366 -302.38039) (xy 167.638191 -302.378409)
			(xy 167.589972 -302.368565) (xy 167.543956 -302.351113) (xy 167.501335 -302.326506) (xy 167.463214 -302.295381)
			(xy 167.430579 -302.258544) (xy 167.404276 -302.216948) (xy 167.384985 -302.171672) (xy 167.373208 -302.123888)
			(xy 167.369248 -302.074834) (xy 167.0304 -302.074834) (xy 167.029905 -302.099441) (xy 167.02201 -302.148018)
			(xy 167.006426 -302.194699) (xy 166.983555 -302.238276) (xy 166.95399 -302.27762) (xy 166.918497 -302.311712)
			(xy 166.877994 -302.339668) (xy 166.833532 -302.360766) (xy 166.786261 -302.374458) (xy 166.737406 -302.38039)
			(xy 166.688231 -302.378409) (xy 166.640012 -302.368565) (xy 166.593996 -302.351113) (xy 166.551375 -302.326506)
			(xy 166.513254 -302.295381) (xy 166.480619 -302.258544) (xy 166.454316 -302.216948) (xy 166.435025 -302.171672)
			(xy 166.423248 -302.123888) (xy 166.419288 -302.074834) (xy 166.080186 -302.074834) (xy 166.079691 -302.099441)
			(xy 166.071796 -302.148018) (xy 166.056212 -302.194699) (xy 166.033341 -302.238276) (xy 166.003776 -302.27762)
			(xy 165.968283 -302.311712) (xy 165.92778 -302.339668) (xy 165.883318 -302.360766) (xy 165.836047 -302.374458)
			(xy 165.787192 -302.38039) (xy 165.738017 -302.378409) (xy 165.689798 -302.368565) (xy 165.643782 -302.351113)
			(xy 165.601161 -302.326506) (xy 165.56304 -302.295381) (xy 165.530405 -302.258544) (xy 165.504102 -302.216948)
			(xy 165.484811 -302.171672) (xy 165.473034 -302.123888) (xy 165.469074 -302.074834) (xy 162.280862 -302.074834)
			(xy 162.276694 -302.12514) (xy 162.264295 -302.174107) (xy 162.244006 -302.220365) (xy 162.21638 -302.262654)
			(xy 162.182171 -302.299819) (xy 162.142312 -302.330847) (xy 162.09789 -302.354892) (xy 162.050116 -302.371298)
			(xy 162.000294 -302.379617) (xy 161.975038 -302.380142) (xy 161.960855 -302.37996) (xy 161.932615 -302.377291)
			(xy 161.91865 -302.374808) (xy 161.906204 -302.372522) (xy 161.882582 -302.379888) (xy 161.805112 -302.457358)
			(xy 161.797746 -302.48098) (xy 161.800032 -302.493426) (xy 161.802508 -302.507392) (xy 161.80518 -302.535631)
			(xy 161.805366 -302.549814) (xy 161.805192 -302.563997) (xy 161.802518 -302.592237) (xy 161.800032 -302.606202)
			(xy 161.797746 -302.618648) (xy 161.805112 -302.64227) (xy 161.882582 -302.71974) (xy 161.906204 -302.727106)
			(xy 161.91865 -302.72482) (xy 161.932615 -302.722341) (xy 161.960855 -302.719671) (xy 161.975038 -302.719486)
			(xy 162.000291 -302.720023) (xy 162.050107 -302.728341) (xy 162.097874 -302.744745) (xy 162.142291 -302.768787)
			(xy 162.182144 -302.799811) (xy 162.216349 -302.836971) (xy 162.243971 -302.879254) (xy 162.264257 -302.925506)
			(xy 162.276655 -302.974467) (xy 162.280825 -303.024794) (xy 162.619194 -303.024794) (xy 162.623154 -302.97574)
			(xy 162.634931 -302.927956) (xy 162.654222 -302.88268) (xy 162.680525 -302.841084) (xy 162.71316 -302.804247)
			(xy 162.751281 -302.773122) (xy 162.793902 -302.748515) (xy 162.839918 -302.731063) (xy 162.888137 -302.721219)
			(xy 162.937312 -302.719238) (xy 162.986167 -302.72517) (xy 163.033438 -302.738862) (xy 163.0779 -302.75996)
			(xy 163.118403 -302.787916) (xy 163.153896 -302.822008) (xy 163.183461 -302.861352) (xy 163.206332 -302.904929)
			(xy 163.221916 -302.95161) (xy 163.229811 -303.000187) (xy 163.230306 -303.024794) (xy 163.569154 -303.024794)
			(xy 163.573114 -302.97574) (xy 163.584891 -302.927956) (xy 163.604182 -302.88268) (xy 163.630485 -302.841084)
			(xy 163.66312 -302.804247) (xy 163.701241 -302.773122) (xy 163.743862 -302.748515) (xy 163.789878 -302.731063)
			(xy 163.838097 -302.721219) (xy 163.887272 -302.719238) (xy 163.936127 -302.72517) (xy 163.983398 -302.738862)
			(xy 164.02786 -302.75996) (xy 164.068363 -302.787916) (xy 164.103856 -302.822008) (xy 164.133421 -302.861352)
			(xy 164.156292 -302.904929) (xy 164.171876 -302.95161) (xy 164.179771 -303.000187) (xy 164.180266 -303.024794)
			(xy 164.519114 -303.024794) (xy 164.523074 -302.97574) (xy 164.534851 -302.927956) (xy 164.554142 -302.88268)
			(xy 164.580445 -302.841084) (xy 164.61308 -302.804247) (xy 164.651201 -302.773122) (xy 164.693822 -302.748515)
			(xy 164.739838 -302.731063) (xy 164.788057 -302.721219) (xy 164.837232 -302.719238) (xy 164.886087 -302.72517)
			(xy 164.933358 -302.738862) (xy 164.97782 -302.75996) (xy 165.018323 -302.787916) (xy 165.053816 -302.822008)
			(xy 165.083381 -302.861352) (xy 165.106252 -302.904929) (xy 165.121836 -302.95161) (xy 165.129731 -303.000187)
			(xy 165.130226 -303.024794) (xy 165.469074 -303.024794) (xy 165.473034 -302.97574) (xy 165.484811 -302.927956)
			(xy 165.504102 -302.88268) (xy 165.530405 -302.841084) (xy 165.56304 -302.804247) (xy 165.601161 -302.773122)
			(xy 165.643782 -302.748515) (xy 165.689798 -302.731063) (xy 165.738017 -302.721219) (xy 165.787192 -302.719238)
			(xy 165.836047 -302.72517) (xy 165.883318 -302.738862) (xy 165.92778 -302.75996) (xy 165.968283 -302.787916)
			(xy 166.003776 -302.822008) (xy 166.033341 -302.861352) (xy 166.056212 -302.904929) (xy 166.071796 -302.95161)
			(xy 166.079691 -303.000187) (xy 166.080186 -303.024794) (xy 166.419288 -303.024794) (xy 166.423248 -302.97574)
			(xy 166.435025 -302.927956) (xy 166.454316 -302.88268) (xy 166.480619 -302.841084) (xy 166.513254 -302.804247)
			(xy 166.551375 -302.773122) (xy 166.593996 -302.748515) (xy 166.640012 -302.731063) (xy 166.688231 -302.721219)
			(xy 166.737406 -302.719238) (xy 166.786261 -302.72517) (xy 166.833532 -302.738862) (xy 166.877994 -302.75996)
			(xy 166.918497 -302.787916) (xy 166.95399 -302.822008) (xy 166.983555 -302.861352) (xy 167.006426 -302.904929)
			(xy 167.02201 -302.95161) (xy 167.029905 -303.000187) (xy 167.0304 -303.024794) (xy 167.369248 -303.024794)
			(xy 167.373208 -302.97574) (xy 167.384985 -302.927956) (xy 167.404276 -302.88268) (xy 167.430579 -302.841084)
			(xy 167.463214 -302.804247) (xy 167.501335 -302.773122) (xy 167.543956 -302.748515) (xy 167.589972 -302.731063)
			(xy 167.638191 -302.721219) (xy 167.687366 -302.719238) (xy 167.736221 -302.72517) (xy 167.783492 -302.738862)
			(xy 167.827954 -302.75996) (xy 167.868457 -302.787916) (xy 167.90395 -302.822008) (xy 167.933515 -302.861352)
			(xy 167.956386 -302.904929) (xy 167.97197 -302.95161) (xy 167.979865 -303.000187) (xy 167.98036 -303.024794)
			(xy 168.319208 -303.024794) (xy 168.323168 -302.97574) (xy 168.334945 -302.927956) (xy 168.354236 -302.88268)
			(xy 168.380539 -302.841084) (xy 168.413174 -302.804247) (xy 168.451295 -302.773122) (xy 168.493916 -302.748515)
			(xy 168.539932 -302.731063) (xy 168.588151 -302.721219) (xy 168.637326 -302.719238) (xy 168.686181 -302.72517)
			(xy 168.733452 -302.738862) (xy 168.777914 -302.75996) (xy 168.818417 -302.787916) (xy 168.85391 -302.822008)
			(xy 168.883475 -302.861352) (xy 168.906346 -302.904929) (xy 168.92193 -302.95161) (xy 168.929825 -303.000187)
			(xy 168.93032 -303.024794) (xy 169.269168 -303.024794) (xy 169.273128 -302.97574) (xy 169.284905 -302.927956)
			(xy 169.304196 -302.88268) (xy 169.330499 -302.841084) (xy 169.363134 -302.804247) (xy 169.401255 -302.773122)
			(xy 169.443876 -302.748515) (xy 169.489892 -302.731063) (xy 169.538111 -302.721219) (xy 169.587286 -302.719238)
			(xy 169.636141 -302.72517) (xy 169.683412 -302.738862) (xy 169.727874 -302.75996) (xy 169.768377 -302.787916)
			(xy 169.80387 -302.822008) (xy 169.833435 -302.861352) (xy 169.856306 -302.904929) (xy 169.87189 -302.95161)
			(xy 169.879785 -303.000187) (xy 169.88028 -303.024794) (xy 170.219128 -303.024794) (xy 170.223088 -302.97574)
			(xy 170.234865 -302.927956) (xy 170.254156 -302.88268) (xy 170.280459 -302.841084) (xy 170.313094 -302.804247)
			(xy 170.351215 -302.773122) (xy 170.393836 -302.748515) (xy 170.439852 -302.731063) (xy 170.488071 -302.721219)
			(xy 170.537246 -302.719238) (xy 170.586101 -302.72517) (xy 170.633372 -302.738862) (xy 170.677834 -302.75996)
			(xy 170.718337 -302.787916) (xy 170.75383 -302.822008) (xy 170.783395 -302.861352) (xy 170.806266 -302.904929)
			(xy 170.82185 -302.95161) (xy 170.829745 -303.000187) (xy 170.83024 -303.024794) (xy 171.169088 -303.024794)
			(xy 171.173048 -302.97574) (xy 171.184825 -302.927956) (xy 171.204116 -302.88268) (xy 171.230419 -302.841084)
			(xy 171.263054 -302.804247) (xy 171.301175 -302.773122) (xy 171.343796 -302.748515) (xy 171.389812 -302.731063)
			(xy 171.438031 -302.721219) (xy 171.487206 -302.719238) (xy 171.536061 -302.72517) (xy 171.583332 -302.738862)
			(xy 171.627794 -302.75996) (xy 171.668297 -302.787916) (xy 171.70379 -302.822008) (xy 171.733355 -302.861352)
			(xy 171.756226 -302.904929) (xy 171.77181 -302.95161) (xy 171.779705 -303.000187) (xy 171.7802 -303.024794)
			(xy 172.119048 -303.024794) (xy 172.123008 -302.97574) (xy 172.134785 -302.927956) (xy 172.154076 -302.88268)
			(xy 172.180379 -302.841084) (xy 172.213014 -302.804247) (xy 172.251135 -302.773122) (xy 172.293756 -302.748515)
			(xy 172.339772 -302.731063) (xy 172.387991 -302.721219) (xy 172.437166 -302.719238) (xy 172.486021 -302.72517)
			(xy 172.533292 -302.738862) (xy 172.577754 -302.75996) (xy 172.618257 -302.787916) (xy 172.65375 -302.822008)
			(xy 172.683315 -302.861352) (xy 172.706186 -302.904929) (xy 172.72177 -302.95161) (xy 172.729665 -303.000187)
			(xy 172.73016 -303.024794) (xy 173.069262 -303.024794) (xy 173.073222 -302.97574) (xy 173.084999 -302.927956)
			(xy 173.10429 -302.88268) (xy 173.130593 -302.841084) (xy 173.163228 -302.804247) (xy 173.201349 -302.773122)
			(xy 173.24397 -302.748515) (xy 173.289986 -302.731063) (xy 173.338205 -302.721219) (xy 173.38738 -302.719238)
			(xy 173.436235 -302.72517) (xy 173.483506 -302.738862) (xy 173.527968 -302.75996) (xy 173.568471 -302.787916)
			(xy 173.603964 -302.822008) (xy 173.633529 -302.861352) (xy 173.6564 -302.904929) (xy 173.671984 -302.95161)
			(xy 173.679879 -303.000187) (xy 173.680374 -303.024794) (xy 174.019222 -303.024794) (xy 174.023182 -302.97574)
			(xy 174.034959 -302.927956) (xy 174.05425 -302.88268) (xy 174.080553 -302.841084) (xy 174.113188 -302.804247)
			(xy 174.151309 -302.773122) (xy 174.19393 -302.748515) (xy 174.239946 -302.731063) (xy 174.288165 -302.721219)
			(xy 174.33734 -302.719238) (xy 174.386195 -302.72517) (xy 174.433466 -302.738862) (xy 174.477928 -302.75996)
			(xy 174.518431 -302.787916) (xy 174.553924 -302.822008) (xy 174.583489 -302.861352) (xy 174.60636 -302.904929)
			(xy 174.621944 -302.95161) (xy 174.629839 -303.000187) (xy 174.630334 -303.024794) (xy 175.919142 -303.024794)
			(xy 175.923102 -302.97574) (xy 175.934879 -302.927956) (xy 175.95417 -302.88268) (xy 175.980473 -302.841084)
			(xy 176.013108 -302.804247) (xy 176.051229 -302.773122) (xy 176.09385 -302.748515) (xy 176.139866 -302.731063)
			(xy 176.188085 -302.721219) (xy 176.23726 -302.719238) (xy 176.286115 -302.72517) (xy 176.333386 -302.738862)
			(xy 176.377848 -302.75996) (xy 176.418351 -302.787916) (xy 176.453844 -302.822008) (xy 176.483409 -302.861352)
			(xy 176.50628 -302.904929) (xy 176.521864 -302.95161) (xy 176.529759 -303.000187) (xy 176.530254 -303.024794)
			(xy 176.869102 -303.024794) (xy 176.873062 -302.97574) (xy 176.884839 -302.927956) (xy 176.90413 -302.88268)
			(xy 176.930433 -302.841084) (xy 176.963068 -302.804247) (xy 177.001189 -302.773122) (xy 177.04381 -302.748515)
			(xy 177.089826 -302.731063) (xy 177.138045 -302.721219) (xy 177.18722 -302.719238) (xy 177.236075 -302.72517)
			(xy 177.283346 -302.738862) (xy 177.327808 -302.75996) (xy 177.368311 -302.787916) (xy 177.403804 -302.822008)
			(xy 177.433369 -302.861352) (xy 177.45624 -302.904929) (xy 177.471824 -302.95161) (xy 177.479719 -303.000187)
			(xy 177.480214 -303.024794) (xy 177.819062 -303.024794) (xy 177.823022 -302.97574) (xy 177.834799 -302.927956)
			(xy 177.85409 -302.88268) (xy 177.880393 -302.841084) (xy 177.913028 -302.804247) (xy 177.951149 -302.773122)
			(xy 177.99377 -302.748515) (xy 178.039786 -302.731063) (xy 178.088005 -302.721219) (xy 178.13718 -302.719238)
			(xy 178.186035 -302.72517) (xy 178.233306 -302.738862) (xy 178.277768 -302.75996) (xy 178.318271 -302.787916)
			(xy 178.353764 -302.822008) (xy 178.383329 -302.861352) (xy 178.4062 -302.904929) (xy 178.421784 -302.95161)
			(xy 178.429679 -303.000187) (xy 178.430174 -303.024794) (xy 178.769276 -303.024794) (xy 178.773236 -302.97574)
			(xy 178.785013 -302.927956) (xy 178.804304 -302.88268) (xy 178.830607 -302.841084) (xy 178.863242 -302.804247)
			(xy 178.901363 -302.773122) (xy 178.943984 -302.748515) (xy 178.99 -302.731063) (xy 179.038219 -302.721219)
			(xy 179.087394 -302.719238) (xy 179.136249 -302.72517) (xy 179.18352 -302.738862) (xy 179.227982 -302.75996)
			(xy 179.268485 -302.787916) (xy 179.303978 -302.822008) (xy 179.333543 -302.861352) (xy 179.356414 -302.904929)
			(xy 179.371998 -302.95161) (xy 179.379893 -303.000187) (xy 179.380388 -303.024794) (xy 179.719236 -303.024794)
			(xy 179.723196 -302.97574) (xy 179.734973 -302.927956) (xy 179.754264 -302.88268) (xy 179.780567 -302.841084)
			(xy 179.813202 -302.804247) (xy 179.851323 -302.773122) (xy 179.893944 -302.748515) (xy 179.93996 -302.731063)
			(xy 179.988179 -302.721219) (xy 180.037354 -302.719238) (xy 180.086209 -302.72517) (xy 180.13348 -302.738862)
			(xy 180.177942 -302.75996) (xy 180.218445 -302.787916) (xy 180.253938 -302.822008) (xy 180.283503 -302.861352)
			(xy 180.306374 -302.904929) (xy 180.321958 -302.95161) (xy 180.329853 -303.000187) (xy 180.330348 -303.024794)
			(xy 180.669196 -303.024794) (xy 180.673156 -302.97574) (xy 180.684933 -302.927956) (xy 180.704224 -302.88268)
			(xy 180.730527 -302.841084) (xy 180.763162 -302.804247) (xy 180.801283 -302.773122) (xy 180.843904 -302.748515)
			(xy 180.88992 -302.731063) (xy 180.938139 -302.721219) (xy 180.987314 -302.719238) (xy 181.036169 -302.72517)
			(xy 181.08344 -302.738862) (xy 181.127902 -302.75996) (xy 181.168405 -302.787916) (xy 181.203898 -302.822008)
			(xy 181.233463 -302.861352) (xy 181.256334 -302.904929) (xy 181.271918 -302.95161) (xy 181.279813 -303.000187)
			(xy 181.280308 -303.024794) (xy 181.619156 -303.024794) (xy 181.623116 -302.97574) (xy 181.634893 -302.927956)
			(xy 181.654184 -302.88268) (xy 181.680487 -302.841084) (xy 181.713122 -302.804247) (xy 181.751243 -302.773122)
			(xy 181.793864 -302.748515) (xy 181.83988 -302.731063) (xy 181.888099 -302.721219) (xy 181.937274 -302.719238)
			(xy 181.986129 -302.72517) (xy 182.0334 -302.738862) (xy 182.077862 -302.75996) (xy 182.118365 -302.787916)
			(xy 182.153858 -302.822008) (xy 182.183423 -302.861352) (xy 182.206294 -302.904929) (xy 182.221878 -302.95161)
			(xy 182.229773 -303.000187) (xy 182.230268 -303.024794) (xy 182.569116 -303.024794) (xy 182.573076 -302.97574)
			(xy 182.584853 -302.927956) (xy 182.604144 -302.88268) (xy 182.630447 -302.841084) (xy 182.663082 -302.804247)
			(xy 182.701203 -302.773122) (xy 182.743824 -302.748515) (xy 182.78984 -302.731063) (xy 182.838059 -302.721219)
			(xy 182.887234 -302.719238) (xy 182.936089 -302.72517) (xy 182.98336 -302.738862) (xy 183.027822 -302.75996)
			(xy 183.068325 -302.787916) (xy 183.103818 -302.822008) (xy 183.133383 -302.861352) (xy 183.156254 -302.904929)
			(xy 183.171838 -302.95161) (xy 183.179733 -303.000187) (xy 183.180228 -303.024794) (xy 183.519076 -303.024794)
			(xy 183.523036 -302.97574) (xy 183.534813 -302.927956) (xy 183.554104 -302.88268) (xy 183.580407 -302.841084)
			(xy 183.613042 -302.804247) (xy 183.651163 -302.773122) (xy 183.693784 -302.748515) (xy 183.7398 -302.731063)
			(xy 183.788019 -302.721219) (xy 183.837194 -302.719238) (xy 183.886049 -302.72517) (xy 183.93332 -302.738862)
			(xy 183.977782 -302.75996) (xy 184.018285 -302.787916) (xy 184.053778 -302.822008) (xy 184.083343 -302.861352)
			(xy 184.106214 -302.904929) (xy 184.121798 -302.95161) (xy 184.129693 -303.000187) (xy 184.130188 -303.024794)
			(xy 184.129693 -303.049401) (xy 184.121798 -303.097978) (xy 184.106214 -303.144659) (xy 184.083343 -303.188236)
			(xy 184.053778 -303.22758) (xy 184.018285 -303.261672) (xy 183.977782 -303.289628) (xy 183.93332 -303.310726)
			(xy 183.886049 -303.324418) (xy 183.837194 -303.33035) (xy 183.788019 -303.328369) (xy 183.7398 -303.318525)
			(xy 183.693784 -303.301073) (xy 183.651163 -303.276466) (xy 183.613042 -303.245341) (xy 183.580407 -303.208504)
			(xy 183.554104 -303.166908) (xy 183.534813 -303.121632) (xy 183.523036 -303.073848) (xy 183.519076 -303.024794)
			(xy 183.180228 -303.024794) (xy 183.179733 -303.049401) (xy 183.171838 -303.097978) (xy 183.156254 -303.144659)
			(xy 183.133383 -303.188236) (xy 183.103818 -303.22758) (xy 183.068325 -303.261672) (xy 183.027822 -303.289628)
			(xy 182.98336 -303.310726) (xy 182.936089 -303.324418) (xy 182.887234 -303.33035) (xy 182.838059 -303.328369)
			(xy 182.78984 -303.318525) (xy 182.743824 -303.301073) (xy 182.701203 -303.276466) (xy 182.663082 -303.245341)
			(xy 182.630447 -303.208504) (xy 182.604144 -303.166908) (xy 182.584853 -303.121632) (xy 182.573076 -303.073848)
			(xy 182.569116 -303.024794) (xy 182.230268 -303.024794) (xy 182.229773 -303.049401) (xy 182.221878 -303.097978)
			(xy 182.206294 -303.144659) (xy 182.183423 -303.188236) (xy 182.153858 -303.22758) (xy 182.118365 -303.261672)
			(xy 182.077862 -303.289628) (xy 182.0334 -303.310726) (xy 181.986129 -303.324418) (xy 181.937274 -303.33035)
			(xy 181.888099 -303.328369) (xy 181.83988 -303.318525) (xy 181.793864 -303.301073) (xy 181.751243 -303.276466)
			(xy 181.713122 -303.245341) (xy 181.680487 -303.208504) (xy 181.654184 -303.166908) (xy 181.634893 -303.121632)
			(xy 181.623116 -303.073848) (xy 181.619156 -303.024794) (xy 181.280308 -303.024794) (xy 181.279813 -303.049401)
			(xy 181.271918 -303.097978) (xy 181.256334 -303.144659) (xy 181.233463 -303.188236) (xy 181.203898 -303.22758)
			(xy 181.168405 -303.261672) (xy 181.127902 -303.289628) (xy 181.08344 -303.310726) (xy 181.036169 -303.324418)
			(xy 180.987314 -303.33035) (xy 180.938139 -303.328369) (xy 180.88992 -303.318525) (xy 180.843904 -303.301073)
			(xy 180.801283 -303.276466) (xy 180.763162 -303.245341) (xy 180.730527 -303.208504) (xy 180.704224 -303.166908)
			(xy 180.684933 -303.121632) (xy 180.673156 -303.073848) (xy 180.669196 -303.024794) (xy 180.330348 -303.024794)
			(xy 180.329853 -303.049401) (xy 180.321958 -303.097978) (xy 180.306374 -303.144659) (xy 180.283503 -303.188236)
			(xy 180.253938 -303.22758) (xy 180.218445 -303.261672) (xy 180.177942 -303.289628) (xy 180.13348 -303.310726)
			(xy 180.086209 -303.324418) (xy 180.037354 -303.33035) (xy 179.988179 -303.328369) (xy 179.93996 -303.318525)
			(xy 179.893944 -303.301073) (xy 179.851323 -303.276466) (xy 179.813202 -303.245341) (xy 179.780567 -303.208504)
			(xy 179.754264 -303.166908) (xy 179.734973 -303.121632) (xy 179.723196 -303.073848) (xy 179.719236 -303.024794)
			(xy 179.380388 -303.024794) (xy 179.379893 -303.049401) (xy 179.371998 -303.097978) (xy 179.356414 -303.144659)
			(xy 179.333543 -303.188236) (xy 179.303978 -303.22758) (xy 179.268485 -303.261672) (xy 179.227982 -303.289628)
			(xy 179.18352 -303.310726) (xy 179.136249 -303.324418) (xy 179.087394 -303.33035) (xy 179.038219 -303.328369)
			(xy 178.99 -303.318525) (xy 178.943984 -303.301073) (xy 178.901363 -303.276466) (xy 178.863242 -303.245341)
			(xy 178.830607 -303.208504) (xy 178.804304 -303.166908) (xy 178.785013 -303.121632) (xy 178.773236 -303.073848)
			(xy 178.769276 -303.024794) (xy 178.430174 -303.024794) (xy 178.429679 -303.049401) (xy 178.421784 -303.097978)
			(xy 178.4062 -303.144659) (xy 178.383329 -303.188236) (xy 178.353764 -303.22758) (xy 178.318271 -303.261672)
			(xy 178.277768 -303.289628) (xy 178.233306 -303.310726) (xy 178.186035 -303.324418) (xy 178.13718 -303.33035)
			(xy 178.088005 -303.328369) (xy 178.039786 -303.318525) (xy 177.99377 -303.301073) (xy 177.951149 -303.276466)
			(xy 177.913028 -303.245341) (xy 177.880393 -303.208504) (xy 177.85409 -303.166908) (xy 177.834799 -303.121632)
			(xy 177.823022 -303.073848) (xy 177.819062 -303.024794) (xy 177.480214 -303.024794) (xy 177.479719 -303.049401)
			(xy 177.471824 -303.097978) (xy 177.45624 -303.144659) (xy 177.433369 -303.188236) (xy 177.403804 -303.22758)
			(xy 177.368311 -303.261672) (xy 177.327808 -303.289628) (xy 177.283346 -303.310726) (xy 177.236075 -303.324418)
			(xy 177.18722 -303.33035) (xy 177.138045 -303.328369) (xy 177.089826 -303.318525) (xy 177.04381 -303.301073)
			(xy 177.001189 -303.276466) (xy 176.963068 -303.245341) (xy 176.930433 -303.208504) (xy 176.90413 -303.166908)
			(xy 176.884839 -303.121632) (xy 176.873062 -303.073848) (xy 176.869102 -303.024794) (xy 176.530254 -303.024794)
			(xy 176.529759 -303.049401) (xy 176.521864 -303.097978) (xy 176.50628 -303.144659) (xy 176.483409 -303.188236)
			(xy 176.453844 -303.22758) (xy 176.418351 -303.261672) (xy 176.377848 -303.289628) (xy 176.333386 -303.310726)
			(xy 176.286115 -303.324418) (xy 176.23726 -303.33035) (xy 176.188085 -303.328369) (xy 176.139866 -303.318525)
			(xy 176.09385 -303.301073) (xy 176.051229 -303.276466) (xy 176.013108 -303.245341) (xy 175.980473 -303.208504)
			(xy 175.95417 -303.166908) (xy 175.934879 -303.121632) (xy 175.923102 -303.073848) (xy 175.919142 -303.024794)
			(xy 174.630334 -303.024794) (xy 174.629839 -303.049401) (xy 174.621944 -303.097978) (xy 174.60636 -303.144659)
			(xy 174.583489 -303.188236) (xy 174.553924 -303.22758) (xy 174.518431 -303.261672) (xy 174.477928 -303.289628)
			(xy 174.433466 -303.310726) (xy 174.386195 -303.324418) (xy 174.33734 -303.33035) (xy 174.288165 -303.328369)
			(xy 174.239946 -303.318525) (xy 174.19393 -303.301073) (xy 174.151309 -303.276466) (xy 174.113188 -303.245341)
			(xy 174.080553 -303.208504) (xy 174.05425 -303.166908) (xy 174.034959 -303.121632) (xy 174.023182 -303.073848)
			(xy 174.019222 -303.024794) (xy 173.680374 -303.024794) (xy 173.679879 -303.049401) (xy 173.671984 -303.097978)
			(xy 173.6564 -303.144659) (xy 173.633529 -303.188236) (xy 173.603964 -303.22758) (xy 173.568471 -303.261672)
			(xy 173.527968 -303.289628) (xy 173.483506 -303.310726) (xy 173.436235 -303.324418) (xy 173.38738 -303.33035)
			(xy 173.338205 -303.328369) (xy 173.289986 -303.318525) (xy 173.24397 -303.301073) (xy 173.201349 -303.276466)
			(xy 173.163228 -303.245341) (xy 173.130593 -303.208504) (xy 173.10429 -303.166908) (xy 173.084999 -303.121632)
			(xy 173.073222 -303.073848) (xy 173.069262 -303.024794) (xy 172.73016 -303.024794) (xy 172.729665 -303.049401)
			(xy 172.72177 -303.097978) (xy 172.706186 -303.144659) (xy 172.683315 -303.188236) (xy 172.65375 -303.22758)
			(xy 172.618257 -303.261672) (xy 172.577754 -303.289628) (xy 172.533292 -303.310726) (xy 172.486021 -303.324418)
			(xy 172.437166 -303.33035) (xy 172.387991 -303.328369) (xy 172.339772 -303.318525) (xy 172.293756 -303.301073)
			(xy 172.251135 -303.276466) (xy 172.213014 -303.245341) (xy 172.180379 -303.208504) (xy 172.154076 -303.166908)
			(xy 172.134785 -303.121632) (xy 172.123008 -303.073848) (xy 172.119048 -303.024794) (xy 171.7802 -303.024794)
			(xy 171.779705 -303.049401) (xy 171.77181 -303.097978) (xy 171.756226 -303.144659) (xy 171.733355 -303.188236)
			(xy 171.70379 -303.22758) (xy 171.668297 -303.261672) (xy 171.627794 -303.289628) (xy 171.583332 -303.310726)
			(xy 171.536061 -303.324418) (xy 171.487206 -303.33035) (xy 171.438031 -303.328369) (xy 171.389812 -303.318525)
			(xy 171.343796 -303.301073) (xy 171.301175 -303.276466) (xy 171.263054 -303.245341) (xy 171.230419 -303.208504)
			(xy 171.204116 -303.166908) (xy 171.184825 -303.121632) (xy 171.173048 -303.073848) (xy 171.169088 -303.024794)
			(xy 170.83024 -303.024794) (xy 170.829745 -303.049401) (xy 170.82185 -303.097978) (xy 170.806266 -303.144659)
			(xy 170.783395 -303.188236) (xy 170.75383 -303.22758) (xy 170.718337 -303.261672) (xy 170.677834 -303.289628)
			(xy 170.633372 -303.310726) (xy 170.586101 -303.324418) (xy 170.537246 -303.33035) (xy 170.488071 -303.328369)
			(xy 170.439852 -303.318525) (xy 170.393836 -303.301073) (xy 170.351215 -303.276466) (xy 170.313094 -303.245341)
			(xy 170.280459 -303.208504) (xy 170.254156 -303.166908) (xy 170.234865 -303.121632) (xy 170.223088 -303.073848)
			(xy 170.219128 -303.024794) (xy 169.88028 -303.024794) (xy 169.879785 -303.049401) (xy 169.87189 -303.097978)
			(xy 169.856306 -303.144659) (xy 169.833435 -303.188236) (xy 169.80387 -303.22758) (xy 169.768377 -303.261672)
			(xy 169.727874 -303.289628) (xy 169.683412 -303.310726) (xy 169.636141 -303.324418) (xy 169.587286 -303.33035)
			(xy 169.538111 -303.328369) (xy 169.489892 -303.318525) (xy 169.443876 -303.301073) (xy 169.401255 -303.276466)
			(xy 169.363134 -303.245341) (xy 169.330499 -303.208504) (xy 169.304196 -303.166908) (xy 169.284905 -303.121632)
			(xy 169.273128 -303.073848) (xy 169.269168 -303.024794) (xy 168.93032 -303.024794) (xy 168.929825 -303.049401)
			(xy 168.92193 -303.097978) (xy 168.906346 -303.144659) (xy 168.883475 -303.188236) (xy 168.85391 -303.22758)
			(xy 168.818417 -303.261672) (xy 168.777914 -303.289628) (xy 168.733452 -303.310726) (xy 168.686181 -303.324418)
			(xy 168.637326 -303.33035) (xy 168.588151 -303.328369) (xy 168.539932 -303.318525) (xy 168.493916 -303.301073)
			(xy 168.451295 -303.276466) (xy 168.413174 -303.245341) (xy 168.380539 -303.208504) (xy 168.354236 -303.166908)
			(xy 168.334945 -303.121632) (xy 168.323168 -303.073848) (xy 168.319208 -303.024794) (xy 167.98036 -303.024794)
			(xy 167.979865 -303.049401) (xy 167.97197 -303.097978) (xy 167.956386 -303.144659) (xy 167.933515 -303.188236)
			(xy 167.90395 -303.22758) (xy 167.868457 -303.261672) (xy 167.827954 -303.289628) (xy 167.783492 -303.310726)
			(xy 167.736221 -303.324418) (xy 167.687366 -303.33035) (xy 167.638191 -303.328369) (xy 167.589972 -303.318525)
			(xy 167.543956 -303.301073) (xy 167.501335 -303.276466) (xy 167.463214 -303.245341) (xy 167.430579 -303.208504)
			(xy 167.404276 -303.166908) (xy 167.384985 -303.121632) (xy 167.373208 -303.073848) (xy 167.369248 -303.024794)
			(xy 167.0304 -303.024794) (xy 167.029905 -303.049401) (xy 167.02201 -303.097978) (xy 167.006426 -303.144659)
			(xy 166.983555 -303.188236) (xy 166.95399 -303.22758) (xy 166.918497 -303.261672) (xy 166.877994 -303.289628)
			(xy 166.833532 -303.310726) (xy 166.786261 -303.324418) (xy 166.737406 -303.33035) (xy 166.688231 -303.328369)
			(xy 166.640012 -303.318525) (xy 166.593996 -303.301073) (xy 166.551375 -303.276466) (xy 166.513254 -303.245341)
			(xy 166.480619 -303.208504) (xy 166.454316 -303.166908) (xy 166.435025 -303.121632) (xy 166.423248 -303.073848)
			(xy 166.419288 -303.024794) (xy 166.080186 -303.024794) (xy 166.079691 -303.049401) (xy 166.071796 -303.097978)
			(xy 166.056212 -303.144659) (xy 166.033341 -303.188236) (xy 166.003776 -303.22758) (xy 165.968283 -303.261672)
			(xy 165.92778 -303.289628) (xy 165.883318 -303.310726) (xy 165.836047 -303.324418) (xy 165.787192 -303.33035)
			(xy 165.738017 -303.328369) (xy 165.689798 -303.318525) (xy 165.643782 -303.301073) (xy 165.601161 -303.276466)
			(xy 165.56304 -303.245341) (xy 165.530405 -303.208504) (xy 165.504102 -303.166908) (xy 165.484811 -303.121632)
			(xy 165.473034 -303.073848) (xy 165.469074 -303.024794) (xy 165.130226 -303.024794) (xy 165.129731 -303.049401)
			(xy 165.121836 -303.097978) (xy 165.106252 -303.144659) (xy 165.083381 -303.188236) (xy 165.053816 -303.22758)
			(xy 165.018323 -303.261672) (xy 164.97782 -303.289628) (xy 164.933358 -303.310726) (xy 164.886087 -303.324418)
			(xy 164.837232 -303.33035) (xy 164.788057 -303.328369) (xy 164.739838 -303.318525) (xy 164.693822 -303.301073)
			(xy 164.651201 -303.276466) (xy 164.61308 -303.245341) (xy 164.580445 -303.208504) (xy 164.554142 -303.166908)
			(xy 164.534851 -303.121632) (xy 164.523074 -303.073848) (xy 164.519114 -303.024794) (xy 164.180266 -303.024794)
			(xy 164.179771 -303.049401) (xy 164.171876 -303.097978) (xy 164.156292 -303.144659) (xy 164.133421 -303.188236)
			(xy 164.103856 -303.22758) (xy 164.068363 -303.261672) (xy 164.02786 -303.289628) (xy 163.983398 -303.310726)
			(xy 163.936127 -303.324418) (xy 163.887272 -303.33035) (xy 163.838097 -303.328369) (xy 163.789878 -303.318525)
			(xy 163.743862 -303.301073) (xy 163.701241 -303.276466) (xy 163.66312 -303.245341) (xy 163.630485 -303.208504)
			(xy 163.604182 -303.166908) (xy 163.584891 -303.121632) (xy 163.573114 -303.073848) (xy 163.569154 -303.024794)
			(xy 163.230306 -303.024794) (xy 163.229811 -303.049401) (xy 163.221916 -303.097978) (xy 163.206332 -303.144659)
			(xy 163.183461 -303.188236) (xy 163.153896 -303.22758) (xy 163.118403 -303.261672) (xy 163.0779 -303.289628)
			(xy 163.033438 -303.310726) (xy 162.986167 -303.324418) (xy 162.937312 -303.33035) (xy 162.888137 -303.328369)
			(xy 162.839918 -303.318525) (xy 162.793902 -303.301073) (xy 162.751281 -303.276466) (xy 162.71316 -303.245341)
			(xy 162.680525 -303.208504) (xy 162.654222 -303.166908) (xy 162.634931 -303.121632) (xy 162.623154 -303.073848)
			(xy 162.619194 -303.024794) (xy 162.280825 -303.024794) (xy 162.280825 -303.0248) (xy 162.276655 -303.075133)
			(xy 162.264257 -303.124094) (xy 162.243971 -303.170346) (xy 162.216349 -303.212629) (xy 162.182144 -303.249789)
			(xy 162.142291 -303.280813) (xy 162.097874 -303.304855) (xy 162.050107 -303.321259) (xy 162.000291 -303.329577)
			(xy 161.975038 -303.330102) (xy 161.960855 -303.32992) (xy 161.932615 -303.327252) (xy 161.91865 -303.324768)
			(xy 161.906204 -303.322482) (xy 161.882582 -303.329848) (xy 161.805112 -303.407318) (xy 161.797746 -303.43094)
			(xy 161.800032 -303.443386) (xy 161.802503 -303.457353) (xy 161.805178 -303.485592) (xy 161.805366 -303.499774)
			(xy 161.80495 -303.524597) (xy 161.796923 -303.573589) (xy 161.781075 -303.620637) (xy 161.757825 -303.664501)
			(xy 161.727784 -303.704026) (xy 161.691745 -303.738171) (xy 161.650657 -303.766035) (xy 161.605602 -303.786885)
			(xy 161.557768 -303.800171) (xy 161.508414 -303.805544) (xy 161.458841 -303.802861) (xy 161.410355 -303.792194)
			(xy 161.364234 -303.773823) (xy 161.321692 -303.748233) (xy 161.283851 -303.716098) (xy 161.251707 -303.678263)
			(xy 161.226107 -303.635727) (xy 161.207726 -303.58961) (xy 161.197048 -303.541127) (xy 161.194354 -303.491554)
			(xy 161.199716 -303.442199) (xy 161.212991 -303.394362) (xy 161.233831 -303.349302) (xy 161.261687 -303.308208)
			(xy 161.295823 -303.272161) (xy 161.335341 -303.242112) (xy 161.379201 -303.218852) (xy 161.426245 -303.202994)
			(xy 161.475235 -303.194955) (xy 161.500058 -303.194466) (xy 161.514241 -303.194649) (xy 161.542481 -303.197317)
			(xy 161.556446 -303.1998) (xy 161.568892 -303.202086) (xy 161.592514 -303.19472) (xy 161.669984 -303.11725)
			(xy 161.67735 -303.093628) (xy 161.675064 -303.081182) (xy 161.67259 -303.067216) (xy 161.669916 -303.038976)
			(xy 161.66973 -303.024794) (xy 161.669905 -303.010611) (xy 161.672578 -302.982371) (xy 161.675064 -302.968406)
			(xy 161.67735 -302.95596) (xy 161.669984 -302.932338) (xy 161.592514 -302.854868) (xy 161.568892 -302.847502)
			(xy 161.556446 -302.849788) (xy 161.542481 -302.852268) (xy 161.514241 -302.854937) (xy 161.500058 -302.855122)
			(xy 161.474806 -302.854569) (xy 161.424992 -302.84625) (xy 161.377226 -302.829847) (xy 161.332812 -302.805805)
			(xy 161.292959 -302.774782) (xy 161.258757 -302.737623) (xy 161.231136 -302.695341) (xy 161.21085 -302.64909)
			(xy 161.198453 -302.600131) (xy 161.194283 -302.5498) (xy 161.198453 -302.499469) (xy 161.21085 -302.45051)
			(xy 161.231136 -302.404259) (xy 161.258757 -302.361977) (xy 161.292959 -302.324818) (xy 161.332812 -302.293795)
			(xy 161.377226 -302.269753) (xy 161.424992 -302.25335) (xy 161.474806 -302.245031) (xy 161.500058 -302.244506)
			(xy 161.514241 -302.244688) (xy 161.542481 -302.247357) (xy 161.556446 -302.24984) (xy 161.568892 -302.252126)
			(xy 161.592514 -302.24476) (xy 161.669984 -302.16729) (xy 161.67735 -302.143668) (xy 161.675064 -302.131222)
			(xy 161.672581 -302.117257) (xy 161.669914 -302.089017) (xy 161.66973 -302.074834) (xy 161.669911 -302.060651)
			(xy 161.67258 -302.032411) (xy 161.675064 -302.018446) (xy 161.67735 -302.006) (xy 161.669984 -301.982378)
			(xy 161.592514 -301.904908) (xy 161.568892 -301.897542) (xy 161.556446 -301.899828) (xy 161.542481 -301.902308)
			(xy 161.514241 -301.904977) (xy 161.500058 -301.905162) (xy 161.476061 -301.9048) (xy 161.42866 -301.897286)
			(xy 161.383018 -301.882449) (xy 161.340259 -301.860654) (xy 161.301435 -301.832439) (xy 161.267504 -301.798498)
			(xy 161.2393 -301.759666) (xy 161.217517 -301.716901) (xy 161.202693 -301.671254) (xy 161.195193 -301.623851)
			(xy 161.19475 -301.599854) (xy 161.194935 -301.585671) (xy 161.197602 -301.557431) (xy 161.200084 -301.543466)
			(xy 161.20237 -301.53102) (xy 161.195004 -301.507398) (xy 161.117534 -301.429928) (xy 161.093912 -301.422562)
			(xy 161.081466 -301.424848) (xy 161.0675 -301.427325) (xy 161.039261 -301.429996) (xy 161.025078 -301.430182)
			(xy 161.010831 -301.430011) (xy 160.982464 -301.427341) (xy 160.968436 -301.424848) (xy 160.95599 -301.422562)
			(xy 160.932368 -301.429928) (xy 160.863788 -301.498254) (xy 160.855641 -301.507499) (xy 160.848328 -301.530983)
			(xy 160.849818 -301.543212) (xy 160.849818 -301.54372) (xy 160.85228 -301.557624) (xy 160.854952 -301.585735)
			(xy 160.855152 -301.599854) (xy 160.854672 -301.62468) (xy 160.846646 -301.67368) (xy 160.830798 -301.720735)
			(xy 160.807546 -301.764606) (xy 160.777502 -301.804137) (xy 160.741458 -301.838287) (xy 160.700364 -301.866155)
			(xy 160.655302 -301.887007) (xy 160.60746 -301.900294) (xy 160.5581 -301.905665) (xy 160.50852 -301.902979)
			(xy 160.460028 -301.892307) (xy 160.413902 -301.87393) (xy 160.371356 -301.848333) (xy 160.333513 -301.816189)
			(xy 160.301368 -301.778346) (xy 160.275771 -301.7358) (xy 160.257393 -301.689674) (xy 160.246721 -301.641182)
			(xy 160.244035 -301.591602) (xy 159.905026 -301.591602) (xy 159.905192 -301.599854) (xy 159.904697 -301.624461)
			(xy 159.896802 -301.673038) (xy 159.881218 -301.719719) (xy 159.858347 -301.763296) (xy 159.828782 -301.80264)
			(xy 159.793289 -301.836732) (xy 159.752786 -301.864688) (xy 159.708324 -301.885786) (xy 159.661053 -301.899478)
			(xy 159.612198 -301.90541) (xy 159.563023 -301.903429) (xy 159.514804 -301.893585) (xy 159.468788 -301.876133)
			(xy 159.426167 -301.851526) (xy 159.388046 -301.820401) (xy 159.355411 -301.783564) (xy 159.329108 -301.741968)
			(xy 159.309817 -301.696692) (xy 159.29804 -301.648908) (xy 159.29408 -301.599854) (xy 158.955232 -301.599854)
			(xy 158.954737 -301.624461) (xy 158.946842 -301.673038) (xy 158.931258 -301.719719) (xy 158.908387 -301.763296)
			(xy 158.878822 -301.80264) (xy 158.843329 -301.836732) (xy 158.802826 -301.864688) (xy 158.758364 -301.885786)
			(xy 158.711093 -301.899478) (xy 158.662238 -301.90541) (xy 158.613063 -301.903429) (xy 158.564844 -301.893585)
			(xy 158.518828 -301.876133) (xy 158.476207 -301.851526) (xy 158.438086 -301.820401) (xy 158.405451 -301.783564)
			(xy 158.379148 -301.741968) (xy 158.359857 -301.696692) (xy 158.34808 -301.648908) (xy 158.34412 -301.599854)
			(xy 158.005272 -301.599854) (xy 158.004777 -301.624461) (xy 157.996882 -301.673038) (xy 157.981298 -301.719719)
			(xy 157.958427 -301.763296) (xy 157.928862 -301.80264) (xy 157.893369 -301.836732) (xy 157.852866 -301.864688)
			(xy 157.808404 -301.885786) (xy 157.761133 -301.899478) (xy 157.712278 -301.90541) (xy 157.663103 -301.903429)
			(xy 157.614884 -301.893585) (xy 157.568868 -301.876133) (xy 157.526247 -301.851526) (xy 157.488126 -301.820401)
			(xy 157.455491 -301.783564) (xy 157.429188 -301.741968) (xy 157.409897 -301.696692) (xy 157.39812 -301.648908)
			(xy 157.39416 -301.599854) (xy 157.055312 -301.599854) (xy 157.054817 -301.624461) (xy 157.046922 -301.673038)
			(xy 157.031338 -301.719719) (xy 157.008467 -301.763296) (xy 156.978902 -301.80264) (xy 156.943409 -301.836732)
			(xy 156.902906 -301.864688) (xy 156.858444 -301.885786) (xy 156.811173 -301.899478) (xy 156.762318 -301.90541)
			(xy 156.713143 -301.903429) (xy 156.664924 -301.893585) (xy 156.618908 -301.876133) (xy 156.576287 -301.851526)
			(xy 156.538166 -301.820401) (xy 156.505531 -301.783564) (xy 156.479228 -301.741968) (xy 156.459937 -301.696692)
			(xy 156.44816 -301.648908) (xy 156.4442 -301.599854) (xy 156.105352 -301.599854) (xy 156.104857 -301.624461)
			(xy 156.096962 -301.673038) (xy 156.081378 -301.719719) (xy 156.058507 -301.763296) (xy 156.028942 -301.80264)
			(xy 155.993449 -301.836732) (xy 155.952946 -301.864688) (xy 155.908484 -301.885786) (xy 155.861213 -301.899478)
			(xy 155.812358 -301.90541) (xy 155.763183 -301.903429) (xy 155.714964 -301.893585) (xy 155.668948 -301.876133)
			(xy 155.626327 -301.851526) (xy 155.588206 -301.820401) (xy 155.555571 -301.783564) (xy 155.529268 -301.741968)
			(xy 155.509977 -301.696692) (xy 155.4982 -301.648908) (xy 155.49424 -301.599854) (xy 155.155392 -301.599854)
			(xy 155.154897 -301.624461) (xy 155.147002 -301.673038) (xy 155.131418 -301.719719) (xy 155.108547 -301.763296)
			(xy 155.078982 -301.80264) (xy 155.043489 -301.836732) (xy 155.002986 -301.864688) (xy 154.958524 -301.885786)
			(xy 154.911253 -301.899478) (xy 154.862398 -301.90541) (xy 154.813223 -301.903429) (xy 154.765004 -301.893585)
			(xy 154.718988 -301.876133) (xy 154.676367 -301.851526) (xy 154.638246 -301.820401) (xy 154.605611 -301.783564)
			(xy 154.579308 -301.741968) (xy 154.560017 -301.696692) (xy 154.54824 -301.648908) (xy 154.54428 -301.599854)
			(xy 154.205178 -301.599854) (xy 154.204683 -301.624461) (xy 154.196788 -301.673038) (xy 154.181204 -301.719719)
			(xy 154.158333 -301.763296) (xy 154.128768 -301.80264) (xy 154.093275 -301.836732) (xy 154.052772 -301.864688)
			(xy 154.00831 -301.885786) (xy 153.961039 -301.899478) (xy 153.912184 -301.90541) (xy 153.863009 -301.903429)
			(xy 153.81479 -301.893585) (xy 153.768774 -301.876133) (xy 153.726153 -301.851526) (xy 153.688032 -301.820401)
			(xy 153.655397 -301.783564) (xy 153.629094 -301.741968) (xy 153.609803 -301.696692) (xy 153.598026 -301.648908)
			(xy 153.594066 -301.599854) (xy 153.255218 -301.599854) (xy 153.254723 -301.624461) (xy 153.246828 -301.673038)
			(xy 153.231244 -301.719719) (xy 153.208373 -301.763296) (xy 153.178808 -301.80264) (xy 153.143315 -301.836732)
			(xy 153.102812 -301.864688) (xy 153.05835 -301.885786) (xy 153.011079 -301.899478) (xy 152.962224 -301.90541)
			(xy 152.913049 -301.903429) (xy 152.86483 -301.893585) (xy 152.818814 -301.876133) (xy 152.776193 -301.851526)
			(xy 152.738072 -301.820401) (xy 152.705437 -301.783564) (xy 152.679134 -301.741968) (xy 152.659843 -301.696692)
			(xy 152.648066 -301.648908) (xy 152.644106 -301.599854) (xy 118.832884 -301.599854) (xy 118.832884 -302.550068)
			(xy 151.693892 -302.550068) (xy 151.697852 -302.501014) (xy 151.709629 -302.45323) (xy 151.72892 -302.407954)
			(xy 151.755223 -302.366358) (xy 151.787858 -302.329521) (xy 151.825979 -302.298396) (xy 151.8686 -302.273789)
			(xy 151.914616 -302.256337) (xy 151.962835 -302.246493) (xy 152.01201 -302.244512) (xy 152.060865 -302.250444)
			(xy 152.108136 -302.264136) (xy 152.152598 -302.285234) (xy 152.193101 -302.31319) (xy 152.228594 -302.347282)
			(xy 152.258159 -302.386626) (xy 152.28103 -302.430203) (xy 152.296614 -302.476884) (xy 152.304509 -302.525461)
			(xy 152.304999 -302.549814) (xy 152.644106 -302.549814) (xy 152.648066 -302.50076) (xy 152.659843 -302.452976)
			(xy 152.679134 -302.4077) (xy 152.705437 -302.366104) (xy 152.738072 -302.329267) (xy 152.776193 -302.298142)
			(xy 152.818814 -302.273535) (xy 152.86483 -302.256083) (xy 152.913049 -302.246239) (xy 152.962224 -302.244258)
			(xy 153.011079 -302.25019) (xy 153.05835 -302.263882) (xy 153.102812 -302.28498) (xy 153.143315 -302.312936)
			(xy 153.178808 -302.347028) (xy 153.208373 -302.386372) (xy 153.231244 -302.429949) (xy 153.246828 -302.47663)
			(xy 153.254723 -302.525207) (xy 153.255218 -302.549814) (xy 153.594066 -302.549814) (xy 153.598026 -302.50076)
			(xy 153.609803 -302.452976) (xy 153.629094 -302.4077) (xy 153.655397 -302.366104) (xy 153.688032 -302.329267)
			(xy 153.726153 -302.298142) (xy 153.768774 -302.273535) (xy 153.81479 -302.256083) (xy 153.863009 -302.246239)
			(xy 153.912184 -302.244258) (xy 153.961039 -302.25019) (xy 154.00831 -302.263882) (xy 154.052772 -302.28498)
			(xy 154.093275 -302.312936) (xy 154.128768 -302.347028) (xy 154.158333 -302.386372) (xy 154.181204 -302.429949)
			(xy 154.196788 -302.47663) (xy 154.204683 -302.525207) (xy 154.205178 -302.549814) (xy 154.54428 -302.549814)
			(xy 154.54824 -302.50076) (xy 154.560017 -302.452976) (xy 154.579308 -302.4077) (xy 154.605611 -302.366104)
			(xy 154.638246 -302.329267) (xy 154.676367 -302.298142) (xy 154.718988 -302.273535) (xy 154.765004 -302.256083)
			(xy 154.813223 -302.246239) (xy 154.862398 -302.244258) (xy 154.911253 -302.25019) (xy 154.958524 -302.263882)
			(xy 155.002986 -302.28498) (xy 155.043489 -302.312936) (xy 155.078982 -302.347028) (xy 155.108547 -302.386372)
			(xy 155.131418 -302.429949) (xy 155.147002 -302.47663) (xy 155.154897 -302.525207) (xy 155.155392 -302.549814)
			(xy 155.49424 -302.549814) (xy 155.4982 -302.50076) (xy 155.509977 -302.452976) (xy 155.529268 -302.4077)
			(xy 155.555571 -302.366104) (xy 155.588206 -302.329267) (xy 155.626327 -302.298142) (xy 155.668948 -302.273535)
			(xy 155.714964 -302.256083) (xy 155.763183 -302.246239) (xy 155.812358 -302.244258) (xy 155.861213 -302.25019)
			(xy 155.908484 -302.263882) (xy 155.952946 -302.28498) (xy 155.993449 -302.312936) (xy 156.028942 -302.347028)
			(xy 156.058507 -302.386372) (xy 156.081378 -302.429949) (xy 156.096962 -302.47663) (xy 156.104857 -302.525207)
			(xy 156.105352 -302.549814) (xy 156.4442 -302.549814) (xy 156.44816 -302.50076) (xy 156.459937 -302.452976)
			(xy 156.479228 -302.4077) (xy 156.505531 -302.366104) (xy 156.538166 -302.329267) (xy 156.576287 -302.298142)
			(xy 156.618908 -302.273535) (xy 156.664924 -302.256083) (xy 156.713143 -302.246239) (xy 156.762318 -302.244258)
			(xy 156.811173 -302.25019) (xy 156.858444 -302.263882) (xy 156.902906 -302.28498) (xy 156.943409 -302.312936)
			(xy 156.978902 -302.347028) (xy 157.008467 -302.386372) (xy 157.031338 -302.429949) (xy 157.046922 -302.47663)
			(xy 157.054817 -302.525207) (xy 157.055312 -302.549814) (xy 157.39416 -302.549814) (xy 157.39812 -302.50076)
			(xy 157.409897 -302.452976) (xy 157.429188 -302.4077) (xy 157.455491 -302.366104) (xy 157.488126 -302.329267)
			(xy 157.526247 -302.298142) (xy 157.568868 -302.273535) (xy 157.614884 -302.256083) (xy 157.663103 -302.246239)
			(xy 157.712278 -302.244258) (xy 157.761133 -302.25019) (xy 157.808404 -302.263882) (xy 157.852866 -302.28498)
			(xy 157.893369 -302.312936) (xy 157.928862 -302.347028) (xy 157.958427 -302.386372) (xy 157.981298 -302.429949)
			(xy 157.996882 -302.47663) (xy 158.004777 -302.525207) (xy 158.005272 -302.549814) (xy 158.34412 -302.549814)
			(xy 158.34808 -302.50076) (xy 158.359857 -302.452976) (xy 158.379148 -302.4077) (xy 158.405451 -302.366104)
			(xy 158.438086 -302.329267) (xy 158.476207 -302.298142) (xy 158.518828 -302.273535) (xy 158.564844 -302.256083)
			(xy 158.613063 -302.246239) (xy 158.662238 -302.244258) (xy 158.711093 -302.25019) (xy 158.758364 -302.263882)
			(xy 158.802826 -302.28498) (xy 158.843329 -302.312936) (xy 158.878822 -302.347028) (xy 158.908387 -302.386372)
			(xy 158.931258 -302.429949) (xy 158.946842 -302.47663) (xy 158.954737 -302.525207) (xy 158.955232 -302.549814)
			(xy 159.29408 -302.549814) (xy 159.29804 -302.50076) (xy 159.309817 -302.452976) (xy 159.329108 -302.4077)
			(xy 159.355411 -302.366104) (xy 159.388046 -302.329267) (xy 159.426167 -302.298142) (xy 159.468788 -302.273535)
			(xy 159.514804 -302.256083) (xy 159.563023 -302.246239) (xy 159.612198 -302.244258) (xy 159.661053 -302.25019)
			(xy 159.708324 -302.263882) (xy 159.752786 -302.28498) (xy 159.793289 -302.312936) (xy 159.828782 -302.347028)
			(xy 159.858347 -302.386372) (xy 159.881218 -302.429949) (xy 159.896802 -302.47663) (xy 159.904697 -302.525207)
			(xy 159.905192 -302.549814) (xy 160.24404 -302.549814) (xy 160.248 -302.50076) (xy 160.259777 -302.452976)
			(xy 160.279068 -302.4077) (xy 160.305371 -302.366104) (xy 160.338006 -302.329267) (xy 160.376127 -302.298142)
			(xy 160.418748 -302.273535) (xy 160.464764 -302.256083) (xy 160.512983 -302.246239) (xy 160.562158 -302.244258)
			(xy 160.611013 -302.25019) (xy 160.658284 -302.263882) (xy 160.702746 -302.28498) (xy 160.743249 -302.312936)
			(xy 160.778742 -302.347028) (xy 160.808307 -302.386372) (xy 160.831178 -302.429949) (xy 160.846762 -302.47663)
			(xy 160.854657 -302.525207) (xy 160.855152 -302.549814) (xy 160.854657 -302.574421) (xy 160.846762 -302.622998)
			(xy 160.831178 -302.669679) (xy 160.808307 -302.713256) (xy 160.778742 -302.7526) (xy 160.743249 -302.786692)
			(xy 160.702746 -302.814648) (xy 160.658284 -302.835746) (xy 160.611013 -302.849438) (xy 160.562158 -302.85537)
			(xy 160.512983 -302.853389) (xy 160.464764 -302.843545) (xy 160.418748 -302.826093) (xy 160.376127 -302.801486)
			(xy 160.338006 -302.770361) (xy 160.305371 -302.733524) (xy 160.279068 -302.691928) (xy 160.259777 -302.646652)
			(xy 160.248 -302.598868) (xy 160.24404 -302.549814) (xy 159.905192 -302.549814) (xy 159.904697 -302.574421)
			(xy 159.896802 -302.622998) (xy 159.881218 -302.669679) (xy 159.858347 -302.713256) (xy 159.828782 -302.7526)
			(xy 159.793289 -302.786692) (xy 159.752786 -302.814648) (xy 159.708324 -302.835746) (xy 159.661053 -302.849438)
			(xy 159.612198 -302.85537) (xy 159.563023 -302.853389) (xy 159.514804 -302.843545) (xy 159.468788 -302.826093)
			(xy 159.426167 -302.801486) (xy 159.388046 -302.770361) (xy 159.355411 -302.733524) (xy 159.329108 -302.691928)
			(xy 159.309817 -302.646652) (xy 159.29804 -302.598868) (xy 159.29408 -302.549814) (xy 158.955232 -302.549814)
			(xy 158.954737 -302.574421) (xy 158.946842 -302.622998) (xy 158.931258 -302.669679) (xy 158.908387 -302.713256)
			(xy 158.878822 -302.7526) (xy 158.843329 -302.786692) (xy 158.802826 -302.814648) (xy 158.758364 -302.835746)
			(xy 158.711093 -302.849438) (xy 158.662238 -302.85537) (xy 158.613063 -302.853389) (xy 158.564844 -302.843545)
			(xy 158.518828 -302.826093) (xy 158.476207 -302.801486) (xy 158.438086 -302.770361) (xy 158.405451 -302.733524)
			(xy 158.379148 -302.691928) (xy 158.359857 -302.646652) (xy 158.34808 -302.598868) (xy 158.34412 -302.549814)
			(xy 158.005272 -302.549814) (xy 158.004777 -302.574421) (xy 157.996882 -302.622998) (xy 157.981298 -302.669679)
			(xy 157.958427 -302.713256) (xy 157.928862 -302.7526) (xy 157.893369 -302.786692) (xy 157.852866 -302.814648)
			(xy 157.808404 -302.835746) (xy 157.761133 -302.849438) (xy 157.712278 -302.85537) (xy 157.663103 -302.853389)
			(xy 157.614884 -302.843545) (xy 157.568868 -302.826093) (xy 157.526247 -302.801486) (xy 157.488126 -302.770361)
			(xy 157.455491 -302.733524) (xy 157.429188 -302.691928) (xy 157.409897 -302.646652) (xy 157.39812 -302.598868)
			(xy 157.39416 -302.549814) (xy 157.055312 -302.549814) (xy 157.054817 -302.574421) (xy 157.046922 -302.622998)
			(xy 157.031338 -302.669679) (xy 157.008467 -302.713256) (xy 156.978902 -302.7526) (xy 156.943409 -302.786692)
			(xy 156.902906 -302.814648) (xy 156.858444 -302.835746) (xy 156.811173 -302.849438) (xy 156.762318 -302.85537)
			(xy 156.713143 -302.853389) (xy 156.664924 -302.843545) (xy 156.618908 -302.826093) (xy 156.576287 -302.801486)
			(xy 156.538166 -302.770361) (xy 156.505531 -302.733524) (xy 156.479228 -302.691928) (xy 156.459937 -302.646652)
			(xy 156.44816 -302.598868) (xy 156.4442 -302.549814) (xy 156.105352 -302.549814) (xy 156.104857 -302.574421)
			(xy 156.096962 -302.622998) (xy 156.081378 -302.669679) (xy 156.058507 -302.713256) (xy 156.028942 -302.7526)
			(xy 155.993449 -302.786692) (xy 155.952946 -302.814648) (xy 155.908484 -302.835746) (xy 155.861213 -302.849438)
			(xy 155.812358 -302.85537) (xy 155.763183 -302.853389) (xy 155.714964 -302.843545) (xy 155.668948 -302.826093)
			(xy 155.626327 -302.801486) (xy 155.588206 -302.770361) (xy 155.555571 -302.733524) (xy 155.529268 -302.691928)
			(xy 155.509977 -302.646652) (xy 155.4982 -302.598868) (xy 155.49424 -302.549814) (xy 155.155392 -302.549814)
			(xy 155.154897 -302.574421) (xy 155.147002 -302.622998) (xy 155.131418 -302.669679) (xy 155.108547 -302.713256)
			(xy 155.078982 -302.7526) (xy 155.043489 -302.786692) (xy 155.002986 -302.814648) (xy 154.958524 -302.835746)
			(xy 154.911253 -302.849438) (xy 154.862398 -302.85537) (xy 154.813223 -302.853389) (xy 154.765004 -302.843545)
			(xy 154.718988 -302.826093) (xy 154.676367 -302.801486) (xy 154.638246 -302.770361) (xy 154.605611 -302.733524)
			(xy 154.579308 -302.691928) (xy 154.560017 -302.646652) (xy 154.54824 -302.598868) (xy 154.54428 -302.549814)
			(xy 154.205178 -302.549814) (xy 154.204683 -302.574421) (xy 154.196788 -302.622998) (xy 154.181204 -302.669679)
			(xy 154.158333 -302.713256) (xy 154.128768 -302.7526) (xy 154.093275 -302.786692) (xy 154.052772 -302.814648)
			(xy 154.00831 -302.835746) (xy 153.961039 -302.849438) (xy 153.912184 -302.85537) (xy 153.863009 -302.853389)
			(xy 153.81479 -302.843545) (xy 153.768774 -302.826093) (xy 153.726153 -302.801486) (xy 153.688032 -302.770361)
			(xy 153.655397 -302.733524) (xy 153.629094 -302.691928) (xy 153.609803 -302.646652) (xy 153.598026 -302.598868)
			(xy 153.594066 -302.549814) (xy 153.255218 -302.549814) (xy 153.254723 -302.574421) (xy 153.246828 -302.622998)
			(xy 153.231244 -302.669679) (xy 153.208373 -302.713256) (xy 153.178808 -302.7526) (xy 153.143315 -302.786692)
			(xy 153.102812 -302.814648) (xy 153.05835 -302.835746) (xy 153.011079 -302.849438) (xy 152.962224 -302.85537)
			(xy 152.913049 -302.853389) (xy 152.86483 -302.843545) (xy 152.818814 -302.826093) (xy 152.776193 -302.801486)
			(xy 152.738072 -302.770361) (xy 152.705437 -302.733524) (xy 152.679134 -302.691928) (xy 152.659843 -302.646652)
			(xy 152.648066 -302.598868) (xy 152.644106 -302.549814) (xy 152.304999 -302.549814) (xy 152.305004 -302.550068)
			(xy 152.304509 -302.574675) (xy 152.296614 -302.623252) (xy 152.28103 -302.669933) (xy 152.258159 -302.71351)
			(xy 152.228594 -302.752854) (xy 152.193101 -302.786946) (xy 152.152598 -302.814902) (xy 152.108136 -302.836)
			(xy 152.060865 -302.849692) (xy 152.01201 -302.855624) (xy 151.962835 -302.853643) (xy 151.914616 -302.843799)
			(xy 151.8686 -302.826347) (xy 151.825979 -302.80174) (xy 151.787858 -302.770615) (xy 151.755223 -302.733778)
			(xy 151.72892 -302.692182) (xy 151.709629 -302.646906) (xy 151.697852 -302.599122) (xy 151.693892 -302.550068)
			(xy 118.832884 -302.550068) (xy 118.832884 -303.499774) (xy 152.644106 -303.499774) (xy 152.648066 -303.45072)
			(xy 152.659843 -303.402936) (xy 152.679134 -303.35766) (xy 152.705437 -303.316064) (xy 152.738072 -303.279227)
			(xy 152.776193 -303.248102) (xy 152.818814 -303.223495) (xy 152.86483 -303.206043) (xy 152.913049 -303.196199)
			(xy 152.962224 -303.194218) (xy 153.011079 -303.20015) (xy 153.05835 -303.213842) (xy 153.102812 -303.23494)
			(xy 153.143315 -303.262896) (xy 153.178808 -303.296988) (xy 153.208373 -303.336332) (xy 153.231244 -303.379909)
			(xy 153.246828 -303.42659) (xy 153.254723 -303.475167) (xy 153.255218 -303.499774) (xy 153.594066 -303.499774)
			(xy 153.598026 -303.45072) (xy 153.609803 -303.402936) (xy 153.629094 -303.35766) (xy 153.655397 -303.316064)
			(xy 153.688032 -303.279227) (xy 153.726153 -303.248102) (xy 153.768774 -303.223495) (xy 153.81479 -303.206043)
			(xy 153.863009 -303.196199) (xy 153.912184 -303.194218) (xy 153.961039 -303.20015) (xy 154.00831 -303.213842)
			(xy 154.052772 -303.23494) (xy 154.093275 -303.262896) (xy 154.128768 -303.296988) (xy 154.158333 -303.336332)
			(xy 154.181204 -303.379909) (xy 154.196788 -303.42659) (xy 154.204683 -303.475167) (xy 154.205178 -303.499774)
			(xy 154.54428 -303.499774) (xy 154.54824 -303.45072) (xy 154.560017 -303.402936) (xy 154.579308 -303.35766)
			(xy 154.605611 -303.316064) (xy 154.638246 -303.279227) (xy 154.676367 -303.248102) (xy 154.718988 -303.223495)
			(xy 154.765004 -303.206043) (xy 154.813223 -303.196199) (xy 154.862398 -303.194218) (xy 154.911253 -303.20015)
			(xy 154.958524 -303.213842) (xy 155.002986 -303.23494) (xy 155.043489 -303.262896) (xy 155.078982 -303.296988)
			(xy 155.108547 -303.336332) (xy 155.131418 -303.379909) (xy 155.147002 -303.42659) (xy 155.154897 -303.475167)
			(xy 155.155392 -303.499774) (xy 155.49424 -303.499774) (xy 155.4982 -303.45072) (xy 155.509977 -303.402936)
			(xy 155.529268 -303.35766) (xy 155.555571 -303.316064) (xy 155.588206 -303.279227) (xy 155.626327 -303.248102)
			(xy 155.668948 -303.223495) (xy 155.714964 -303.206043) (xy 155.763183 -303.196199) (xy 155.812358 -303.194218)
			(xy 155.861213 -303.20015) (xy 155.908484 -303.213842) (xy 155.952946 -303.23494) (xy 155.993449 -303.262896)
			(xy 156.028942 -303.296988) (xy 156.058507 -303.336332) (xy 156.081378 -303.379909) (xy 156.096962 -303.42659)
			(xy 156.104857 -303.475167) (xy 156.105352 -303.499774) (xy 156.4442 -303.499774) (xy 156.44816 -303.45072)
			(xy 156.459937 -303.402936) (xy 156.479228 -303.35766) (xy 156.505531 -303.316064) (xy 156.538166 -303.279227)
			(xy 156.576287 -303.248102) (xy 156.618908 -303.223495) (xy 156.664924 -303.206043) (xy 156.713143 -303.196199)
			(xy 156.762318 -303.194218) (xy 156.811173 -303.20015) (xy 156.858444 -303.213842) (xy 156.902906 -303.23494)
			(xy 156.943409 -303.262896) (xy 156.978902 -303.296988) (xy 157.008467 -303.336332) (xy 157.031338 -303.379909)
			(xy 157.046922 -303.42659) (xy 157.054817 -303.475167) (xy 157.055312 -303.499774) (xy 157.39416 -303.499774)
			(xy 157.39812 -303.45072) (xy 157.409897 -303.402936) (xy 157.429188 -303.35766) (xy 157.455491 -303.316064)
			(xy 157.488126 -303.279227) (xy 157.526247 -303.248102) (xy 157.568868 -303.223495) (xy 157.614884 -303.206043)
			(xy 157.663103 -303.196199) (xy 157.712278 -303.194218) (xy 157.761133 -303.20015) (xy 157.808404 -303.213842)
			(xy 157.852866 -303.23494) (xy 157.893369 -303.262896) (xy 157.928862 -303.296988) (xy 157.958427 -303.336332)
			(xy 157.981298 -303.379909) (xy 157.996882 -303.42659) (xy 158.004777 -303.475167) (xy 158.005272 -303.499774)
			(xy 158.34412 -303.499774) (xy 158.34808 -303.45072) (xy 158.359857 -303.402936) (xy 158.379148 -303.35766)
			(xy 158.405451 -303.316064) (xy 158.438086 -303.279227) (xy 158.476207 -303.248102) (xy 158.518828 -303.223495)
			(xy 158.564844 -303.206043) (xy 158.613063 -303.196199) (xy 158.662238 -303.194218) (xy 158.711093 -303.20015)
			(xy 158.758364 -303.213842) (xy 158.802826 -303.23494) (xy 158.843329 -303.262896) (xy 158.878822 -303.296988)
			(xy 158.908387 -303.336332) (xy 158.931258 -303.379909) (xy 158.946842 -303.42659) (xy 158.954737 -303.475167)
			(xy 158.955232 -303.499774) (xy 159.29408 -303.499774) (xy 159.29804 -303.45072) (xy 159.309817 -303.402936)
			(xy 159.329108 -303.35766) (xy 159.355411 -303.316064) (xy 159.388046 -303.279227) (xy 159.426167 -303.248102)
			(xy 159.468788 -303.223495) (xy 159.514804 -303.206043) (xy 159.563023 -303.196199) (xy 159.612198 -303.194218)
			(xy 159.661053 -303.20015) (xy 159.708324 -303.213842) (xy 159.752786 -303.23494) (xy 159.793289 -303.262896)
			(xy 159.828782 -303.296988) (xy 159.858347 -303.336332) (xy 159.881218 -303.379909) (xy 159.896802 -303.42659)
			(xy 159.904697 -303.475167) (xy 159.905192 -303.499774) (xy 160.24404 -303.499774) (xy 160.248 -303.45072)
			(xy 160.259777 -303.402936) (xy 160.279068 -303.35766) (xy 160.305371 -303.316064) (xy 160.338006 -303.279227)
			(xy 160.376127 -303.248102) (xy 160.418748 -303.223495) (xy 160.464764 -303.206043) (xy 160.512983 -303.196199)
			(xy 160.562158 -303.194218) (xy 160.611013 -303.20015) (xy 160.658284 -303.213842) (xy 160.702746 -303.23494)
			(xy 160.743249 -303.262896) (xy 160.778742 -303.296988) (xy 160.808307 -303.336332) (xy 160.831178 -303.379909)
			(xy 160.846762 -303.42659) (xy 160.854657 -303.475167) (xy 160.855152 -303.499774) (xy 160.854657 -303.524381)
			(xy 160.846762 -303.572958) (xy 160.831178 -303.619639) (xy 160.808307 -303.663216) (xy 160.778742 -303.70256)
			(xy 160.743249 -303.736652) (xy 160.702746 -303.764608) (xy 160.658284 -303.785706) (xy 160.611013 -303.799398)
			(xy 160.562158 -303.80533) (xy 160.512983 -303.803349) (xy 160.464764 -303.793505) (xy 160.418748 -303.776053)
			(xy 160.376127 -303.751446) (xy 160.338006 -303.720321) (xy 160.305371 -303.683484) (xy 160.279068 -303.641888)
			(xy 160.259777 -303.596612) (xy 160.248 -303.548828) (xy 160.24404 -303.499774) (xy 159.905192 -303.499774)
			(xy 159.904697 -303.524381) (xy 159.896802 -303.572958) (xy 159.881218 -303.619639) (xy 159.858347 -303.663216)
			(xy 159.828782 -303.70256) (xy 159.793289 -303.736652) (xy 159.752786 -303.764608) (xy 159.708324 -303.785706)
			(xy 159.661053 -303.799398) (xy 159.612198 -303.80533) (xy 159.563023 -303.803349) (xy 159.514804 -303.793505)
			(xy 159.468788 -303.776053) (xy 159.426167 -303.751446) (xy 159.388046 -303.720321) (xy 159.355411 -303.683484)
			(xy 159.329108 -303.641888) (xy 159.309817 -303.596612) (xy 159.29804 -303.548828) (xy 159.29408 -303.499774)
			(xy 158.955232 -303.499774) (xy 158.954737 -303.524381) (xy 158.946842 -303.572958) (xy 158.931258 -303.619639)
			(xy 158.908387 -303.663216) (xy 158.878822 -303.70256) (xy 158.843329 -303.736652) (xy 158.802826 -303.764608)
			(xy 158.758364 -303.785706) (xy 158.711093 -303.799398) (xy 158.662238 -303.80533) (xy 158.613063 -303.803349)
			(xy 158.564844 -303.793505) (xy 158.518828 -303.776053) (xy 158.476207 -303.751446) (xy 158.438086 -303.720321)
			(xy 158.405451 -303.683484) (xy 158.379148 -303.641888) (xy 158.359857 -303.596612) (xy 158.34808 -303.548828)
			(xy 158.34412 -303.499774) (xy 158.005272 -303.499774) (xy 158.004777 -303.524381) (xy 157.996882 -303.572958)
			(xy 157.981298 -303.619639) (xy 157.958427 -303.663216) (xy 157.928862 -303.70256) (xy 157.893369 -303.736652)
			(xy 157.852866 -303.764608) (xy 157.808404 -303.785706) (xy 157.761133 -303.799398) (xy 157.712278 -303.80533)
			(xy 157.663103 -303.803349) (xy 157.614884 -303.793505) (xy 157.568868 -303.776053) (xy 157.526247 -303.751446)
			(xy 157.488126 -303.720321) (xy 157.455491 -303.683484) (xy 157.429188 -303.641888) (xy 157.409897 -303.596612)
			(xy 157.39812 -303.548828) (xy 157.39416 -303.499774) (xy 157.055312 -303.499774) (xy 157.054817 -303.524381)
			(xy 157.046922 -303.572958) (xy 157.031338 -303.619639) (xy 157.008467 -303.663216) (xy 156.978902 -303.70256)
			(xy 156.943409 -303.736652) (xy 156.902906 -303.764608) (xy 156.858444 -303.785706) (xy 156.811173 -303.799398)
			(xy 156.762318 -303.80533) (xy 156.713143 -303.803349) (xy 156.664924 -303.793505) (xy 156.618908 -303.776053)
			(xy 156.576287 -303.751446) (xy 156.538166 -303.720321) (xy 156.505531 -303.683484) (xy 156.479228 -303.641888)
			(xy 156.459937 -303.596612) (xy 156.44816 -303.548828) (xy 156.4442 -303.499774) (xy 156.105352 -303.499774)
			(xy 156.104857 -303.524381) (xy 156.096962 -303.572958) (xy 156.081378 -303.619639) (xy 156.058507 -303.663216)
			(xy 156.028942 -303.70256) (xy 155.993449 -303.736652) (xy 155.952946 -303.764608) (xy 155.908484 -303.785706)
			(xy 155.861213 -303.799398) (xy 155.812358 -303.80533) (xy 155.763183 -303.803349) (xy 155.714964 -303.793505)
			(xy 155.668948 -303.776053) (xy 155.626327 -303.751446) (xy 155.588206 -303.720321) (xy 155.555571 -303.683484)
			(xy 155.529268 -303.641888) (xy 155.509977 -303.596612) (xy 155.4982 -303.548828) (xy 155.49424 -303.499774)
			(xy 155.155392 -303.499774) (xy 155.154897 -303.524381) (xy 155.147002 -303.572958) (xy 155.131418 -303.619639)
			(xy 155.108547 -303.663216) (xy 155.078982 -303.70256) (xy 155.043489 -303.736652) (xy 155.002986 -303.764608)
			(xy 154.958524 -303.785706) (xy 154.911253 -303.799398) (xy 154.862398 -303.80533) (xy 154.813223 -303.803349)
			(xy 154.765004 -303.793505) (xy 154.718988 -303.776053) (xy 154.676367 -303.751446) (xy 154.638246 -303.720321)
			(xy 154.605611 -303.683484) (xy 154.579308 -303.641888) (xy 154.560017 -303.596612) (xy 154.54824 -303.548828)
			(xy 154.54428 -303.499774) (xy 154.205178 -303.499774) (xy 154.204683 -303.524381) (xy 154.196788 -303.572958)
			(xy 154.181204 -303.619639) (xy 154.158333 -303.663216) (xy 154.128768 -303.70256) (xy 154.093275 -303.736652)
			(xy 154.052772 -303.764608) (xy 154.00831 -303.785706) (xy 153.961039 -303.799398) (xy 153.912184 -303.80533)
			(xy 153.863009 -303.803349) (xy 153.81479 -303.793505) (xy 153.768774 -303.776053) (xy 153.726153 -303.751446)
			(xy 153.688032 -303.720321) (xy 153.655397 -303.683484) (xy 153.629094 -303.641888) (xy 153.609803 -303.596612)
			(xy 153.598026 -303.548828) (xy 153.594066 -303.499774) (xy 153.255218 -303.499774) (xy 153.254723 -303.524381)
			(xy 153.246828 -303.572958) (xy 153.231244 -303.619639) (xy 153.208373 -303.663216) (xy 153.178808 -303.70256)
			(xy 153.143315 -303.736652) (xy 153.102812 -303.764608) (xy 153.05835 -303.785706) (xy 153.011079 -303.799398)
			(xy 152.962224 -303.80533) (xy 152.913049 -303.803349) (xy 152.86483 -303.793505) (xy 152.818814 -303.776053)
			(xy 152.776193 -303.751446) (xy 152.738072 -303.720321) (xy 152.705437 -303.683484) (xy 152.679134 -303.641888)
			(xy 152.659843 -303.596612) (xy 152.648066 -303.548828) (xy 152.644106 -303.499774) (xy 118.832884 -303.499774)
			(xy 118.832884 -303.974754) (xy 162.619194 -303.974754) (xy 162.623154 -303.9257) (xy 162.634931 -303.877916)
			(xy 162.654222 -303.83264) (xy 162.680525 -303.791044) (xy 162.71316 -303.754207) (xy 162.751281 -303.723082)
			(xy 162.793902 -303.698475) (xy 162.839918 -303.681023) (xy 162.888137 -303.671179) (xy 162.937312 -303.669198)
			(xy 162.986167 -303.67513) (xy 163.033438 -303.688822) (xy 163.0779 -303.70992) (xy 163.118403 -303.737876)
			(xy 163.153896 -303.771968) (xy 163.183461 -303.811312) (xy 163.206332 -303.854889) (xy 163.221916 -303.90157)
			(xy 163.229811 -303.950147) (xy 163.230306 -303.974754) (xy 163.569154 -303.974754) (xy 163.573114 -303.9257)
			(xy 163.584891 -303.877916) (xy 163.604182 -303.83264) (xy 163.630485 -303.791044) (xy 163.66312 -303.754207)
			(xy 163.701241 -303.723082) (xy 163.743862 -303.698475) (xy 163.789878 -303.681023) (xy 163.838097 -303.671179)
			(xy 163.887272 -303.669198) (xy 163.936127 -303.67513) (xy 163.983398 -303.688822) (xy 164.02786 -303.70992)
			(xy 164.068363 -303.737876) (xy 164.103856 -303.771968) (xy 164.133421 -303.811312) (xy 164.156292 -303.854889)
			(xy 164.171876 -303.90157) (xy 164.179771 -303.950147) (xy 164.180266 -303.974754) (xy 164.519114 -303.974754)
			(xy 164.523074 -303.9257) (xy 164.534851 -303.877916) (xy 164.554142 -303.83264) (xy 164.580445 -303.791044)
			(xy 164.61308 -303.754207) (xy 164.651201 -303.723082) (xy 164.693822 -303.698475) (xy 164.739838 -303.681023)
			(xy 164.788057 -303.671179) (xy 164.837232 -303.669198) (xy 164.886087 -303.67513) (xy 164.933358 -303.688822)
			(xy 164.97782 -303.70992) (xy 165.018323 -303.737876) (xy 165.053816 -303.771968) (xy 165.083381 -303.811312)
			(xy 165.106252 -303.854889) (xy 165.121836 -303.90157) (xy 165.129731 -303.950147) (xy 165.130226 -303.974754)
			(xy 165.469074 -303.974754) (xy 165.473034 -303.9257) (xy 165.484811 -303.877916) (xy 165.504102 -303.83264)
			(xy 165.530405 -303.791044) (xy 165.56304 -303.754207) (xy 165.601161 -303.723082) (xy 165.643782 -303.698475)
			(xy 165.689798 -303.681023) (xy 165.738017 -303.671179) (xy 165.787192 -303.669198) (xy 165.836047 -303.67513)
			(xy 165.883318 -303.688822) (xy 165.92778 -303.70992) (xy 165.968283 -303.737876) (xy 166.003776 -303.771968)
			(xy 166.033341 -303.811312) (xy 166.056212 -303.854889) (xy 166.071796 -303.90157) (xy 166.079691 -303.950147)
			(xy 166.080186 -303.974754) (xy 166.079691 -303.999361) (xy 166.071796 -304.047938) (xy 166.056212 -304.094619)
			(xy 166.033341 -304.138196) (xy 166.003776 -304.17754) (xy 165.968283 -304.211632) (xy 165.92778 -304.239588)
			(xy 165.883318 -304.260686) (xy 165.836047 -304.274378) (xy 165.787192 -304.28031) (xy 165.738017 -304.278329)
			(xy 165.689798 -304.268485) (xy 165.643782 -304.251033) (xy 165.601161 -304.226426) (xy 165.56304 -304.195301)
			(xy 165.530405 -304.158464) (xy 165.504102 -304.116868) (xy 165.484811 -304.071592) (xy 165.473034 -304.023808)
			(xy 165.469074 -303.974754) (xy 165.130226 -303.974754) (xy 165.129731 -303.999361) (xy 165.121836 -304.047938)
			(xy 165.106252 -304.094619) (xy 165.083381 -304.138196) (xy 165.053816 -304.17754) (xy 165.018323 -304.211632)
			(xy 164.97782 -304.239588) (xy 164.933358 -304.260686) (xy 164.886087 -304.274378) (xy 164.837232 -304.28031)
			(xy 164.788057 -304.278329) (xy 164.739838 -304.268485) (xy 164.693822 -304.251033) (xy 164.651201 -304.226426)
			(xy 164.61308 -304.195301) (xy 164.580445 -304.158464) (xy 164.554142 -304.116868) (xy 164.534851 -304.071592)
			(xy 164.523074 -304.023808) (xy 164.519114 -303.974754) (xy 164.180266 -303.974754) (xy 164.179771 -303.999361)
			(xy 164.171876 -304.047938) (xy 164.156292 -304.094619) (xy 164.133421 -304.138196) (xy 164.103856 -304.17754)
			(xy 164.068363 -304.211632) (xy 164.02786 -304.239588) (xy 163.983398 -304.260686) (xy 163.936127 -304.274378)
			(xy 163.887272 -304.28031) (xy 163.838097 -304.278329) (xy 163.789878 -304.268485) (xy 163.743862 -304.251033)
			(xy 163.701241 -304.226426) (xy 163.66312 -304.195301) (xy 163.630485 -304.158464) (xy 163.604182 -304.116868)
			(xy 163.584891 -304.071592) (xy 163.573114 -304.023808) (xy 163.569154 -303.974754) (xy 163.230306 -303.974754)
			(xy 163.229811 -303.999361) (xy 163.221916 -304.047938) (xy 163.206332 -304.094619) (xy 163.183461 -304.138196)
			(xy 163.153896 -304.17754) (xy 163.118403 -304.211632) (xy 163.0779 -304.239588) (xy 163.033438 -304.260686)
			(xy 162.986167 -304.274378) (xy 162.937312 -304.28031) (xy 162.888137 -304.278329) (xy 162.839918 -304.268485)
			(xy 162.793902 -304.251033) (xy 162.751281 -304.226426) (xy 162.71316 -304.195301) (xy 162.680525 -304.158464)
			(xy 162.654222 -304.116868) (xy 162.634931 -304.071592) (xy 162.623154 -304.023808) (xy 162.619194 -303.974754)
			(xy 118.832884 -303.974754) (xy 118.832884 -305.008534) (xy 120.828816 -305.008534) (xy 120.829298 -304.981164)
			(xy 120.837111 -304.926986) (xy 120.852597 -304.874483) (xy 120.875435 -304.824736) (xy 120.905156 -304.778768)
			(xy 120.922796 -304.757836) (xy 120.92305 -304.757582) (xy 120.928656 -304.750509) (xy 120.93489 -304.733582)
			(xy 120.935242 -304.724562) (xy 120.935242 -304.657506) (xy 120.934895 -304.648488) (xy 120.928642 -304.63157)
			(xy 120.92305 -304.624486) (xy 120.922796 -304.624486) (xy 120.922796 -304.624232) (xy 120.905158 -304.603299)
			(xy 120.875446 -304.557327) (xy 120.85261 -304.507579) (xy 120.837119 -304.455079) (xy 120.82929 -304.400903)
			(xy 120.828816 -304.373534) (xy 120.829302 -304.346283) (xy 120.837058 -304.292335) (xy 120.852413 -304.24004)
			(xy 120.875055 -304.190463) (xy 120.904521 -304.144613) (xy 120.940212 -304.103422) (xy 120.981403 -304.067731)
			(xy 121.027253 -304.038265) (xy 121.07683 -304.015623) (xy 121.129125 -304.000268) (xy 121.183073 -303.992512)
			(xy 121.237575 -303.992512) (xy 121.291523 -304.000268) (xy 121.343818 -304.015623) (xy 121.393395 -304.038265)
			(xy 121.439245 -304.067731) (xy 121.480436 -304.103422) (xy 121.516127 -304.144613) (xy 121.545593 -304.190463)
			(xy 121.568235 -304.24004) (xy 121.58359 -304.292335) (xy 121.591346 -304.346283) (xy 121.591832 -304.373534)
			(xy 121.591402 -304.400906) (xy 121.583578 -304.455087) (xy 121.568082 -304.507591) (xy 121.545231 -304.557338)
			(xy 121.515498 -304.603302) (xy 121.497852 -304.624232) (xy 121.497598 -304.624486) (xy 121.492011 -304.631572)
			(xy 121.485765 -304.648489) (xy 121.485406 -304.657506) (xy 121.485406 -304.724562) (xy 121.48578 -304.733577)
			(xy 121.492016 -304.750494) (xy 121.497598 -304.757582) (xy 121.497852 -304.757582) (xy 121.497852 -304.757836)
			(xy 121.515467 -304.778788) (xy 121.545184 -304.824754) (xy 121.568026 -304.874497) (xy 121.583522 -304.926993)
			(xy 121.591355 -304.981166) (xy 121.591832 -305.008534) (xy 124.248926 -305.008534) (xy 124.249406 -304.981164)
			(xy 124.257219 -304.926985) (xy 124.272705 -304.874482) (xy 124.295544 -304.824735) (xy 124.325266 -304.778768)
			(xy 124.342906 -304.757836) (xy 124.34316 -304.757582) (xy 124.348767 -304.75051) (xy 124.355 -304.733582)
			(xy 124.355352 -304.724562) (xy 124.355352 -304.657506) (xy 124.355002 -304.648488) (xy 124.348751 -304.631571)
			(xy 124.34316 -304.624486) (xy 124.342906 -304.624486) (xy 124.342906 -304.624232) (xy 124.325269 -304.603298)
			(xy 124.295557 -304.557326) (xy 124.27272 -304.507579) (xy 124.257229 -304.455079) (xy 124.2494 -304.400903)
			(xy 124.248926 -304.373534) (xy 124.249412 -304.346283) (xy 124.257168 -304.292335) (xy 124.272523 -304.24004)
			(xy 124.295165 -304.190463) (xy 124.324631 -304.144613) (xy 124.360322 -304.103422) (xy 124.401513 -304.067731)
			(xy 124.447363 -304.038265) (xy 124.49694 -304.015623) (xy 124.549235 -304.000268) (xy 124.603183 -303.992512)
			(xy 124.657685 -303.992512) (xy 124.711633 -304.000268) (xy 124.763928 -304.015623) (xy 124.813505 -304.038265)
			(xy 124.859355 -304.067731) (xy 124.900546 -304.103422) (xy 124.936237 -304.144613) (xy 124.965703 -304.190463)
			(xy 124.988345 -304.24004) (xy 125.0037 -304.292335) (xy 125.011456 -304.346283) (xy 125.011942 -304.373534)
			(xy 125.01151 -304.400906) (xy 125.003686 -304.455087) (xy 124.98819 -304.507591) (xy 124.96534 -304.557337)
			(xy 124.935607 -304.603302) (xy 124.917962 -304.624232) (xy 124.917708 -304.624486) (xy 124.912122 -304.631573)
			(xy 124.905875 -304.648489) (xy 124.905516 -304.657506) (xy 124.905516 -304.724562) (xy 124.905888 -304.733577)
			(xy 124.912125 -304.750495) (xy 124.917708 -304.757582) (xy 124.917962 -304.757582) (xy 124.917962 -304.757836)
			(xy 124.935579 -304.778786) (xy 124.965295 -304.824753) (xy 124.988136 -304.874496) (xy 125.003632 -304.926993)
			(xy 125.011465 -304.981166) (xy 125.011942 -305.008534) (xy 125.637036 -305.008534) (xy 125.637513 -304.981164)
			(xy 125.645327 -304.926985) (xy 125.660813 -304.874482) (xy 125.683652 -304.824735) (xy 125.713375 -304.778768)
			(xy 125.731016 -304.757836) (xy 125.73127 -304.757582) (xy 125.736878 -304.750511) (xy 125.74311 -304.733582)
			(xy 125.743462 -304.724562) (xy 125.743462 -304.657506) (xy 125.74311 -304.648488) (xy 125.73686 -304.631571)
			(xy 125.73127 -304.624486) (xy 125.731016 -304.624486) (xy 125.731016 -304.624232) (xy 125.713381 -304.603297)
			(xy 125.683668 -304.557325) (xy 125.660831 -304.507578) (xy 125.645339 -304.455078) (xy 125.63751 -304.400903)
			(xy 125.637036 -304.373534) (xy 125.637522 -304.346283) (xy 125.645278 -304.292335) (xy 125.660633 -304.24004)
			(xy 125.683275 -304.190463) (xy 125.712741 -304.144613) (xy 125.748432 -304.103422) (xy 125.789623 -304.067731)
			(xy 125.835473 -304.038265) (xy 125.88505 -304.015623) (xy 125.937345 -304.000268) (xy 125.991293 -303.992512)
			(xy 126.045795 -303.992512) (xy 126.099743 -304.000268) (xy 126.152038 -304.015623) (xy 126.201615 -304.038265)
			(xy 126.247465 -304.067731) (xy 126.288656 -304.103422) (xy 126.324347 -304.144613) (xy 126.353813 -304.190463)
			(xy 126.376455 -304.24004) (xy 126.39181 -304.292335) (xy 126.399566 -304.346283) (xy 126.400052 -304.373534)
			(xy 126.399618 -304.400906) (xy 126.391794 -304.455086) (xy 126.376298 -304.50759) (xy 126.353449 -304.557337)
			(xy 126.323717 -304.603302) (xy 126.306072 -304.624232) (xy 126.305818 -304.624486) (xy 126.300234 -304.631574)
			(xy 126.293985 -304.64849) (xy 126.293626 -304.657506) (xy 126.293626 -304.724562) (xy 126.293996 -304.733578)
			(xy 126.300234 -304.750495) (xy 126.305818 -304.757582) (xy 126.306072 -304.757582) (xy 126.306072 -304.757836)
			(xy 126.32369 -304.778785) (xy 126.353406 -304.824753) (xy 126.376247 -304.874496) (xy 126.391742 -304.926993)
			(xy 126.399576 -304.981166) (xy 126.400052 -305.008534) (xy 127.669036 -305.008534) (xy 127.669513 -304.981164)
			(xy 127.677327 -304.926985) (xy 127.692813 -304.874482) (xy 127.715652 -304.824735) (xy 127.745375 -304.778768)
			(xy 127.763016 -304.757836) (xy 127.76327 -304.757582) (xy 127.768878 -304.750511) (xy 127.77511 -304.733582)
			(xy 127.775462 -304.724562) (xy 127.775462 -304.657506) (xy 127.77511 -304.648488) (xy 127.76886 -304.631571)
			(xy 127.76327 -304.624486) (xy 127.763016 -304.624486) (xy 127.763016 -304.624232) (xy 127.745381 -304.603297)
			(xy 127.715668 -304.557325) (xy 127.692831 -304.507578) (xy 127.677339 -304.455078) (xy 127.66951 -304.400903)
			(xy 127.669036 -304.373534) (xy 127.669522 -304.346283) (xy 127.677278 -304.292335) (xy 127.692633 -304.24004)
			(xy 127.715275 -304.190463) (xy 127.744741 -304.144613) (xy 127.780432 -304.103422) (xy 127.821623 -304.067731)
			(xy 127.867473 -304.038265) (xy 127.91705 -304.015623) (xy 127.969345 -304.000268) (xy 128.023293 -303.992512)
			(xy 128.077795 -303.992512) (xy 128.131743 -304.000268) (xy 128.184038 -304.015623) (xy 128.233615 -304.038265)
			(xy 128.279465 -304.067731) (xy 128.320656 -304.103422) (xy 128.356347 -304.144613) (xy 128.385813 -304.190463)
			(xy 128.408455 -304.24004) (xy 128.42381 -304.292335) (xy 128.431566 -304.346283) (xy 128.432052 -304.373534)
			(xy 128.431618 -304.400906) (xy 128.423794 -304.455086) (xy 128.408298 -304.50759) (xy 128.385449 -304.557337)
			(xy 128.355717 -304.603302) (xy 128.338072 -304.624232) (xy 128.337818 -304.624486) (xy 128.332234 -304.631574)
			(xy 128.325985 -304.64849) (xy 128.325626 -304.657506) (xy 128.325626 -304.724562) (xy 128.325996 -304.733578)
			(xy 128.332234 -304.750495) (xy 128.337818 -304.757582) (xy 128.338072 -304.757582) (xy 128.338072 -304.757836)
			(xy 128.35569 -304.778785) (xy 128.385406 -304.824753) (xy 128.408247 -304.874496) (xy 128.423742 -304.926993)
			(xy 128.431576 -304.981166) (xy 128.432052 -305.008534) (xy 132.477256 -305.008534) (xy 132.477728 -304.981164)
			(xy 132.485543 -304.926984) (xy 132.501029 -304.874481) (xy 132.52387 -304.824734) (xy 132.553595 -304.778767)
			(xy 132.571236 -304.757836) (xy 132.57149 -304.757582) (xy 132.577089 -304.750504) (xy 132.583329 -304.733581)
			(xy 132.583682 -304.724562) (xy 132.583682 -304.657506) (xy 132.583326 -304.648489) (xy 132.577078 -304.631572)
			(xy 132.57149 -304.624486) (xy 132.571236 -304.624486) (xy 132.571236 -304.624232) (xy 132.553604 -304.603294)
			(xy 132.52389 -304.557323) (xy 132.501052 -304.507577) (xy 132.485559 -304.455078) (xy 132.47773 -304.400903)
			(xy 132.477256 -304.373534) (xy 132.477742 -304.346283) (xy 132.485498 -304.292335) (xy 132.500853 -304.24004)
			(xy 132.523495 -304.190463) (xy 132.552961 -304.144613) (xy 132.588652 -304.103422) (xy 132.629843 -304.067731)
			(xy 132.675693 -304.038265) (xy 132.72527 -304.015623) (xy 132.777565 -304.000268) (xy 132.831513 -303.992512)
			(xy 132.886015 -303.992512) (xy 132.939963 -304.000268) (xy 132.992258 -304.015623) (xy 133.041835 -304.038265)
			(xy 133.087685 -304.067731) (xy 133.128876 -304.103422) (xy 133.164567 -304.144613) (xy 133.194033 -304.190463)
			(xy 133.216675 -304.24004) (xy 133.23203 -304.292335) (xy 133.239786 -304.346283) (xy 133.240272 -304.373534)
			(xy 133.239833 -304.400905) (xy 133.232009 -304.455086) (xy 133.216514 -304.507589) (xy 133.193667 -304.557336)
			(xy 133.163936 -304.603301) (xy 133.146292 -304.624232) (xy 133.146038 -304.624486) (xy 133.140444 -304.631567)
			(xy 133.134203 -304.648488) (xy 133.133846 -304.657506) (xy 133.133846 -304.724562) (xy 133.134211 -304.733578)
			(xy 133.140452 -304.750496) (xy 133.146038 -304.757582) (xy 133.146292 -304.757582) (xy 133.146292 -304.757836)
			(xy 133.163913 -304.778782) (xy 133.193628 -304.824751) (xy 133.216468 -304.874495) (xy 133.231963 -304.926993)
			(xy 133.239796 -304.981166) (xy 133.240272 -305.008534) (xy 133.239786 -305.035785) (xy 133.23203 -305.089733)
			(xy 133.216675 -305.142028) (xy 133.194033 -305.191605) (xy 133.164567 -305.237455) (xy 133.128876 -305.278646)
			(xy 133.096209 -305.306951) (xy 143.510416 -305.306951) (xy 143.518174 -305.252993) (xy 143.533531 -305.200689)
			(xy 143.556176 -305.151102) (xy 143.585647 -305.105243) (xy 143.621345 -305.064045) (xy 143.662543 -305.028347)
			(xy 143.708403 -304.998876) (xy 143.757989 -304.976231) (xy 143.810294 -304.960873) (xy 143.864252 -304.953116)
			(xy 143.891508 -304.952654) (xy 143.891762 -304.952654) (xy 143.919448 -304.95367) (xy 143.930624 -304.954432)
			(xy 143.951706 -304.946558) (xy 144.02181 -304.873914) (xy 144.029176 -304.852578) (xy 144.027906 -304.841402)
			(xy 144.026845 -304.831148) (xy 144.025701 -304.810562) (xy 144.02562 -304.800254) (xy 144.026127 -304.773007)
			(xy 144.033889 -304.719069) (xy 144.049247 -304.666785) (xy 144.07189 -304.617218) (xy 144.101356 -304.571378)
			(xy 144.137045 -304.530197) (xy 144.178232 -304.494515) (xy 144.224077 -304.465057) (xy 144.273648 -304.442424)
			(xy 144.325935 -304.427074) (xy 144.379874 -304.419323) (xy 144.434368 -304.419326) (xy 144.488307 -304.427084)
			(xy 144.540592 -304.442438) (xy 144.557122 -304.449988) (xy 151.693892 -304.449988) (xy 151.697852 -304.400934)
			(xy 151.709629 -304.35315) (xy 151.72892 -304.307874) (xy 151.755223 -304.266278) (xy 151.787858 -304.229441)
			(xy 151.825979 -304.198316) (xy 151.8686 -304.173709) (xy 151.914616 -304.156257) (xy 151.962835 -304.146413)
			(xy 152.01201 -304.144432) (xy 152.060865 -304.150364) (xy 152.108136 -304.164056) (xy 152.152598 -304.185154)
			(xy 152.193101 -304.21311) (xy 152.228594 -304.247202) (xy 152.258159 -304.286546) (xy 152.28103 -304.330123)
			(xy 152.296614 -304.376804) (xy 152.304509 -304.425381) (xy 152.304999 -304.449734) (xy 152.644106 -304.449734)
			(xy 152.648066 -304.40068) (xy 152.659843 -304.352896) (xy 152.679134 -304.30762) (xy 152.705437 -304.266024)
			(xy 152.738072 -304.229187) (xy 152.776193 -304.198062) (xy 152.818814 -304.173455) (xy 152.86483 -304.156003)
			(xy 152.913049 -304.146159) (xy 152.962224 -304.144178) (xy 153.011079 -304.15011) (xy 153.05835 -304.163802)
			(xy 153.102812 -304.1849) (xy 153.143315 -304.212856) (xy 153.178808 -304.246948) (xy 153.208373 -304.286292)
			(xy 153.231244 -304.329869) (xy 153.246828 -304.37655) (xy 153.254723 -304.425127) (xy 153.255218 -304.449734)
			(xy 153.594066 -304.449734) (xy 153.598026 -304.40068) (xy 153.609803 -304.352896) (xy 153.629094 -304.30762)
			(xy 153.655397 -304.266024) (xy 153.688032 -304.229187) (xy 153.726153 -304.198062) (xy 153.768774 -304.173455)
			(xy 153.81479 -304.156003) (xy 153.863009 -304.146159) (xy 153.912184 -304.144178) (xy 153.961039 -304.15011)
			(xy 154.00831 -304.163802) (xy 154.052772 -304.1849) (xy 154.093275 -304.212856) (xy 154.128768 -304.246948)
			(xy 154.158333 -304.286292) (xy 154.181204 -304.329869) (xy 154.196788 -304.37655) (xy 154.204683 -304.425127)
			(xy 154.205178 -304.449734) (xy 154.54428 -304.449734) (xy 154.54824 -304.40068) (xy 154.560017 -304.352896)
			(xy 154.579308 -304.30762) (xy 154.605611 -304.266024) (xy 154.638246 -304.229187) (xy 154.676367 -304.198062)
			(xy 154.718988 -304.173455) (xy 154.765004 -304.156003) (xy 154.813223 -304.146159) (xy 154.862398 -304.144178)
			(xy 154.911253 -304.15011) (xy 154.958524 -304.163802) (xy 155.002986 -304.1849) (xy 155.043489 -304.212856)
			(xy 155.078982 -304.246948) (xy 155.108547 -304.286292) (xy 155.131418 -304.329869) (xy 155.147002 -304.37655)
			(xy 155.154897 -304.425127) (xy 155.155392 -304.449734) (xy 155.49424 -304.449734) (xy 155.4982 -304.40068)
			(xy 155.509977 -304.352896) (xy 155.529268 -304.30762) (xy 155.555571 -304.266024) (xy 155.588206 -304.229187)
			(xy 155.626327 -304.198062) (xy 155.668948 -304.173455) (xy 155.714964 -304.156003) (xy 155.763183 -304.146159)
			(xy 155.812358 -304.144178) (xy 155.861213 -304.15011) (xy 155.908484 -304.163802) (xy 155.952946 -304.1849)
			(xy 155.993449 -304.212856) (xy 156.028942 -304.246948) (xy 156.058507 -304.286292) (xy 156.081378 -304.329869)
			(xy 156.096962 -304.37655) (xy 156.104857 -304.425127) (xy 156.105352 -304.449734) (xy 156.4442 -304.449734)
			(xy 156.44816 -304.40068) (xy 156.459937 -304.352896) (xy 156.479228 -304.30762) (xy 156.505531 -304.266024)
			(xy 156.538166 -304.229187) (xy 156.576287 -304.198062) (xy 156.618908 -304.173455) (xy 156.664924 -304.156003)
			(xy 156.713143 -304.146159) (xy 156.762318 -304.144178) (xy 156.811173 -304.15011) (xy 156.858444 -304.163802)
			(xy 156.902906 -304.1849) (xy 156.943409 -304.212856) (xy 156.978902 -304.246948) (xy 157.008467 -304.286292)
			(xy 157.031338 -304.329869) (xy 157.046922 -304.37655) (xy 157.054817 -304.425127) (xy 157.055312 -304.449734)
			(xy 157.39416 -304.449734) (xy 157.39812 -304.40068) (xy 157.409897 -304.352896) (xy 157.429188 -304.30762)
			(xy 157.455491 -304.266024) (xy 157.488126 -304.229187) (xy 157.526247 -304.198062) (xy 157.568868 -304.173455)
			(xy 157.614884 -304.156003) (xy 157.663103 -304.146159) (xy 157.712278 -304.144178) (xy 157.761133 -304.15011)
			(xy 157.808404 -304.163802) (xy 157.852866 -304.1849) (xy 157.893369 -304.212856) (xy 157.928862 -304.246948)
			(xy 157.958427 -304.286292) (xy 157.981298 -304.329869) (xy 157.996882 -304.37655) (xy 158.004777 -304.425127)
			(xy 158.005272 -304.449734) (xy 158.34412 -304.449734) (xy 158.34808 -304.40068) (xy 158.359857 -304.352896)
			(xy 158.379148 -304.30762) (xy 158.405451 -304.266024) (xy 158.438086 -304.229187) (xy 158.476207 -304.198062)
			(xy 158.518828 -304.173455) (xy 158.564844 -304.156003) (xy 158.613063 -304.146159) (xy 158.662238 -304.144178)
			(xy 158.711093 -304.15011) (xy 158.758364 -304.163802) (xy 158.802826 -304.1849) (xy 158.843329 -304.212856)
			(xy 158.878822 -304.246948) (xy 158.908387 -304.286292) (xy 158.931258 -304.329869) (xy 158.946842 -304.37655)
			(xy 158.954737 -304.425127) (xy 158.955232 -304.449734) (xy 159.29408 -304.449734) (xy 159.29804 -304.40068)
			(xy 159.309817 -304.352896) (xy 159.329108 -304.30762) (xy 159.355411 -304.266024) (xy 159.388046 -304.229187)
			(xy 159.426167 -304.198062) (xy 159.468788 -304.173455) (xy 159.514804 -304.156003) (xy 159.563023 -304.146159)
			(xy 159.612198 -304.144178) (xy 159.661053 -304.15011) (xy 159.708324 -304.163802) (xy 159.752786 -304.1849)
			(xy 159.793289 -304.212856) (xy 159.828782 -304.246948) (xy 159.858347 -304.286292) (xy 159.881218 -304.329869)
			(xy 159.896802 -304.37655) (xy 159.904697 -304.425127) (xy 159.905192 -304.449734) (xy 160.24404 -304.449734)
			(xy 160.248 -304.40068) (xy 160.259777 -304.352896) (xy 160.279068 -304.30762) (xy 160.305371 -304.266024)
			(xy 160.338006 -304.229187) (xy 160.376127 -304.198062) (xy 160.418748 -304.173455) (xy 160.464764 -304.156003)
			(xy 160.512983 -304.146159) (xy 160.562158 -304.144178) (xy 160.611013 -304.15011) (xy 160.658284 -304.163802)
			(xy 160.702746 -304.1849) (xy 160.743249 -304.212856) (xy 160.778742 -304.246948) (xy 160.808307 -304.286292)
			(xy 160.831178 -304.329869) (xy 160.846762 -304.37655) (xy 160.854657 -304.425127) (xy 160.855152 -304.449734)
			(xy 161.194254 -304.449734) (xy 161.198214 -304.40068) (xy 161.209991 -304.352896) (xy 161.229282 -304.30762)
			(xy 161.255585 -304.266024) (xy 161.28822 -304.229187) (xy 161.326341 -304.198062) (xy 161.368962 -304.173455)
			(xy 161.414978 -304.156003) (xy 161.463197 -304.146159) (xy 161.512372 -304.144178) (xy 161.561227 -304.15011)
			(xy 161.608498 -304.163802) (xy 161.65296 -304.1849) (xy 161.693463 -304.212856) (xy 161.728956 -304.246948)
			(xy 161.758521 -304.286292) (xy 161.781392 -304.329869) (xy 161.796976 -304.37655) (xy 161.804871 -304.425127)
			(xy 161.805366 -304.449734) (xy 161.804871 -304.474341) (xy 161.796976 -304.522918) (xy 161.781392 -304.569599)
			(xy 161.758521 -304.613176) (xy 161.728956 -304.65252) (xy 161.693463 -304.686612) (xy 161.65296 -304.714568)
			(xy 161.608498 -304.735666) (xy 161.561227 -304.749358) (xy 161.512372 -304.75529) (xy 161.463197 -304.753309)
			(xy 161.414978 -304.743465) (xy 161.368962 -304.726013) (xy 161.326341 -304.701406) (xy 161.28822 -304.670281)
			(xy 161.255585 -304.633444) (xy 161.229282 -304.591848) (xy 161.209991 -304.546572) (xy 161.198214 -304.498788)
			(xy 161.194254 -304.449734) (xy 160.855152 -304.449734) (xy 160.854657 -304.474341) (xy 160.846762 -304.522918)
			(xy 160.831178 -304.569599) (xy 160.808307 -304.613176) (xy 160.778742 -304.65252) (xy 160.743249 -304.686612)
			(xy 160.702746 -304.714568) (xy 160.658284 -304.735666) (xy 160.611013 -304.749358) (xy 160.562158 -304.75529)
			(xy 160.512983 -304.753309) (xy 160.464764 -304.743465) (xy 160.418748 -304.726013) (xy 160.376127 -304.701406)
			(xy 160.338006 -304.670281) (xy 160.305371 -304.633444) (xy 160.279068 -304.591848) (xy 160.259777 -304.546572)
			(xy 160.248 -304.498788) (xy 160.24404 -304.449734) (xy 159.905192 -304.449734) (xy 159.904697 -304.474341)
			(xy 159.896802 -304.522918) (xy 159.881218 -304.569599) (xy 159.858347 -304.613176) (xy 159.828782 -304.65252)
			(xy 159.793289 -304.686612) (xy 159.752786 -304.714568) (xy 159.708324 -304.735666) (xy 159.661053 -304.749358)
			(xy 159.612198 -304.75529) (xy 159.563023 -304.753309) (xy 159.514804 -304.743465) (xy 159.468788 -304.726013)
			(xy 159.426167 -304.701406) (xy 159.388046 -304.670281) (xy 159.355411 -304.633444) (xy 159.329108 -304.591848)
			(xy 159.309817 -304.546572) (xy 159.29804 -304.498788) (xy 159.29408 -304.449734) (xy 158.955232 -304.449734)
			(xy 158.954737 -304.474341) (xy 158.946842 -304.522918) (xy 158.931258 -304.569599) (xy 158.908387 -304.613176)
			(xy 158.878822 -304.65252) (xy 158.843329 -304.686612) (xy 158.802826 -304.714568) (xy 158.758364 -304.735666)
			(xy 158.711093 -304.749358) (xy 158.662238 -304.75529) (xy 158.613063 -304.753309) (xy 158.564844 -304.743465)
			(xy 158.518828 -304.726013) (xy 158.476207 -304.701406) (xy 158.438086 -304.670281) (xy 158.405451 -304.633444)
			(xy 158.379148 -304.591848) (xy 158.359857 -304.546572) (xy 158.34808 -304.498788) (xy 158.34412 -304.449734)
			(xy 158.005272 -304.449734) (xy 158.004777 -304.474341) (xy 157.996882 -304.522918) (xy 157.981298 -304.569599)
			(xy 157.958427 -304.613176) (xy 157.928862 -304.65252) (xy 157.893369 -304.686612) (xy 157.852866 -304.714568)
			(xy 157.808404 -304.735666) (xy 157.761133 -304.749358) (xy 157.712278 -304.75529) (xy 157.663103 -304.753309)
			(xy 157.614884 -304.743465) (xy 157.568868 -304.726013) (xy 157.526247 -304.701406) (xy 157.488126 -304.670281)
			(xy 157.455491 -304.633444) (xy 157.429188 -304.591848) (xy 157.409897 -304.546572) (xy 157.39812 -304.498788)
			(xy 157.39416 -304.449734) (xy 157.055312 -304.449734) (xy 157.054817 -304.474341) (xy 157.046922 -304.522918)
			(xy 157.031338 -304.569599) (xy 157.008467 -304.613176) (xy 156.978902 -304.65252) (xy 156.943409 -304.686612)
			(xy 156.902906 -304.714568) (xy 156.858444 -304.735666) (xy 156.811173 -304.749358) (xy 156.762318 -304.75529)
			(xy 156.713143 -304.753309) (xy 156.664924 -304.743465) (xy 156.618908 -304.726013) (xy 156.576287 -304.701406)
			(xy 156.538166 -304.670281) (xy 156.505531 -304.633444) (xy 156.479228 -304.591848) (xy 156.459937 -304.546572)
			(xy 156.44816 -304.498788) (xy 156.4442 -304.449734) (xy 156.105352 -304.449734) (xy 156.104857 -304.474341)
			(xy 156.096962 -304.522918) (xy 156.081378 -304.569599) (xy 156.058507 -304.613176) (xy 156.028942 -304.65252)
			(xy 155.993449 -304.686612) (xy 155.952946 -304.714568) (xy 155.908484 -304.735666) (xy 155.861213 -304.749358)
			(xy 155.812358 -304.75529) (xy 155.763183 -304.753309) (xy 155.714964 -304.743465) (xy 155.668948 -304.726013)
			(xy 155.626327 -304.701406) (xy 155.588206 -304.670281) (xy 155.555571 -304.633444) (xy 155.529268 -304.591848)
			(xy 155.509977 -304.546572) (xy 155.4982 -304.498788) (xy 155.49424 -304.449734) (xy 155.155392 -304.449734)
			(xy 155.154897 -304.474341) (xy 155.147002 -304.522918) (xy 155.131418 -304.569599) (xy 155.108547 -304.613176)
			(xy 155.078982 -304.65252) (xy 155.043489 -304.686612) (xy 155.002986 -304.714568) (xy 154.958524 -304.735666)
			(xy 154.911253 -304.749358) (xy 154.862398 -304.75529) (xy 154.813223 -304.753309) (xy 154.765004 -304.743465)
			(xy 154.718988 -304.726013) (xy 154.676367 -304.701406) (xy 154.638246 -304.670281) (xy 154.605611 -304.633444)
			(xy 154.579308 -304.591848) (xy 154.560017 -304.546572) (xy 154.54824 -304.498788) (xy 154.54428 -304.449734)
			(xy 154.205178 -304.449734) (xy 154.204683 -304.474341) (xy 154.196788 -304.522918) (xy 154.181204 -304.569599)
			(xy 154.158333 -304.613176) (xy 154.128768 -304.65252) (xy 154.093275 -304.686612) (xy 154.052772 -304.714568)
			(xy 154.00831 -304.735666) (xy 153.961039 -304.749358) (xy 153.912184 -304.75529) (xy 153.863009 -304.753309)
			(xy 153.81479 -304.743465) (xy 153.768774 -304.726013) (xy 153.726153 -304.701406) (xy 153.688032 -304.670281)
			(xy 153.655397 -304.633444) (xy 153.629094 -304.591848) (xy 153.609803 -304.546572) (xy 153.598026 -304.498788)
			(xy 153.594066 -304.449734) (xy 153.255218 -304.449734) (xy 153.254723 -304.474341) (xy 153.246828 -304.522918)
			(xy 153.231244 -304.569599) (xy 153.208373 -304.613176) (xy 153.178808 -304.65252) (xy 153.143315 -304.686612)
			(xy 153.102812 -304.714568) (xy 153.05835 -304.735666) (xy 153.011079 -304.749358) (xy 152.962224 -304.75529)
			(xy 152.913049 -304.753309) (xy 152.86483 -304.743465) (xy 152.818814 -304.726013) (xy 152.776193 -304.701406)
			(xy 152.738072 -304.670281) (xy 152.705437 -304.633444) (xy 152.679134 -304.591848) (xy 152.659843 -304.546572)
			(xy 152.648066 -304.498788) (xy 152.644106 -304.449734) (xy 152.304999 -304.449734) (xy 152.305004 -304.449988)
			(xy 152.304509 -304.474595) (xy 152.296614 -304.523172) (xy 152.28103 -304.569853) (xy 152.258159 -304.61343)
			(xy 152.228594 -304.652774) (xy 152.193101 -304.686866) (xy 152.152598 -304.714822) (xy 152.108136 -304.73592)
			(xy 152.060865 -304.749612) (xy 152.01201 -304.755544) (xy 151.962835 -304.753563) (xy 151.914616 -304.743719)
			(xy 151.8686 -304.726267) (xy 151.825979 -304.70166) (xy 151.787858 -304.670535) (xy 151.755223 -304.633698)
			(xy 151.72892 -304.592102) (xy 151.709629 -304.546826) (xy 151.697852 -304.499042) (xy 151.693892 -304.449988)
			(xy 144.557122 -304.449988) (xy 144.590161 -304.465078) (xy 144.636003 -304.494541) (xy 144.677185 -304.530228)
			(xy 144.71287 -304.571412) (xy 144.742331 -304.617255) (xy 144.764968 -304.666825) (xy 144.78032 -304.719111)
			(xy 144.788076 -304.77305) (xy 144.788076 -304.827543) (xy 144.780322 -304.881483) (xy 144.767629 -304.924714)
			(xy 162.619194 -304.924714) (xy 162.623154 -304.87566) (xy 162.634931 -304.827876) (xy 162.654222 -304.7826)
			(xy 162.680525 -304.741004) (xy 162.71316 -304.704167) (xy 162.751281 -304.673042) (xy 162.793902 -304.648435)
			(xy 162.839918 -304.630983) (xy 162.888137 -304.621139) (xy 162.937312 -304.619158) (xy 162.986167 -304.62509)
			(xy 163.033438 -304.638782) (xy 163.0779 -304.65988) (xy 163.118403 -304.687836) (xy 163.153896 -304.721928)
			(xy 163.183461 -304.761272) (xy 163.206332 -304.804849) (xy 163.221916 -304.85153) (xy 163.229811 -304.900107)
			(xy 163.230306 -304.924714) (xy 163.569154 -304.924714) (xy 163.573114 -304.87566) (xy 163.584891 -304.827876)
			(xy 163.604182 -304.7826) (xy 163.630485 -304.741004) (xy 163.66312 -304.704167) (xy 163.701241 -304.673042)
			(xy 163.743862 -304.648435) (xy 163.789878 -304.630983) (xy 163.838097 -304.621139) (xy 163.887272 -304.619158)
			(xy 163.936127 -304.62509) (xy 163.983398 -304.638782) (xy 164.02786 -304.65988) (xy 164.068363 -304.687836)
			(xy 164.103856 -304.721928) (xy 164.133421 -304.761272) (xy 164.156292 -304.804849) (xy 164.171876 -304.85153)
			(xy 164.179771 -304.900107) (xy 164.180266 -304.924714) (xy 164.519114 -304.924714) (xy 164.523074 -304.87566)
			(xy 164.534851 -304.827876) (xy 164.554142 -304.7826) (xy 164.580445 -304.741004) (xy 164.61308 -304.704167)
			(xy 164.651201 -304.673042) (xy 164.693822 -304.648435) (xy 164.739838 -304.630983) (xy 164.788057 -304.621139)
			(xy 164.837232 -304.619158) (xy 164.886087 -304.62509) (xy 164.933358 -304.638782) (xy 164.97782 -304.65988)
			(xy 165.018323 -304.687836) (xy 165.053816 -304.721928) (xy 165.083381 -304.761272) (xy 165.106252 -304.804849)
			(xy 165.121836 -304.85153) (xy 165.129731 -304.900107) (xy 165.130226 -304.924714) (xy 165.129731 -304.949321)
			(xy 165.121836 -304.997898) (xy 165.106252 -305.044579) (xy 165.083381 -305.088156) (xy 165.053816 -305.1275)
			(xy 165.018323 -305.161592) (xy 164.97782 -305.189548) (xy 164.933358 -305.210646) (xy 164.886087 -305.224338)
			(xy 164.837232 -305.23027) (xy 164.788057 -305.228289) (xy 164.739838 -305.218445) (xy 164.693822 -305.200993)
			(xy 164.651201 -305.176386) (xy 164.61308 -305.145261) (xy 164.580445 -305.108424) (xy 164.554142 -305.066828)
			(xy 164.534851 -305.021552) (xy 164.523074 -304.973768) (xy 164.519114 -304.924714) (xy 164.180266 -304.924714)
			(xy 164.179771 -304.949321) (xy 164.171876 -304.997898) (xy 164.156292 -305.044579) (xy 164.133421 -305.088156)
			(xy 164.103856 -305.1275) (xy 164.068363 -305.161592) (xy 164.02786 -305.189548) (xy 163.983398 -305.210646)
			(xy 163.936127 -305.224338) (xy 163.887272 -305.23027) (xy 163.838097 -305.228289) (xy 163.789878 -305.218445)
			(xy 163.743862 -305.200993) (xy 163.701241 -305.176386) (xy 163.66312 -305.145261) (xy 163.630485 -305.108424)
			(xy 163.604182 -305.066828) (xy 163.584891 -305.021552) (xy 163.573114 -304.973768) (xy 163.569154 -304.924714)
			(xy 163.230306 -304.924714) (xy 163.229811 -304.949321) (xy 163.221916 -304.997898) (xy 163.206332 -305.044579)
			(xy 163.183461 -305.088156) (xy 163.153896 -305.1275) (xy 163.118403 -305.161592) (xy 163.0779 -305.189548)
			(xy 163.033438 -305.210646) (xy 162.986167 -305.224338) (xy 162.937312 -305.23027) (xy 162.888137 -305.228289)
			(xy 162.839918 -305.218445) (xy 162.793902 -305.200993) (xy 162.751281 -305.176386) (xy 162.71316 -305.145261)
			(xy 162.680525 -305.108424) (xy 162.654222 -305.066828) (xy 162.634931 -305.021552) (xy 162.623154 -304.973768)
			(xy 162.619194 -304.924714) (xy 144.767629 -304.924714) (xy 144.76497 -304.933769) (xy 144.742334 -304.983339)
			(xy 144.712874 -305.029183) (xy 144.67719 -305.070368) (xy 144.636008 -305.106055) (xy 144.590166 -305.135519)
			(xy 144.540599 -305.158159) (xy 144.488313 -305.173515) (xy 144.434375 -305.181274) (xy 144.407128 -305.181762)
			(xy 144.406874 -305.181762) (xy 144.379188 -305.180746) (xy 144.368012 -305.179984) (xy 144.34693 -305.187858)
			(xy 144.276826 -305.260502) (xy 144.26946 -305.281838) (xy 144.27073 -305.293014) (xy 144.271792 -305.303268)
			(xy 144.272935 -305.323853) (xy 144.273016 -305.334162) (xy 144.272586 -305.361418) (xy 144.26705 -305.399948)
			(xy 152.644106 -305.399948) (xy 152.648066 -305.350894) (xy 152.659843 -305.30311) (xy 152.679134 -305.257834)
			(xy 152.705437 -305.216238) (xy 152.738072 -305.179401) (xy 152.776193 -305.148276) (xy 152.818814 -305.123669)
			(xy 152.86483 -305.106217) (xy 152.913049 -305.096373) (xy 152.962224 -305.094392) (xy 153.011079 -305.100324)
			(xy 153.05835 -305.114016) (xy 153.102812 -305.135114) (xy 153.143315 -305.16307) (xy 153.178808 -305.197162)
			(xy 153.208373 -305.236506) (xy 153.231244 -305.280083) (xy 153.246828 -305.326764) (xy 153.254723 -305.375341)
			(xy 153.255218 -305.399948) (xy 153.594066 -305.399948) (xy 153.598026 -305.350894) (xy 153.609803 -305.30311)
			(xy 153.629094 -305.257834) (xy 153.655397 -305.216238) (xy 153.688032 -305.179401) (xy 153.726153 -305.148276)
			(xy 153.768774 -305.123669) (xy 153.81479 -305.106217) (xy 153.863009 -305.096373) (xy 153.912184 -305.094392)
			(xy 153.961039 -305.100324) (xy 154.00831 -305.114016) (xy 154.052772 -305.135114) (xy 154.093275 -305.16307)
			(xy 154.128768 -305.197162) (xy 154.158333 -305.236506) (xy 154.181204 -305.280083) (xy 154.196788 -305.326764)
			(xy 154.204683 -305.375341) (xy 154.205178 -305.399948) (xy 154.54428 -305.399948) (xy 154.54824 -305.350894)
			(xy 154.560017 -305.30311) (xy 154.579308 -305.257834) (xy 154.605611 -305.216238) (xy 154.638246 -305.179401)
			(xy 154.676367 -305.148276) (xy 154.718988 -305.123669) (xy 154.765004 -305.106217) (xy 154.813223 -305.096373)
			(xy 154.862398 -305.094392) (xy 154.911253 -305.100324) (xy 154.958524 -305.114016) (xy 155.002986 -305.135114)
			(xy 155.043489 -305.16307) (xy 155.078982 -305.197162) (xy 155.108547 -305.236506) (xy 155.131418 -305.280083)
			(xy 155.147002 -305.326764) (xy 155.154897 -305.375341) (xy 155.155392 -305.399948) (xy 155.49424 -305.399948)
			(xy 155.4982 -305.350894) (xy 155.509977 -305.30311) (xy 155.529268 -305.257834) (xy 155.555571 -305.216238)
			(xy 155.588206 -305.179401) (xy 155.626327 -305.148276) (xy 155.668948 -305.123669) (xy 155.714964 -305.106217)
			(xy 155.763183 -305.096373) (xy 155.812358 -305.094392) (xy 155.861213 -305.100324) (xy 155.908484 -305.114016)
			(xy 155.952946 -305.135114) (xy 155.993449 -305.16307) (xy 156.028942 -305.197162) (xy 156.058507 -305.236506)
			(xy 156.081378 -305.280083) (xy 156.096962 -305.326764) (xy 156.104857 -305.375341) (xy 156.105352 -305.399948)
			(xy 156.4442 -305.399948) (xy 156.44816 -305.350894) (xy 156.459937 -305.30311) (xy 156.479228 -305.257834)
			(xy 156.505531 -305.216238) (xy 156.538166 -305.179401) (xy 156.576287 -305.148276) (xy 156.618908 -305.123669)
			(xy 156.664924 -305.106217) (xy 156.713143 -305.096373) (xy 156.762318 -305.094392) (xy 156.811173 -305.100324)
			(xy 156.858444 -305.114016) (xy 156.902906 -305.135114) (xy 156.943409 -305.16307) (xy 156.978902 -305.197162)
			(xy 157.008467 -305.236506) (xy 157.031338 -305.280083) (xy 157.046922 -305.326764) (xy 157.054817 -305.375341)
			(xy 157.055312 -305.399948) (xy 157.39416 -305.399948) (xy 157.39812 -305.350894) (xy 157.409897 -305.30311)
			(xy 157.429188 -305.257834) (xy 157.455491 -305.216238) (xy 157.488126 -305.179401) (xy 157.526247 -305.148276)
			(xy 157.568868 -305.123669) (xy 157.614884 -305.106217) (xy 157.663103 -305.096373) (xy 157.712278 -305.094392)
			(xy 157.761133 -305.100324) (xy 157.808404 -305.114016) (xy 157.852866 -305.135114) (xy 157.893369 -305.16307)
			(xy 157.928862 -305.197162) (xy 157.958427 -305.236506) (xy 157.981298 -305.280083) (xy 157.996882 -305.326764)
			(xy 158.004777 -305.375341) (xy 158.005272 -305.399948) (xy 158.34412 -305.399948) (xy 158.34808 -305.350894)
			(xy 158.359857 -305.30311) (xy 158.379148 -305.257834) (xy 158.405451 -305.216238) (xy 158.438086 -305.179401)
			(xy 158.476207 -305.148276) (xy 158.518828 -305.123669) (xy 158.564844 -305.106217) (xy 158.613063 -305.096373)
			(xy 158.662238 -305.094392) (xy 158.711093 -305.100324) (xy 158.758364 -305.114016) (xy 158.802826 -305.135114)
			(xy 158.843329 -305.16307) (xy 158.878822 -305.197162) (xy 158.908387 -305.236506) (xy 158.931258 -305.280083)
			(xy 158.946842 -305.326764) (xy 158.954737 -305.375341) (xy 158.955232 -305.399948) (xy 159.29408 -305.399948)
			(xy 159.29804 -305.350894) (xy 159.309817 -305.30311) (xy 159.329108 -305.257834) (xy 159.355411 -305.216238)
			(xy 159.388046 -305.179401) (xy 159.426167 -305.148276) (xy 159.468788 -305.123669) (xy 159.514804 -305.106217)
			(xy 159.563023 -305.096373) (xy 159.612198 -305.094392) (xy 159.661053 -305.100324) (xy 159.708324 -305.114016)
			(xy 159.752786 -305.135114) (xy 159.793289 -305.16307) (xy 159.828782 -305.197162) (xy 159.858347 -305.236506)
			(xy 159.881218 -305.280083) (xy 159.896802 -305.326764) (xy 159.904697 -305.375341) (xy 159.905192 -305.399948)
			(xy 160.24404 -305.399948) (xy 160.248 -305.350894) (xy 160.259777 -305.30311) (xy 160.279068 -305.257834)
			(xy 160.305371 -305.216238) (xy 160.338006 -305.179401) (xy 160.376127 -305.148276) (xy 160.418748 -305.123669)
			(xy 160.464764 -305.106217) (xy 160.512983 -305.096373) (xy 160.562158 -305.094392) (xy 160.611013 -305.100324)
			(xy 160.658284 -305.114016) (xy 160.702746 -305.135114) (xy 160.743249 -305.16307) (xy 160.778742 -305.197162)
			(xy 160.808307 -305.236506) (xy 160.831178 -305.280083) (xy 160.846762 -305.326764) (xy 160.854657 -305.375341)
			(xy 160.855152 -305.399948) (xy 161.194254 -305.399948) (xy 161.198214 -305.350894) (xy 161.209991 -305.30311)
			(xy 161.229282 -305.257834) (xy 161.255585 -305.216238) (xy 161.28822 -305.179401) (xy 161.326341 -305.148276)
			(xy 161.368962 -305.123669) (xy 161.414978 -305.106217) (xy 161.463197 -305.096373) (xy 161.512372 -305.094392)
			(xy 161.561227 -305.100324) (xy 161.608498 -305.114016) (xy 161.65296 -305.135114) (xy 161.693463 -305.16307)
			(xy 161.728956 -305.197162) (xy 161.758521 -305.236506) (xy 161.781392 -305.280083) (xy 161.796976 -305.326764)
			(xy 161.804871 -305.375341) (xy 161.805366 -305.399948) (xy 161.804871 -305.424555) (xy 161.796976 -305.473132)
			(xy 161.781392 -305.519813) (xy 161.758521 -305.56339) (xy 161.728956 -305.602734) (xy 161.693463 -305.636826)
			(xy 161.65296 -305.664782) (xy 161.608498 -305.68588) (xy 161.561227 -305.699572) (xy 161.512372 -305.705504)
			(xy 161.463197 -305.703523) (xy 161.414978 -305.693679) (xy 161.368962 -305.676227) (xy 161.326341 -305.65162)
			(xy 161.28822 -305.620495) (xy 161.255585 -305.583658) (xy 161.229282 -305.542062) (xy 161.209991 -305.496786)
			(xy 161.198214 -305.449002) (xy 161.194254 -305.399948) (xy 160.855152 -305.399948) (xy 160.854657 -305.424555)
			(xy 160.846762 -305.473132) (xy 160.831178 -305.519813) (xy 160.808307 -305.56339) (xy 160.778742 -305.602734)
			(xy 160.743249 -305.636826) (xy 160.702746 -305.664782) (xy 160.658284 -305.68588) (xy 160.611013 -305.699572)
			(xy 160.562158 -305.705504) (xy 160.512983 -305.703523) (xy 160.464764 -305.693679) (xy 160.418748 -305.676227)
			(xy 160.376127 -305.65162) (xy 160.338006 -305.620495) (xy 160.305371 -305.583658) (xy 160.279068 -305.542062)
			(xy 160.259777 -305.496786) (xy 160.248 -305.449002) (xy 160.24404 -305.399948) (xy 159.905192 -305.399948)
			(xy 159.904697 -305.424555) (xy 159.896802 -305.473132) (xy 159.881218 -305.519813) (xy 159.858347 -305.56339)
			(xy 159.828782 -305.602734) (xy 159.793289 -305.636826) (xy 159.752786 -305.664782) (xy 159.708324 -305.68588)
			(xy 159.661053 -305.699572) (xy 159.612198 -305.705504) (xy 159.563023 -305.703523) (xy 159.514804 -305.693679)
			(xy 159.468788 -305.676227) (xy 159.426167 -305.65162) (xy 159.388046 -305.620495) (xy 159.355411 -305.583658)
			(xy 159.329108 -305.542062) (xy 159.309817 -305.496786) (xy 159.29804 -305.449002) (xy 159.29408 -305.399948)
			(xy 158.955232 -305.399948) (xy 158.954737 -305.424555) (xy 158.946842 -305.473132) (xy 158.931258 -305.519813)
			(xy 158.908387 -305.56339) (xy 158.878822 -305.602734) (xy 158.843329 -305.636826) (xy 158.802826 -305.664782)
			(xy 158.758364 -305.68588) (xy 158.711093 -305.699572) (xy 158.662238 -305.705504) (xy 158.613063 -305.703523)
			(xy 158.564844 -305.693679) (xy 158.518828 -305.676227) (xy 158.476207 -305.65162) (xy 158.438086 -305.620495)
			(xy 158.405451 -305.583658) (xy 158.379148 -305.542062) (xy 158.359857 -305.496786) (xy 158.34808 -305.449002)
			(xy 158.34412 -305.399948) (xy 158.005272 -305.399948) (xy 158.004777 -305.424555) (xy 157.996882 -305.473132)
			(xy 157.981298 -305.519813) (xy 157.958427 -305.56339) (xy 157.928862 -305.602734) (xy 157.893369 -305.636826)
			(xy 157.852866 -305.664782) (xy 157.808404 -305.68588) (xy 157.761133 -305.699572) (xy 157.712278 -305.705504)
			(xy 157.663103 -305.703523) (xy 157.614884 -305.693679) (xy 157.568868 -305.676227) (xy 157.526247 -305.65162)
			(xy 157.488126 -305.620495) (xy 157.455491 -305.583658) (xy 157.429188 -305.542062) (xy 157.409897 -305.496786)
			(xy 157.39812 -305.449002) (xy 157.39416 -305.399948) (xy 157.055312 -305.399948) (xy 157.054817 -305.424555)
			(xy 157.046922 -305.473132) (xy 157.031338 -305.519813) (xy 157.008467 -305.56339) (xy 156.978902 -305.602734)
			(xy 156.943409 -305.636826) (xy 156.902906 -305.664782) (xy 156.858444 -305.68588) (xy 156.811173 -305.699572)
			(xy 156.762318 -305.705504) (xy 156.713143 -305.703523) (xy 156.664924 -305.693679) (xy 156.618908 -305.676227)
			(xy 156.576287 -305.65162) (xy 156.538166 -305.620495) (xy 156.505531 -305.583658) (xy 156.479228 -305.542062)
			(xy 156.459937 -305.496786) (xy 156.44816 -305.449002) (xy 156.4442 -305.399948) (xy 156.105352 -305.399948)
			(xy 156.104857 -305.424555) (xy 156.096962 -305.473132) (xy 156.081378 -305.519813) (xy 156.058507 -305.56339)
			(xy 156.028942 -305.602734) (xy 155.993449 -305.636826) (xy 155.952946 -305.664782) (xy 155.908484 -305.68588)
			(xy 155.861213 -305.699572) (xy 155.812358 -305.705504) (xy 155.763183 -305.703523) (xy 155.714964 -305.693679)
			(xy 155.668948 -305.676227) (xy 155.626327 -305.65162) (xy 155.588206 -305.620495) (xy 155.555571 -305.583658)
			(xy 155.529268 -305.542062) (xy 155.509977 -305.496786) (xy 155.4982 -305.449002) (xy 155.49424 -305.399948)
			(xy 155.155392 -305.399948) (xy 155.154897 -305.424555) (xy 155.147002 -305.473132) (xy 155.131418 -305.519813)
			(xy 155.108547 -305.56339) (xy 155.078982 -305.602734) (xy 155.043489 -305.636826) (xy 155.002986 -305.664782)
			(xy 154.958524 -305.68588) (xy 154.911253 -305.699572) (xy 154.862398 -305.705504) (xy 154.813223 -305.703523)
			(xy 154.765004 -305.693679) (xy 154.718988 -305.676227) (xy 154.676367 -305.65162) (xy 154.638246 -305.620495)
			(xy 154.605611 -305.583658) (xy 154.579308 -305.542062) (xy 154.560017 -305.496786) (xy 154.54824 -305.449002)
			(xy 154.54428 -305.399948) (xy 154.205178 -305.399948) (xy 154.204683 -305.424555) (xy 154.196788 -305.473132)
			(xy 154.181204 -305.519813) (xy 154.158333 -305.56339) (xy 154.128768 -305.602734) (xy 154.093275 -305.636826)
			(xy 154.052772 -305.664782) (xy 154.00831 -305.68588) (xy 153.961039 -305.699572) (xy 153.912184 -305.705504)
			(xy 153.863009 -305.703523) (xy 153.81479 -305.693679) (xy 153.768774 -305.676227) (xy 153.726153 -305.65162)
			(xy 153.688032 -305.620495) (xy 153.655397 -305.583658) (xy 153.629094 -305.542062) (xy 153.609803 -305.496786)
			(xy 153.598026 -305.449002) (xy 153.594066 -305.399948) (xy 153.255218 -305.399948) (xy 153.254723 -305.424555)
			(xy 153.246828 -305.473132) (xy 153.231244 -305.519813) (xy 153.208373 -305.56339) (xy 153.178808 -305.602734)
			(xy 153.143315 -305.636826) (xy 153.102812 -305.664782) (xy 153.05835 -305.68588) (xy 153.011079 -305.699572)
			(xy 152.962224 -305.705504) (xy 152.913049 -305.703523) (xy 152.86483 -305.693679) (xy 152.818814 -305.676227)
			(xy 152.776193 -305.65162) (xy 152.738072 -305.620495) (xy 152.705437 -305.583658) (xy 152.679134 -305.542062)
			(xy 152.659843 -305.496786) (xy 152.648066 -305.449002) (xy 152.644106 -305.399948) (xy 144.26705 -305.399948)
			(xy 144.264833 -305.415377) (xy 144.24948 -305.467683) (xy 144.226839 -305.517271) (xy 144.197371 -305.563132)
			(xy 144.161676 -305.604333) (xy 144.120481 -305.640035) (xy 144.074624 -305.66951) (xy 144.02504 -305.692159)
			(xy 143.972736 -305.70752) (xy 143.918779 -305.715281) (xy 143.864266 -305.715285) (xy 143.810308 -305.70753)
			(xy 143.758003 -305.692174) (xy 143.708415 -305.669531) (xy 143.662555 -305.640062) (xy 143.621356 -305.604365)
			(xy 143.585656 -305.563169) (xy 143.556183 -305.517311) (xy 143.533536 -305.467725) (xy 143.518177 -305.415421)
			(xy 143.510418 -305.361464) (xy 143.510416 -305.306951) (xy 133.096209 -305.306951) (xy 133.087685 -305.314337)
			(xy 133.041835 -305.343803) (xy 132.992258 -305.366445) (xy 132.939963 -305.3818) (xy 132.886015 -305.389556)
			(xy 132.831513 -305.389556) (xy 132.777565 -305.3818) (xy 132.72527 -305.366445) (xy 132.675693 -305.343803)
			(xy 132.629843 -305.314337) (xy 132.588652 -305.278646) (xy 132.552961 -305.237455) (xy 132.523495 -305.191605)
			(xy 132.500853 -305.142028) (xy 132.485498 -305.089733) (xy 132.477742 -305.035785) (xy 132.477256 -305.008534)
			(xy 128.432052 -305.008534) (xy 128.431566 -305.035785) (xy 128.42381 -305.089733) (xy 128.408455 -305.142028)
			(xy 128.385813 -305.191605) (xy 128.356347 -305.237455) (xy 128.320656 -305.278646) (xy 128.279465 -305.314337)
			(xy 128.233615 -305.343803) (xy 128.184038 -305.366445) (xy 128.131743 -305.3818) (xy 128.077795 -305.389556)
			(xy 128.023293 -305.389556) (xy 127.969345 -305.3818) (xy 127.91705 -305.366445) (xy 127.867473 -305.343803)
			(xy 127.821623 -305.314337) (xy 127.780432 -305.278646) (xy 127.744741 -305.237455) (xy 127.715275 -305.191605)
			(xy 127.692633 -305.142028) (xy 127.677278 -305.089733) (xy 127.669522 -305.035785) (xy 127.669036 -305.008534)
			(xy 126.400052 -305.008534) (xy 126.399566 -305.035785) (xy 126.39181 -305.089733) (xy 126.376455 -305.142028)
			(xy 126.353813 -305.191605) (xy 126.324347 -305.237455) (xy 126.288656 -305.278646) (xy 126.247465 -305.314337)
			(xy 126.201615 -305.343803) (xy 126.152038 -305.366445) (xy 126.099743 -305.3818) (xy 126.045795 -305.389556)
			(xy 125.991293 -305.389556) (xy 125.937345 -305.3818) (xy 125.88505 -305.366445) (xy 125.835473 -305.343803)
			(xy 125.789623 -305.314337) (xy 125.748432 -305.278646) (xy 125.712741 -305.237455) (xy 125.683275 -305.191605)
			(xy 125.660633 -305.142028) (xy 125.645278 -305.089733) (xy 125.637522 -305.035785) (xy 125.637036 -305.008534)
			(xy 125.011942 -305.008534) (xy 125.011456 -305.035785) (xy 125.0037 -305.089733) (xy 124.988345 -305.142028)
			(xy 124.965703 -305.191605) (xy 124.936237 -305.237455) (xy 124.900546 -305.278646) (xy 124.859355 -305.314337)
			(xy 124.813505 -305.343803) (xy 124.763928 -305.366445) (xy 124.711633 -305.3818) (xy 124.657685 -305.389556)
			(xy 124.603183 -305.389556) (xy 124.549235 -305.3818) (xy 124.49694 -305.366445) (xy 124.447363 -305.343803)
			(xy 124.401513 -305.314337) (xy 124.360322 -305.278646) (xy 124.324631 -305.237455) (xy 124.295165 -305.191605)
			(xy 124.272523 -305.142028) (xy 124.257168 -305.089733) (xy 124.249412 -305.035785) (xy 124.248926 -305.008534)
			(xy 121.591832 -305.008534) (xy 121.591346 -305.035785) (xy 121.58359 -305.089733) (xy 121.568235 -305.142028)
			(xy 121.545593 -305.191605) (xy 121.516127 -305.237455) (xy 121.480436 -305.278646) (xy 121.439245 -305.314337)
			(xy 121.393395 -305.343803) (xy 121.343818 -305.366445) (xy 121.291523 -305.3818) (xy 121.237575 -305.389556)
			(xy 121.183073 -305.389556) (xy 121.129125 -305.3818) (xy 121.07683 -305.366445) (xy 121.027253 -305.343803)
			(xy 120.981403 -305.314337) (xy 120.940212 -305.278646) (xy 120.904521 -305.237455) (xy 120.875055 -305.191605)
			(xy 120.852413 -305.142028) (xy 120.837058 -305.089733) (xy 120.829302 -305.035785) (xy 120.828816 -305.008534)
			(xy 118.832884 -305.008534) (xy 118.832884 -307.82387) (xy 121.416826 -307.82387) (xy 121.417268 -307.796499)
			(xy 121.425091 -307.742318) (xy 121.440585 -307.689815) (xy 121.463432 -307.640068) (xy 121.493162 -307.594103)
			(xy 121.510806 -307.573172) (xy 121.51106 -307.572918) (xy 121.516652 -307.565836) (xy 121.522894 -307.548915)
			(xy 121.523252 -307.539898) (xy 121.523252 -307.472842) (xy 121.522885 -307.463826) (xy 121.516646 -307.446908)
			(xy 121.51106 -307.439822) (xy 121.510806 -307.439822) (xy 121.510806 -307.439568) (xy 121.493137 -307.418659)
			(xy 121.463415 -307.372686) (xy 121.440572 -307.322936) (xy 121.425079 -307.270431) (xy 121.417254 -307.216249)
			(xy 121.417257 -307.161506) (xy 121.425089 -307.107325) (xy 121.440588 -307.054822) (xy 121.463437 -307.005074)
			(xy 121.493164 -306.959105) (xy 121.510806 -306.938172) (xy 121.51106 -306.937918) (xy 121.516652 -306.930836)
			(xy 121.522894 -306.913915) (xy 121.523252 -306.904898) (xy 121.523252 -306.837842) (xy 121.522885 -306.828826)
			(xy 121.516646 -306.811908) (xy 121.51106 -306.804822) (xy 121.510806 -306.804822) (xy 121.510806 -306.804568)
			(xy 121.493137 -306.783659) (xy 121.463415 -306.737686) (xy 121.440572 -306.687936) (xy 121.425079 -306.635431)
			(xy 121.417254 -306.581249) (xy 121.417257 -306.526506) (xy 121.425089 -306.472325) (xy 121.440588 -306.419822)
			(xy 121.463437 -306.370074) (xy 121.493164 -306.324105) (xy 121.510806 -306.303172) (xy 121.51106 -306.302918)
			(xy 121.516652 -306.295836) (xy 121.522894 -306.278915) (xy 121.523252 -306.269898) (xy 121.523252 -306.202842)
			(xy 121.522885 -306.193826) (xy 121.516646 -306.176908) (xy 121.51106 -306.169822) (xy 121.510806 -306.169822)
			(xy 121.510806 -306.169568) (xy 121.493186 -306.14862) (xy 121.463471 -306.102652) (xy 121.440632 -306.052908)
			(xy 121.425136 -306.000411) (xy 121.417303 -305.946238) (xy 121.416826 -305.91887) (xy 121.417312 -305.891619)
			(xy 121.425068 -305.837671) (xy 121.440423 -305.785376) (xy 121.463065 -305.735799) (xy 121.492531 -305.689949)
			(xy 121.528222 -305.648758) (xy 121.569413 -305.613067) (xy 121.615263 -305.583601) (xy 121.66484 -305.560959)
			(xy 121.717135 -305.545604) (xy 121.771083 -305.537848) (xy 121.825585 -305.537848) (xy 121.879533 -305.545604)
			(xy 121.931828 -305.560959) (xy 121.981405 -305.583601) (xy 122.027255 -305.613067) (xy 122.068446 -305.648758)
			(xy 122.104137 -305.689949) (xy 122.133603 -305.735799) (xy 122.156245 -305.785376) (xy 122.1716 -305.837671)
			(xy 122.179356 -305.891619) (xy 122.179842 -305.91887) (xy 122.179372 -305.94624) (xy 122.171558 -306.00042)
			(xy 122.15607 -306.052923) (xy 122.133229 -306.10267) (xy 122.103504 -306.148637) (xy 122.085862 -306.169568)
			(xy 122.085608 -306.169822) (xy 122.080007 -306.176899) (xy 122.073769 -306.193823) (xy 122.073416 -306.202842)
			(xy 122.073416 -306.269898) (xy 122.07377 -306.278915) (xy 122.080019 -306.295832) (xy 122.085608 -306.302918)
			(xy 122.085862 -306.302918) (xy 122.085862 -306.303172) (xy 122.103474 -306.324128) (xy 122.133201 -306.370092)
			(xy 122.156048 -306.419834) (xy 122.171547 -306.472333) (xy 122.179379 -306.526508) (xy 122.179382 -306.581247)
			(xy 122.171557 -306.635423) (xy 122.156064 -306.687924) (xy 122.133222 -306.737669) (xy 122.103501 -306.783636)
			(xy 122.085862 -306.804568) (xy 122.085608 -306.804822) (xy 122.080007 -306.811899) (xy 122.073769 -306.828823)
			(xy 122.073416 -306.837842) (xy 122.073416 -306.904898) (xy 122.07377 -306.913915) (xy 122.080019 -306.930832)
			(xy 122.085608 -306.937918) (xy 122.085862 -306.937918) (xy 122.085862 -306.938172) (xy 122.103474 -306.959128)
			(xy 122.133201 -307.005092) (xy 122.156048 -307.054834) (xy 122.171547 -307.107333) (xy 122.179379 -307.161508)
			(xy 122.179382 -307.216247) (xy 122.171557 -307.270423) (xy 122.156064 -307.322924) (xy 122.133222 -307.372669)
			(xy 122.103501 -307.418636) (xy 122.085862 -307.439568) (xy 122.085608 -307.439822) (xy 122.080007 -307.446899)
			(xy 122.073769 -307.463823) (xy 122.073416 -307.472842) (xy 122.073416 -307.539898) (xy 122.07377 -307.548915)
			(xy 122.080019 -307.565832) (xy 122.085608 -307.572918) (xy 122.085862 -307.572918) (xy 122.085862 -307.573172)
			(xy 122.103496 -307.594109) (xy 122.133209 -307.64008) (xy 122.156047 -307.689826) (xy 122.171539 -307.742326)
			(xy 122.179368 -307.796501) (xy 122.179842 -307.82387) (xy 122.179356 -307.851121) (xy 122.175532 -307.877718)
			(xy 125.049026 -307.877718) (xy 125.049496 -307.850348) (xy 125.057312 -307.796169) (xy 125.0728 -307.743665)
			(xy 125.095641 -307.693918) (xy 125.125365 -307.647952) (xy 125.143006 -307.62702) (xy 125.14326 -307.626766)
			(xy 125.148832 -307.61967) (xy 125.155086 -307.60276) (xy 125.155452 -307.593746) (xy 125.155452 -307.52669)
			(xy 125.15511 -307.517671) (xy 125.148853 -307.500754) (xy 125.14326 -307.49367) (xy 125.143006 -307.49367)
			(xy 125.143006 -307.493416) (xy 125.125384 -307.472469) (xy 125.09566 -307.426503) (xy 125.072815 -307.376759)
			(xy 125.057318 -307.324259) (xy 125.049488 -307.270083) (xy 125.049486 -307.215344) (xy 125.057312 -307.161167)
			(xy 125.072805 -307.108667) (xy 125.095647 -307.058921) (xy 125.125367 -307.012953) (xy 125.143006 -306.99202)
			(xy 125.14326 -306.991766) (xy 125.148832 -306.98467) (xy 125.155086 -306.96776) (xy 125.155452 -306.958746)
			(xy 125.155452 -306.89169) (xy 125.15511 -306.882671) (xy 125.148853 -306.865754) (xy 125.14326 -306.85867)
			(xy 125.143006 -306.85867) (xy 125.143006 -306.858416) (xy 125.125384 -306.837469) (xy 125.09566 -306.791503)
			(xy 125.072815 -306.741759) (xy 125.057318 -306.689259) (xy 125.049488 -306.635083) (xy 125.049486 -306.580344)
			(xy 125.057312 -306.526167) (xy 125.072805 -306.473667) (xy 125.095647 -306.423921) (xy 125.125367 -306.377953)
			(xy 125.143006 -306.35702) (xy 125.14326 -306.356766) (xy 125.148832 -306.34967) (xy 125.155086 -306.33276)
			(xy 125.155452 -306.323746) (xy 125.155452 -306.25669) (xy 125.15511 -306.247671) (xy 125.148853 -306.230754)
			(xy 125.14326 -306.22367) (xy 125.143006 -306.22367) (xy 125.143006 -306.223416) (xy 125.125362 -306.202488)
			(xy 125.095651 -306.156514) (xy 125.072816 -306.106766) (xy 125.057326 -306.054264) (xy 125.049499 -306.000087)
			(xy 125.049026 -305.972718) (xy 125.049512 -305.945467) (xy 125.057268 -305.891519) (xy 125.072623 -305.839224)
			(xy 125.095265 -305.789647) (xy 125.124731 -305.743797) (xy 125.160422 -305.702606) (xy 125.201613 -305.666915)
			(xy 125.247463 -305.637449) (xy 125.29704 -305.614807) (xy 125.349335 -305.599452) (xy 125.403283 -305.591696)
			(xy 125.457785 -305.591696) (xy 125.511733 -305.599452) (xy 125.564028 -305.614807) (xy 125.613605 -305.637449)
			(xy 125.659455 -305.666915) (xy 125.700646 -305.702606) (xy 125.736337 -305.743797) (xy 125.765803 -305.789647)
			(xy 125.788445 -305.839224) (xy 125.8038 -305.891519) (xy 125.811556 -305.945467) (xy 125.812042 -305.972718)
			(xy 125.811601 -306.000089) (xy 125.803779 -306.05427) (xy 125.788285 -306.106774) (xy 125.765437 -306.15652)
			(xy 125.735706 -306.202486) (xy 125.718062 -306.223416) (xy 125.717808 -306.22367) (xy 125.712229 -306.230762)
			(xy 125.705977 -306.247674) (xy 125.705616 -306.25669) (xy 125.705616 -306.323746) (xy 125.705996 -306.332761)
			(xy 125.712227 -306.349678) (xy 125.717808 -306.356766) (xy 125.718062 -306.356766) (xy 125.718062 -306.35702)
			(xy 125.735721 -306.377938) (xy 125.765446 -306.423908) (xy 125.788291 -306.473657) (xy 125.803786 -306.526161)
			(xy 125.811613 -306.580342) (xy 125.811611 -306.635085) (xy 125.80378 -306.689265) (xy 125.788281 -306.741769)
			(xy 125.765433 -306.791516) (xy 125.735704 -306.837483) (xy 125.718062 -306.858416) (xy 125.717808 -306.85867)
			(xy 125.712229 -306.865762) (xy 125.705977 -306.882674) (xy 125.705616 -306.89169) (xy 125.705616 -306.958746)
			(xy 125.705996 -306.967761) (xy 125.712227 -306.984678) (xy 125.717808 -306.991766) (xy 125.718062 -306.991766)
			(xy 125.718062 -306.99202) (xy 125.735721 -307.012938) (xy 125.765446 -307.058908) (xy 125.788291 -307.108657)
			(xy 125.803786 -307.161161) (xy 125.811613 -307.215342) (xy 125.811611 -307.270085) (xy 125.80378 -307.324265)
			(xy 125.788281 -307.376769) (xy 125.765433 -307.426516) (xy 125.735704 -307.472483) (xy 125.718062 -307.493416)
			(xy 125.717808 -307.49367) (xy 125.712229 -307.500762) (xy 125.705977 -307.517674) (xy 125.705616 -307.52669)
			(xy 125.705616 -307.593746) (xy 125.705996 -307.602761) (xy 125.712227 -307.619678) (xy 125.717808 -307.626766)
			(xy 125.718062 -307.626766) (xy 125.718062 -307.62702) (xy 125.735671 -307.647976) (xy 125.765389 -307.693942)
			(xy 125.788231 -307.743683) (xy 125.803729 -307.796179) (xy 125.807734 -307.82387) (xy 128.257046 -307.82387)
			(xy 128.257483 -307.796499) (xy 128.265306 -307.742318) (xy 128.280802 -307.689814) (xy 128.30365 -307.640068)
			(xy 128.333381 -307.594102) (xy 128.351026 -307.573172) (xy 128.35128 -307.572918) (xy 128.356875 -307.565837)
			(xy 128.363114 -307.548916) (xy 128.363472 -307.539898) (xy 128.363472 -307.472842) (xy 128.363101 -307.463826)
			(xy 128.356864 -307.446909) (xy 128.35128 -307.439822) (xy 128.351026 -307.439822) (xy 128.351026 -307.439568)
			(xy 128.333356 -307.418659) (xy 128.303632 -307.372687) (xy 128.280789 -307.322937) (xy 128.265295 -307.270431)
			(xy 128.257469 -307.216249) (xy 128.257472 -307.161505) (xy 128.265305 -307.107325) (xy 128.280805 -307.054821)
			(xy 128.303654 -307.005073) (xy 128.333383 -306.959105) (xy 128.351026 -306.938172) (xy 128.35128 -306.937918)
			(xy 128.356875 -306.930837) (xy 128.363114 -306.913916) (xy 128.363472 -306.904898) (xy 128.363472 -306.837842)
			(xy 128.363101 -306.828826) (xy 128.356864 -306.811909) (xy 128.35128 -306.804822) (xy 128.351026 -306.804822)
			(xy 128.351026 -306.804568) (xy 128.333356 -306.783659) (xy 128.303632 -306.737687) (xy 128.280789 -306.687937)
			(xy 128.265295 -306.635431) (xy 128.257469 -306.581249) (xy 128.257472 -306.526505) (xy 128.265305 -306.472325)
			(xy 128.280805 -306.419821) (xy 128.303654 -306.370073) (xy 128.333383 -306.324105) (xy 128.351026 -306.303172)
			(xy 128.35128 -306.302918) (xy 128.356875 -306.295837) (xy 128.363114 -306.278916) (xy 128.363472 -306.269898)
			(xy 128.363472 -306.202842) (xy 128.363101 -306.193826) (xy 128.356864 -306.176909) (xy 128.35128 -306.169822)
			(xy 128.351026 -306.169822) (xy 128.351026 -306.169568) (xy 128.333409 -306.148618) (xy 128.303693 -306.10265)
			(xy 128.280853 -306.052908) (xy 128.265356 -306.000411) (xy 128.257523 -305.946238) (xy 128.257046 -305.91887)
			(xy 128.257532 -305.891619) (xy 128.265288 -305.837671) (xy 128.280643 -305.785376) (xy 128.303285 -305.735799)
			(xy 128.332751 -305.689949) (xy 128.368442 -305.648758) (xy 128.409633 -305.613067) (xy 128.455483 -305.583601)
			(xy 128.50506 -305.560959) (xy 128.557355 -305.545604) (xy 128.611303 -305.537848) (xy 128.665805 -305.537848)
			(xy 128.719753 -305.545604) (xy 128.772048 -305.560959) (xy 128.821625 -305.583601) (xy 128.867475 -305.613067)
			(xy 128.908666 -305.648758) (xy 128.944357 -305.689949) (xy 128.973823 -305.735799) (xy 128.996465 -305.785376)
			(xy 129.01182 -305.837671) (xy 129.019576 -305.891619) (xy 129.020062 -305.91887) (xy 129.019588 -305.94624)
			(xy 129.011773 -306.000419) (xy 128.996287 -306.052923) (xy 128.973446 -306.10267) (xy 128.943723 -306.148636)
			(xy 128.926082 -306.169568) (xy 128.925828 -306.169822) (xy 128.920218 -306.176892) (xy 128.913987 -306.193822)
			(xy 128.913636 -306.202842) (xy 128.913636 -306.269898) (xy 128.913986 -306.278916) (xy 128.920238 -306.295833)
			(xy 128.925828 -306.302918) (xy 128.926082 -306.302918) (xy 128.926082 -306.303172) (xy 128.943693 -306.324129)
			(xy 128.973418 -306.370093) (xy 128.996265 -306.419835) (xy 129.011763 -306.472333) (xy 129.019594 -306.526508)
			(xy 129.019597 -306.581247) (xy 129.011773 -306.635423) (xy 128.996281 -306.687923) (xy 128.97344 -306.737668)
			(xy 128.94372 -306.783635) (xy 128.926082 -306.804568) (xy 128.925828 -306.804822) (xy 128.920218 -306.811892)
			(xy 128.913987 -306.828822) (xy 128.913636 -306.837842) (xy 128.913636 -306.904898) (xy 128.913986 -306.913916)
			(xy 128.920238 -306.930833) (xy 128.925828 -306.937918) (xy 128.926082 -306.937918) (xy 128.926082 -306.938172)
			(xy 128.943693 -306.959129) (xy 128.973418 -307.005093) (xy 128.996265 -307.054835) (xy 129.011763 -307.107333)
			(xy 129.019594 -307.161508) (xy 129.019597 -307.216247) (xy 129.011773 -307.270423) (xy 128.996281 -307.322923)
			(xy 128.97344 -307.372668) (xy 128.94372 -307.418635) (xy 128.926082 -307.439568) (xy 128.925828 -307.439822)
			(xy 128.920218 -307.446892) (xy 128.913987 -307.463822) (xy 128.913636 -307.472842) (xy 128.913636 -307.539898)
			(xy 128.913986 -307.548916) (xy 128.920238 -307.565833) (xy 128.925828 -307.572918) (xy 128.926082 -307.572918)
			(xy 128.926082 -307.573172) (xy 128.943719 -307.594106) (xy 128.973431 -307.640078) (xy 128.996268 -307.689825)
			(xy 129.01176 -307.742325) (xy 129.019588 -307.796501) (xy 129.020062 -307.82387) (xy 129.019576 -307.851121)
			(xy 129.015752 -307.877718) (xy 131.889246 -307.877718) (xy 131.889711 -307.850348) (xy 131.897528 -307.796168)
			(xy 131.913016 -307.743665) (xy 131.935858 -307.693918) (xy 131.965584 -307.647951) (xy 131.983226 -307.62702)
			(xy 131.98348 -307.626766) (xy 131.989054 -307.619672) (xy 131.995306 -307.60276) (xy 131.995672 -307.593746)
			(xy 131.995672 -307.52669) (xy 131.995326 -307.517672) (xy 131.989072 -307.500755) (xy 131.98348 -307.49367)
			(xy 131.983226 -307.49367) (xy 131.983226 -307.493416) (xy 131.965603 -307.472469) (xy 131.935878 -307.426504)
			(xy 131.913031 -307.37676) (xy 131.897534 -307.32426) (xy 131.889703 -307.270083) (xy 131.889701 -307.215344)
			(xy 131.897528 -307.161167) (xy 131.913022 -307.108666) (xy 131.935864 -307.05892) (xy 131.965587 -307.012953)
			(xy 131.983226 -306.99202) (xy 131.98348 -306.991766) (xy 131.989054 -306.984672) (xy 131.995306 -306.96776)
			(xy 131.995672 -306.958746) (xy 131.995672 -306.89169) (xy 131.995326 -306.882672) (xy 131.989072 -306.865755)
			(xy 131.98348 -306.85867) (xy 131.983226 -306.85867) (xy 131.983226 -306.858416) (xy 131.965603 -306.837469)
			(xy 131.935878 -306.791504) (xy 131.913031 -306.74176) (xy 131.897534 -306.68926) (xy 131.889703 -306.635083)
			(xy 131.889701 -306.580344) (xy 131.897528 -306.526167) (xy 131.913022 -306.473666) (xy 131.935864 -306.42392)
			(xy 131.965587 -306.377953) (xy 131.983226 -306.35702) (xy 131.98348 -306.356766) (xy 131.989054 -306.349672)
			(xy 131.995306 -306.33276) (xy 131.995672 -306.323746) (xy 131.995672 -306.25669) (xy 131.995326 -306.247672)
			(xy 131.989072 -306.230755) (xy 131.98348 -306.22367) (xy 131.983226 -306.22367) (xy 131.983226 -306.223416)
			(xy 131.965585 -306.202485) (xy 131.935873 -306.156513) (xy 131.913037 -306.106765) (xy 131.897546 -306.054264)
			(xy 131.889719 -306.000087) (xy 131.889246 -305.972718) (xy 131.889732 -305.945467) (xy 131.897488 -305.891519)
			(xy 131.912843 -305.839224) (xy 131.935485 -305.789647) (xy 131.964951 -305.743797) (xy 132.000642 -305.702606)
			(xy 132.041833 -305.666915) (xy 132.087683 -305.637449) (xy 132.13726 -305.614807) (xy 132.189555 -305.599452)
			(xy 132.243503 -305.591696) (xy 132.298005 -305.591696) (xy 132.351953 -305.599452) (xy 132.404248 -305.614807)
			(xy 132.453825 -305.637449) (xy 132.499675 -305.666915) (xy 132.540866 -305.702606) (xy 132.576557 -305.743797)
			(xy 132.606023 -305.789647) (xy 132.628665 -305.839224) (xy 132.64402 -305.891519) (xy 132.651776 -305.945467)
			(xy 132.652262 -305.972718) (xy 132.651816 -306.000089) (xy 132.644217 -306.052728) (xy 142.790924 -306.052728)
			(xy 142.794995 -305.997106) (xy 142.807121 -305.942669) (xy 142.827044 -305.890578) (xy 142.85434 -305.841943)
			(xy 142.888426 -305.7978) (xy 142.928575 -305.759091) (xy 142.973933 -305.72664) (xy 143.023533 -305.701139)
			(xy 143.076317 -305.683132) (xy 143.13116 -305.673002) (xy 143.186894 -305.670965) (xy 143.242331 -305.677065)
			(xy 143.296288 -305.691171) (xy 143.347617 -305.712983) (xy 143.395223 -305.742037) (xy 143.438091 -305.777712)
			(xy 143.475308 -305.819249) (xy 143.506081 -305.865762) (xy 143.510378 -305.874928) (xy 162.619194 -305.874928)
			(xy 162.623154 -305.825874) (xy 162.634931 -305.77809) (xy 162.654222 -305.732814) (xy 162.680525 -305.691218)
			(xy 162.71316 -305.654381) (xy 162.751281 -305.623256) (xy 162.793902 -305.598649) (xy 162.839918 -305.581197)
			(xy 162.888137 -305.571353) (xy 162.937312 -305.569372) (xy 162.986167 -305.575304) (xy 163.033438 -305.588996)
			(xy 163.0779 -305.610094) (xy 163.118403 -305.63805) (xy 163.153896 -305.672142) (xy 163.183461 -305.711486)
			(xy 163.206332 -305.755063) (xy 163.221916 -305.801744) (xy 163.229811 -305.850321) (xy 163.230306 -305.874928)
			(xy 163.569154 -305.874928) (xy 163.573114 -305.825874) (xy 163.584891 -305.77809) (xy 163.604182 -305.732814)
			(xy 163.630485 -305.691218) (xy 163.66312 -305.654381) (xy 163.701241 -305.623256) (xy 163.743862 -305.598649)
			(xy 163.789878 -305.581197) (xy 163.838097 -305.571353) (xy 163.887272 -305.569372) (xy 163.936127 -305.575304)
			(xy 163.983398 -305.588996) (xy 164.02786 -305.610094) (xy 164.068363 -305.63805) (xy 164.103856 -305.672142)
			(xy 164.133421 -305.711486) (xy 164.156292 -305.755063) (xy 164.171876 -305.801744) (xy 164.179771 -305.850321)
			(xy 164.180266 -305.874928) (xy 164.519114 -305.874928) (xy 164.523074 -305.825874) (xy 164.534851 -305.77809)
			(xy 164.554142 -305.732814) (xy 164.580445 -305.691218) (xy 164.61308 -305.654381) (xy 164.651201 -305.623256)
			(xy 164.693822 -305.598649) (xy 164.739838 -305.581197) (xy 164.788057 -305.571353) (xy 164.837232 -305.569372)
			(xy 164.886087 -305.575304) (xy 164.933358 -305.588996) (xy 164.97782 -305.610094) (xy 165.018323 -305.63805)
			(xy 165.053816 -305.672142) (xy 165.083381 -305.711486) (xy 165.106252 -305.755063) (xy 165.121836 -305.801744)
			(xy 165.129731 -305.850321) (xy 165.130226 -305.874928) (xy 165.129731 -305.899535) (xy 165.121836 -305.948112)
			(xy 165.106252 -305.994793) (xy 165.083381 -306.03837) (xy 165.053816 -306.077714) (xy 165.018323 -306.111806)
			(xy 164.97782 -306.139762) (xy 164.933358 -306.16086) (xy 164.886087 -306.174552) (xy 164.837232 -306.180484)
			(xy 164.788057 -306.178503) (xy 164.739838 -306.168659) (xy 164.693822 -306.151207) (xy 164.651201 -306.1266)
			(xy 164.61308 -306.095475) (xy 164.580445 -306.058638) (xy 164.554142 -306.017042) (xy 164.534851 -305.971766)
			(xy 164.523074 -305.923982) (xy 164.519114 -305.874928) (xy 164.180266 -305.874928) (xy 164.179771 -305.899535)
			(xy 164.171876 -305.948112) (xy 164.156292 -305.994793) (xy 164.133421 -306.03837) (xy 164.103856 -306.077714)
			(xy 164.068363 -306.111806) (xy 164.02786 -306.139762) (xy 163.983398 -306.16086) (xy 163.936127 -306.174552)
			(xy 163.887272 -306.180484) (xy 163.838097 -306.178503) (xy 163.789878 -306.168659) (xy 163.743862 -306.151207)
			(xy 163.701241 -306.1266) (xy 163.66312 -306.095475) (xy 163.630485 -306.058638) (xy 163.604182 -306.017042)
			(xy 163.584891 -305.971766) (xy 163.573114 -305.923982) (xy 163.569154 -305.874928) (xy 163.230306 -305.874928)
			(xy 163.229811 -305.899535) (xy 163.221916 -305.948112) (xy 163.206332 -305.994793) (xy 163.183461 -306.03837)
			(xy 163.153896 -306.077714) (xy 163.118403 -306.111806) (xy 163.0779 -306.139762) (xy 163.033438 -306.16086)
			(xy 162.986167 -306.174552) (xy 162.937312 -306.180484) (xy 162.888137 -306.178503) (xy 162.839918 -306.168659)
			(xy 162.793902 -306.151207) (xy 162.751281 -306.1266) (xy 162.71316 -306.095475) (xy 162.680525 -306.058638)
			(xy 162.654222 -306.017042) (xy 162.634931 -305.971766) (xy 162.623154 -305.923982) (xy 162.619194 -305.874928)
			(xy 143.510378 -305.874928) (xy 143.529753 -305.916259) (xy 143.545821 -305.969666) (xy 143.553941 -306.024842)
			(xy 143.55445 -306.052728) (xy 143.553941 -306.080614) (xy 143.545821 -306.13579) (xy 143.529753 -306.189197)
			(xy 143.506081 -306.239694) (xy 143.475308 -306.286207) (xy 143.438091 -306.327744) (xy 143.411153 -306.350162)
			(xy 151.693892 -306.350162) (xy 151.697852 -306.301108) (xy 151.709629 -306.253324) (xy 151.72892 -306.208048)
			(xy 151.755223 -306.166452) (xy 151.787858 -306.129615) (xy 151.825979 -306.09849) (xy 151.8686 -306.073883)
			(xy 151.914616 -306.056431) (xy 151.962835 -306.046587) (xy 152.01201 -306.044606) (xy 152.060865 -306.050538)
			(xy 152.108136 -306.06423) (xy 152.152598 -306.085328) (xy 152.193101 -306.113284) (xy 152.228594 -306.147376)
			(xy 152.258159 -306.18672) (xy 152.28103 -306.230297) (xy 152.296614 -306.276978) (xy 152.304509 -306.325555)
			(xy 152.304999 -306.349908) (xy 152.644106 -306.349908) (xy 152.648066 -306.300854) (xy 152.659843 -306.25307)
			(xy 152.679134 -306.207794) (xy 152.705437 -306.166198) (xy 152.738072 -306.129361) (xy 152.776193 -306.098236)
			(xy 152.818814 -306.073629) (xy 152.86483 -306.056177) (xy 152.913049 -306.046333) (xy 152.962224 -306.044352)
			(xy 153.011079 -306.050284) (xy 153.05835 -306.063976) (xy 153.102812 -306.085074) (xy 153.143315 -306.11303)
			(xy 153.178808 -306.147122) (xy 153.208373 -306.186466) (xy 153.231244 -306.230043) (xy 153.246828 -306.276724)
			(xy 153.254723 -306.325301) (xy 153.255218 -306.349908) (xy 153.594066 -306.349908) (xy 153.598026 -306.300854)
			(xy 153.609803 -306.25307) (xy 153.629094 -306.207794) (xy 153.655397 -306.166198) (xy 153.688032 -306.129361)
			(xy 153.726153 -306.098236) (xy 153.768774 -306.073629) (xy 153.81479 -306.056177) (xy 153.863009 -306.046333)
			(xy 153.912184 -306.044352) (xy 153.961039 -306.050284) (xy 154.00831 -306.063976) (xy 154.052772 -306.085074)
			(xy 154.093275 -306.11303) (xy 154.128768 -306.147122) (xy 154.158333 -306.186466) (xy 154.181204 -306.230043)
			(xy 154.196788 -306.276724) (xy 154.204683 -306.325301) (xy 154.205178 -306.349908) (xy 154.54428 -306.349908)
			(xy 154.54824 -306.300854) (xy 154.560017 -306.25307) (xy 154.579308 -306.207794) (xy 154.605611 -306.166198)
			(xy 154.638246 -306.129361) (xy 154.676367 -306.098236) (xy 154.718988 -306.073629) (xy 154.765004 -306.056177)
			(xy 154.813223 -306.046333) (xy 154.862398 -306.044352) (xy 154.911253 -306.050284) (xy 154.958524 -306.063976)
			(xy 155.002986 -306.085074) (xy 155.043489 -306.11303) (xy 155.078982 -306.147122) (xy 155.108547 -306.186466)
			(xy 155.131418 -306.230043) (xy 155.147002 -306.276724) (xy 155.154897 -306.325301) (xy 155.155392 -306.349908)
			(xy 155.49424 -306.349908) (xy 155.4982 -306.300854) (xy 155.509977 -306.25307) (xy 155.529268 -306.207794)
			(xy 155.555571 -306.166198) (xy 155.588206 -306.129361) (xy 155.626327 -306.098236) (xy 155.668948 -306.073629)
			(xy 155.714964 -306.056177) (xy 155.763183 -306.046333) (xy 155.812358 -306.044352) (xy 155.861213 -306.050284)
			(xy 155.908484 -306.063976) (xy 155.952946 -306.085074) (xy 155.993449 -306.11303) (xy 156.028942 -306.147122)
			(xy 156.058507 -306.186466) (xy 156.081378 -306.230043) (xy 156.096962 -306.276724) (xy 156.104857 -306.325301)
			(xy 156.105352 -306.349908) (xy 156.4442 -306.349908) (xy 156.44816 -306.300854) (xy 156.459937 -306.25307)
			(xy 156.479228 -306.207794) (xy 156.505531 -306.166198) (xy 156.538166 -306.129361) (xy 156.576287 -306.098236)
			(xy 156.618908 -306.073629) (xy 156.664924 -306.056177) (xy 156.713143 -306.046333) (xy 156.762318 -306.044352)
			(xy 156.811173 -306.050284) (xy 156.858444 -306.063976) (xy 156.902906 -306.085074) (xy 156.943409 -306.11303)
			(xy 156.978902 -306.147122) (xy 157.008467 -306.186466) (xy 157.031338 -306.230043) (xy 157.046922 -306.276724)
			(xy 157.054817 -306.325301) (xy 157.055312 -306.349908) (xy 157.39416 -306.349908) (xy 157.39812 -306.300854)
			(xy 157.409897 -306.25307) (xy 157.429188 -306.207794) (xy 157.455491 -306.166198) (xy 157.488126 -306.129361)
			(xy 157.526247 -306.098236) (xy 157.568868 -306.073629) (xy 157.614884 -306.056177) (xy 157.663103 -306.046333)
			(xy 157.712278 -306.044352) (xy 157.761133 -306.050284) (xy 157.808404 -306.063976) (xy 157.852866 -306.085074)
			(xy 157.893369 -306.11303) (xy 157.928862 -306.147122) (xy 157.958427 -306.186466) (xy 157.981298 -306.230043)
			(xy 157.996882 -306.276724) (xy 158.004777 -306.325301) (xy 158.005272 -306.349908) (xy 158.34412 -306.349908)
			(xy 158.34808 -306.300854) (xy 158.359857 -306.25307) (xy 158.379148 -306.207794) (xy 158.405451 -306.166198)
			(xy 158.438086 -306.129361) (xy 158.476207 -306.098236) (xy 158.518828 -306.073629) (xy 158.564844 -306.056177)
			(xy 158.613063 -306.046333) (xy 158.662238 -306.044352) (xy 158.711093 -306.050284) (xy 158.758364 -306.063976)
			(xy 158.802826 -306.085074) (xy 158.843329 -306.11303) (xy 158.878822 -306.147122) (xy 158.908387 -306.186466)
			(xy 158.931258 -306.230043) (xy 158.946842 -306.276724) (xy 158.954737 -306.325301) (xy 158.955232 -306.349908)
			(xy 159.29408 -306.349908) (xy 159.29804 -306.300854) (xy 159.309817 -306.25307) (xy 159.329108 -306.207794)
			(xy 159.355411 -306.166198) (xy 159.388046 -306.129361) (xy 159.426167 -306.098236) (xy 159.468788 -306.073629)
			(xy 159.514804 -306.056177) (xy 159.563023 -306.046333) (xy 159.612198 -306.044352) (xy 159.661053 -306.050284)
			(xy 159.708324 -306.063976) (xy 159.752786 -306.085074) (xy 159.793289 -306.11303) (xy 159.828782 -306.147122)
			(xy 159.858347 -306.186466) (xy 159.881218 -306.230043) (xy 159.896802 -306.276724) (xy 159.904697 -306.325301)
			(xy 159.905192 -306.349908) (xy 160.24404 -306.349908) (xy 160.248 -306.300854) (xy 160.259777 -306.25307)
			(xy 160.279068 -306.207794) (xy 160.305371 -306.166198) (xy 160.338006 -306.129361) (xy 160.376127 -306.098236)
			(xy 160.418748 -306.073629) (xy 160.464764 -306.056177) (xy 160.512983 -306.046333) (xy 160.562158 -306.044352)
			(xy 160.611013 -306.050284) (xy 160.658284 -306.063976) (xy 160.702746 -306.085074) (xy 160.743249 -306.11303)
			(xy 160.778742 -306.147122) (xy 160.808307 -306.186466) (xy 160.831178 -306.230043) (xy 160.846762 -306.276724)
			(xy 160.854657 -306.325301) (xy 160.855152 -306.349908) (xy 161.194254 -306.349908) (xy 161.198214 -306.300854)
			(xy 161.209991 -306.25307) (xy 161.229282 -306.207794) (xy 161.255585 -306.166198) (xy 161.28822 -306.129361)
			(xy 161.326341 -306.098236) (xy 161.368962 -306.073629) (xy 161.414978 -306.056177) (xy 161.463197 -306.046333)
			(xy 161.512372 -306.044352) (xy 161.561227 -306.050284) (xy 161.608498 -306.063976) (xy 161.65296 -306.085074)
			(xy 161.693463 -306.11303) (xy 161.728956 -306.147122) (xy 161.758521 -306.186466) (xy 161.781392 -306.230043)
			(xy 161.796976 -306.276724) (xy 161.804871 -306.325301) (xy 161.805366 -306.349908) (xy 161.804871 -306.374515)
			(xy 161.796976 -306.423092) (xy 161.781392 -306.469773) (xy 161.758521 -306.51335) (xy 161.728956 -306.552694)
			(xy 161.693463 -306.586786) (xy 161.65296 -306.614742) (xy 161.608498 -306.63584) (xy 161.561227 -306.649532)
			(xy 161.512372 -306.655464) (xy 161.463197 -306.653483) (xy 161.414978 -306.643639) (xy 161.368962 -306.626187)
			(xy 161.326341 -306.60158) (xy 161.28822 -306.570455) (xy 161.255585 -306.533618) (xy 161.229282 -306.492022)
			(xy 161.209991 -306.446746) (xy 161.198214 -306.398962) (xy 161.194254 -306.349908) (xy 160.855152 -306.349908)
			(xy 160.854657 -306.374515) (xy 160.846762 -306.423092) (xy 160.831178 -306.469773) (xy 160.808307 -306.51335)
			(xy 160.778742 -306.552694) (xy 160.743249 -306.586786) (xy 160.702746 -306.614742) (xy 160.658284 -306.63584)
			(xy 160.611013 -306.649532) (xy 160.562158 -306.655464) (xy 160.512983 -306.653483) (xy 160.464764 -306.643639)
			(xy 160.418748 -306.626187) (xy 160.376127 -306.60158) (xy 160.338006 -306.570455) (xy 160.305371 -306.533618)
			(xy 160.279068 -306.492022) (xy 160.259777 -306.446746) (xy 160.248 -306.398962) (xy 160.24404 -306.349908)
			(xy 159.905192 -306.349908) (xy 159.904697 -306.374515) (xy 159.896802 -306.423092) (xy 159.881218 -306.469773)
			(xy 159.858347 -306.51335) (xy 159.828782 -306.552694) (xy 159.793289 -306.586786) (xy 159.752786 -306.614742)
			(xy 159.708324 -306.63584) (xy 159.661053 -306.649532) (xy 159.612198 -306.655464) (xy 159.563023 -306.653483)
			(xy 159.514804 -306.643639) (xy 159.468788 -306.626187) (xy 159.426167 -306.60158) (xy 159.388046 -306.570455)
			(xy 159.355411 -306.533618) (xy 159.329108 -306.492022) (xy 159.309817 -306.446746) (xy 159.29804 -306.398962)
			(xy 159.29408 -306.349908) (xy 158.955232 -306.349908) (xy 158.954737 -306.374515) (xy 158.946842 -306.423092)
			(xy 158.931258 -306.469773) (xy 158.908387 -306.51335) (xy 158.878822 -306.552694) (xy 158.843329 -306.586786)
			(xy 158.802826 -306.614742) (xy 158.758364 -306.63584) (xy 158.711093 -306.649532) (xy 158.662238 -306.655464)
			(xy 158.613063 -306.653483) (xy 158.564844 -306.643639) (xy 158.518828 -306.626187) (xy 158.476207 -306.60158)
			(xy 158.438086 -306.570455) (xy 158.405451 -306.533618) (xy 158.379148 -306.492022) (xy 158.359857 -306.446746)
			(xy 158.34808 -306.398962) (xy 158.34412 -306.349908) (xy 158.005272 -306.349908) (xy 158.004777 -306.374515)
			(xy 157.996882 -306.423092) (xy 157.981298 -306.469773) (xy 157.958427 -306.51335) (xy 157.928862 -306.552694)
			(xy 157.893369 -306.586786) (xy 157.852866 -306.614742) (xy 157.808404 -306.63584) (xy 157.761133 -306.649532)
			(xy 157.712278 -306.655464) (xy 157.663103 -306.653483) (xy 157.614884 -306.643639) (xy 157.568868 -306.626187)
			(xy 157.526247 -306.60158) (xy 157.488126 -306.570455) (xy 157.455491 -306.533618) (xy 157.429188 -306.492022)
			(xy 157.409897 -306.446746) (xy 157.39812 -306.398962) (xy 157.39416 -306.349908) (xy 157.055312 -306.349908)
			(xy 157.054817 -306.374515) (xy 157.046922 -306.423092) (xy 157.031338 -306.469773) (xy 157.008467 -306.51335)
			(xy 156.978902 -306.552694) (xy 156.943409 -306.586786) (xy 156.902906 -306.614742) (xy 156.858444 -306.63584)
			(xy 156.811173 -306.649532) (xy 156.762318 -306.655464) (xy 156.713143 -306.653483) (xy 156.664924 -306.643639)
			(xy 156.618908 -306.626187) (xy 156.576287 -306.60158) (xy 156.538166 -306.570455) (xy 156.505531 -306.533618)
			(xy 156.479228 -306.492022) (xy 156.459937 -306.446746) (xy 156.44816 -306.398962) (xy 156.4442 -306.349908)
			(xy 156.105352 -306.349908) (xy 156.104857 -306.374515) (xy 156.096962 -306.423092) (xy 156.081378 -306.469773)
			(xy 156.058507 -306.51335) (xy 156.028942 -306.552694) (xy 155.993449 -306.586786) (xy 155.952946 -306.614742)
			(xy 155.908484 -306.63584) (xy 155.861213 -306.649532) (xy 155.812358 -306.655464) (xy 155.763183 -306.653483)
			(xy 155.714964 -306.643639) (xy 155.668948 -306.626187) (xy 155.626327 -306.60158) (xy 155.588206 -306.570455)
			(xy 155.555571 -306.533618) (xy 155.529268 -306.492022) (xy 155.509977 -306.446746) (xy 155.4982 -306.398962)
			(xy 155.49424 -306.349908) (xy 155.155392 -306.349908) (xy 155.154897 -306.374515) (xy 155.147002 -306.423092)
			(xy 155.131418 -306.469773) (xy 155.108547 -306.51335) (xy 155.078982 -306.552694) (xy 155.043489 -306.586786)
			(xy 155.002986 -306.614742) (xy 154.958524 -306.63584) (xy 154.911253 -306.649532) (xy 154.862398 -306.655464)
			(xy 154.813223 -306.653483) (xy 154.765004 -306.643639) (xy 154.718988 -306.626187) (xy 154.676367 -306.60158)
			(xy 154.638246 -306.570455) (xy 154.605611 -306.533618) (xy 154.579308 -306.492022) (xy 154.560017 -306.446746)
			(xy 154.54824 -306.398962) (xy 154.54428 -306.349908) (xy 154.205178 -306.349908) (xy 154.204683 -306.374515)
			(xy 154.196788 -306.423092) (xy 154.181204 -306.469773) (xy 154.158333 -306.51335) (xy 154.128768 -306.552694)
			(xy 154.093275 -306.586786) (xy 154.052772 -306.614742) (xy 154.00831 -306.63584) (xy 153.961039 -306.649532)
			(xy 153.912184 -306.655464) (xy 153.863009 -306.653483) (xy 153.81479 -306.643639) (xy 153.768774 -306.626187)
			(xy 153.726153 -306.60158) (xy 153.688032 -306.570455) (xy 153.655397 -306.533618) (xy 153.629094 -306.492022)
			(xy 153.609803 -306.446746) (xy 153.598026 -306.398962) (xy 153.594066 -306.349908) (xy 153.255218 -306.349908)
			(xy 153.254723 -306.374515) (xy 153.246828 -306.423092) (xy 153.231244 -306.469773) (xy 153.208373 -306.51335)
			(xy 153.178808 -306.552694) (xy 153.143315 -306.586786) (xy 153.102812 -306.614742) (xy 153.05835 -306.63584)
			(xy 153.011079 -306.649532) (xy 152.962224 -306.655464) (xy 152.913049 -306.653483) (xy 152.86483 -306.643639)
			(xy 152.818814 -306.626187) (xy 152.776193 -306.60158) (xy 152.738072 -306.570455) (xy 152.705437 -306.533618)
			(xy 152.679134 -306.492022) (xy 152.659843 -306.446746) (xy 152.648066 -306.398962) (xy 152.644106 -306.349908)
			(xy 152.304999 -306.349908) (xy 152.305004 -306.350162) (xy 152.304509 -306.374769) (xy 152.296614 -306.423346)
			(xy 152.28103 -306.470027) (xy 152.258159 -306.513604) (xy 152.228594 -306.552948) (xy 152.193101 -306.58704)
			(xy 152.152598 -306.614996) (xy 152.108136 -306.636094) (xy 152.060865 -306.649786) (xy 152.01201 -306.655718)
			(xy 151.962835 -306.653737) (xy 151.914616 -306.643893) (xy 151.8686 -306.626441) (xy 151.825979 -306.601834)
			(xy 151.787858 -306.570709) (xy 151.755223 -306.533872) (xy 151.72892 -306.492276) (xy 151.709629 -306.447)
			(xy 151.697852 -306.399216) (xy 151.693892 -306.350162) (xy 143.411153 -306.350162) (xy 143.395223 -306.363419)
			(xy 143.347617 -306.392473) (xy 143.296288 -306.414285) (xy 143.242331 -306.428391) (xy 143.186894 -306.434491)
			(xy 143.13116 -306.432454) (xy 143.076317 -306.422324) (xy 143.023533 -306.404317) (xy 142.973933 -306.378816)
			(xy 142.928575 -306.346365) (xy 142.888426 -306.307656) (xy 142.85434 -306.263513) (xy 142.827044 -306.214878)
			(xy 142.807121 -306.162787) (xy 142.794995 -306.10835) (xy 142.790924 -306.052728) (xy 132.644217 -306.052728)
			(xy 132.643995 -306.054269) (xy 132.628501 -306.106773) (xy 132.605655 -306.15652) (xy 132.575926 -306.202485)
			(xy 132.558282 -306.223416) (xy 132.558028 -306.22367) (xy 132.552439 -306.230755) (xy 132.546196 -306.247673)
			(xy 132.545836 -306.25669) (xy 132.545836 -306.323746) (xy 132.546211 -306.332761) (xy 132.552445 -306.349679)
			(xy 132.558028 -306.356766) (xy 132.558282 -306.356766) (xy 132.558282 -306.35702) (xy 132.57594 -306.377939)
			(xy 132.605663 -306.423909) (xy 132.628507 -306.473658) (xy 132.644002 -306.526162) (xy 132.651828 -306.580342)
			(xy 132.651826 -306.635085) (xy 132.643996 -306.689265) (xy 132.628498 -306.741768) (xy 132.617737 -306.765198)
			(xy 145.825462 -306.765198) (xy 145.829533 -306.709576) (xy 145.841659 -306.655139) (xy 145.861582 -306.603048)
			(xy 145.888878 -306.554413) (xy 145.922964 -306.51027) (xy 145.963113 -306.471561) (xy 146.008471 -306.43911)
			(xy 146.058071 -306.413609) (xy 146.110855 -306.395602) (xy 146.165698 -306.385472) (xy 146.221432 -306.383435)
			(xy 146.276869 -306.389535) (xy 146.330826 -306.403641) (xy 146.382155 -306.425453) (xy 146.429761 -306.454507)
			(xy 146.472629 -306.490182) (xy 146.509846 -306.531719) (xy 146.540619 -306.578232) (xy 146.564291 -306.628729)
			(xy 146.580359 -306.682136) (xy 146.588479 -306.737312) (xy 146.588988 -306.765198) (xy 146.588479 -306.793084)
			(xy 146.583799 -306.824888) (xy 162.619194 -306.824888) (xy 162.623154 -306.775834) (xy 162.634931 -306.72805)
			(xy 162.654222 -306.682774) (xy 162.680525 -306.641178) (xy 162.71316 -306.604341) (xy 162.751281 -306.573216)
			(xy 162.793902 -306.548609) (xy 162.839918 -306.531157) (xy 162.888137 -306.521313) (xy 162.937312 -306.519332)
			(xy 162.986167 -306.525264) (xy 163.033438 -306.538956) (xy 163.0779 -306.560054) (xy 163.118403 -306.58801)
			(xy 163.153896 -306.622102) (xy 163.183461 -306.661446) (xy 163.206332 -306.705023) (xy 163.221916 -306.751704)
			(xy 163.229811 -306.800281) (xy 163.230306 -306.824888) (xy 163.569154 -306.824888) (xy 163.573114 -306.775834)
			(xy 163.584891 -306.72805) (xy 163.604182 -306.682774) (xy 163.630485 -306.641178) (xy 163.66312 -306.604341)
			(xy 163.701241 -306.573216) (xy 163.743862 -306.548609) (xy 163.789878 -306.531157) (xy 163.838097 -306.521313)
			(xy 163.887272 -306.519332) (xy 163.936127 -306.525264) (xy 163.983398 -306.538956) (xy 164.02786 -306.560054)
			(xy 164.068363 -306.58801) (xy 164.103856 -306.622102) (xy 164.133421 -306.661446) (xy 164.156292 -306.705023)
			(xy 164.171876 -306.751704) (xy 164.179771 -306.800281) (xy 164.180266 -306.824888) (xy 164.519114 -306.824888)
			(xy 164.523074 -306.775834) (xy 164.534851 -306.72805) (xy 164.554142 -306.682774) (xy 164.580445 -306.641178)
			(xy 164.61308 -306.604341) (xy 164.651201 -306.573216) (xy 164.693822 -306.548609) (xy 164.739838 -306.531157)
			(xy 164.788057 -306.521313) (xy 164.837232 -306.519332) (xy 164.886087 -306.525264) (xy 164.933358 -306.538956)
			(xy 164.97782 -306.560054) (xy 165.018323 -306.58801) (xy 165.053816 -306.622102) (xy 165.083381 -306.661446)
			(xy 165.106252 -306.705023) (xy 165.121836 -306.751704) (xy 165.129731 -306.800281) (xy 165.130226 -306.824888)
			(xy 165.129731 -306.849495) (xy 165.121836 -306.898072) (xy 165.106252 -306.944753) (xy 165.083381 -306.98833)
			(xy 165.053816 -307.027674) (xy 165.018323 -307.061766) (xy 164.97782 -307.089722) (xy 164.933358 -307.11082)
			(xy 164.886087 -307.124512) (xy 164.837232 -307.130444) (xy 164.788057 -307.128463) (xy 164.739838 -307.118619)
			(xy 164.693822 -307.101167) (xy 164.651201 -307.07656) (xy 164.61308 -307.045435) (xy 164.580445 -307.008598)
			(xy 164.554142 -306.967002) (xy 164.534851 -306.921726) (xy 164.523074 -306.873942) (xy 164.519114 -306.824888)
			(xy 164.180266 -306.824888) (xy 164.179771 -306.849495) (xy 164.171876 -306.898072) (xy 164.156292 -306.944753)
			(xy 164.133421 -306.98833) (xy 164.103856 -307.027674) (xy 164.068363 -307.061766) (xy 164.02786 -307.089722)
			(xy 163.983398 -307.11082) (xy 163.936127 -307.124512) (xy 163.887272 -307.130444) (xy 163.838097 -307.128463)
			(xy 163.789878 -307.118619) (xy 163.743862 -307.101167) (xy 163.701241 -307.07656) (xy 163.66312 -307.045435)
			(xy 163.630485 -307.008598) (xy 163.604182 -306.967002) (xy 163.584891 -306.921726) (xy 163.573114 -306.873942)
			(xy 163.569154 -306.824888) (xy 163.230306 -306.824888) (xy 163.229811 -306.849495) (xy 163.221916 -306.898072)
			(xy 163.206332 -306.944753) (xy 163.183461 -306.98833) (xy 163.153896 -307.027674) (xy 163.118403 -307.061766)
			(xy 163.0779 -307.089722) (xy 163.033438 -307.11082) (xy 162.986167 -307.124512) (xy 162.937312 -307.130444)
			(xy 162.888137 -307.128463) (xy 162.839918 -307.118619) (xy 162.793902 -307.101167) (xy 162.751281 -307.07656)
			(xy 162.71316 -307.045435) (xy 162.680525 -307.008598) (xy 162.654222 -306.967002) (xy 162.634931 -306.921726)
			(xy 162.623154 -306.873942) (xy 162.619194 -306.824888) (xy 146.583799 -306.824888) (xy 146.580359 -306.84826)
			(xy 146.564291 -306.901667) (xy 146.540619 -306.952164) (xy 146.509846 -306.998677) (xy 146.472629 -307.040214)
			(xy 146.429761 -307.075889) (xy 146.382155 -307.104943) (xy 146.330826 -307.126755) (xy 146.276869 -307.140861)
			(xy 146.221432 -307.146961) (xy 146.165698 -307.144924) (xy 146.110855 -307.134794) (xy 146.058071 -307.116787)
			(xy 146.008471 -307.091286) (xy 145.963113 -307.058835) (xy 145.922964 -307.020126) (xy 145.888878 -306.975983)
			(xy 145.861582 -306.927348) (xy 145.841659 -306.875257) (xy 145.829533 -306.82082) (xy 145.825462 -306.765198)
			(xy 132.617737 -306.765198) (xy 132.60565 -306.791515) (xy 132.575924 -306.837483) (xy 132.558282 -306.858416)
			(xy 132.558028 -306.85867) (xy 132.552439 -306.865755) (xy 132.546196 -306.882673) (xy 132.545836 -306.89169)
			(xy 132.545836 -306.958746) (xy 132.546211 -306.967761) (xy 132.552445 -306.984679) (xy 132.558028 -306.991766)
			(xy 132.558282 -306.991766) (xy 132.558282 -306.99202) (xy 132.57594 -307.012939) (xy 132.605663 -307.058909)
			(xy 132.628507 -307.108658) (xy 132.644002 -307.161162) (xy 132.651828 -307.215342) (xy 132.651827 -307.240178)
			(xy 147.960078 -307.240178) (xy 147.964149 -307.184556) (xy 147.976275 -307.130119) (xy 147.996198 -307.078028)
			(xy 148.023494 -307.029393) (xy 148.05758 -306.98525) (xy 148.097729 -306.946541) (xy 148.143087 -306.91409)
			(xy 148.192687 -306.888589) (xy 148.245471 -306.870582) (xy 148.300314 -306.860452) (xy 148.356048 -306.858415)
			(xy 148.411485 -306.864515) (xy 148.465442 -306.878621) (xy 148.516771 -306.900433) (xy 148.564377 -306.929487)
			(xy 148.607245 -306.965162) (xy 148.644462 -307.006699) (xy 148.675235 -307.053212) (xy 148.698907 -307.103709)
			(xy 148.714975 -307.157116) (xy 148.723095 -307.212292) (xy 148.723604 -307.240178) (xy 148.723095 -307.268064)
			(xy 148.718415 -307.299868) (xy 152.644106 -307.299868) (xy 152.648066 -307.250814) (xy 152.659843 -307.20303)
			(xy 152.679134 -307.157754) (xy 152.705437 -307.116158) (xy 152.738072 -307.079321) (xy 152.776193 -307.048196)
			(xy 152.818814 -307.023589) (xy 152.86483 -307.006137) (xy 152.913049 -306.996293) (xy 152.962224 -306.994312)
			(xy 153.011079 -307.000244) (xy 153.05835 -307.013936) (xy 153.102812 -307.035034) (xy 153.143315 -307.06299)
			(xy 153.178808 -307.097082) (xy 153.208373 -307.136426) (xy 153.231244 -307.180003) (xy 153.246828 -307.226684)
			(xy 153.254723 -307.275261) (xy 153.255218 -307.299868) (xy 153.594066 -307.299868) (xy 153.598026 -307.250814)
			(xy 153.609803 -307.20303) (xy 153.629094 -307.157754) (xy 153.655397 -307.116158) (xy 153.688032 -307.079321)
			(xy 153.726153 -307.048196) (xy 153.768774 -307.023589) (xy 153.81479 -307.006137) (xy 153.863009 -306.996293)
			(xy 153.912184 -306.994312) (xy 153.961039 -307.000244) (xy 154.00831 -307.013936) (xy 154.052772 -307.035034)
			(xy 154.093275 -307.06299) (xy 154.128768 -307.097082) (xy 154.158333 -307.136426) (xy 154.181204 -307.180003)
			(xy 154.196788 -307.226684) (xy 154.204683 -307.275261) (xy 154.205178 -307.299868) (xy 154.54428 -307.299868)
			(xy 154.54824 -307.250814) (xy 154.560017 -307.20303) (xy 154.579308 -307.157754) (xy 154.605611 -307.116158)
			(xy 154.638246 -307.079321) (xy 154.676367 -307.048196) (xy 154.718988 -307.023589) (xy 154.765004 -307.006137)
			(xy 154.813223 -306.996293) (xy 154.862398 -306.994312) (xy 154.911253 -307.000244) (xy 154.958524 -307.013936)
			(xy 155.002986 -307.035034) (xy 155.043489 -307.06299) (xy 155.078982 -307.097082) (xy 155.108547 -307.136426)
			(xy 155.131418 -307.180003) (xy 155.147002 -307.226684) (xy 155.154897 -307.275261) (xy 155.155392 -307.299868)
			(xy 155.49424 -307.299868) (xy 155.4982 -307.250814) (xy 155.509977 -307.20303) (xy 155.529268 -307.157754)
			(xy 155.555571 -307.116158) (xy 155.588206 -307.079321) (xy 155.626327 -307.048196) (xy 155.668948 -307.023589)
			(xy 155.714964 -307.006137) (xy 155.763183 -306.996293) (xy 155.812358 -306.994312) (xy 155.861213 -307.000244)
			(xy 155.908484 -307.013936) (xy 155.952946 -307.035034) (xy 155.993449 -307.06299) (xy 156.028942 -307.097082)
			(xy 156.058507 -307.136426) (xy 156.081378 -307.180003) (xy 156.096962 -307.226684) (xy 156.104857 -307.275261)
			(xy 156.105352 -307.299868) (xy 156.4442 -307.299868) (xy 156.44816 -307.250814) (xy 156.459937 -307.20303)
			(xy 156.479228 -307.157754) (xy 156.505531 -307.116158) (xy 156.538166 -307.079321) (xy 156.576287 -307.048196)
			(xy 156.618908 -307.023589) (xy 156.664924 -307.006137) (xy 156.713143 -306.996293) (xy 156.762318 -306.994312)
			(xy 156.811173 -307.000244) (xy 156.858444 -307.013936) (xy 156.902906 -307.035034) (xy 156.943409 -307.06299)
			(xy 156.978902 -307.097082) (xy 157.008467 -307.136426) (xy 157.031338 -307.180003) (xy 157.046922 -307.226684)
			(xy 157.054817 -307.275261) (xy 157.055312 -307.299868) (xy 157.39416 -307.299868) (xy 157.39812 -307.250814)
			(xy 157.409897 -307.20303) (xy 157.429188 -307.157754) (xy 157.455491 -307.116158) (xy 157.488126 -307.079321)
			(xy 157.526247 -307.048196) (xy 157.568868 -307.023589) (xy 157.614884 -307.006137) (xy 157.663103 -306.996293)
			(xy 157.712278 -306.994312) (xy 157.761133 -307.000244) (xy 157.808404 -307.013936) (xy 157.852866 -307.035034)
			(xy 157.893369 -307.06299) (xy 157.928862 -307.097082) (xy 157.958427 -307.136426) (xy 157.981298 -307.180003)
			(xy 157.996882 -307.226684) (xy 158.004777 -307.275261) (xy 158.005272 -307.299868) (xy 158.34412 -307.299868)
			(xy 158.34808 -307.250814) (xy 158.359857 -307.20303) (xy 158.379148 -307.157754) (xy 158.405451 -307.116158)
			(xy 158.438086 -307.079321) (xy 158.476207 -307.048196) (xy 158.518828 -307.023589) (xy 158.564844 -307.006137)
			(xy 158.613063 -306.996293) (xy 158.662238 -306.994312) (xy 158.711093 -307.000244) (xy 158.758364 -307.013936)
			(xy 158.802826 -307.035034) (xy 158.843329 -307.06299) (xy 158.878822 -307.097082) (xy 158.908387 -307.136426)
			(xy 158.931258 -307.180003) (xy 158.946842 -307.226684) (xy 158.954737 -307.275261) (xy 158.955232 -307.299868)
			(xy 159.29408 -307.299868) (xy 159.29804 -307.250814) (xy 159.309817 -307.20303) (xy 159.329108 -307.157754)
			(xy 159.355411 -307.116158) (xy 159.388046 -307.079321) (xy 159.426167 -307.048196) (xy 159.468788 -307.023589)
			(xy 159.514804 -307.006137) (xy 159.563023 -306.996293) (xy 159.612198 -306.994312) (xy 159.661053 -307.000244)
			(xy 159.708324 -307.013936) (xy 159.752786 -307.035034) (xy 159.793289 -307.06299) (xy 159.828782 -307.097082)
			(xy 159.858347 -307.136426) (xy 159.881218 -307.180003) (xy 159.896802 -307.226684) (xy 159.904697 -307.275261)
			(xy 159.905192 -307.299868) (xy 160.24404 -307.299868) (xy 160.248 -307.250814) (xy 160.259777 -307.20303)
			(xy 160.279068 -307.157754) (xy 160.305371 -307.116158) (xy 160.338006 -307.079321) (xy 160.376127 -307.048196)
			(xy 160.418748 -307.023589) (xy 160.464764 -307.006137) (xy 160.512983 -306.996293) (xy 160.562158 -306.994312)
			(xy 160.611013 -307.000244) (xy 160.658284 -307.013936) (xy 160.702746 -307.035034) (xy 160.743249 -307.06299)
			(xy 160.778742 -307.097082) (xy 160.808307 -307.136426) (xy 160.831178 -307.180003) (xy 160.846762 -307.226684)
			(xy 160.854657 -307.275261) (xy 160.855152 -307.299868) (xy 161.194254 -307.299868) (xy 161.198214 -307.250814)
			(xy 161.209991 -307.20303) (xy 161.229282 -307.157754) (xy 161.255585 -307.116158) (xy 161.28822 -307.079321)
			(xy 161.326341 -307.048196) (xy 161.368962 -307.023589) (xy 161.414978 -307.006137) (xy 161.463197 -306.996293)
			(xy 161.512372 -306.994312) (xy 161.561227 -307.000244) (xy 161.608498 -307.013936) (xy 161.65296 -307.035034)
			(xy 161.693463 -307.06299) (xy 161.728956 -307.097082) (xy 161.758521 -307.136426) (xy 161.781392 -307.180003)
			(xy 161.796976 -307.226684) (xy 161.804871 -307.275261) (xy 161.805366 -307.299868) (xy 161.804871 -307.324475)
			(xy 161.796976 -307.373052) (xy 161.781392 -307.419733) (xy 161.758521 -307.46331) (xy 161.728956 -307.502654)
			(xy 161.693463 -307.536746) (xy 161.65296 -307.564702) (xy 161.608498 -307.5858) (xy 161.561227 -307.599492)
			(xy 161.512372 -307.605424) (xy 161.463197 -307.603443) (xy 161.414978 -307.593599) (xy 161.368962 -307.576147)
			(xy 161.326341 -307.55154) (xy 161.28822 -307.520415) (xy 161.255585 -307.483578) (xy 161.229282 -307.441982)
			(xy 161.209991 -307.396706) (xy 161.198214 -307.348922) (xy 161.194254 -307.299868) (xy 160.855152 -307.299868)
			(xy 160.854657 -307.324475) (xy 160.846762 -307.373052) (xy 160.831178 -307.419733) (xy 160.808307 -307.46331)
			(xy 160.778742 -307.502654) (xy 160.743249 -307.536746) (xy 160.702746 -307.564702) (xy 160.658284 -307.5858)
			(xy 160.611013 -307.599492) (xy 160.562158 -307.605424) (xy 160.512983 -307.603443) (xy 160.464764 -307.593599)
			(xy 160.418748 -307.576147) (xy 160.376127 -307.55154) (xy 160.338006 -307.520415) (xy 160.305371 -307.483578)
			(xy 160.279068 -307.441982) (xy 160.259777 -307.396706) (xy 160.248 -307.348922) (xy 160.24404 -307.299868)
			(xy 159.905192 -307.299868) (xy 159.904697 -307.324475) (xy 159.896802 -307.373052) (xy 159.881218 -307.419733)
			(xy 159.858347 -307.46331) (xy 159.828782 -307.502654) (xy 159.793289 -307.536746) (xy 159.752786 -307.564702)
			(xy 159.708324 -307.5858) (xy 159.661053 -307.599492) (xy 159.612198 -307.605424) (xy 159.563023 -307.603443)
			(xy 159.514804 -307.593599) (xy 159.468788 -307.576147) (xy 159.426167 -307.55154) (xy 159.388046 -307.520415)
			(xy 159.355411 -307.483578) (xy 159.329108 -307.441982) (xy 159.309817 -307.396706) (xy 159.29804 -307.348922)
			(xy 159.29408 -307.299868) (xy 158.955232 -307.299868) (xy 158.954737 -307.324475) (xy 158.946842 -307.373052)
			(xy 158.931258 -307.419733) (xy 158.908387 -307.46331) (xy 158.878822 -307.502654) (xy 158.843329 -307.536746)
			(xy 158.802826 -307.564702) (xy 158.758364 -307.5858) (xy 158.711093 -307.599492) (xy 158.662238 -307.605424)
			(xy 158.613063 -307.603443) (xy 158.564844 -307.593599) (xy 158.518828 -307.576147) (xy 158.476207 -307.55154)
			(xy 158.438086 -307.520415) (xy 158.405451 -307.483578) (xy 158.379148 -307.441982) (xy 158.359857 -307.396706)
			(xy 158.34808 -307.348922) (xy 158.34412 -307.299868) (xy 158.005272 -307.299868) (xy 158.004777 -307.324475)
			(xy 157.996882 -307.373052) (xy 157.981298 -307.419733) (xy 157.958427 -307.46331) (xy 157.928862 -307.502654)
			(xy 157.893369 -307.536746) (xy 157.852866 -307.564702) (xy 157.808404 -307.5858) (xy 157.761133 -307.599492)
			(xy 157.712278 -307.605424) (xy 157.663103 -307.603443) (xy 157.614884 -307.593599) (xy 157.568868 -307.576147)
			(xy 157.526247 -307.55154) (xy 157.488126 -307.520415) (xy 157.455491 -307.483578) (xy 157.429188 -307.441982)
			(xy 157.409897 -307.396706) (xy 157.39812 -307.348922) (xy 157.39416 -307.299868) (xy 157.055312 -307.299868)
			(xy 157.054817 -307.324475) (xy 157.046922 -307.373052) (xy 157.031338 -307.419733) (xy 157.008467 -307.46331)
			(xy 156.978902 -307.502654) (xy 156.943409 -307.536746) (xy 156.902906 -307.564702) (xy 156.858444 -307.5858)
			(xy 156.811173 -307.599492) (xy 156.762318 -307.605424) (xy 156.713143 -307.603443) (xy 156.664924 -307.593599)
			(xy 156.618908 -307.576147) (xy 156.576287 -307.55154) (xy 156.538166 -307.520415) (xy 156.505531 -307.483578)
			(xy 156.479228 -307.441982) (xy 156.459937 -307.396706) (xy 156.44816 -307.348922) (xy 156.4442 -307.299868)
			(xy 156.105352 -307.299868) (xy 156.104857 -307.324475) (xy 156.096962 -307.373052) (xy 156.081378 -307.419733)
			(xy 156.058507 -307.46331) (xy 156.028942 -307.502654) (xy 155.993449 -307.536746) (xy 155.952946 -307.564702)
			(xy 155.908484 -307.5858) (xy 155.861213 -307.599492) (xy 155.812358 -307.605424) (xy 155.763183 -307.603443)
			(xy 155.714964 -307.593599) (xy 155.668948 -307.576147) (xy 155.626327 -307.55154) (xy 155.588206 -307.520415)
			(xy 155.555571 -307.483578) (xy 155.529268 -307.441982) (xy 155.509977 -307.396706) (xy 155.4982 -307.348922)
			(xy 155.49424 -307.299868) (xy 155.155392 -307.299868) (xy 155.154897 -307.324475) (xy 155.147002 -307.373052)
			(xy 155.131418 -307.419733) (xy 155.108547 -307.46331) (xy 155.078982 -307.502654) (xy 155.043489 -307.536746)
			(xy 155.002986 -307.564702) (xy 154.958524 -307.5858) (xy 154.911253 -307.599492) (xy 154.862398 -307.605424)
			(xy 154.813223 -307.603443) (xy 154.765004 -307.593599) (xy 154.718988 -307.576147) (xy 154.676367 -307.55154)
			(xy 154.638246 -307.520415) (xy 154.605611 -307.483578) (xy 154.579308 -307.441982) (xy 154.560017 -307.396706)
			(xy 154.54824 -307.348922) (xy 154.54428 -307.299868) (xy 154.205178 -307.299868) (xy 154.204683 -307.324475)
			(xy 154.196788 -307.373052) (xy 154.181204 -307.419733) (xy 154.158333 -307.46331) (xy 154.128768 -307.502654)
			(xy 154.093275 -307.536746) (xy 154.052772 -307.564702) (xy 154.00831 -307.5858) (xy 153.961039 -307.599492)
			(xy 153.912184 -307.605424) (xy 153.863009 -307.603443) (xy 153.81479 -307.593599) (xy 153.768774 -307.576147)
			(xy 153.726153 -307.55154) (xy 153.688032 -307.520415) (xy 153.655397 -307.483578) (xy 153.629094 -307.441982)
			(xy 153.609803 -307.396706) (xy 153.598026 -307.348922) (xy 153.594066 -307.299868) (xy 153.255218 -307.299868)
			(xy 153.254723 -307.324475) (xy 153.246828 -307.373052) (xy 153.231244 -307.419733) (xy 153.208373 -307.46331)
			(xy 153.178808 -307.502654) (xy 153.143315 -307.536746) (xy 153.102812 -307.564702) (xy 153.05835 -307.5858)
			(xy 153.011079 -307.599492) (xy 152.962224 -307.605424) (xy 152.913049 -307.603443) (xy 152.86483 -307.593599)
			(xy 152.818814 -307.576147) (xy 152.776193 -307.55154) (xy 152.738072 -307.520415) (xy 152.705437 -307.483578)
			(xy 152.679134 -307.441982) (xy 152.659843 -307.396706) (xy 152.648066 -307.348922) (xy 152.644106 -307.299868)
			(xy 148.718415 -307.299868) (xy 148.714975 -307.32324) (xy 148.698907 -307.376647) (xy 148.675235 -307.427144)
			(xy 148.644462 -307.473657) (xy 148.607245 -307.515194) (xy 148.564377 -307.550869) (xy 148.516771 -307.579923)
			(xy 148.465442 -307.601735) (xy 148.411485 -307.615841) (xy 148.356048 -307.621941) (xy 148.300314 -307.619904)
			(xy 148.245471 -307.609774) (xy 148.192687 -307.591767) (xy 148.143087 -307.566266) (xy 148.097729 -307.533815)
			(xy 148.05758 -307.495106) (xy 148.023494 -307.450963) (xy 147.996198 -307.402328) (xy 147.976275 -307.350237)
			(xy 147.964149 -307.2958) (xy 147.960078 -307.240178) (xy 132.651827 -307.240178) (xy 132.651826 -307.270085)
			(xy 132.643996 -307.324265) (xy 132.628498 -307.376768) (xy 132.60565 -307.426515) (xy 132.575924 -307.472483)
			(xy 132.558282 -307.493416) (xy 132.558028 -307.49367) (xy 132.552439 -307.500755) (xy 132.546196 -307.517673)
			(xy 132.545836 -307.52669) (xy 132.545836 -307.593746) (xy 132.546211 -307.602761) (xy 132.552445 -307.619679)
			(xy 132.558028 -307.626766) (xy 132.558282 -307.626766) (xy 132.558282 -307.62702) (xy 132.575894 -307.647974)
			(xy 132.605611 -307.69394) (xy 132.628452 -307.743682) (xy 132.637652 -307.774848) (xy 162.619194 -307.774848)
			(xy 162.623154 -307.725794) (xy 162.634931 -307.67801) (xy 162.654222 -307.632734) (xy 162.680525 -307.591138)
			(xy 162.71316 -307.554301) (xy 162.751281 -307.523176) (xy 162.793902 -307.498569) (xy 162.839918 -307.481117)
			(xy 162.888137 -307.471273) (xy 162.937312 -307.469292) (xy 162.986167 -307.475224) (xy 163.033438 -307.488916)
			(xy 163.0779 -307.510014) (xy 163.118403 -307.53797) (xy 163.153896 -307.572062) (xy 163.183461 -307.611406)
			(xy 163.206332 -307.654983) (xy 163.221916 -307.701664) (xy 163.229811 -307.750241) (xy 163.230306 -307.774848)
			(xy 163.569154 -307.774848) (xy 163.573114 -307.725794) (xy 163.584891 -307.67801) (xy 163.604182 -307.632734)
			(xy 163.630485 -307.591138) (xy 163.66312 -307.554301) (xy 163.701241 -307.523176) (xy 163.743862 -307.498569)
			(xy 163.789878 -307.481117) (xy 163.838097 -307.471273) (xy 163.887272 -307.469292) (xy 163.936127 -307.475224)
			(xy 163.983398 -307.488916) (xy 164.02786 -307.510014) (xy 164.068363 -307.53797) (xy 164.103856 -307.572062)
			(xy 164.133421 -307.611406) (xy 164.156292 -307.654983) (xy 164.171876 -307.701664) (xy 164.179771 -307.750241)
			(xy 164.180266 -307.774848) (xy 164.519114 -307.774848) (xy 164.523074 -307.725794) (xy 164.534851 -307.67801)
			(xy 164.554142 -307.632734) (xy 164.580445 -307.591138) (xy 164.61308 -307.554301) (xy 164.651201 -307.523176)
			(xy 164.693822 -307.498569) (xy 164.739838 -307.481117) (xy 164.788057 -307.471273) (xy 164.837232 -307.469292)
			(xy 164.886087 -307.475224) (xy 164.933358 -307.488916) (xy 164.97782 -307.510014) (xy 165.018323 -307.53797)
			(xy 165.053816 -307.572062) (xy 165.083381 -307.611406) (xy 165.106252 -307.654983) (xy 165.121836 -307.701664)
			(xy 165.129731 -307.750241) (xy 165.130226 -307.774848) (xy 165.129731 -307.799455) (xy 165.121836 -307.848032)
			(xy 165.106252 -307.894713) (xy 165.083381 -307.93829) (xy 165.053816 -307.977634) (xy 165.018323 -308.011726)
			(xy 164.97782 -308.039682) (xy 164.933358 -308.06078) (xy 164.886087 -308.074472) (xy 164.837232 -308.080404)
			(xy 164.788057 -308.078423) (xy 164.739838 -308.068579) (xy 164.693822 -308.051127) (xy 164.651201 -308.02652)
			(xy 164.61308 -307.995395) (xy 164.580445 -307.958558) (xy 164.554142 -307.916962) (xy 164.534851 -307.871686)
			(xy 164.523074 -307.823902) (xy 164.519114 -307.774848) (xy 164.180266 -307.774848) (xy 164.179771 -307.799455)
			(xy 164.171876 -307.848032) (xy 164.156292 -307.894713) (xy 164.133421 -307.93829) (xy 164.103856 -307.977634)
			(xy 164.068363 -308.011726) (xy 164.02786 -308.039682) (xy 163.983398 -308.06078) (xy 163.936127 -308.074472)
			(xy 163.887272 -308.080404) (xy 163.838097 -308.078423) (xy 163.789878 -308.068579) (xy 163.743862 -308.051127)
			(xy 163.701241 -308.02652) (xy 163.66312 -307.995395) (xy 163.630485 -307.958558) (xy 163.604182 -307.916962)
			(xy 163.584891 -307.871686) (xy 163.573114 -307.823902) (xy 163.569154 -307.774848) (xy 163.230306 -307.774848)
			(xy 163.229811 -307.799455) (xy 163.221916 -307.848032) (xy 163.206332 -307.894713) (xy 163.183461 -307.93829)
			(xy 163.153896 -307.977634) (xy 163.118403 -308.011726) (xy 163.0779 -308.039682) (xy 163.033438 -308.06078)
			(xy 162.986167 -308.074472) (xy 162.937312 -308.080404) (xy 162.888137 -308.078423) (xy 162.839918 -308.068579)
			(xy 162.793902 -308.051127) (xy 162.751281 -308.02652) (xy 162.71316 -307.995395) (xy 162.680525 -307.958558)
			(xy 162.654222 -307.916962) (xy 162.634931 -307.871686) (xy 162.623154 -307.823902) (xy 162.619194 -307.774848)
			(xy 132.637652 -307.774848) (xy 132.643949 -307.796178) (xy 132.651784 -307.85035) (xy 132.652262 -307.877718)
			(xy 132.651776 -307.904969) (xy 132.64402 -307.958917) (xy 132.628665 -308.011212) (xy 132.606023 -308.060789)
			(xy 132.576557 -308.106639) (xy 132.540866 -308.14783) (xy 132.499675 -308.183521) (xy 132.453825 -308.212987)
			(xy 132.404248 -308.235629) (xy 132.351953 -308.250984) (xy 132.298005 -308.25874) (xy 132.243503 -308.25874)
			(xy 132.189555 -308.250984) (xy 132.13726 -308.235629) (xy 132.087683 -308.212987) (xy 132.041833 -308.183521)
			(xy 132.000642 -308.14783) (xy 131.964951 -308.106639) (xy 131.935485 -308.060789) (xy 131.912843 -308.011212)
			(xy 131.897488 -307.958917) (xy 131.889732 -307.904969) (xy 131.889246 -307.877718) (xy 129.015752 -307.877718)
			(xy 129.01182 -307.905069) (xy 128.996465 -307.957364) (xy 128.973823 -308.006941) (xy 128.944357 -308.052791)
			(xy 128.908666 -308.093982) (xy 128.867475 -308.129673) (xy 128.821625 -308.159139) (xy 128.772048 -308.181781)
			(xy 128.719753 -308.197136) (xy 128.665805 -308.204892) (xy 128.611303 -308.204892) (xy 128.557355 -308.197136)
			(xy 128.50506 -308.181781) (xy 128.455483 -308.159139) (xy 128.409633 -308.129673) (xy 128.368442 -308.093982)
			(xy 128.332751 -308.052791) (xy 128.303285 -308.006941) (xy 128.280643 -307.957364) (xy 128.265288 -307.905069)
			(xy 128.257532 -307.851121) (xy 128.257046 -307.82387) (xy 125.807734 -307.82387) (xy 125.811564 -307.85035)
			(xy 125.812042 -307.877718) (xy 125.811556 -307.904969) (xy 125.8038 -307.958917) (xy 125.788445 -308.011212)
			(xy 125.765803 -308.060789) (xy 125.736337 -308.106639) (xy 125.700646 -308.14783) (xy 125.659455 -308.183521)
			(xy 125.613605 -308.212987) (xy 125.564028 -308.235629) (xy 125.511733 -308.250984) (xy 125.457785 -308.25874)
			(xy 125.403283 -308.25874) (xy 125.349335 -308.250984) (xy 125.29704 -308.235629) (xy 125.247463 -308.212987)
			(xy 125.201613 -308.183521) (xy 125.160422 -308.14783) (xy 125.124731 -308.106639) (xy 125.095265 -308.060789)
			(xy 125.072623 -308.011212) (xy 125.057268 -307.958917) (xy 125.049512 -307.904969) (xy 125.049026 -307.877718)
			(xy 122.175532 -307.877718) (xy 122.1716 -307.905069) (xy 122.156245 -307.957364) (xy 122.133603 -308.006941)
			(xy 122.104137 -308.052791) (xy 122.068446 -308.093982) (xy 122.027255 -308.129673) (xy 121.981405 -308.159139)
			(xy 121.931828 -308.181781) (xy 121.879533 -308.197136) (xy 121.825585 -308.204892) (xy 121.771083 -308.204892)
			(xy 121.717135 -308.197136) (xy 121.66484 -308.181781) (xy 121.615263 -308.159139) (xy 121.569413 -308.129673)
			(xy 121.528222 -308.093982) (xy 121.492531 -308.052791) (xy 121.463065 -308.006941) (xy 121.440423 -307.957364)
			(xy 121.425068 -307.905069) (xy 121.417312 -307.851121) (xy 121.416826 -307.82387) (xy 118.832884 -307.82387)
			(xy 118.832884 -308.450488) (xy 144.178272 -308.450488) (xy 144.182343 -308.394866) (xy 144.194469 -308.340429)
			(xy 144.214392 -308.288338) (xy 144.241688 -308.239703) (xy 144.275774 -308.19556) (xy 144.315923 -308.156851)
			(xy 144.361281 -308.1244) (xy 144.410881 -308.098899) (xy 144.463665 -308.080892) (xy 144.518508 -308.070762)
			(xy 144.574242 -308.068725) (xy 144.629679 -308.074825) (xy 144.683636 -308.088931) (xy 144.734965 -308.110743)
			(xy 144.782571 -308.139797) (xy 144.825439 -308.175472) (xy 144.862656 -308.217009) (xy 144.884537 -308.250082)
			(xy 151.693892 -308.250082) (xy 151.697852 -308.201028) (xy 151.709629 -308.153244) (xy 151.72892 -308.107968)
			(xy 151.755223 -308.066372) (xy 151.787858 -308.029535) (xy 151.825979 -307.99841) (xy 151.8686 -307.973803)
			(xy 151.914616 -307.956351) (xy 151.962835 -307.946507) (xy 152.01201 -307.944526) (xy 152.060865 -307.950458)
			(xy 152.108136 -307.96415) (xy 152.152598 -307.985248) (xy 152.193101 -308.013204) (xy 152.228594 -308.047296)
			(xy 152.258159 -308.08664) (xy 152.28103 -308.130217) (xy 152.296614 -308.176898) (xy 152.304509 -308.225475)
			(xy 152.304999 -308.249828) (xy 152.644106 -308.249828) (xy 152.648066 -308.200774) (xy 152.659843 -308.15299)
			(xy 152.679134 -308.107714) (xy 152.705437 -308.066118) (xy 152.738072 -308.029281) (xy 152.776193 -307.998156)
			(xy 152.818814 -307.973549) (xy 152.86483 -307.956097) (xy 152.913049 -307.946253) (xy 152.962224 -307.944272)
			(xy 153.011079 -307.950204) (xy 153.05835 -307.963896) (xy 153.102812 -307.984994) (xy 153.143315 -308.01295)
			(xy 153.178808 -308.047042) (xy 153.208373 -308.086386) (xy 153.231244 -308.129963) (xy 153.246828 -308.176644)
			(xy 153.254723 -308.225221) (xy 153.255218 -308.249828) (xy 153.594066 -308.249828) (xy 153.598026 -308.200774)
			(xy 153.609803 -308.15299) (xy 153.629094 -308.107714) (xy 153.655397 -308.066118) (xy 153.688032 -308.029281)
			(xy 153.726153 -307.998156) (xy 153.768774 -307.973549) (xy 153.81479 -307.956097) (xy 153.863009 -307.946253)
			(xy 153.912184 -307.944272) (xy 153.961039 -307.950204) (xy 154.00831 -307.963896) (xy 154.052772 -307.984994)
			(xy 154.093275 -308.01295) (xy 154.128768 -308.047042) (xy 154.158333 -308.086386) (xy 154.181204 -308.129963)
			(xy 154.196788 -308.176644) (xy 154.204683 -308.225221) (xy 154.205178 -308.249828) (xy 154.54428 -308.249828)
			(xy 154.54824 -308.200774) (xy 154.560017 -308.15299) (xy 154.579308 -308.107714) (xy 154.605611 -308.066118)
			(xy 154.638246 -308.029281) (xy 154.676367 -307.998156) (xy 154.718988 -307.973549) (xy 154.765004 -307.956097)
			(xy 154.813223 -307.946253) (xy 154.862398 -307.944272) (xy 154.911253 -307.950204) (xy 154.958524 -307.963896)
			(xy 155.002986 -307.984994) (xy 155.043489 -308.01295) (xy 155.078982 -308.047042) (xy 155.108547 -308.086386)
			(xy 155.131418 -308.129963) (xy 155.147002 -308.176644) (xy 155.154897 -308.225221) (xy 155.155392 -308.249828)
			(xy 155.49424 -308.249828) (xy 155.4982 -308.200774) (xy 155.509977 -308.15299) (xy 155.529268 -308.107714)
			(xy 155.555571 -308.066118) (xy 155.588206 -308.029281) (xy 155.626327 -307.998156) (xy 155.668948 -307.973549)
			(xy 155.714964 -307.956097) (xy 155.763183 -307.946253) (xy 155.812358 -307.944272) (xy 155.861213 -307.950204)
			(xy 155.908484 -307.963896) (xy 155.952946 -307.984994) (xy 155.993449 -308.01295) (xy 156.028942 -308.047042)
			(xy 156.058507 -308.086386) (xy 156.081378 -308.129963) (xy 156.096962 -308.176644) (xy 156.104857 -308.225221)
			(xy 156.105352 -308.249828) (xy 156.4442 -308.249828) (xy 156.44816 -308.200774) (xy 156.459937 -308.15299)
			(xy 156.479228 -308.107714) (xy 156.505531 -308.066118) (xy 156.538166 -308.029281) (xy 156.576287 -307.998156)
			(xy 156.618908 -307.973549) (xy 156.664924 -307.956097) (xy 156.713143 -307.946253) (xy 156.762318 -307.944272)
			(xy 156.811173 -307.950204) (xy 156.858444 -307.963896) (xy 156.902906 -307.984994) (xy 156.943409 -308.01295)
			(xy 156.978902 -308.047042) (xy 157.008467 -308.086386) (xy 157.031338 -308.129963) (xy 157.046922 -308.176644)
			(xy 157.054817 -308.225221) (xy 157.055312 -308.249828) (xy 157.39416 -308.249828) (xy 157.39812 -308.200774)
			(xy 157.409897 -308.15299) (xy 157.429188 -308.107714) (xy 157.455491 -308.066118) (xy 157.488126 -308.029281)
			(xy 157.526247 -307.998156) (xy 157.568868 -307.973549) (xy 157.614884 -307.956097) (xy 157.663103 -307.946253)
			(xy 157.712278 -307.944272) (xy 157.761133 -307.950204) (xy 157.808404 -307.963896) (xy 157.852866 -307.984994)
			(xy 157.893369 -308.01295) (xy 157.928862 -308.047042) (xy 157.958427 -308.086386) (xy 157.981298 -308.129963)
			(xy 157.996882 -308.176644) (xy 158.004777 -308.225221) (xy 158.005272 -308.249828) (xy 158.34412 -308.249828)
			(xy 158.34808 -308.200774) (xy 158.359857 -308.15299) (xy 158.379148 -308.107714) (xy 158.405451 -308.066118)
			(xy 158.438086 -308.029281) (xy 158.476207 -307.998156) (xy 158.518828 -307.973549) (xy 158.564844 -307.956097)
			(xy 158.613063 -307.946253) (xy 158.662238 -307.944272) (xy 158.711093 -307.950204) (xy 158.758364 -307.963896)
			(xy 158.802826 -307.984994) (xy 158.843329 -308.01295) (xy 158.878822 -308.047042) (xy 158.908387 -308.086386)
			(xy 158.931258 -308.129963) (xy 158.946842 -308.176644) (xy 158.954737 -308.225221) (xy 158.955232 -308.249828)
			(xy 159.29408 -308.249828) (xy 159.29804 -308.200774) (xy 159.309817 -308.15299) (xy 159.329108 -308.107714)
			(xy 159.355411 -308.066118) (xy 159.388046 -308.029281) (xy 159.426167 -307.998156) (xy 159.468788 -307.973549)
			(xy 159.514804 -307.956097) (xy 159.563023 -307.946253) (xy 159.612198 -307.944272) (xy 159.661053 -307.950204)
			(xy 159.708324 -307.963896) (xy 159.752786 -307.984994) (xy 159.793289 -308.01295) (xy 159.828782 -308.047042)
			(xy 159.858347 -308.086386) (xy 159.881218 -308.129963) (xy 159.896802 -308.176644) (xy 159.904697 -308.225221)
			(xy 159.905192 -308.249828) (xy 160.24404 -308.249828) (xy 160.248 -308.200774) (xy 160.259777 -308.15299)
			(xy 160.279068 -308.107714) (xy 160.305371 -308.066118) (xy 160.338006 -308.029281) (xy 160.376127 -307.998156)
			(xy 160.418748 -307.973549) (xy 160.464764 -307.956097) (xy 160.512983 -307.946253) (xy 160.562158 -307.944272)
			(xy 160.611013 -307.950204) (xy 160.658284 -307.963896) (xy 160.702746 -307.984994) (xy 160.743249 -308.01295)
			(xy 160.778742 -308.047042) (xy 160.808307 -308.086386) (xy 160.831178 -308.129963) (xy 160.846762 -308.176644)
			(xy 160.854657 -308.225221) (xy 160.855152 -308.249828) (xy 161.194254 -308.249828) (xy 161.198214 -308.200774)
			(xy 161.209991 -308.15299) (xy 161.229282 -308.107714) (xy 161.255585 -308.066118) (xy 161.28822 -308.029281)
			(xy 161.326341 -307.998156) (xy 161.368962 -307.973549) (xy 161.414978 -307.956097) (xy 161.463197 -307.946253)
			(xy 161.512372 -307.944272) (xy 161.561227 -307.950204) (xy 161.608498 -307.963896) (xy 161.65296 -307.984994)
			(xy 161.693463 -308.01295) (xy 161.728956 -308.047042) (xy 161.758521 -308.086386) (xy 161.781392 -308.129963)
			(xy 161.796976 -308.176644) (xy 161.804871 -308.225221) (xy 161.805366 -308.249828) (xy 161.804871 -308.274435)
			(xy 161.796976 -308.323012) (xy 161.781392 -308.369693) (xy 161.758521 -308.41327) (xy 161.728956 -308.452614)
			(xy 161.693463 -308.486706) (xy 161.65296 -308.514662) (xy 161.608498 -308.53576) (xy 161.561227 -308.549452)
			(xy 161.512372 -308.555384) (xy 161.463197 -308.553403) (xy 161.414978 -308.543559) (xy 161.368962 -308.526107)
			(xy 161.326341 -308.5015) (xy 161.28822 -308.470375) (xy 161.255585 -308.433538) (xy 161.229282 -308.391942)
			(xy 161.209991 -308.346666) (xy 161.198214 -308.298882) (xy 161.194254 -308.249828) (xy 160.855152 -308.249828)
			(xy 160.854657 -308.274435) (xy 160.846762 -308.323012) (xy 160.831178 -308.369693) (xy 160.808307 -308.41327)
			(xy 160.778742 -308.452614) (xy 160.743249 -308.486706) (xy 160.702746 -308.514662) (xy 160.658284 -308.53576)
			(xy 160.611013 -308.549452) (xy 160.562158 -308.555384) (xy 160.512983 -308.553403) (xy 160.464764 -308.543559)
			(xy 160.418748 -308.526107) (xy 160.376127 -308.5015) (xy 160.338006 -308.470375) (xy 160.305371 -308.433538)
			(xy 160.279068 -308.391942) (xy 160.259777 -308.346666) (xy 160.248 -308.298882) (xy 160.24404 -308.249828)
			(xy 159.905192 -308.249828) (xy 159.904697 -308.274435) (xy 159.896802 -308.323012) (xy 159.881218 -308.369693)
			(xy 159.858347 -308.41327) (xy 159.828782 -308.452614) (xy 159.793289 -308.486706) (xy 159.752786 -308.514662)
			(xy 159.708324 -308.53576) (xy 159.661053 -308.549452) (xy 159.612198 -308.555384) (xy 159.563023 -308.553403)
			(xy 159.514804 -308.543559) (xy 159.468788 -308.526107) (xy 159.426167 -308.5015) (xy 159.388046 -308.470375)
			(xy 159.355411 -308.433538) (xy 159.329108 -308.391942) (xy 159.309817 -308.346666) (xy 159.29804 -308.298882)
			(xy 159.29408 -308.249828) (xy 158.955232 -308.249828) (xy 158.954737 -308.274435) (xy 158.946842 -308.323012)
			(xy 158.931258 -308.369693) (xy 158.908387 -308.41327) (xy 158.878822 -308.452614) (xy 158.843329 -308.486706)
			(xy 158.802826 -308.514662) (xy 158.758364 -308.53576) (xy 158.711093 -308.549452) (xy 158.662238 -308.555384)
			(xy 158.613063 -308.553403) (xy 158.564844 -308.543559) (xy 158.518828 -308.526107) (xy 158.476207 -308.5015)
			(xy 158.438086 -308.470375) (xy 158.405451 -308.433538) (xy 158.379148 -308.391942) (xy 158.359857 -308.346666)
			(xy 158.34808 -308.298882) (xy 158.34412 -308.249828) (xy 158.005272 -308.249828) (xy 158.004777 -308.274435)
			(xy 157.996882 -308.323012) (xy 157.981298 -308.369693) (xy 157.958427 -308.41327) (xy 157.928862 -308.452614)
			(xy 157.893369 -308.486706) (xy 157.852866 -308.514662) (xy 157.808404 -308.53576) (xy 157.761133 -308.549452)
			(xy 157.712278 -308.555384) (xy 157.663103 -308.553403) (xy 157.614884 -308.543559) (xy 157.568868 -308.526107)
			(xy 157.526247 -308.5015) (xy 157.488126 -308.470375) (xy 157.455491 -308.433538) (xy 157.429188 -308.391942)
			(xy 157.409897 -308.346666) (xy 157.39812 -308.298882) (xy 157.39416 -308.249828) (xy 157.055312 -308.249828)
			(xy 157.054817 -308.274435) (xy 157.046922 -308.323012) (xy 157.031338 -308.369693) (xy 157.008467 -308.41327)
			(xy 156.978902 -308.452614) (xy 156.943409 -308.486706) (xy 156.902906 -308.514662) (xy 156.858444 -308.53576)
			(xy 156.811173 -308.549452) (xy 156.762318 -308.555384) (xy 156.713143 -308.553403) (xy 156.664924 -308.543559)
			(xy 156.618908 -308.526107) (xy 156.576287 -308.5015) (xy 156.538166 -308.470375) (xy 156.505531 -308.433538)
			(xy 156.479228 -308.391942) (xy 156.459937 -308.346666) (xy 156.44816 -308.298882) (xy 156.4442 -308.249828)
			(xy 156.105352 -308.249828) (xy 156.104857 -308.274435) (xy 156.096962 -308.323012) (xy 156.081378 -308.369693)
			(xy 156.058507 -308.41327) (xy 156.028942 -308.452614) (xy 155.993449 -308.486706) (xy 155.952946 -308.514662)
			(xy 155.908484 -308.53576) (xy 155.861213 -308.549452) (xy 155.812358 -308.555384) (xy 155.763183 -308.553403)
			(xy 155.714964 -308.543559) (xy 155.668948 -308.526107) (xy 155.626327 -308.5015) (xy 155.588206 -308.470375)
			(xy 155.555571 -308.433538) (xy 155.529268 -308.391942) (xy 155.509977 -308.346666) (xy 155.4982 -308.298882)
			(xy 155.49424 -308.249828) (xy 155.155392 -308.249828) (xy 155.154897 -308.274435) (xy 155.147002 -308.323012)
			(xy 155.131418 -308.369693) (xy 155.108547 -308.41327) (xy 155.078982 -308.452614) (xy 155.043489 -308.486706)
			(xy 155.002986 -308.514662) (xy 154.958524 -308.53576) (xy 154.911253 -308.549452) (xy 154.862398 -308.555384)
			(xy 154.813223 -308.553403) (xy 154.765004 -308.543559) (xy 154.718988 -308.526107) (xy 154.676367 -308.5015)
			(xy 154.638246 -308.470375) (xy 154.605611 -308.433538) (xy 154.579308 -308.391942) (xy 154.560017 -308.346666)
			(xy 154.54824 -308.298882) (xy 154.54428 -308.249828) (xy 154.205178 -308.249828) (xy 154.204683 -308.274435)
			(xy 154.196788 -308.323012) (xy 154.181204 -308.369693) (xy 154.158333 -308.41327) (xy 154.128768 -308.452614)
			(xy 154.093275 -308.486706) (xy 154.052772 -308.514662) (xy 154.00831 -308.53576) (xy 153.961039 -308.549452)
			(xy 153.912184 -308.555384) (xy 153.863009 -308.553403) (xy 153.81479 -308.543559) (xy 153.768774 -308.526107)
			(xy 153.726153 -308.5015) (xy 153.688032 -308.470375) (xy 153.655397 -308.433538) (xy 153.629094 -308.391942)
			(xy 153.609803 -308.346666) (xy 153.598026 -308.298882) (xy 153.594066 -308.249828) (xy 153.255218 -308.249828)
			(xy 153.254723 -308.274435) (xy 153.246828 -308.323012) (xy 153.231244 -308.369693) (xy 153.208373 -308.41327)
			(xy 153.178808 -308.452614) (xy 153.143315 -308.486706) (xy 153.102812 -308.514662) (xy 153.05835 -308.53576)
			(xy 153.011079 -308.549452) (xy 152.962224 -308.555384) (xy 152.913049 -308.553403) (xy 152.86483 -308.543559)
			(xy 152.818814 -308.526107) (xy 152.776193 -308.5015) (xy 152.738072 -308.470375) (xy 152.705437 -308.433538)
			(xy 152.679134 -308.391942) (xy 152.659843 -308.346666) (xy 152.648066 -308.298882) (xy 152.644106 -308.249828)
			(xy 152.304999 -308.249828) (xy 152.305004 -308.250082) (xy 152.304509 -308.274689) (xy 152.296614 -308.323266)
			(xy 152.28103 -308.369947) (xy 152.258159 -308.413524) (xy 152.228594 -308.452868) (xy 152.193101 -308.48696)
			(xy 152.152598 -308.514916) (xy 152.108136 -308.536014) (xy 152.060865 -308.549706) (xy 152.01201 -308.555638)
			(xy 151.962835 -308.553657) (xy 151.914616 -308.543813) (xy 151.8686 -308.526361) (xy 151.825979 -308.501754)
			(xy 151.787858 -308.470629) (xy 151.755223 -308.433792) (xy 151.72892 -308.392196) (xy 151.709629 -308.34692)
			(xy 151.697852 -308.299136) (xy 151.693892 -308.250082) (xy 144.884537 -308.250082) (xy 144.893429 -308.263522)
			(xy 144.917101 -308.314019) (xy 144.933169 -308.367426) (xy 144.941289 -308.422602) (xy 144.941798 -308.450488)
			(xy 144.941289 -308.478374) (xy 144.933169 -308.53355) (xy 144.917101 -308.586957) (xy 144.893429 -308.637454)
			(xy 144.878824 -308.65953) (xy 146.505674 -308.65953) (xy 146.509745 -308.603908) (xy 146.521871 -308.549471)
			(xy 146.541794 -308.49738) (xy 146.56909 -308.448745) (xy 146.603176 -308.404602) (xy 146.643325 -308.365893)
			(xy 146.688683 -308.333442) (xy 146.738283 -308.307941) (xy 146.791067 -308.289934) (xy 146.84591 -308.279804)
			(xy 146.901644 -308.277767) (xy 146.957081 -308.283867) (xy 147.011038 -308.297973) (xy 147.062367 -308.319785)
			(xy 147.109973 -308.348839) (xy 147.152841 -308.384514) (xy 147.190058 -308.426051) (xy 147.220831 -308.472564)
			(xy 147.244503 -308.523061) (xy 147.260571 -308.576468) (xy 147.268691 -308.631644) (xy 147.2692 -308.65953)
			(xy 147.268691 -308.687416) (xy 147.263188 -308.724808) (xy 162.619194 -308.724808) (xy 162.623154 -308.675754)
			(xy 162.634931 -308.62797) (xy 162.654222 -308.582694) (xy 162.680525 -308.541098) (xy 162.71316 -308.504261)
			(xy 162.751281 -308.473136) (xy 162.793902 -308.448529) (xy 162.839918 -308.431077) (xy 162.888137 -308.421233)
			(xy 162.937312 -308.419252) (xy 162.986167 -308.425184) (xy 163.033438 -308.438876) (xy 163.0779 -308.459974)
			(xy 163.118403 -308.48793) (xy 163.153896 -308.522022) (xy 163.183461 -308.561366) (xy 163.206332 -308.604943)
			(xy 163.221916 -308.651624) (xy 163.229811 -308.700201) (xy 163.230306 -308.724808) (xy 163.569154 -308.724808)
			(xy 163.573114 -308.675754) (xy 163.584891 -308.62797) (xy 163.604182 -308.582694) (xy 163.630485 -308.541098)
			(xy 163.66312 -308.504261) (xy 163.701241 -308.473136) (xy 163.743862 -308.448529) (xy 163.789878 -308.431077)
			(xy 163.838097 -308.421233) (xy 163.887272 -308.419252) (xy 163.936127 -308.425184) (xy 163.983398 -308.438876)
			(xy 164.02786 -308.459974) (xy 164.068363 -308.48793) (xy 164.103856 -308.522022) (xy 164.133421 -308.561366)
			(xy 164.156292 -308.604943) (xy 164.171876 -308.651624) (xy 164.179771 -308.700201) (xy 164.180266 -308.724808)
			(xy 164.519114 -308.724808) (xy 164.523074 -308.675754) (xy 164.534851 -308.62797) (xy 164.554142 -308.582694)
			(xy 164.580445 -308.541098) (xy 164.61308 -308.504261) (xy 164.651201 -308.473136) (xy 164.693822 -308.448529)
			(xy 164.739838 -308.431077) (xy 164.788057 -308.421233) (xy 164.837232 -308.419252) (xy 164.886087 -308.425184)
			(xy 164.933358 -308.438876) (xy 164.97782 -308.459974) (xy 165.018323 -308.48793) (xy 165.053816 -308.522022)
			(xy 165.083381 -308.561366) (xy 165.106252 -308.604943) (xy 165.121836 -308.651624) (xy 165.129731 -308.700201)
			(xy 165.130226 -308.724808) (xy 165.129731 -308.749415) (xy 165.121836 -308.797992) (xy 165.106252 -308.844673)
			(xy 165.083381 -308.88825) (xy 165.053816 -308.927594) (xy 165.018323 -308.961686) (xy 164.97782 -308.989642)
			(xy 164.933358 -309.01074) (xy 164.886087 -309.024432) (xy 164.837232 -309.030364) (xy 164.788057 -309.028383)
			(xy 164.739838 -309.018539) (xy 164.693822 -309.001087) (xy 164.651201 -308.97648) (xy 164.61308 -308.945355)
			(xy 164.580445 -308.908518) (xy 164.554142 -308.866922) (xy 164.534851 -308.821646) (xy 164.523074 -308.773862)
			(xy 164.519114 -308.724808) (xy 164.180266 -308.724808) (xy 164.179771 -308.749415) (xy 164.171876 -308.797992)
			(xy 164.156292 -308.844673) (xy 164.133421 -308.88825) (xy 164.103856 -308.927594) (xy 164.068363 -308.961686)
			(xy 164.02786 -308.989642) (xy 163.983398 -309.01074) (xy 163.936127 -309.024432) (xy 163.887272 -309.030364)
			(xy 163.838097 -309.028383) (xy 163.789878 -309.018539) (xy 163.743862 -309.001087) (xy 163.701241 -308.97648)
			(xy 163.66312 -308.945355) (xy 163.630485 -308.908518) (xy 163.604182 -308.866922) (xy 163.584891 -308.821646)
			(xy 163.573114 -308.773862) (xy 163.569154 -308.724808) (xy 163.230306 -308.724808) (xy 163.229811 -308.749415)
			(xy 163.221916 -308.797992) (xy 163.206332 -308.844673) (xy 163.183461 -308.88825) (xy 163.153896 -308.927594)
			(xy 163.118403 -308.961686) (xy 163.0779 -308.989642) (xy 163.033438 -309.01074) (xy 162.986167 -309.024432)
			(xy 162.937312 -309.030364) (xy 162.888137 -309.028383) (xy 162.839918 -309.018539) (xy 162.793902 -309.001087)
			(xy 162.751281 -308.97648) (xy 162.71316 -308.945355) (xy 162.680525 -308.908518) (xy 162.654222 -308.866922)
			(xy 162.634931 -308.821646) (xy 162.623154 -308.773862) (xy 162.619194 -308.724808) (xy 147.263188 -308.724808)
			(xy 147.260571 -308.742592) (xy 147.244503 -308.795999) (xy 147.220831 -308.846496) (xy 147.190058 -308.893009)
			(xy 147.152841 -308.934546) (xy 147.109973 -308.970221) (xy 147.062367 -308.999275) (xy 147.011038 -309.021087)
			(xy 146.957081 -309.035193) (xy 146.901644 -309.041293) (xy 146.84591 -309.039256) (xy 146.791067 -309.029126)
			(xy 146.738283 -309.011119) (xy 146.688683 -308.985618) (xy 146.643325 -308.953167) (xy 146.603176 -308.914458)
			(xy 146.56909 -308.870315) (xy 146.541794 -308.82168) (xy 146.521871 -308.769589) (xy 146.509745 -308.715152)
			(xy 146.505674 -308.65953) (xy 144.878824 -308.65953) (xy 144.862656 -308.683967) (xy 144.825439 -308.725504)
			(xy 144.782571 -308.761179) (xy 144.734965 -308.790233) (xy 144.683636 -308.812045) (xy 144.629679 -308.826151)
			(xy 144.574242 -308.832251) (xy 144.518508 -308.830214) (xy 144.463665 -308.820084) (xy 144.410881 -308.802077)
			(xy 144.361281 -308.776576) (xy 144.315923 -308.744125) (xy 144.275774 -308.705416) (xy 144.241688 -308.661273)
			(xy 144.214392 -308.612638) (xy 144.194469 -308.560547) (xy 144.182343 -308.50611) (xy 144.178272 -308.450488)
			(xy 118.832884 -308.450488) (xy 118.832884 -309.414926) (xy 143.100042 -309.414926) (xy 143.104113 -309.359304)
			(xy 143.116239 -309.304867) (xy 143.136162 -309.252776) (xy 143.163458 -309.204141) (xy 143.197544 -309.159998)
			(xy 143.237693 -309.121289) (xy 143.283051 -309.088838) (xy 143.332651 -309.063337) (xy 143.385435 -309.04533)
			(xy 143.440278 -309.0352) (xy 143.496012 -309.033163) (xy 143.551449 -309.039263) (xy 143.605406 -309.053369)
			(xy 143.656735 -309.075181) (xy 143.704341 -309.104235) (xy 143.747209 -309.13991) (xy 143.784426 -309.181447)
			(xy 143.79656 -309.199788) (xy 152.644106 -309.199788) (xy 152.648066 -309.150734) (xy 152.659843 -309.10295)
			(xy 152.679134 -309.057674) (xy 152.705437 -309.016078) (xy 152.738072 -308.979241) (xy 152.776193 -308.948116)
			(xy 152.818814 -308.923509) (xy 152.86483 -308.906057) (xy 152.913049 -308.896213) (xy 152.962224 -308.894232)
			(xy 153.011079 -308.900164) (xy 153.05835 -308.913856) (xy 153.102812 -308.934954) (xy 153.143315 -308.96291)
			(xy 153.178808 -308.997002) (xy 153.208373 -309.036346) (xy 153.231244 -309.079923) (xy 153.246828 -309.126604)
			(xy 153.254723 -309.175181) (xy 153.255218 -309.199788) (xy 153.594066 -309.199788) (xy 153.598026 -309.150734)
			(xy 153.609803 -309.10295) (xy 153.629094 -309.057674) (xy 153.655397 -309.016078) (xy 153.688032 -308.979241)
			(xy 153.726153 -308.948116) (xy 153.768774 -308.923509) (xy 153.81479 -308.906057) (xy 153.863009 -308.896213)
			(xy 153.912184 -308.894232) (xy 153.961039 -308.900164) (xy 154.00831 -308.913856) (xy 154.052772 -308.934954)
			(xy 154.093275 -308.96291) (xy 154.128768 -308.997002) (xy 154.158333 -309.036346) (xy 154.181204 -309.079923)
			(xy 154.196788 -309.126604) (xy 154.204683 -309.175181) (xy 154.205178 -309.199788) (xy 154.54428 -309.199788)
			(xy 154.54824 -309.150734) (xy 154.560017 -309.10295) (xy 154.579308 -309.057674) (xy 154.605611 -309.016078)
			(xy 154.638246 -308.979241) (xy 154.676367 -308.948116) (xy 154.718988 -308.923509) (xy 154.765004 -308.906057)
			(xy 154.813223 -308.896213) (xy 154.862398 -308.894232) (xy 154.911253 -308.900164) (xy 154.958524 -308.913856)
			(xy 155.002986 -308.934954) (xy 155.043489 -308.96291) (xy 155.078982 -308.997002) (xy 155.108547 -309.036346)
			(xy 155.131418 -309.079923) (xy 155.147002 -309.126604) (xy 155.154897 -309.175181) (xy 155.155392 -309.199788)
			(xy 155.49424 -309.199788) (xy 155.4982 -309.150734) (xy 155.509977 -309.10295) (xy 155.529268 -309.057674)
			(xy 155.555571 -309.016078) (xy 155.588206 -308.979241) (xy 155.626327 -308.948116) (xy 155.668948 -308.923509)
			(xy 155.714964 -308.906057) (xy 155.763183 -308.896213) (xy 155.812358 -308.894232) (xy 155.861213 -308.900164)
			(xy 155.908484 -308.913856) (xy 155.952946 -308.934954) (xy 155.993449 -308.96291) (xy 156.028942 -308.997002)
			(xy 156.058507 -309.036346) (xy 156.081378 -309.079923) (xy 156.096962 -309.126604) (xy 156.104857 -309.175181)
			(xy 156.105352 -309.199788) (xy 156.4442 -309.199788) (xy 156.44816 -309.150734) (xy 156.459937 -309.10295)
			(xy 156.479228 -309.057674) (xy 156.505531 -309.016078) (xy 156.538166 -308.979241) (xy 156.576287 -308.948116)
			(xy 156.618908 -308.923509) (xy 156.664924 -308.906057) (xy 156.713143 -308.896213) (xy 156.762318 -308.894232)
			(xy 156.811173 -308.900164) (xy 156.858444 -308.913856) (xy 156.902906 -308.934954) (xy 156.943409 -308.96291)
			(xy 156.978902 -308.997002) (xy 157.008467 -309.036346) (xy 157.031338 -309.079923) (xy 157.046922 -309.126604)
			(xy 157.054817 -309.175181) (xy 157.055312 -309.199788) (xy 157.39416 -309.199788) (xy 157.39812 -309.150734)
			(xy 157.409897 -309.10295) (xy 157.429188 -309.057674) (xy 157.455491 -309.016078) (xy 157.488126 -308.979241)
			(xy 157.526247 -308.948116) (xy 157.568868 -308.923509) (xy 157.614884 -308.906057) (xy 157.663103 -308.896213)
			(xy 157.712278 -308.894232) (xy 157.761133 -308.900164) (xy 157.808404 -308.913856) (xy 157.852866 -308.934954)
			(xy 157.893369 -308.96291) (xy 157.928862 -308.997002) (xy 157.958427 -309.036346) (xy 157.981298 -309.079923)
			(xy 157.996882 -309.126604) (xy 158.004777 -309.175181) (xy 158.005272 -309.199788) (xy 158.34412 -309.199788)
			(xy 158.34808 -309.150734) (xy 158.359857 -309.10295) (xy 158.379148 -309.057674) (xy 158.405451 -309.016078)
			(xy 158.438086 -308.979241) (xy 158.476207 -308.948116) (xy 158.518828 -308.923509) (xy 158.564844 -308.906057)
			(xy 158.613063 -308.896213) (xy 158.662238 -308.894232) (xy 158.711093 -308.900164) (xy 158.758364 -308.913856)
			(xy 158.802826 -308.934954) (xy 158.843329 -308.96291) (xy 158.878822 -308.997002) (xy 158.908387 -309.036346)
			(xy 158.931258 -309.079923) (xy 158.946842 -309.126604) (xy 158.954737 -309.175181) (xy 158.955232 -309.199788)
			(xy 159.29408 -309.199788) (xy 159.29804 -309.150734) (xy 159.309817 -309.10295) (xy 159.329108 -309.057674)
			(xy 159.355411 -309.016078) (xy 159.388046 -308.979241) (xy 159.426167 -308.948116) (xy 159.468788 -308.923509)
			(xy 159.514804 -308.906057) (xy 159.563023 -308.896213) (xy 159.612198 -308.894232) (xy 159.661053 -308.900164)
			(xy 159.708324 -308.913856) (xy 159.752786 -308.934954) (xy 159.793289 -308.96291) (xy 159.828782 -308.997002)
			(xy 159.858347 -309.036346) (xy 159.881218 -309.079923) (xy 159.896802 -309.126604) (xy 159.904697 -309.175181)
			(xy 159.905192 -309.199788) (xy 160.24404 -309.199788) (xy 160.248 -309.150734) (xy 160.259777 -309.10295)
			(xy 160.279068 -309.057674) (xy 160.305371 -309.016078) (xy 160.338006 -308.979241) (xy 160.376127 -308.948116)
			(xy 160.418748 -308.923509) (xy 160.464764 -308.906057) (xy 160.512983 -308.896213) (xy 160.562158 -308.894232)
			(xy 160.611013 -308.900164) (xy 160.658284 -308.913856) (xy 160.702746 -308.934954) (xy 160.743249 -308.96291)
			(xy 160.778742 -308.997002) (xy 160.808307 -309.036346) (xy 160.831178 -309.079923) (xy 160.846762 -309.126604)
			(xy 160.854657 -309.175181) (xy 160.855152 -309.199788) (xy 161.194254 -309.199788) (xy 161.198214 -309.150734)
			(xy 161.209991 -309.10295) (xy 161.229282 -309.057674) (xy 161.255585 -309.016078) (xy 161.28822 -308.979241)
			(xy 161.326341 -308.948116) (xy 161.368962 -308.923509) (xy 161.414978 -308.906057) (xy 161.463197 -308.896213)
			(xy 161.512372 -308.894232) (xy 161.561227 -308.900164) (xy 161.608498 -308.913856) (xy 161.65296 -308.934954)
			(xy 161.693463 -308.96291) (xy 161.728956 -308.997002) (xy 161.758521 -309.036346) (xy 161.781392 -309.079923)
			(xy 161.796976 -309.126604) (xy 161.804871 -309.175181) (xy 161.805366 -309.199788) (xy 161.804871 -309.224395)
			(xy 161.796976 -309.272972) (xy 161.781392 -309.319653) (xy 161.758521 -309.36323) (xy 161.728956 -309.402574)
			(xy 161.693463 -309.436666) (xy 161.65296 -309.464622) (xy 161.608498 -309.48572) (xy 161.561227 -309.499412)
			(xy 161.512372 -309.505344) (xy 161.463197 -309.503363) (xy 161.414978 -309.493519) (xy 161.368962 -309.476067)
			(xy 161.326341 -309.45146) (xy 161.28822 -309.420335) (xy 161.255585 -309.383498) (xy 161.229282 -309.341902)
			(xy 161.209991 -309.296626) (xy 161.198214 -309.248842) (xy 161.194254 -309.199788) (xy 160.855152 -309.199788)
			(xy 160.854657 -309.224395) (xy 160.846762 -309.272972) (xy 160.831178 -309.319653) (xy 160.808307 -309.36323)
			(xy 160.778742 -309.402574) (xy 160.743249 -309.436666) (xy 160.702746 -309.464622) (xy 160.658284 -309.48572)
			(xy 160.611013 -309.499412) (xy 160.562158 -309.505344) (xy 160.512983 -309.503363) (xy 160.464764 -309.493519)
			(xy 160.418748 -309.476067) (xy 160.376127 -309.45146) (xy 160.338006 -309.420335) (xy 160.305371 -309.383498)
			(xy 160.279068 -309.341902) (xy 160.259777 -309.296626) (xy 160.248 -309.248842) (xy 160.24404 -309.199788)
			(xy 159.905192 -309.199788) (xy 159.904697 -309.224395) (xy 159.896802 -309.272972) (xy 159.881218 -309.319653)
			(xy 159.858347 -309.36323) (xy 159.828782 -309.402574) (xy 159.793289 -309.436666) (xy 159.752786 -309.464622)
			(xy 159.708324 -309.48572) (xy 159.661053 -309.499412) (xy 159.612198 -309.505344) (xy 159.563023 -309.503363)
			(xy 159.514804 -309.493519) (xy 159.468788 -309.476067) (xy 159.426167 -309.45146) (xy 159.388046 -309.420335)
			(xy 159.355411 -309.383498) (xy 159.329108 -309.341902) (xy 159.309817 -309.296626) (xy 159.29804 -309.248842)
			(xy 159.29408 -309.199788) (xy 158.955232 -309.199788) (xy 158.954737 -309.224395) (xy 158.946842 -309.272972)
			(xy 158.931258 -309.319653) (xy 158.908387 -309.36323) (xy 158.878822 -309.402574) (xy 158.843329 -309.436666)
			(xy 158.802826 -309.464622) (xy 158.758364 -309.48572) (xy 158.711093 -309.499412) (xy 158.662238 -309.505344)
			(xy 158.613063 -309.503363) (xy 158.564844 -309.493519) (xy 158.518828 -309.476067) (xy 158.476207 -309.45146)
			(xy 158.438086 -309.420335) (xy 158.405451 -309.383498) (xy 158.379148 -309.341902) (xy 158.359857 -309.296626)
			(xy 158.34808 -309.248842) (xy 158.34412 -309.199788) (xy 158.005272 -309.199788) (xy 158.004777 -309.224395)
			(xy 157.996882 -309.272972) (xy 157.981298 -309.319653) (xy 157.958427 -309.36323) (xy 157.928862 -309.402574)
			(xy 157.893369 -309.436666) (xy 157.852866 -309.464622) (xy 157.808404 -309.48572) (xy 157.761133 -309.499412)
			(xy 157.712278 -309.505344) (xy 157.663103 -309.503363) (xy 157.614884 -309.493519) (xy 157.568868 -309.476067)
			(xy 157.526247 -309.45146) (xy 157.488126 -309.420335) (xy 157.455491 -309.383498) (xy 157.429188 -309.341902)
			(xy 157.409897 -309.296626) (xy 157.39812 -309.248842) (xy 157.39416 -309.199788) (xy 157.055312 -309.199788)
			(xy 157.054817 -309.224395) (xy 157.046922 -309.272972) (xy 157.031338 -309.319653) (xy 157.008467 -309.36323)
			(xy 156.978902 -309.402574) (xy 156.943409 -309.436666) (xy 156.902906 -309.464622) (xy 156.858444 -309.48572)
			(xy 156.811173 -309.499412) (xy 156.762318 -309.505344) (xy 156.713143 -309.503363) (xy 156.664924 -309.493519)
			(xy 156.618908 -309.476067) (xy 156.576287 -309.45146) (xy 156.538166 -309.420335) (xy 156.505531 -309.383498)
			(xy 156.479228 -309.341902) (xy 156.459937 -309.296626) (xy 156.44816 -309.248842) (xy 156.4442 -309.199788)
			(xy 156.105352 -309.199788) (xy 156.104857 -309.224395) (xy 156.096962 -309.272972) (xy 156.081378 -309.319653)
			(xy 156.058507 -309.36323) (xy 156.028942 -309.402574) (xy 155.993449 -309.436666) (xy 155.952946 -309.464622)
			(xy 155.908484 -309.48572) (xy 155.861213 -309.499412) (xy 155.812358 -309.505344) (xy 155.763183 -309.503363)
			(xy 155.714964 -309.493519) (xy 155.668948 -309.476067) (xy 155.626327 -309.45146) (xy 155.588206 -309.420335)
			(xy 155.555571 -309.383498) (xy 155.529268 -309.341902) (xy 155.509977 -309.296626) (xy 155.4982 -309.248842)
			(xy 155.49424 -309.199788) (xy 155.155392 -309.199788) (xy 155.154897 -309.224395) (xy 155.147002 -309.272972)
			(xy 155.131418 -309.319653) (xy 155.108547 -309.36323) (xy 155.078982 -309.402574) (xy 155.043489 -309.436666)
			(xy 155.002986 -309.464622) (xy 154.958524 -309.48572) (xy 154.911253 -309.499412) (xy 154.862398 -309.505344)
			(xy 154.813223 -309.503363) (xy 154.765004 -309.493519) (xy 154.718988 -309.476067) (xy 154.676367 -309.45146)
			(xy 154.638246 -309.420335) (xy 154.605611 -309.383498) (xy 154.579308 -309.341902) (xy 154.560017 -309.296626)
			(xy 154.54824 -309.248842) (xy 154.54428 -309.199788) (xy 154.205178 -309.199788) (xy 154.204683 -309.224395)
			(xy 154.196788 -309.272972) (xy 154.181204 -309.319653) (xy 154.158333 -309.36323) (xy 154.128768 -309.402574)
			(xy 154.093275 -309.436666) (xy 154.052772 -309.464622) (xy 154.00831 -309.48572) (xy 153.961039 -309.499412)
			(xy 153.912184 -309.505344) (xy 153.863009 -309.503363) (xy 153.81479 -309.493519) (xy 153.768774 -309.476067)
			(xy 153.726153 -309.45146) (xy 153.688032 -309.420335) (xy 153.655397 -309.383498) (xy 153.629094 -309.341902)
			(xy 153.609803 -309.296626) (xy 153.598026 -309.248842) (xy 153.594066 -309.199788) (xy 153.255218 -309.199788)
			(xy 153.254723 -309.224395) (xy 153.246828 -309.272972) (xy 153.231244 -309.319653) (xy 153.208373 -309.36323)
			(xy 153.178808 -309.402574) (xy 153.143315 -309.436666) (xy 153.102812 -309.464622) (xy 153.05835 -309.48572)
			(xy 153.011079 -309.499412) (xy 152.962224 -309.505344) (xy 152.913049 -309.503363) (xy 152.86483 -309.493519)
			(xy 152.818814 -309.476067) (xy 152.776193 -309.45146) (xy 152.738072 -309.420335) (xy 152.705437 -309.383498)
			(xy 152.679134 -309.341902) (xy 152.659843 -309.296626) (xy 152.648066 -309.248842) (xy 152.644106 -309.199788)
			(xy 143.79656 -309.199788) (xy 143.815199 -309.22796) (xy 143.838871 -309.278457) (xy 143.854939 -309.331864)
			(xy 143.863059 -309.38704) (xy 143.863568 -309.414926) (xy 143.863059 -309.442812) (xy 143.854939 -309.497988)
			(xy 143.838871 -309.551395) (xy 143.815199 -309.601892) (xy 143.784426 -309.648405) (xy 143.747209 -309.689942)
			(xy 143.704341 -309.725617) (xy 143.656735 -309.754671) (xy 143.605406 -309.776483) (xy 143.551449 -309.790589)
			(xy 143.496012 -309.796689) (xy 143.440278 -309.794652) (xy 143.385435 -309.784522) (xy 143.332651 -309.766515)
			(xy 143.283051 -309.741014) (xy 143.237693 -309.708563) (xy 143.197544 -309.669854) (xy 143.163458 -309.625711)
			(xy 143.136162 -309.577076) (xy 143.116239 -309.524985) (xy 143.104113 -309.470548) (xy 143.100042 -309.414926)
			(xy 118.832884 -309.414926) (xy 118.832884 -309.897272) (xy 150.540464 -309.897272) (xy 150.544535 -309.84165)
			(xy 150.556661 -309.787213) (xy 150.576584 -309.735122) (xy 150.60388 -309.686487) (xy 150.637966 -309.642344)
			(xy 150.678115 -309.603635) (xy 150.723473 -309.571184) (xy 150.773073 -309.545683) (xy 150.825857 -309.527676)
			(xy 150.8807 -309.517546) (xy 150.936434 -309.515509) (xy 150.991871 -309.521609) (xy 151.045828 -309.535715)
			(xy 151.097157 -309.557527) (xy 151.144763 -309.586581) (xy 151.187631 -309.622256) (xy 151.224848 -309.663793)
			(xy 151.255621 -309.710306) (xy 151.279293 -309.760803) (xy 151.295361 -309.81421) (xy 151.303481 -309.869386)
			(xy 151.30399 -309.897272) (xy 151.303481 -309.925158) (xy 151.295361 -309.980334) (xy 151.279293 -310.033741)
			(xy 151.255621 -310.084238) (xy 151.224848 -310.130751) (xy 151.207599 -310.150002) (xy 151.693892 -310.150002)
			(xy 151.697852 -310.100948) (xy 151.709629 -310.053164) (xy 151.72892 -310.007888) (xy 151.755223 -309.966292)
			(xy 151.787858 -309.929455) (xy 151.825979 -309.89833) (xy 151.8686 -309.873723) (xy 151.914616 -309.856271)
			(xy 151.962835 -309.846427) (xy 152.01201 -309.844446) (xy 152.060865 -309.850378) (xy 152.108136 -309.86407)
			(xy 152.152598 -309.885168) (xy 152.193101 -309.913124) (xy 152.228594 -309.947216) (xy 152.258159 -309.98656)
			(xy 152.28103 -310.030137) (xy 152.296614 -310.076818) (xy 152.304509 -310.125395) (xy 152.304999 -310.149748)
			(xy 152.644106 -310.149748) (xy 152.648066 -310.100694) (xy 152.659843 -310.05291) (xy 152.679134 -310.007634)
			(xy 152.705437 -309.966038) (xy 152.738072 -309.929201) (xy 152.776193 -309.898076) (xy 152.818814 -309.873469)
			(xy 152.86483 -309.856017) (xy 152.913049 -309.846173) (xy 152.962224 -309.844192) (xy 153.011079 -309.850124)
			(xy 153.05835 -309.863816) (xy 153.102812 -309.884914) (xy 153.143315 -309.91287) (xy 153.178808 -309.946962)
			(xy 153.208373 -309.986306) (xy 153.231244 -310.029883) (xy 153.246828 -310.076564) (xy 153.254723 -310.125141)
			(xy 153.255218 -310.149748) (xy 153.594066 -310.149748) (xy 153.598026 -310.100694) (xy 153.609803 -310.05291)
			(xy 153.629094 -310.007634) (xy 153.655397 -309.966038) (xy 153.688032 -309.929201) (xy 153.726153 -309.898076)
			(xy 153.768774 -309.873469) (xy 153.81479 -309.856017) (xy 153.863009 -309.846173) (xy 153.912184 -309.844192)
			(xy 153.961039 -309.850124) (xy 154.00831 -309.863816) (xy 154.052772 -309.884914) (xy 154.093275 -309.91287)
			(xy 154.128768 -309.946962) (xy 154.158333 -309.986306) (xy 154.181204 -310.029883) (xy 154.196788 -310.076564)
			(xy 154.204683 -310.125141) (xy 154.205178 -310.149748) (xy 154.54428 -310.149748) (xy 154.54824 -310.100694)
			(xy 154.560017 -310.05291) (xy 154.579308 -310.007634) (xy 154.605611 -309.966038) (xy 154.638246 -309.929201)
			(xy 154.676367 -309.898076) (xy 154.718988 -309.873469) (xy 154.765004 -309.856017) (xy 154.813223 -309.846173)
			(xy 154.862398 -309.844192) (xy 154.911253 -309.850124) (xy 154.958524 -309.863816) (xy 155.002986 -309.884914)
			(xy 155.043489 -309.91287) (xy 155.078982 -309.946962) (xy 155.108547 -309.986306) (xy 155.131418 -310.029883)
			(xy 155.147002 -310.076564) (xy 155.154897 -310.125141) (xy 155.155392 -310.149748) (xy 155.49424 -310.149748)
			(xy 155.4982 -310.100694) (xy 155.509977 -310.05291) (xy 155.529268 -310.007634) (xy 155.555571 -309.966038)
			(xy 155.588206 -309.929201) (xy 155.626327 -309.898076) (xy 155.668948 -309.873469) (xy 155.714964 -309.856017)
			(xy 155.763183 -309.846173) (xy 155.812358 -309.844192) (xy 155.861213 -309.850124) (xy 155.908484 -309.863816)
			(xy 155.952946 -309.884914) (xy 155.993449 -309.91287) (xy 156.028942 -309.946962) (xy 156.058507 -309.986306)
			(xy 156.081378 -310.029883) (xy 156.096962 -310.076564) (xy 156.104857 -310.125141) (xy 156.105352 -310.149748)
			(xy 156.4442 -310.149748) (xy 156.44816 -310.100694) (xy 156.459937 -310.05291) (xy 156.479228 -310.007634)
			(xy 156.505531 -309.966038) (xy 156.538166 -309.929201) (xy 156.576287 -309.898076) (xy 156.618908 -309.873469)
			(xy 156.664924 -309.856017) (xy 156.713143 -309.846173) (xy 156.762318 -309.844192) (xy 156.811173 -309.850124)
			(xy 156.858444 -309.863816) (xy 156.902906 -309.884914) (xy 156.943409 -309.91287) (xy 156.978902 -309.946962)
			(xy 157.008467 -309.986306) (xy 157.031338 -310.029883) (xy 157.046922 -310.076564) (xy 157.054817 -310.125141)
			(xy 157.055312 -310.149748) (xy 157.39416 -310.149748) (xy 157.39812 -310.100694) (xy 157.409897 -310.05291)
			(xy 157.429188 -310.007634) (xy 157.455491 -309.966038) (xy 157.488126 -309.929201) (xy 157.526247 -309.898076)
			(xy 157.568868 -309.873469) (xy 157.614884 -309.856017) (xy 157.663103 -309.846173) (xy 157.712278 -309.844192)
			(xy 157.761133 -309.850124) (xy 157.808404 -309.863816) (xy 157.852866 -309.884914) (xy 157.893369 -309.91287)
			(xy 157.928862 -309.946962) (xy 157.958427 -309.986306) (xy 157.981298 -310.029883) (xy 157.996882 -310.076564)
			(xy 158.004777 -310.125141) (xy 158.005272 -310.149748) (xy 158.34412 -310.149748) (xy 158.34808 -310.100694)
			(xy 158.359857 -310.05291) (xy 158.379148 -310.007634) (xy 158.405451 -309.966038) (xy 158.438086 -309.929201)
			(xy 158.476207 -309.898076) (xy 158.518828 -309.873469) (xy 158.564844 -309.856017) (xy 158.613063 -309.846173)
			(xy 158.662238 -309.844192) (xy 158.711093 -309.850124) (xy 158.758364 -309.863816) (xy 158.802826 -309.884914)
			(xy 158.843329 -309.91287) (xy 158.878822 -309.946962) (xy 158.908387 -309.986306) (xy 158.931258 -310.029883)
			(xy 158.946842 -310.076564) (xy 158.954737 -310.125141) (xy 158.955232 -310.149748) (xy 159.29408 -310.149748)
			(xy 159.29804 -310.100694) (xy 159.309817 -310.05291) (xy 159.329108 -310.007634) (xy 159.355411 -309.966038)
			(xy 159.388046 -309.929201) (xy 159.426167 -309.898076) (xy 159.468788 -309.873469) (xy 159.514804 -309.856017)
			(xy 159.563023 -309.846173) (xy 159.612198 -309.844192) (xy 159.661053 -309.850124) (xy 159.708324 -309.863816)
			(xy 159.752786 -309.884914) (xy 159.793289 -309.91287) (xy 159.828782 -309.946962) (xy 159.858347 -309.986306)
			(xy 159.881218 -310.029883) (xy 159.896802 -310.076564) (xy 159.904697 -310.125141) (xy 159.905192 -310.149748)
			(xy 160.24404 -310.149748) (xy 160.248 -310.100694) (xy 160.259777 -310.05291) (xy 160.279068 -310.007634)
			(xy 160.305371 -309.966038) (xy 160.338006 -309.929201) (xy 160.376127 -309.898076) (xy 160.418748 -309.873469)
			(xy 160.464764 -309.856017) (xy 160.512983 -309.846173) (xy 160.562158 -309.844192) (xy 160.611013 -309.850124)
			(xy 160.658284 -309.863816) (xy 160.702746 -309.884914) (xy 160.743249 -309.91287) (xy 160.778742 -309.946962)
			(xy 160.808307 -309.986306) (xy 160.831178 -310.029883) (xy 160.846762 -310.076564) (xy 160.854657 -310.125141)
			(xy 160.855152 -310.149748) (xy 161.194254 -310.149748) (xy 161.198214 -310.100694) (xy 161.209991 -310.05291)
			(xy 161.229282 -310.007634) (xy 161.255585 -309.966038) (xy 161.28822 -309.929201) (xy 161.326341 -309.898076)
			(xy 161.368962 -309.873469) (xy 161.414978 -309.856017) (xy 161.463197 -309.846173) (xy 161.512372 -309.844192)
			(xy 161.561227 -309.850124) (xy 161.608498 -309.863816) (xy 161.65296 -309.884914) (xy 161.693463 -309.91287)
			(xy 161.728956 -309.946962) (xy 161.758521 -309.986306) (xy 161.781392 -310.029883) (xy 161.796976 -310.076564)
			(xy 161.804871 -310.125141) (xy 161.805198 -310.141392) (xy 162.14433 -310.141392) (xy 162.149701 -310.09205)
			(xy 162.162983 -310.044228) (xy 162.183827 -309.999184) (xy 162.211684 -309.958105) (xy 162.245819 -309.922075)
			(xy 162.285333 -309.892041) (xy 162.329186 -309.868796) (xy 162.376222 -309.852951) (xy 162.425202 -309.844924)
			(xy 162.450018 -309.84444) (xy 162.464201 -309.844613) (xy 162.492441 -309.847288) (xy 162.506406 -309.849774)
			(xy 162.518852 -309.85206) (xy 162.542474 -309.844694) (xy 162.619944 -309.767224) (xy 162.62731 -309.743602)
			(xy 162.625024 -309.731156) (xy 162.622546 -309.71719) (xy 162.619875 -309.688951) (xy 162.61969 -309.674768)
			(xy 162.620212 -309.649513) (xy 162.628525 -309.599691) (xy 162.644926 -309.551917) (xy 162.668967 -309.507494)
			(xy 162.699991 -309.467634) (xy 162.737153 -309.433424) (xy 162.779439 -309.405798) (xy 162.825695 -309.385508)
			(xy 162.87466 -309.373108) (xy 162.924998 -309.368937) (xy 162.975336 -309.373108) (xy 163.024301 -309.385508)
			(xy 163.070557 -309.405798) (xy 163.112843 -309.433424) (xy 163.150005 -309.467634) (xy 163.181029 -309.507494)
			(xy 163.20507 -309.551917) (xy 163.221471 -309.599691) (xy 163.229784 -309.649513) (xy 163.230306 -309.674768)
			(xy 163.230125 -309.688951) (xy 163.227456 -309.717191) (xy 163.224972 -309.731156) (xy 163.222686 -309.743602)
			(xy 163.230052 -309.767224) (xy 163.307522 -309.844694) (xy 163.331144 -309.85206) (xy 163.34359 -309.849774)
			(xy 163.357557 -309.847303) (xy 163.385796 -309.844627) (xy 163.399978 -309.84444) (xy 163.4248 -309.844854)
			(xy 163.473791 -309.852882) (xy 163.520838 -309.86873) (xy 163.564701 -309.89198) (xy 163.604225 -309.92202)
			(xy 163.638369 -309.958059) (xy 163.666232 -309.999147) (xy 163.687082 -310.044201) (xy 163.700368 -310.092034)
			(xy 163.70574 -310.141387) (xy 163.703057 -310.190959) (xy 163.69239 -310.239444) (xy 163.67402 -310.285564)
			(xy 163.64843 -310.328105) (xy 163.616296 -310.365946) (xy 163.578462 -310.398089) (xy 163.535927 -310.423689)
			(xy 163.489811 -310.44207) (xy 163.441328 -310.452748) (xy 163.391757 -310.455442) (xy 163.342403 -310.450081)
			(xy 163.294567 -310.436806) (xy 163.249508 -310.415967) (xy 163.208414 -310.388113) (xy 163.172367 -310.353978)
			(xy 163.142318 -310.31446) (xy 163.119058 -310.270603) (xy 163.103199 -310.223559) (xy 163.09516 -310.17457)
			(xy 163.09467 -310.149748) (xy 163.094854 -310.135565) (xy 163.097521 -310.107325) (xy 163.100004 -310.09336)
			(xy 163.10229 -310.080914) (xy 163.094924 -310.057292) (xy 163.017454 -309.979822) (xy 162.993832 -309.972456)
			(xy 162.981386 -309.974742) (xy 162.96742 -309.977216) (xy 162.93918 -309.97989) (xy 162.924998 -309.980076)
			(xy 162.910815 -309.9799) (xy 162.882575 -309.977228) (xy 162.86861 -309.974742) (xy 162.856164 -309.972456)
			(xy 162.832542 -309.979822) (xy 162.755072 -310.057292) (xy 162.747706 -310.080914) (xy 162.749992 -310.09336)
			(xy 162.752473 -310.107325) (xy 162.755142 -310.135565) (xy 162.755326 -310.149748) (xy 162.75477 -310.174564)
			(xy 162.746733 -310.223542) (xy 162.730878 -310.270575) (xy 162.707623 -310.314422) (xy 162.677581 -310.35393)
			(xy 162.641543 -310.388058) (xy 162.600459 -310.415906) (xy 162.55541 -310.43674) (xy 162.507585 -310.450012)
			(xy 162.458242 -310.455372) (xy 162.408682 -310.452679) (xy 162.360211 -310.442003) (xy 162.314106 -310.423627)
			(xy 162.27158 -310.398034) (xy 162.233755 -310.365898) (xy 162.201628 -310.328066) (xy 162.176044 -310.285535)
			(xy 162.157677 -310.239426) (xy 162.147012 -310.190952) (xy 162.14433 -310.141392) (xy 161.805198 -310.141392)
			(xy 161.805366 -310.149748) (xy 161.804871 -310.174355) (xy 161.796976 -310.222932) (xy 161.781392 -310.269613)
			(xy 161.758521 -310.31319) (xy 161.728956 -310.352534) (xy 161.693463 -310.386626) (xy 161.65296 -310.414582)
			(xy 161.608498 -310.43568) (xy 161.561227 -310.449372) (xy 161.512372 -310.455304) (xy 161.463197 -310.453323)
			(xy 161.414978 -310.443479) (xy 161.368962 -310.426027) (xy 161.326341 -310.40142) (xy 161.28822 -310.370295)
			(xy 161.255585 -310.333458) (xy 161.229282 -310.291862) (xy 161.209991 -310.246586) (xy 161.198214 -310.198802)
			(xy 161.194254 -310.149748) (xy 160.855152 -310.149748) (xy 160.854657 -310.174355) (xy 160.846762 -310.222932)
			(xy 160.831178 -310.269613) (xy 160.808307 -310.31319) (xy 160.778742 -310.352534) (xy 160.743249 -310.386626)
			(xy 160.702746 -310.414582) (xy 160.658284 -310.43568) (xy 160.611013 -310.449372) (xy 160.562158 -310.455304)
			(xy 160.512983 -310.453323) (xy 160.464764 -310.443479) (xy 160.418748 -310.426027) (xy 160.376127 -310.40142)
			(xy 160.338006 -310.370295) (xy 160.305371 -310.333458) (xy 160.279068 -310.291862) (xy 160.259777 -310.246586)
			(xy 160.248 -310.198802) (xy 160.24404 -310.149748) (xy 159.905192 -310.149748) (xy 159.904697 -310.174355)
			(xy 159.896802 -310.222932) (xy 159.881218 -310.269613) (xy 159.858347 -310.31319) (xy 159.828782 -310.352534)
			(xy 159.793289 -310.386626) (xy 159.752786 -310.414582) (xy 159.708324 -310.43568) (xy 159.661053 -310.449372)
			(xy 159.612198 -310.455304) (xy 159.563023 -310.453323) (xy 159.514804 -310.443479) (xy 159.468788 -310.426027)
			(xy 159.426167 -310.40142) (xy 159.388046 -310.370295) (xy 159.355411 -310.333458) (xy 159.329108 -310.291862)
			(xy 159.309817 -310.246586) (xy 159.29804 -310.198802) (xy 159.29408 -310.149748) (xy 158.955232 -310.149748)
			(xy 158.954737 -310.174355) (xy 158.946842 -310.222932) (xy 158.931258 -310.269613) (xy 158.908387 -310.31319)
			(xy 158.878822 -310.352534) (xy 158.843329 -310.386626) (xy 158.802826 -310.414582) (xy 158.758364 -310.43568)
			(xy 158.711093 -310.449372) (xy 158.662238 -310.455304) (xy 158.613063 -310.453323) (xy 158.564844 -310.443479)
			(xy 158.518828 -310.426027) (xy 158.476207 -310.40142) (xy 158.438086 -310.370295) (xy 158.405451 -310.333458)
			(xy 158.379148 -310.291862) (xy 158.359857 -310.246586) (xy 158.34808 -310.198802) (xy 158.34412 -310.149748)
			(xy 158.005272 -310.149748) (xy 158.004777 -310.174355) (xy 157.996882 -310.222932) (xy 157.981298 -310.269613)
			(xy 157.958427 -310.31319) (xy 157.928862 -310.352534) (xy 157.893369 -310.386626) (xy 157.852866 -310.414582)
			(xy 157.808404 -310.43568) (xy 157.761133 -310.449372) (xy 157.712278 -310.455304) (xy 157.663103 -310.453323)
			(xy 157.614884 -310.443479) (xy 157.568868 -310.426027) (xy 157.526247 -310.40142) (xy 157.488126 -310.370295)
			(xy 157.455491 -310.333458) (xy 157.429188 -310.291862) (xy 157.409897 -310.246586) (xy 157.39812 -310.198802)
			(xy 157.39416 -310.149748) (xy 157.055312 -310.149748) (xy 157.054817 -310.174355) (xy 157.046922 -310.222932)
			(xy 157.031338 -310.269613) (xy 157.008467 -310.31319) (xy 156.978902 -310.352534) (xy 156.943409 -310.386626)
			(xy 156.902906 -310.414582) (xy 156.858444 -310.43568) (xy 156.811173 -310.449372) (xy 156.762318 -310.455304)
			(xy 156.713143 -310.453323) (xy 156.664924 -310.443479) (xy 156.618908 -310.426027) (xy 156.576287 -310.40142)
			(xy 156.538166 -310.370295) (xy 156.505531 -310.333458) (xy 156.479228 -310.291862) (xy 156.459937 -310.246586)
			(xy 156.44816 -310.198802) (xy 156.4442 -310.149748) (xy 156.105352 -310.149748) (xy 156.104857 -310.174355)
			(xy 156.096962 -310.222932) (xy 156.081378 -310.269613) (xy 156.058507 -310.31319) (xy 156.028942 -310.352534)
			(xy 155.993449 -310.386626) (xy 155.952946 -310.414582) (xy 155.908484 -310.43568) (xy 155.861213 -310.449372)
			(xy 155.812358 -310.455304) (xy 155.763183 -310.453323) (xy 155.714964 -310.443479) (xy 155.668948 -310.426027)
			(xy 155.626327 -310.40142) (xy 155.588206 -310.370295) (xy 155.555571 -310.333458) (xy 155.529268 -310.291862)
			(xy 155.509977 -310.246586) (xy 155.4982 -310.198802) (xy 155.49424 -310.149748) (xy 155.155392 -310.149748)
			(xy 155.154897 -310.174355) (xy 155.147002 -310.222932) (xy 155.131418 -310.269613) (xy 155.108547 -310.31319)
			(xy 155.078982 -310.352534) (xy 155.043489 -310.386626) (xy 155.002986 -310.414582) (xy 154.958524 -310.43568)
			(xy 154.911253 -310.449372) (xy 154.862398 -310.455304) (xy 154.813223 -310.453323) (xy 154.765004 -310.443479)
			(xy 154.718988 -310.426027) (xy 154.676367 -310.40142) (xy 154.638246 -310.370295) (xy 154.605611 -310.333458)
			(xy 154.579308 -310.291862) (xy 154.560017 -310.246586) (xy 154.54824 -310.198802) (xy 154.54428 -310.149748)
			(xy 154.205178 -310.149748) (xy 154.204683 -310.174355) (xy 154.196788 -310.222932) (xy 154.181204 -310.269613)
			(xy 154.158333 -310.31319) (xy 154.128768 -310.352534) (xy 154.093275 -310.386626) (xy 154.052772 -310.414582)
			(xy 154.00831 -310.43568) (xy 153.961039 -310.449372) (xy 153.912184 -310.455304) (xy 153.863009 -310.453323)
			(xy 153.81479 -310.443479) (xy 153.768774 -310.426027) (xy 153.726153 -310.40142) (xy 153.688032 -310.370295)
			(xy 153.655397 -310.333458) (xy 153.629094 -310.291862) (xy 153.609803 -310.246586) (xy 153.598026 -310.198802)
			(xy 153.594066 -310.149748) (xy 153.255218 -310.149748) (xy 153.254723 -310.174355) (xy 153.246828 -310.222932)
			(xy 153.231244 -310.269613) (xy 153.208373 -310.31319) (xy 153.178808 -310.352534) (xy 153.143315 -310.386626)
			(xy 153.102812 -310.414582) (xy 153.05835 -310.43568) (xy 153.011079 -310.449372) (xy 152.962224 -310.455304)
			(xy 152.913049 -310.453323) (xy 152.86483 -310.443479) (xy 152.818814 -310.426027) (xy 152.776193 -310.40142)
			(xy 152.738072 -310.370295) (xy 152.705437 -310.333458) (xy 152.679134 -310.291862) (xy 152.659843 -310.246586)
			(xy 152.648066 -310.198802) (xy 152.644106 -310.149748) (xy 152.304999 -310.149748) (xy 152.305004 -310.150002)
			(xy 152.304509 -310.174609) (xy 152.296614 -310.223186) (xy 152.28103 -310.269867) (xy 152.258159 -310.313444)
			(xy 152.228594 -310.352788) (xy 152.193101 -310.38688) (xy 152.152598 -310.414836) (xy 152.108136 -310.435934)
			(xy 152.060865 -310.449626) (xy 152.01201 -310.455558) (xy 151.962835 -310.453577) (xy 151.914616 -310.443733)
			(xy 151.8686 -310.426281) (xy 151.825979 -310.401674) (xy 151.787858 -310.370549) (xy 151.755223 -310.333712)
			(xy 151.72892 -310.292116) (xy 151.709629 -310.24684) (xy 151.697852 -310.199056) (xy 151.693892 -310.150002)
			(xy 151.207599 -310.150002) (xy 151.187631 -310.172288) (xy 151.144763 -310.207963) (xy 151.097157 -310.237017)
			(xy 151.045828 -310.258829) (xy 150.991871 -310.272935) (xy 150.936434 -310.279035) (xy 150.8807 -310.276998)
			(xy 150.825857 -310.266868) (xy 150.773073 -310.248861) (xy 150.723473 -310.22336) (xy 150.678115 -310.190909)
			(xy 150.637966 -310.1522) (xy 150.60388 -310.108057) (xy 150.576584 -310.059422) (xy 150.556661 -310.007331)
			(xy 150.544535 -309.952894) (xy 150.540464 -309.897272) (xy 118.832884 -309.897272) (xy 118.832884 -310.832246)
			(xy 144.36801 -310.832246) (xy 144.372081 -310.776624) (xy 144.384207 -310.722187) (xy 144.40413 -310.670096)
			(xy 144.431426 -310.621461) (xy 144.465512 -310.577318) (xy 144.505661 -310.538609) (xy 144.551019 -310.506158)
			(xy 144.600619 -310.480657) (xy 144.653403 -310.46265) (xy 144.708246 -310.45252) (xy 144.76398 -310.450483)
			(xy 144.819417 -310.456583) (xy 144.873374 -310.470689) (xy 144.924703 -310.492501) (xy 144.972309 -310.521555)
			(xy 145.015177 -310.55723) (xy 145.052394 -310.598767) (xy 145.083167 -310.64528) (xy 145.106839 -310.695777)
			(xy 145.122907 -310.749184) (xy 145.131027 -310.80436) (xy 145.131536 -310.832246) (xy 145.131027 -310.860132)
			(xy 145.122907 -310.915308) (xy 145.106839 -310.968715) (xy 145.084725 -311.015888) (xy 150.371808 -311.015888)
			(xy 150.375879 -310.960266) (xy 150.388005 -310.905829) (xy 150.407928 -310.853738) (xy 150.435224 -310.805103)
			(xy 150.46931 -310.76096) (xy 150.509459 -310.722251) (xy 150.554817 -310.6898) (xy 150.604417 -310.664299)
			(xy 150.657201 -310.646292) (xy 150.712044 -310.636162) (xy 150.767778 -310.634125) (xy 150.823215 -310.640225)
			(xy 150.877172 -310.654331) (xy 150.928501 -310.676143) (xy 150.976107 -310.705197) (xy 151.018975 -310.740872)
			(xy 151.056192 -310.782409) (xy 151.086965 -310.828922) (xy 151.110637 -310.879419) (xy 151.126705 -310.932826)
			(xy 151.134825 -310.988002) (xy 151.135334 -311.015888) (xy 151.134825 -311.043774) (xy 151.126705 -311.09895)
			(xy 151.126401 -311.099962) (xy 152.644106 -311.099962) (xy 152.648066 -311.050908) (xy 152.659843 -311.003124)
			(xy 152.679134 -310.957848) (xy 152.705437 -310.916252) (xy 152.738072 -310.879415) (xy 152.776193 -310.84829)
			(xy 152.818814 -310.823683) (xy 152.86483 -310.806231) (xy 152.913049 -310.796387) (xy 152.962224 -310.794406)
			(xy 153.011079 -310.800338) (xy 153.05835 -310.81403) (xy 153.102812 -310.835128) (xy 153.143315 -310.863084)
			(xy 153.178808 -310.897176) (xy 153.208373 -310.93652) (xy 153.231244 -310.980097) (xy 153.246828 -311.026778)
			(xy 153.254723 -311.075355) (xy 153.255218 -311.099962) (xy 153.594066 -311.099962) (xy 153.598026 -311.050908)
			(xy 153.609803 -311.003124) (xy 153.629094 -310.957848) (xy 153.655397 -310.916252) (xy 153.688032 -310.879415)
			(xy 153.726153 -310.84829) (xy 153.768774 -310.823683) (xy 153.81479 -310.806231) (xy 153.863009 -310.796387)
			(xy 153.912184 -310.794406) (xy 153.961039 -310.800338) (xy 154.00831 -310.81403) (xy 154.052772 -310.835128)
			(xy 154.093275 -310.863084) (xy 154.128768 -310.897176) (xy 154.158333 -310.93652) (xy 154.181204 -310.980097)
			(xy 154.196788 -311.026778) (xy 154.204683 -311.075355) (xy 154.205178 -311.099962) (xy 154.54428 -311.099962)
			(xy 154.54824 -311.050908) (xy 154.560017 -311.003124) (xy 154.579308 -310.957848) (xy 154.605611 -310.916252)
			(xy 154.638246 -310.879415) (xy 154.676367 -310.84829) (xy 154.718988 -310.823683) (xy 154.765004 -310.806231)
			(xy 154.813223 -310.796387) (xy 154.862398 -310.794406) (xy 154.911253 -310.800338) (xy 154.958524 -310.81403)
			(xy 155.002986 -310.835128) (xy 155.043489 -310.863084) (xy 155.078982 -310.897176) (xy 155.108547 -310.93652)
			(xy 155.131418 -310.980097) (xy 155.147002 -311.026778) (xy 155.154897 -311.075355) (xy 155.155392 -311.099962)
			(xy 155.49424 -311.099962) (xy 155.4982 -311.050908) (xy 155.509977 -311.003124) (xy 155.529268 -310.957848)
			(xy 155.555571 -310.916252) (xy 155.588206 -310.879415) (xy 155.626327 -310.84829) (xy 155.668948 -310.823683)
			(xy 155.714964 -310.806231) (xy 155.763183 -310.796387) (xy 155.812358 -310.794406) (xy 155.861213 -310.800338)
			(xy 155.908484 -310.81403) (xy 155.952946 -310.835128) (xy 155.993449 -310.863084) (xy 156.028942 -310.897176)
			(xy 156.058507 -310.93652) (xy 156.081378 -310.980097) (xy 156.096962 -311.026778) (xy 156.104857 -311.075355)
			(xy 156.105352 -311.099962) (xy 156.4442 -311.099962) (xy 156.44816 -311.050908) (xy 156.459937 -311.003124)
			(xy 156.479228 -310.957848) (xy 156.505531 -310.916252) (xy 156.538166 -310.879415) (xy 156.576287 -310.84829)
			(xy 156.618908 -310.823683) (xy 156.664924 -310.806231) (xy 156.713143 -310.796387) (xy 156.762318 -310.794406)
			(xy 156.811173 -310.800338) (xy 156.858444 -310.81403) (xy 156.902906 -310.835128) (xy 156.943409 -310.863084)
			(xy 156.978902 -310.897176) (xy 157.008467 -310.93652) (xy 157.031338 -310.980097) (xy 157.046922 -311.026778)
			(xy 157.054817 -311.075355) (xy 157.055312 -311.099962) (xy 157.39416 -311.099962) (xy 157.39812 -311.050908)
			(xy 157.409897 -311.003124) (xy 157.429188 -310.957848) (xy 157.455491 -310.916252) (xy 157.488126 -310.879415)
			(xy 157.526247 -310.84829) (xy 157.568868 -310.823683) (xy 157.614884 -310.806231) (xy 157.663103 -310.796387)
			(xy 157.712278 -310.794406) (xy 157.761133 -310.800338) (xy 157.808404 -310.81403) (xy 157.852866 -310.835128)
			(xy 157.893369 -310.863084) (xy 157.928862 -310.897176) (xy 157.958427 -310.93652) (xy 157.981298 -310.980097)
			(xy 157.996882 -311.026778) (xy 158.004777 -311.075355) (xy 158.005272 -311.099962) (xy 158.34412 -311.099962)
			(xy 158.34808 -311.050908) (xy 158.359857 -311.003124) (xy 158.379148 -310.957848) (xy 158.405451 -310.916252)
			(xy 158.438086 -310.879415) (xy 158.476207 -310.84829) (xy 158.518828 -310.823683) (xy 158.564844 -310.806231)
			(xy 158.613063 -310.796387) (xy 158.662238 -310.794406) (xy 158.711093 -310.800338) (xy 158.758364 -310.81403)
			(xy 158.802826 -310.835128) (xy 158.843329 -310.863084) (xy 158.878822 -310.897176) (xy 158.908387 -310.93652)
			(xy 158.931258 -310.980097) (xy 158.946842 -311.026778) (xy 158.954737 -311.075355) (xy 158.955232 -311.099962)
			(xy 159.29408 -311.099962) (xy 159.29804 -311.050908) (xy 159.309817 -311.003124) (xy 159.329108 -310.957848)
			(xy 159.355411 -310.916252) (xy 159.388046 -310.879415) (xy 159.426167 -310.84829) (xy 159.468788 -310.823683)
			(xy 159.514804 -310.806231) (xy 159.563023 -310.796387) (xy 159.612198 -310.794406) (xy 159.661053 -310.800338)
			(xy 159.708324 -310.81403) (xy 159.752786 -310.835128) (xy 159.793289 -310.863084) (xy 159.828782 -310.897176)
			(xy 159.858347 -310.93652) (xy 159.881218 -310.980097) (xy 159.896802 -311.026778) (xy 159.904697 -311.075355)
			(xy 159.905192 -311.099962) (xy 160.24404 -311.099962) (xy 160.248 -311.050908) (xy 160.259777 -311.003124)
			(xy 160.279068 -310.957848) (xy 160.305371 -310.916252) (xy 160.338006 -310.879415) (xy 160.376127 -310.84829)
			(xy 160.418748 -310.823683) (xy 160.464764 -310.806231) (xy 160.512983 -310.796387) (xy 160.562158 -310.794406)
			(xy 160.611013 -310.800338) (xy 160.658284 -310.81403) (xy 160.702746 -310.835128) (xy 160.743249 -310.863084)
			(xy 160.778742 -310.897176) (xy 160.808307 -310.93652) (xy 160.831178 -310.980097) (xy 160.846762 -311.026778)
			(xy 160.854657 -311.075355) (xy 160.855152 -311.099962) (xy 161.194254 -311.099962) (xy 161.198214 -311.050908)
			(xy 161.209991 -311.003124) (xy 161.229282 -310.957848) (xy 161.255585 -310.916252) (xy 161.28822 -310.879415)
			(xy 161.326341 -310.84829) (xy 161.368962 -310.823683) (xy 161.414978 -310.806231) (xy 161.463197 -310.796387)
			(xy 161.512372 -310.794406) (xy 161.561227 -310.800338) (xy 161.608498 -310.81403) (xy 161.65296 -310.835128)
			(xy 161.693463 -310.863084) (xy 161.728956 -310.897176) (xy 161.758521 -310.93652) (xy 161.781392 -310.980097)
			(xy 161.796976 -311.026778) (xy 161.804871 -311.075355) (xy 161.805366 -311.099962) (xy 162.144214 -311.099962)
			(xy 162.148174 -311.050908) (xy 162.159951 -311.003124) (xy 162.179242 -310.957848) (xy 162.205545 -310.916252)
			(xy 162.23818 -310.879415) (xy 162.276301 -310.84829) (xy 162.318922 -310.823683) (xy 162.364938 -310.806231)
			(xy 162.413157 -310.796387) (xy 162.462332 -310.794406) (xy 162.511187 -310.800338) (xy 162.558458 -310.81403)
			(xy 162.60292 -310.835128) (xy 162.643423 -310.863084) (xy 162.678916 -310.897176) (xy 162.708481 -310.93652)
			(xy 162.731352 -310.980097) (xy 162.746936 -311.026778) (xy 162.754831 -311.075355) (xy 162.755326 -311.099962)
			(xy 163.094174 -311.099962) (xy 163.098134 -311.050908) (xy 163.109911 -311.003124) (xy 163.129202 -310.957848)
			(xy 163.155505 -310.916252) (xy 163.18814 -310.879415) (xy 163.226261 -310.84829) (xy 163.268882 -310.823683)
			(xy 163.314898 -310.806231) (xy 163.363117 -310.796387) (xy 163.412292 -310.794406) (xy 163.461147 -310.800338)
			(xy 163.508418 -310.81403) (xy 163.55288 -310.835128) (xy 163.593383 -310.863084) (xy 163.628876 -310.897176)
			(xy 163.658441 -310.93652) (xy 163.681312 -310.980097) (xy 163.696896 -311.026778) (xy 163.704791 -311.075355)
			(xy 163.705286 -311.099962) (xy 163.704791 -311.124569) (xy 163.696896 -311.173146) (xy 163.681312 -311.219827)
			(xy 163.658441 -311.263404) (xy 163.628876 -311.302748) (xy 163.593383 -311.33684) (xy 163.55288 -311.364796)
			(xy 163.508418 -311.385894) (xy 163.461147 -311.399586) (xy 163.412292 -311.405518) (xy 163.363117 -311.403537)
			(xy 163.314898 -311.393693) (xy 163.268882 -311.376241) (xy 163.226261 -311.351634) (xy 163.18814 -311.320509)
			(xy 163.155505 -311.283672) (xy 163.129202 -311.242076) (xy 163.109911 -311.1968) (xy 163.098134 -311.149016)
			(xy 163.094174 -311.099962) (xy 162.755326 -311.099962) (xy 162.754831 -311.124569) (xy 162.746936 -311.173146)
			(xy 162.731352 -311.219827) (xy 162.708481 -311.263404) (xy 162.678916 -311.302748) (xy 162.643423 -311.33684)
			(xy 162.60292 -311.364796) (xy 162.558458 -311.385894) (xy 162.511187 -311.399586) (xy 162.462332 -311.405518)
			(xy 162.413157 -311.403537) (xy 162.364938 -311.393693) (xy 162.318922 -311.376241) (xy 162.276301 -311.351634)
			(xy 162.23818 -311.320509) (xy 162.205545 -311.283672) (xy 162.179242 -311.242076) (xy 162.159951 -311.1968)
			(xy 162.148174 -311.149016) (xy 162.144214 -311.099962) (xy 161.805366 -311.099962) (xy 161.804871 -311.124569)
			(xy 161.796976 -311.173146) (xy 161.781392 -311.219827) (xy 161.758521 -311.263404) (xy 161.728956 -311.302748)
			(xy 161.693463 -311.33684) (xy 161.65296 -311.364796) (xy 161.608498 -311.385894) (xy 161.561227 -311.399586)
			(xy 161.512372 -311.405518) (xy 161.463197 -311.403537) (xy 161.414978 -311.393693) (xy 161.368962 -311.376241)
			(xy 161.326341 -311.351634) (xy 161.28822 -311.320509) (xy 161.255585 -311.283672) (xy 161.229282 -311.242076)
			(xy 161.209991 -311.1968) (xy 161.198214 -311.149016) (xy 161.194254 -311.099962) (xy 160.855152 -311.099962)
			(xy 160.854657 -311.124569) (xy 160.846762 -311.173146) (xy 160.831178 -311.219827) (xy 160.808307 -311.263404)
			(xy 160.778742 -311.302748) (xy 160.743249 -311.33684) (xy 160.702746 -311.364796) (xy 160.658284 -311.385894)
			(xy 160.611013 -311.399586) (xy 160.562158 -311.405518) (xy 160.512983 -311.403537) (xy 160.464764 -311.393693)
			(xy 160.418748 -311.376241) (xy 160.376127 -311.351634) (xy 160.338006 -311.320509) (xy 160.305371 -311.283672)
			(xy 160.279068 -311.242076) (xy 160.259777 -311.1968) (xy 160.248 -311.149016) (xy 160.24404 -311.099962)
			(xy 159.905192 -311.099962) (xy 159.904697 -311.124569) (xy 159.896802 -311.173146) (xy 159.881218 -311.219827)
			(xy 159.858347 -311.263404) (xy 159.828782 -311.302748) (xy 159.793289 -311.33684) (xy 159.752786 -311.364796)
			(xy 159.708324 -311.385894) (xy 159.661053 -311.399586) (xy 159.612198 -311.405518) (xy 159.563023 -311.403537)
			(xy 159.514804 -311.393693) (xy 159.468788 -311.376241) (xy 159.426167 -311.351634) (xy 159.388046 -311.320509)
			(xy 159.355411 -311.283672) (xy 159.329108 -311.242076) (xy 159.309817 -311.1968) (xy 159.29804 -311.149016)
			(xy 159.29408 -311.099962) (xy 158.955232 -311.099962) (xy 158.954737 -311.124569) (xy 158.946842 -311.173146)
			(xy 158.931258 -311.219827) (xy 158.908387 -311.263404) (xy 158.878822 -311.302748) (xy 158.843329 -311.33684)
			(xy 158.802826 -311.364796) (xy 158.758364 -311.385894) (xy 158.711093 -311.399586) (xy 158.662238 -311.405518)
			(xy 158.613063 -311.403537) (xy 158.564844 -311.393693) (xy 158.518828 -311.376241) (xy 158.476207 -311.351634)
			(xy 158.438086 -311.320509) (xy 158.405451 -311.283672) (xy 158.379148 -311.242076) (xy 158.359857 -311.1968)
			(xy 158.34808 -311.149016) (xy 158.34412 -311.099962) (xy 158.005272 -311.099962) (xy 158.004777 -311.124569)
			(xy 157.996882 -311.173146) (xy 157.981298 -311.219827) (xy 157.958427 -311.263404) (xy 157.928862 -311.302748)
			(xy 157.893369 -311.33684) (xy 157.852866 -311.364796) (xy 157.808404 -311.385894) (xy 157.761133 -311.399586)
			(xy 157.712278 -311.405518) (xy 157.663103 -311.403537) (xy 157.614884 -311.393693) (xy 157.568868 -311.376241)
			(xy 157.526247 -311.351634) (xy 157.488126 -311.320509) (xy 157.455491 -311.283672) (xy 157.429188 -311.242076)
			(xy 157.409897 -311.1968) (xy 157.39812 -311.149016) (xy 157.39416 -311.099962) (xy 157.055312 -311.099962)
			(xy 157.054817 -311.124569) (xy 157.046922 -311.173146) (xy 157.031338 -311.219827) (xy 157.008467 -311.263404)
			(xy 156.978902 -311.302748) (xy 156.943409 -311.33684) (xy 156.902906 -311.364796) (xy 156.858444 -311.385894)
			(xy 156.811173 -311.399586) (xy 156.762318 -311.405518) (xy 156.713143 -311.403537) (xy 156.664924 -311.393693)
			(xy 156.618908 -311.376241) (xy 156.576287 -311.351634) (xy 156.538166 -311.320509) (xy 156.505531 -311.283672)
			(xy 156.479228 -311.242076) (xy 156.459937 -311.1968) (xy 156.44816 -311.149016) (xy 156.4442 -311.099962)
			(xy 156.105352 -311.099962) (xy 156.104857 -311.124569) (xy 156.096962 -311.173146) (xy 156.081378 -311.219827)
			(xy 156.058507 -311.263404) (xy 156.028942 -311.302748) (xy 155.993449 -311.33684) (xy 155.952946 -311.364796)
			(xy 155.908484 -311.385894) (xy 155.861213 -311.399586) (xy 155.812358 -311.405518) (xy 155.763183 -311.403537)
			(xy 155.714964 -311.393693) (xy 155.668948 -311.376241) (xy 155.626327 -311.351634) (xy 155.588206 -311.320509)
			(xy 155.555571 -311.283672) (xy 155.529268 -311.242076) (xy 155.509977 -311.1968) (xy 155.4982 -311.149016)
			(xy 155.49424 -311.099962) (xy 155.155392 -311.099962) (xy 155.154897 -311.124569) (xy 155.147002 -311.173146)
			(xy 155.131418 -311.219827) (xy 155.108547 -311.263404) (xy 155.078982 -311.302748) (xy 155.043489 -311.33684)
			(xy 155.002986 -311.364796) (xy 154.958524 -311.385894) (xy 154.911253 -311.399586) (xy 154.862398 -311.405518)
			(xy 154.813223 -311.403537) (xy 154.765004 -311.393693) (xy 154.718988 -311.376241) (xy 154.676367 -311.351634)
			(xy 154.638246 -311.320509) (xy 154.605611 -311.283672) (xy 154.579308 -311.242076) (xy 154.560017 -311.1968)
			(xy 154.54824 -311.149016) (xy 154.54428 -311.099962) (xy 154.205178 -311.099962) (xy 154.204683 -311.124569)
			(xy 154.196788 -311.173146) (xy 154.181204 -311.219827) (xy 154.158333 -311.263404) (xy 154.128768 -311.302748)
			(xy 154.093275 -311.33684) (xy 154.052772 -311.364796) (xy 154.00831 -311.385894) (xy 153.961039 -311.399586)
			(xy 153.912184 -311.405518) (xy 153.863009 -311.403537) (xy 153.81479 -311.393693) (xy 153.768774 -311.376241)
			(xy 153.726153 -311.351634) (xy 153.688032 -311.320509) (xy 153.655397 -311.283672) (xy 153.629094 -311.242076)
			(xy 153.609803 -311.1968) (xy 153.598026 -311.149016) (xy 153.594066 -311.099962) (xy 153.255218 -311.099962)
			(xy 153.254723 -311.124569) (xy 153.246828 -311.173146) (xy 153.231244 -311.219827) (xy 153.208373 -311.263404)
			(xy 153.178808 -311.302748) (xy 153.143315 -311.33684) (xy 153.102812 -311.364796) (xy 153.05835 -311.385894)
			(xy 153.011079 -311.399586) (xy 152.962224 -311.405518) (xy 152.913049 -311.403537) (xy 152.86483 -311.393693)
			(xy 152.818814 -311.376241) (xy 152.776193 -311.351634) (xy 152.738072 -311.320509) (xy 152.705437 -311.283672)
			(xy 152.679134 -311.242076) (xy 152.659843 -311.1968) (xy 152.648066 -311.149016) (xy 152.644106 -311.099962)
			(xy 151.126401 -311.099962) (xy 151.110637 -311.152357) (xy 151.086965 -311.202854) (xy 151.056192 -311.249367)
			(xy 151.018975 -311.290904) (xy 150.976107 -311.326579) (xy 150.928501 -311.355633) (xy 150.877172 -311.377445)
			(xy 150.823215 -311.391551) (xy 150.767778 -311.397651) (xy 150.712044 -311.395614) (xy 150.657201 -311.385484)
			(xy 150.604417 -311.367477) (xy 150.554817 -311.341976) (xy 150.509459 -311.309525) (xy 150.46931 -311.270816)
			(xy 150.435224 -311.226673) (xy 150.407928 -311.178038) (xy 150.388005 -311.125947) (xy 150.375879 -311.07151)
			(xy 150.371808 -311.015888) (xy 145.084725 -311.015888) (xy 145.083167 -311.019212) (xy 145.052394 -311.065725)
			(xy 145.015177 -311.107262) (xy 144.972309 -311.142937) (xy 144.924703 -311.171991) (xy 144.873374 -311.193803)
			(xy 144.819417 -311.207909) (xy 144.76398 -311.214009) (xy 144.708246 -311.211972) (xy 144.653403 -311.201842)
			(xy 144.600619 -311.183835) (xy 144.551019 -311.158334) (xy 144.505661 -311.125883) (xy 144.465512 -311.087174)
			(xy 144.431426 -311.043031) (xy 144.40413 -310.994396) (xy 144.384207 -310.942305) (xy 144.372081 -310.887868)
			(xy 144.36801 -310.832246) (xy 118.832884 -310.832246) (xy 118.832884 -311.7342) (xy 148.58949 -311.7342)
			(xy 148.593561 -311.678578) (xy 148.605687 -311.624141) (xy 148.62561 -311.57205) (xy 148.652906 -311.523415)
			(xy 148.686992 -311.479272) (xy 148.727141 -311.440563) (xy 148.772499 -311.408112) (xy 148.822099 -311.382611)
			(xy 148.874883 -311.364604) (xy 148.929726 -311.354474) (xy 148.98546 -311.352437) (xy 149.040897 -311.358537)
			(xy 149.094854 -311.372643) (xy 149.146183 -311.394455) (xy 149.193789 -311.423509) (xy 149.236657 -311.459184)
			(xy 149.273874 -311.500721) (xy 149.304647 -311.547234) (xy 149.328319 -311.597731) (xy 149.344387 -311.651138)
			(xy 149.352507 -311.706314) (xy 149.353016 -311.7342) (xy 149.352507 -311.762086) (xy 149.344387 -311.817262)
			(xy 149.328319 -311.870669) (xy 149.304647 -311.921166) (xy 149.273874 -311.967679) (xy 149.236657 -312.009216)
			(xy 149.193789 -312.044891) (xy 149.146183 -312.073945) (xy 149.094854 -312.095757) (xy 149.040897 -312.109863)
			(xy 148.98546 -312.115963) (xy 148.929726 -312.113926) (xy 148.874883 -312.103796) (xy 148.822099 -312.085789)
			(xy 148.772499 -312.060288) (xy 148.727141 -312.027837) (xy 148.686992 -311.989128) (xy 148.652906 -311.944985)
			(xy 148.62561 -311.89635) (xy 148.605687 -311.844259) (xy 148.593561 -311.789822) (xy 148.58949 -311.7342)
			(xy 118.832884 -311.7342) (xy 118.832884 -312.523378) (xy 147.832062 -312.523378) (xy 147.836133 -312.467756)
			(xy 147.848259 -312.413319) (xy 147.868182 -312.361228) (xy 147.895478 -312.312593) (xy 147.929564 -312.26845)
			(xy 147.969713 -312.229741) (xy 148.015071 -312.19729) (xy 148.064671 -312.171789) (xy 148.117455 -312.153782)
			(xy 148.172298 -312.143652) (xy 148.228032 -312.141615) (xy 148.283469 -312.147715) (xy 148.337426 -312.161821)
			(xy 148.388755 -312.183633) (xy 148.436361 -312.212687) (xy 148.479229 -312.248362) (xy 148.496921 -312.268108)
			(xy 150.210772 -312.268108) (xy 150.214843 -312.212486) (xy 150.226969 -312.158049) (xy 150.246892 -312.105958)
			(xy 150.274188 -312.057323) (xy 150.308274 -312.01318) (xy 150.348423 -311.974471) (xy 150.393781 -311.94202)
			(xy 150.443381 -311.916519) (xy 150.496165 -311.898512) (xy 150.551008 -311.888382) (xy 150.606742 -311.886345)
			(xy 150.662179 -311.892445) (xy 150.716136 -311.906551) (xy 150.767465 -311.928363) (xy 150.815071 -311.957417)
			(xy 150.857939 -311.993092) (xy 150.895156 -312.034629) (xy 150.905106 -312.049668) (xy 151.693892 -312.049668)
			(xy 151.697852 -312.000614) (xy 151.709629 -311.95283) (xy 151.72892 -311.907554) (xy 151.755223 -311.865958)
			(xy 151.787858 -311.829121) (xy 151.825979 -311.797996) (xy 151.8686 -311.773389) (xy 151.914616 -311.755937)
			(xy 151.962835 -311.746093) (xy 152.01201 -311.744112) (xy 152.060865 -311.750044) (xy 152.108136 -311.763736)
			(xy 152.152598 -311.784834) (xy 152.193101 -311.81279) (xy 152.228594 -311.846882) (xy 152.258159 -311.886226)
			(xy 152.28103 -311.929803) (xy 152.296614 -311.976484) (xy 152.304509 -312.025061) (xy 152.305004 -312.049668)
			(xy 152.304999 -312.049922) (xy 152.644106 -312.049922) (xy 152.648066 -312.000868) (xy 152.659843 -311.953084)
			(xy 152.679134 -311.907808) (xy 152.705437 -311.866212) (xy 152.738072 -311.829375) (xy 152.776193 -311.79825)
			(xy 152.818814 -311.773643) (xy 152.86483 -311.756191) (xy 152.913049 -311.746347) (xy 152.962224 -311.744366)
			(xy 153.011079 -311.750298) (xy 153.05835 -311.76399) (xy 153.102812 -311.785088) (xy 153.143315 -311.813044)
			(xy 153.178808 -311.847136) (xy 153.208373 -311.88648) (xy 153.231244 -311.930057) (xy 153.246828 -311.976738)
			(xy 153.254723 -312.025315) (xy 153.255218 -312.049922) (xy 153.594066 -312.049922) (xy 153.598026 -312.000868)
			(xy 153.609803 -311.953084) (xy 153.629094 -311.907808) (xy 153.655397 -311.866212) (xy 153.688032 -311.829375)
			(xy 153.726153 -311.79825) (xy 153.768774 -311.773643) (xy 153.81479 -311.756191) (xy 153.863009 -311.746347)
			(xy 153.912184 -311.744366) (xy 153.961039 -311.750298) (xy 154.00831 -311.76399) (xy 154.052772 -311.785088)
			(xy 154.093275 -311.813044) (xy 154.128768 -311.847136) (xy 154.158333 -311.88648) (xy 154.181204 -311.930057)
			(xy 154.196788 -311.976738) (xy 154.204683 -312.025315) (xy 154.205178 -312.049922) (xy 154.54428 -312.049922)
			(xy 154.54824 -312.000868) (xy 154.560017 -311.953084) (xy 154.579308 -311.907808) (xy 154.605611 -311.866212)
			(xy 154.638246 -311.829375) (xy 154.676367 -311.79825) (xy 154.718988 -311.773643) (xy 154.765004 -311.756191)
			(xy 154.813223 -311.746347) (xy 154.862398 -311.744366) (xy 154.911253 -311.750298) (xy 154.958524 -311.76399)
			(xy 155.002986 -311.785088) (xy 155.043489 -311.813044) (xy 155.078982 -311.847136) (xy 155.108547 -311.88648)
			(xy 155.131418 -311.930057) (xy 155.147002 -311.976738) (xy 155.154897 -312.025315) (xy 155.155392 -312.049922)
			(xy 155.49424 -312.049922) (xy 155.4982 -312.000868) (xy 155.509977 -311.953084) (xy 155.529268 -311.907808)
			(xy 155.555571 -311.866212) (xy 155.588206 -311.829375) (xy 155.626327 -311.79825) (xy 155.668948 -311.773643)
			(xy 155.714964 -311.756191) (xy 155.763183 -311.746347) (xy 155.812358 -311.744366) (xy 155.861213 -311.750298)
			(xy 155.908484 -311.76399) (xy 155.952946 -311.785088) (xy 155.993449 -311.813044) (xy 156.028942 -311.847136)
			(xy 156.058507 -311.88648) (xy 156.081378 -311.930057) (xy 156.096962 -311.976738) (xy 156.104857 -312.025315)
			(xy 156.105352 -312.049922) (xy 156.4442 -312.049922) (xy 156.44816 -312.000868) (xy 156.459937 -311.953084)
			(xy 156.479228 -311.907808) (xy 156.505531 -311.866212) (xy 156.538166 -311.829375) (xy 156.576287 -311.79825)
			(xy 156.618908 -311.773643) (xy 156.664924 -311.756191) (xy 156.713143 -311.746347) (xy 156.762318 -311.744366)
			(xy 156.811173 -311.750298) (xy 156.858444 -311.76399) (xy 156.902906 -311.785088) (xy 156.943409 -311.813044)
			(xy 156.978902 -311.847136) (xy 157.008467 -311.88648) (xy 157.031338 -311.930057) (xy 157.046922 -311.976738)
			(xy 157.054817 -312.025315) (xy 157.055312 -312.049922) (xy 157.39416 -312.049922) (xy 157.39812 -312.000868)
			(xy 157.409897 -311.953084) (xy 157.429188 -311.907808) (xy 157.455491 -311.866212) (xy 157.488126 -311.829375)
			(xy 157.526247 -311.79825) (xy 157.568868 -311.773643) (xy 157.614884 -311.756191) (xy 157.663103 -311.746347)
			(xy 157.712278 -311.744366) (xy 157.761133 -311.750298) (xy 157.808404 -311.76399) (xy 157.852866 -311.785088)
			(xy 157.893369 -311.813044) (xy 157.928862 -311.847136) (xy 157.958427 -311.88648) (xy 157.981298 -311.930057)
			(xy 157.996882 -311.976738) (xy 158.004777 -312.025315) (xy 158.005272 -312.049922) (xy 158.34412 -312.049922)
			(xy 158.34808 -312.000868) (xy 158.359857 -311.953084) (xy 158.379148 -311.907808) (xy 158.405451 -311.866212)
			(xy 158.438086 -311.829375) (xy 158.476207 -311.79825) (xy 158.518828 -311.773643) (xy 158.564844 -311.756191)
			(xy 158.613063 -311.746347) (xy 158.662238 -311.744366) (xy 158.711093 -311.750298) (xy 158.758364 -311.76399)
			(xy 158.802826 -311.785088) (xy 158.843329 -311.813044) (xy 158.878822 -311.847136) (xy 158.908387 -311.88648)
			(xy 158.931258 -311.930057) (xy 158.946842 -311.976738) (xy 158.954737 -312.025315) (xy 158.955232 -312.049922)
			(xy 159.29408 -312.049922) (xy 159.29804 -312.000868) (xy 159.309817 -311.953084) (xy 159.329108 -311.907808)
			(xy 159.355411 -311.866212) (xy 159.388046 -311.829375) (xy 159.426167 -311.79825) (xy 159.468788 -311.773643)
			(xy 159.514804 -311.756191) (xy 159.563023 -311.746347) (xy 159.612198 -311.744366) (xy 159.661053 -311.750298)
			(xy 159.708324 -311.76399) (xy 159.752786 -311.785088) (xy 159.793289 -311.813044) (xy 159.828782 -311.847136)
			(xy 159.858347 -311.88648) (xy 159.881218 -311.930057) (xy 159.896802 -311.976738) (xy 159.904697 -312.025315)
			(xy 159.905192 -312.049922) (xy 160.24404 -312.049922) (xy 160.248 -312.000868) (xy 160.259777 -311.953084)
			(xy 160.279068 -311.907808) (xy 160.305371 -311.866212) (xy 160.338006 -311.829375) (xy 160.376127 -311.79825)
			(xy 160.418748 -311.773643) (xy 160.464764 -311.756191) (xy 160.512983 -311.746347) (xy 160.562158 -311.744366)
			(xy 160.611013 -311.750298) (xy 160.658284 -311.76399) (xy 160.702746 -311.785088) (xy 160.743249 -311.813044)
			(xy 160.778742 -311.847136) (xy 160.808307 -311.88648) (xy 160.831178 -311.930057) (xy 160.846762 -311.976738)
			(xy 160.854657 -312.025315) (xy 160.855152 -312.049922) (xy 161.194254 -312.049922) (xy 161.198214 -312.000868)
			(xy 161.209991 -311.953084) (xy 161.229282 -311.907808) (xy 161.255585 -311.866212) (xy 161.28822 -311.829375)
			(xy 161.326341 -311.79825) (xy 161.368962 -311.773643) (xy 161.414978 -311.756191) (xy 161.463197 -311.746347)
			(xy 161.512372 -311.744366) (xy 161.561227 -311.750298) (xy 161.608498 -311.76399) (xy 161.65296 -311.785088)
			(xy 161.693463 -311.813044) (xy 161.728956 -311.847136) (xy 161.758521 -311.88648) (xy 161.781392 -311.930057)
			(xy 161.796976 -311.976738) (xy 161.804871 -312.025315) (xy 161.805366 -312.049922) (xy 162.144214 -312.049922)
			(xy 162.148174 -312.000868) (xy 162.159951 -311.953084) (xy 162.179242 -311.907808) (xy 162.205545 -311.866212)
			(xy 162.23818 -311.829375) (xy 162.276301 -311.79825) (xy 162.318922 -311.773643) (xy 162.364938 -311.756191)
			(xy 162.413157 -311.746347) (xy 162.462332 -311.744366) (xy 162.511187 -311.750298) (xy 162.558458 -311.76399)
			(xy 162.60292 -311.785088) (xy 162.643423 -311.813044) (xy 162.678916 -311.847136) (xy 162.708481 -311.88648)
			(xy 162.731352 -311.930057) (xy 162.746936 -311.976738) (xy 162.754831 -312.025315) (xy 162.755326 -312.049922)
			(xy 163.094174 -312.049922) (xy 163.098134 -312.000868) (xy 163.109911 -311.953084) (xy 163.129202 -311.907808)
			(xy 163.155505 -311.866212) (xy 163.18814 -311.829375) (xy 163.226261 -311.79825) (xy 163.268882 -311.773643)
			(xy 163.314898 -311.756191) (xy 163.363117 -311.746347) (xy 163.412292 -311.744366) (xy 163.461147 -311.750298)
			(xy 163.508418 -311.76399) (xy 163.55288 -311.785088) (xy 163.593383 -311.813044) (xy 163.628876 -311.847136)
			(xy 163.658441 -311.88648) (xy 163.681312 -311.930057) (xy 163.696896 -311.976738) (xy 163.704791 -312.025315)
			(xy 163.705286 -312.049922) (xy 163.704791 -312.074529) (xy 163.696896 -312.123106) (xy 163.681312 -312.169787)
			(xy 163.658441 -312.213364) (xy 163.628876 -312.252708) (xy 163.593383 -312.2868) (xy 163.55288 -312.314756)
			(xy 163.508418 -312.335854) (xy 163.461147 -312.349546) (xy 163.412292 -312.355478) (xy 163.363117 -312.353497)
			(xy 163.314898 -312.343653) (xy 163.268882 -312.326201) (xy 163.226261 -312.301594) (xy 163.18814 -312.270469)
			(xy 163.155505 -312.233632) (xy 163.129202 -312.192036) (xy 163.109911 -312.14676) (xy 163.098134 -312.098976)
			(xy 163.094174 -312.049922) (xy 162.755326 -312.049922) (xy 162.754831 -312.074529) (xy 162.746936 -312.123106)
			(xy 162.731352 -312.169787) (xy 162.708481 -312.213364) (xy 162.678916 -312.252708) (xy 162.643423 -312.2868)
			(xy 162.60292 -312.314756) (xy 162.558458 -312.335854) (xy 162.511187 -312.349546) (xy 162.462332 -312.355478)
			(xy 162.413157 -312.353497) (xy 162.364938 -312.343653) (xy 162.318922 -312.326201) (xy 162.276301 -312.301594)
			(xy 162.23818 -312.270469) (xy 162.205545 -312.233632) (xy 162.179242 -312.192036) (xy 162.159951 -312.14676)
			(xy 162.148174 -312.098976) (xy 162.144214 -312.049922) (xy 161.805366 -312.049922) (xy 161.804871 -312.074529)
			(xy 161.796976 -312.123106) (xy 161.781392 -312.169787) (xy 161.758521 -312.213364) (xy 161.728956 -312.252708)
			(xy 161.693463 -312.2868) (xy 161.65296 -312.314756) (xy 161.608498 -312.335854) (xy 161.561227 -312.349546)
			(xy 161.512372 -312.355478) (xy 161.463197 -312.353497) (xy 161.414978 -312.343653) (xy 161.368962 -312.326201)
			(xy 161.326341 -312.301594) (xy 161.28822 -312.270469) (xy 161.255585 -312.233632) (xy 161.229282 -312.192036)
			(xy 161.209991 -312.14676) (xy 161.198214 -312.098976) (xy 161.194254 -312.049922) (xy 160.855152 -312.049922)
			(xy 160.854657 -312.074529) (xy 160.846762 -312.123106) (xy 160.831178 -312.169787) (xy 160.808307 -312.213364)
			(xy 160.778742 -312.252708) (xy 160.743249 -312.2868) (xy 160.702746 -312.314756) (xy 160.658284 -312.335854)
			(xy 160.611013 -312.349546) (xy 160.562158 -312.355478) (xy 160.512983 -312.353497) (xy 160.464764 -312.343653)
			(xy 160.418748 -312.326201) (xy 160.376127 -312.301594) (xy 160.338006 -312.270469) (xy 160.305371 -312.233632)
			(xy 160.279068 -312.192036) (xy 160.259777 -312.14676) (xy 160.248 -312.098976) (xy 160.24404 -312.049922)
			(xy 159.905192 -312.049922) (xy 159.904697 -312.074529) (xy 159.896802 -312.123106) (xy 159.881218 -312.169787)
			(xy 159.858347 -312.213364) (xy 159.828782 -312.252708) (xy 159.793289 -312.2868) (xy 159.752786 -312.314756)
			(xy 159.708324 -312.335854) (xy 159.661053 -312.349546) (xy 159.612198 -312.355478) (xy 159.563023 -312.353497)
			(xy 159.514804 -312.343653) (xy 159.468788 -312.326201) (xy 159.426167 -312.301594) (xy 159.388046 -312.270469)
			(xy 159.355411 -312.233632) (xy 159.329108 -312.192036) (xy 159.309817 -312.14676) (xy 159.29804 -312.098976)
			(xy 159.29408 -312.049922) (xy 158.955232 -312.049922) (xy 158.954737 -312.074529) (xy 158.946842 -312.123106)
			(xy 158.931258 -312.169787) (xy 158.908387 -312.213364) (xy 158.878822 -312.252708) (xy 158.843329 -312.2868)
			(xy 158.802826 -312.314756) (xy 158.758364 -312.335854) (xy 158.711093 -312.349546) (xy 158.662238 -312.355478)
			(xy 158.613063 -312.353497) (xy 158.564844 -312.343653) (xy 158.518828 -312.326201) (xy 158.476207 -312.301594)
			(xy 158.438086 -312.270469) (xy 158.405451 -312.233632) (xy 158.379148 -312.192036) (xy 158.359857 -312.14676)
			(xy 158.34808 -312.098976) (xy 158.34412 -312.049922) (xy 158.005272 -312.049922) (xy 158.004777 -312.074529)
			(xy 157.996882 -312.123106) (xy 157.981298 -312.169787) (xy 157.958427 -312.213364) (xy 157.928862 -312.252708)
			(xy 157.893369 -312.2868) (xy 157.852866 -312.314756) (xy 157.808404 -312.335854) (xy 157.761133 -312.349546)
			(xy 157.712278 -312.355478) (xy 157.663103 -312.353497) (xy 157.614884 -312.343653) (xy 157.568868 -312.326201)
			(xy 157.526247 -312.301594) (xy 157.488126 -312.270469) (xy 157.455491 -312.233632) (xy 157.429188 -312.192036)
			(xy 157.409897 -312.14676) (xy 157.39812 -312.098976) (xy 157.39416 -312.049922) (xy 157.055312 -312.049922)
			(xy 157.054817 -312.074529) (xy 157.046922 -312.123106) (xy 157.031338 -312.169787) (xy 157.008467 -312.213364)
			(xy 156.978902 -312.252708) (xy 156.943409 -312.2868) (xy 156.902906 -312.314756) (xy 156.858444 -312.335854)
			(xy 156.811173 -312.349546) (xy 156.762318 -312.355478) (xy 156.713143 -312.353497) (xy 156.664924 -312.343653)
			(xy 156.618908 -312.326201) (xy 156.576287 -312.301594) (xy 156.538166 -312.270469) (xy 156.505531 -312.233632)
			(xy 156.479228 -312.192036) (xy 156.459937 -312.14676) (xy 156.44816 -312.098976) (xy 156.4442 -312.049922)
			(xy 156.105352 -312.049922) (xy 156.104857 -312.074529) (xy 156.096962 -312.123106) (xy 156.081378 -312.169787)
			(xy 156.058507 -312.213364) (xy 156.028942 -312.252708) (xy 155.993449 -312.2868) (xy 155.952946 -312.314756)
			(xy 155.908484 -312.335854) (xy 155.861213 -312.349546) (xy 155.812358 -312.355478) (xy 155.763183 -312.353497)
			(xy 155.714964 -312.343653) (xy 155.668948 -312.326201) (xy 155.626327 -312.301594) (xy 155.588206 -312.270469)
			(xy 155.555571 -312.233632) (xy 155.529268 -312.192036) (xy 155.509977 -312.14676) (xy 155.4982 -312.098976)
			(xy 155.49424 -312.049922) (xy 155.155392 -312.049922) (xy 155.154897 -312.074529) (xy 155.147002 -312.123106)
			(xy 155.131418 -312.169787) (xy 155.108547 -312.213364) (xy 155.078982 -312.252708) (xy 155.043489 -312.2868)
			(xy 155.002986 -312.314756) (xy 154.958524 -312.335854) (xy 154.911253 -312.349546) (xy 154.862398 -312.355478)
			(xy 154.813223 -312.353497) (xy 154.765004 -312.343653) (xy 154.718988 -312.326201) (xy 154.676367 -312.301594)
			(xy 154.638246 -312.270469) (xy 154.605611 -312.233632) (xy 154.579308 -312.192036) (xy 154.560017 -312.14676)
			(xy 154.54824 -312.098976) (xy 154.54428 -312.049922) (xy 154.205178 -312.049922) (xy 154.204683 -312.074529)
			(xy 154.196788 -312.123106) (xy 154.181204 -312.169787) (xy 154.158333 -312.213364) (xy 154.128768 -312.252708)
			(xy 154.093275 -312.2868) (xy 154.052772 -312.314756) (xy 154.00831 -312.335854) (xy 153.961039 -312.349546)
			(xy 153.912184 -312.355478) (xy 153.863009 -312.353497) (xy 153.81479 -312.343653) (xy 153.768774 -312.326201)
			(xy 153.726153 -312.301594) (xy 153.688032 -312.270469) (xy 153.655397 -312.233632) (xy 153.629094 -312.192036)
			(xy 153.609803 -312.14676) (xy 153.598026 -312.098976) (xy 153.594066 -312.049922) (xy 153.255218 -312.049922)
			(xy 153.254723 -312.074529) (xy 153.246828 -312.123106) (xy 153.231244 -312.169787) (xy 153.208373 -312.213364)
			(xy 153.178808 -312.252708) (xy 153.143315 -312.2868) (xy 153.102812 -312.314756) (xy 153.05835 -312.335854)
			(xy 153.011079 -312.349546) (xy 152.962224 -312.355478) (xy 152.913049 -312.353497) (xy 152.86483 -312.343653)
			(xy 152.818814 -312.326201) (xy 152.776193 -312.301594) (xy 152.738072 -312.270469) (xy 152.705437 -312.233632)
			(xy 152.679134 -312.192036) (xy 152.659843 -312.14676) (xy 152.648066 -312.098976) (xy 152.644106 -312.049922)
			(xy 152.304999 -312.049922) (xy 152.304509 -312.074275) (xy 152.296614 -312.122852) (xy 152.28103 -312.169533)
			(xy 152.258159 -312.21311) (xy 152.228594 -312.252454) (xy 152.193101 -312.286546) (xy 152.152598 -312.314502)
			(xy 152.108136 -312.3356) (xy 152.060865 -312.349292) (xy 152.01201 -312.355224) (xy 151.962835 -312.353243)
			(xy 151.914616 -312.343399) (xy 151.8686 -312.325947) (xy 151.825979 -312.30134) (xy 151.787858 -312.270215)
			(xy 151.755223 -312.233378) (xy 151.72892 -312.191782) (xy 151.709629 -312.146506) (xy 151.697852 -312.098722)
			(xy 151.693892 -312.049668) (xy 150.905106 -312.049668) (xy 150.925929 -312.081142) (xy 150.949601 -312.131639)
			(xy 150.965669 -312.185046) (xy 150.973789 -312.240222) (xy 150.974298 -312.268108) (xy 150.973789 -312.295994)
			(xy 150.965669 -312.35117) (xy 150.949601 -312.404577) (xy 150.925929 -312.455074) (xy 150.895156 -312.501587)
			(xy 150.857939 -312.543124) (xy 150.815071 -312.578799) (xy 150.767465 -312.607853) (xy 150.716136 -312.629665)
			(xy 150.662179 -312.643771) (xy 150.606742 -312.649871) (xy 150.551008 -312.647834) (xy 150.496165 -312.637704)
			(xy 150.443381 -312.619697) (xy 150.393781 -312.594196) (xy 150.348423 -312.561745) (xy 150.308274 -312.523036)
			(xy 150.274188 -312.478893) (xy 150.246892 -312.430258) (xy 150.226969 -312.378167) (xy 150.214843 -312.32373)
			(xy 150.210772 -312.268108) (xy 148.496921 -312.268108) (xy 148.516446 -312.289899) (xy 148.547219 -312.336412)
			(xy 148.570891 -312.386909) (xy 148.586959 -312.440316) (xy 148.595079 -312.495492) (xy 148.595588 -312.523378)
			(xy 148.595079 -312.551264) (xy 148.586959 -312.60644) (xy 148.570891 -312.659847) (xy 148.547219 -312.710344)
			(xy 148.516446 -312.756857) (xy 148.479229 -312.798394) (xy 148.436361 -312.834069) (xy 148.388755 -312.863123)
			(xy 148.337426 -312.884935) (xy 148.283469 -312.899041) (xy 148.228032 -312.905141) (xy 148.172298 -312.903104)
			(xy 148.117455 -312.892974) (xy 148.064671 -312.874967) (xy 148.015071 -312.849466) (xy 147.969713 -312.817015)
			(xy 147.929564 -312.778306) (xy 147.895478 -312.734163) (xy 147.868182 -312.685528) (xy 147.848259 -312.633437)
			(xy 147.836133 -312.579) (xy 147.832062 -312.523378) (xy 118.832884 -312.523378) (xy 118.832884 -312.999882)
			(xy 152.644106 -312.999882) (xy 152.648066 -312.950828) (xy 152.659843 -312.903044) (xy 152.679134 -312.857768)
			(xy 152.705437 -312.816172) (xy 152.738072 -312.779335) (xy 152.776193 -312.74821) (xy 152.818814 -312.723603)
			(xy 152.86483 -312.706151) (xy 152.913049 -312.696307) (xy 152.962224 -312.694326) (xy 153.011079 -312.700258)
			(xy 153.05835 -312.71395) (xy 153.102812 -312.735048) (xy 153.143315 -312.763004) (xy 153.178808 -312.797096)
			(xy 153.208373 -312.83644) (xy 153.231244 -312.880017) (xy 153.246828 -312.926698) (xy 153.254723 -312.975275)
			(xy 153.255218 -312.999882) (xy 153.594066 -312.999882) (xy 153.598026 -312.950828) (xy 153.609803 -312.903044)
			(xy 153.629094 -312.857768) (xy 153.655397 -312.816172) (xy 153.688032 -312.779335) (xy 153.726153 -312.74821)
			(xy 153.768774 -312.723603) (xy 153.81479 -312.706151) (xy 153.863009 -312.696307) (xy 153.912184 -312.694326)
			(xy 153.961039 -312.700258) (xy 154.00831 -312.71395) (xy 154.052772 -312.735048) (xy 154.093275 -312.763004)
			(xy 154.128768 -312.797096) (xy 154.158333 -312.83644) (xy 154.181204 -312.880017) (xy 154.196788 -312.926698)
			(xy 154.204683 -312.975275) (xy 154.205178 -312.999882) (xy 154.54428 -312.999882) (xy 154.54824 -312.950828)
			(xy 154.560017 -312.903044) (xy 154.579308 -312.857768) (xy 154.605611 -312.816172) (xy 154.638246 -312.779335)
			(xy 154.676367 -312.74821) (xy 154.718988 -312.723603) (xy 154.765004 -312.706151) (xy 154.813223 -312.696307)
			(xy 154.862398 -312.694326) (xy 154.911253 -312.700258) (xy 154.958524 -312.71395) (xy 155.002986 -312.735048)
			(xy 155.043489 -312.763004) (xy 155.078982 -312.797096) (xy 155.108547 -312.83644) (xy 155.131418 -312.880017)
			(xy 155.147002 -312.926698) (xy 155.154897 -312.975275) (xy 155.155392 -312.999882) (xy 155.49424 -312.999882)
			(xy 155.4982 -312.950828) (xy 155.509977 -312.903044) (xy 155.529268 -312.857768) (xy 155.555571 -312.816172)
			(xy 155.588206 -312.779335) (xy 155.626327 -312.74821) (xy 155.668948 -312.723603) (xy 155.714964 -312.706151)
			(xy 155.763183 -312.696307) (xy 155.812358 -312.694326) (xy 155.861213 -312.700258) (xy 155.908484 -312.71395)
			(xy 155.952946 -312.735048) (xy 155.993449 -312.763004) (xy 156.028942 -312.797096) (xy 156.058507 -312.83644)
			(xy 156.081378 -312.880017) (xy 156.096962 -312.926698) (xy 156.104857 -312.975275) (xy 156.105352 -312.999882)
			(xy 156.4442 -312.999882) (xy 156.44816 -312.950828) (xy 156.459937 -312.903044) (xy 156.479228 -312.857768)
			(xy 156.505531 -312.816172) (xy 156.538166 -312.779335) (xy 156.576287 -312.74821) (xy 156.618908 -312.723603)
			(xy 156.664924 -312.706151) (xy 156.713143 -312.696307) (xy 156.762318 -312.694326) (xy 156.811173 -312.700258)
			(xy 156.858444 -312.71395) (xy 156.902906 -312.735048) (xy 156.943409 -312.763004) (xy 156.978902 -312.797096)
			(xy 157.008467 -312.83644) (xy 157.031338 -312.880017) (xy 157.046922 -312.926698) (xy 157.054817 -312.975275)
			(xy 157.055312 -312.999882) (xy 157.39416 -312.999882) (xy 157.39812 -312.950828) (xy 157.409897 -312.903044)
			(xy 157.429188 -312.857768) (xy 157.455491 -312.816172) (xy 157.488126 -312.779335) (xy 157.526247 -312.74821)
			(xy 157.568868 -312.723603) (xy 157.614884 -312.706151) (xy 157.663103 -312.696307) (xy 157.712278 -312.694326)
			(xy 157.761133 -312.700258) (xy 157.808404 -312.71395) (xy 157.852866 -312.735048) (xy 157.893369 -312.763004)
			(xy 157.928862 -312.797096) (xy 157.958427 -312.83644) (xy 157.981298 -312.880017) (xy 157.996882 -312.926698)
			(xy 158.004777 -312.975275) (xy 158.005272 -312.999882) (xy 158.34412 -312.999882) (xy 158.34808 -312.950828)
			(xy 158.359857 -312.903044) (xy 158.379148 -312.857768) (xy 158.405451 -312.816172) (xy 158.438086 -312.779335)
			(xy 158.476207 -312.74821) (xy 158.518828 -312.723603) (xy 158.564844 -312.706151) (xy 158.613063 -312.696307)
			(xy 158.662238 -312.694326) (xy 158.711093 -312.700258) (xy 158.758364 -312.71395) (xy 158.802826 -312.735048)
			(xy 158.843329 -312.763004) (xy 158.878822 -312.797096) (xy 158.908387 -312.83644) (xy 158.931258 -312.880017)
			(xy 158.946842 -312.926698) (xy 158.954737 -312.975275) (xy 158.955232 -312.999882) (xy 159.29408 -312.999882)
			(xy 159.29804 -312.950828) (xy 159.309817 -312.903044) (xy 159.329108 -312.857768) (xy 159.355411 -312.816172)
			(xy 159.388046 -312.779335) (xy 159.426167 -312.74821) (xy 159.468788 -312.723603) (xy 159.514804 -312.706151)
			(xy 159.563023 -312.696307) (xy 159.612198 -312.694326) (xy 159.661053 -312.700258) (xy 159.708324 -312.71395)
			(xy 159.752786 -312.735048) (xy 159.793289 -312.763004) (xy 159.828782 -312.797096) (xy 159.858347 -312.83644)
			(xy 159.881218 -312.880017) (xy 159.896802 -312.926698) (xy 159.904697 -312.975275) (xy 159.905192 -312.999882)
			(xy 160.24404 -312.999882) (xy 160.248 -312.950828) (xy 160.259777 -312.903044) (xy 160.279068 -312.857768)
			(xy 160.305371 -312.816172) (xy 160.338006 -312.779335) (xy 160.376127 -312.74821) (xy 160.418748 -312.723603)
			(xy 160.464764 -312.706151) (xy 160.512983 -312.696307) (xy 160.562158 -312.694326) (xy 160.611013 -312.700258)
			(xy 160.658284 -312.71395) (xy 160.702746 -312.735048) (xy 160.743249 -312.763004) (xy 160.778742 -312.797096)
			(xy 160.808307 -312.83644) (xy 160.831178 -312.880017) (xy 160.846762 -312.926698) (xy 160.854657 -312.975275)
			(xy 160.855152 -312.999882) (xy 161.194254 -312.999882) (xy 161.198214 -312.950828) (xy 161.209991 -312.903044)
			(xy 161.229282 -312.857768) (xy 161.255585 -312.816172) (xy 161.28822 -312.779335) (xy 161.326341 -312.74821)
			(xy 161.368962 -312.723603) (xy 161.414978 -312.706151) (xy 161.463197 -312.696307) (xy 161.512372 -312.694326)
			(xy 161.561227 -312.700258) (xy 161.608498 -312.71395) (xy 161.65296 -312.735048) (xy 161.693463 -312.763004)
			(xy 161.728956 -312.797096) (xy 161.758521 -312.83644) (xy 161.781392 -312.880017) (xy 161.796976 -312.926698)
			(xy 161.804871 -312.975275) (xy 161.805366 -312.999882) (xy 162.144214 -312.999882) (xy 162.148174 -312.950828)
			(xy 162.159951 -312.903044) (xy 162.179242 -312.857768) (xy 162.205545 -312.816172) (xy 162.23818 -312.779335)
			(xy 162.276301 -312.74821) (xy 162.318922 -312.723603) (xy 162.364938 -312.706151) (xy 162.413157 -312.696307)
			(xy 162.462332 -312.694326) (xy 162.511187 -312.700258) (xy 162.558458 -312.71395) (xy 162.60292 -312.735048)
			(xy 162.643423 -312.763004) (xy 162.678916 -312.797096) (xy 162.708481 -312.83644) (xy 162.731352 -312.880017)
			(xy 162.746936 -312.926698) (xy 162.754831 -312.975275) (xy 162.755326 -312.999882) (xy 163.094174 -312.999882)
			(xy 163.098134 -312.950828) (xy 163.109911 -312.903044) (xy 163.129202 -312.857768) (xy 163.155505 -312.816172)
			(xy 163.18814 -312.779335) (xy 163.226261 -312.74821) (xy 163.268882 -312.723603) (xy 163.314898 -312.706151)
			(xy 163.363117 -312.696307) (xy 163.412292 -312.694326) (xy 163.461147 -312.700258) (xy 163.508418 -312.71395)
			(xy 163.55288 -312.735048) (xy 163.593383 -312.763004) (xy 163.628876 -312.797096) (xy 163.658441 -312.83644)
			(xy 163.681312 -312.880017) (xy 163.696896 -312.926698) (xy 163.704791 -312.975275) (xy 163.705286 -312.999882)
			(xy 163.704791 -313.024489) (xy 163.696896 -313.073066) (xy 163.681312 -313.119747) (xy 163.658441 -313.163324)
			(xy 163.628876 -313.202668) (xy 163.593383 -313.23676) (xy 163.55288 -313.264716) (xy 163.508418 -313.285814)
			(xy 163.461147 -313.299506) (xy 163.412292 -313.305438) (xy 163.363117 -313.303457) (xy 163.314898 -313.293613)
			(xy 163.268882 -313.276161) (xy 163.226261 -313.251554) (xy 163.18814 -313.220429) (xy 163.155505 -313.183592)
			(xy 163.129202 -313.141996) (xy 163.109911 -313.09672) (xy 163.098134 -313.048936) (xy 163.094174 -312.999882)
			(xy 162.755326 -312.999882) (xy 162.754831 -313.024489) (xy 162.746936 -313.073066) (xy 162.731352 -313.119747)
			(xy 162.708481 -313.163324) (xy 162.678916 -313.202668) (xy 162.643423 -313.23676) (xy 162.60292 -313.264716)
			(xy 162.558458 -313.285814) (xy 162.511187 -313.299506) (xy 162.462332 -313.305438) (xy 162.413157 -313.303457)
			(xy 162.364938 -313.293613) (xy 162.318922 -313.276161) (xy 162.276301 -313.251554) (xy 162.23818 -313.220429)
			(xy 162.205545 -313.183592) (xy 162.179242 -313.141996) (xy 162.159951 -313.09672) (xy 162.148174 -313.048936)
			(xy 162.144214 -312.999882) (xy 161.805366 -312.999882) (xy 161.804871 -313.024489) (xy 161.796976 -313.073066)
			(xy 161.781392 -313.119747) (xy 161.758521 -313.163324) (xy 161.728956 -313.202668) (xy 161.693463 -313.23676)
			(xy 161.65296 -313.264716) (xy 161.608498 -313.285814) (xy 161.561227 -313.299506) (xy 161.512372 -313.305438)
			(xy 161.463197 -313.303457) (xy 161.414978 -313.293613) (xy 161.368962 -313.276161) (xy 161.326341 -313.251554)
			(xy 161.28822 -313.220429) (xy 161.255585 -313.183592) (xy 161.229282 -313.141996) (xy 161.209991 -313.09672)
			(xy 161.198214 -313.048936) (xy 161.194254 -312.999882) (xy 160.855152 -312.999882) (xy 160.854657 -313.024489)
			(xy 160.846762 -313.073066) (xy 160.831178 -313.119747) (xy 160.808307 -313.163324) (xy 160.778742 -313.202668)
			(xy 160.743249 -313.23676) (xy 160.702746 -313.264716) (xy 160.658284 -313.285814) (xy 160.611013 -313.299506)
			(xy 160.562158 -313.305438) (xy 160.512983 -313.303457) (xy 160.464764 -313.293613) (xy 160.418748 -313.276161)
			(xy 160.376127 -313.251554) (xy 160.338006 -313.220429) (xy 160.305371 -313.183592) (xy 160.279068 -313.141996)
			(xy 160.259777 -313.09672) (xy 160.248 -313.048936) (xy 160.24404 -312.999882) (xy 159.905192 -312.999882)
			(xy 159.904697 -313.024489) (xy 159.896802 -313.073066) (xy 159.881218 -313.119747) (xy 159.858347 -313.163324)
			(xy 159.828782 -313.202668) (xy 159.793289 -313.23676) (xy 159.752786 -313.264716) (xy 159.708324 -313.285814)
			(xy 159.661053 -313.299506) (xy 159.612198 -313.305438) (xy 159.563023 -313.303457) (xy 159.514804 -313.293613)
			(xy 159.468788 -313.276161) (xy 159.426167 -313.251554) (xy 159.388046 -313.220429) (xy 159.355411 -313.183592)
			(xy 159.329108 -313.141996) (xy 159.309817 -313.09672) (xy 159.29804 -313.048936) (xy 159.29408 -312.999882)
			(xy 158.955232 -312.999882) (xy 158.954737 -313.024489) (xy 158.946842 -313.073066) (xy 158.931258 -313.119747)
			(xy 158.908387 -313.163324) (xy 158.878822 -313.202668) (xy 158.843329 -313.23676) (xy 158.802826 -313.264716)
			(xy 158.758364 -313.285814) (xy 158.711093 -313.299506) (xy 158.662238 -313.305438) (xy 158.613063 -313.303457)
			(xy 158.564844 -313.293613) (xy 158.518828 -313.276161) (xy 158.476207 -313.251554) (xy 158.438086 -313.220429)
			(xy 158.405451 -313.183592) (xy 158.379148 -313.141996) (xy 158.359857 -313.09672) (xy 158.34808 -313.048936)
			(xy 158.34412 -312.999882) (xy 158.005272 -312.999882) (xy 158.004777 -313.024489) (xy 157.996882 -313.073066)
			(xy 157.981298 -313.119747) (xy 157.958427 -313.163324) (xy 157.928862 -313.202668) (xy 157.893369 -313.23676)
			(xy 157.852866 -313.264716) (xy 157.808404 -313.285814) (xy 157.761133 -313.299506) (xy 157.712278 -313.305438)
			(xy 157.663103 -313.303457) (xy 157.614884 -313.293613) (xy 157.568868 -313.276161) (xy 157.526247 -313.251554)
			(xy 157.488126 -313.220429) (xy 157.455491 -313.183592) (xy 157.429188 -313.141996) (xy 157.409897 -313.09672)
			(xy 157.39812 -313.048936) (xy 157.39416 -312.999882) (xy 157.055312 -312.999882) (xy 157.054817 -313.024489)
			(xy 157.046922 -313.073066) (xy 157.031338 -313.119747) (xy 157.008467 -313.163324) (xy 156.978902 -313.202668)
			(xy 156.943409 -313.23676) (xy 156.902906 -313.264716) (xy 156.858444 -313.285814) (xy 156.811173 -313.299506)
			(xy 156.762318 -313.305438) (xy 156.713143 -313.303457) (xy 156.664924 -313.293613) (xy 156.618908 -313.276161)
			(xy 156.576287 -313.251554) (xy 156.538166 -313.220429) (xy 156.505531 -313.183592) (xy 156.479228 -313.141996)
			(xy 156.459937 -313.09672) (xy 156.44816 -313.048936) (xy 156.4442 -312.999882) (xy 156.105352 -312.999882)
			(xy 156.104857 -313.024489) (xy 156.096962 -313.073066) (xy 156.081378 -313.119747) (xy 156.058507 -313.163324)
			(xy 156.028942 -313.202668) (xy 155.993449 -313.23676) (xy 155.952946 -313.264716) (xy 155.908484 -313.285814)
			(xy 155.861213 -313.299506) (xy 155.812358 -313.305438) (xy 155.763183 -313.303457) (xy 155.714964 -313.293613)
			(xy 155.668948 -313.276161) (xy 155.626327 -313.251554) (xy 155.588206 -313.220429) (xy 155.555571 -313.183592)
			(xy 155.529268 -313.141996) (xy 155.509977 -313.09672) (xy 155.4982 -313.048936) (xy 155.49424 -312.999882)
			(xy 155.155392 -312.999882) (xy 155.154897 -313.024489) (xy 155.147002 -313.073066) (xy 155.131418 -313.119747)
			(xy 155.108547 -313.163324) (xy 155.078982 -313.202668) (xy 155.043489 -313.23676) (xy 155.002986 -313.264716)
			(xy 154.958524 -313.285814) (xy 154.911253 -313.299506) (xy 154.862398 -313.305438) (xy 154.813223 -313.303457)
			(xy 154.765004 -313.293613) (xy 154.718988 -313.276161) (xy 154.676367 -313.251554) (xy 154.638246 -313.220429)
			(xy 154.605611 -313.183592) (xy 154.579308 -313.141996) (xy 154.560017 -313.09672) (xy 154.54824 -313.048936)
			(xy 154.54428 -312.999882) (xy 154.205178 -312.999882) (xy 154.204683 -313.024489) (xy 154.196788 -313.073066)
			(xy 154.181204 -313.119747) (xy 154.158333 -313.163324) (xy 154.128768 -313.202668) (xy 154.093275 -313.23676)
			(xy 154.052772 -313.264716) (xy 154.00831 -313.285814) (xy 153.961039 -313.299506) (xy 153.912184 -313.305438)
			(xy 153.863009 -313.303457) (xy 153.81479 -313.293613) (xy 153.768774 -313.276161) (xy 153.726153 -313.251554)
			(xy 153.688032 -313.220429) (xy 153.655397 -313.183592) (xy 153.629094 -313.141996) (xy 153.609803 -313.09672)
			(xy 153.598026 -313.048936) (xy 153.594066 -312.999882) (xy 153.255218 -312.999882) (xy 153.254723 -313.024489)
			(xy 153.246828 -313.073066) (xy 153.231244 -313.119747) (xy 153.208373 -313.163324) (xy 153.178808 -313.202668)
			(xy 153.143315 -313.23676) (xy 153.102812 -313.264716) (xy 153.05835 -313.285814) (xy 153.011079 -313.299506)
			(xy 152.962224 -313.305438) (xy 152.913049 -313.303457) (xy 152.86483 -313.293613) (xy 152.818814 -313.276161)
			(xy 152.776193 -313.251554) (xy 152.738072 -313.220429) (xy 152.705437 -313.183592) (xy 152.679134 -313.141996)
			(xy 152.659843 -313.09672) (xy 152.648066 -313.048936) (xy 152.644106 -312.999882) (xy 118.832884 -312.999882)
			(xy 118.832884 -313.669934) (xy 150.147018 -313.669934) (xy 150.151089 -313.614312) (xy 150.163215 -313.559875)
			(xy 150.183138 -313.507784) (xy 150.210434 -313.459149) (xy 150.24452 -313.415006) (xy 150.284669 -313.376297)
			(xy 150.330027 -313.343846) (xy 150.379627 -313.318345) (xy 150.432411 -313.300338) (xy 150.487254 -313.290208)
			(xy 150.542988 -313.288171) (xy 150.598425 -313.294271) (xy 150.652382 -313.308377) (xy 150.703711 -313.330189)
			(xy 150.751317 -313.359243) (xy 150.794185 -313.394918) (xy 150.831402 -313.436455) (xy 150.862175 -313.482968)
			(xy 150.885847 -313.533465) (xy 150.901915 -313.586872) (xy 150.910035 -313.642048) (xy 150.910544 -313.669934)
			(xy 150.910035 -313.69782) (xy 150.901915 -313.752996) (xy 150.885847 -313.806403) (xy 150.862175 -313.8569)
			(xy 150.831402 -313.903413) (xy 150.794185 -313.94495) (xy 150.788307 -313.949842) (xy 152.644106 -313.949842)
			(xy 152.648066 -313.900788) (xy 152.659843 -313.853004) (xy 152.679134 -313.807728) (xy 152.705437 -313.766132)
			(xy 152.738072 -313.729295) (xy 152.776193 -313.69817) (xy 152.818814 -313.673563) (xy 152.86483 -313.656111)
			(xy 152.913049 -313.646267) (xy 152.962224 -313.644286) (xy 153.011079 -313.650218) (xy 153.05835 -313.66391)
			(xy 153.102812 -313.685008) (xy 153.143315 -313.712964) (xy 153.178808 -313.747056) (xy 153.208373 -313.7864)
			(xy 153.231244 -313.829977) (xy 153.246828 -313.876658) (xy 153.254723 -313.925235) (xy 153.255218 -313.949842)
			(xy 153.594066 -313.949842) (xy 153.598026 -313.900788) (xy 153.609803 -313.853004) (xy 153.629094 -313.807728)
			(xy 153.655397 -313.766132) (xy 153.688032 -313.729295) (xy 153.726153 -313.69817) (xy 153.768774 -313.673563)
			(xy 153.81479 -313.656111) (xy 153.863009 -313.646267) (xy 153.912184 -313.644286) (xy 153.961039 -313.650218)
			(xy 154.00831 -313.66391) (xy 154.052772 -313.685008) (xy 154.093275 -313.712964) (xy 154.128768 -313.747056)
			(xy 154.158333 -313.7864) (xy 154.181204 -313.829977) (xy 154.196788 -313.876658) (xy 154.204683 -313.925235)
			(xy 154.205178 -313.949842) (xy 154.54428 -313.949842) (xy 154.54824 -313.900788) (xy 154.560017 -313.853004)
			(xy 154.579308 -313.807728) (xy 154.605611 -313.766132) (xy 154.638246 -313.729295) (xy 154.676367 -313.69817)
			(xy 154.718988 -313.673563) (xy 154.765004 -313.656111) (xy 154.813223 -313.646267) (xy 154.862398 -313.644286)
			(xy 154.911253 -313.650218) (xy 154.958524 -313.66391) (xy 155.002986 -313.685008) (xy 155.043489 -313.712964)
			(xy 155.078982 -313.747056) (xy 155.108547 -313.7864) (xy 155.131418 -313.829977) (xy 155.147002 -313.876658)
			(xy 155.154897 -313.925235) (xy 155.155392 -313.949842) (xy 155.49424 -313.949842) (xy 155.4982 -313.900788)
			(xy 155.509977 -313.853004) (xy 155.529268 -313.807728) (xy 155.555571 -313.766132) (xy 155.588206 -313.729295)
			(xy 155.626327 -313.69817) (xy 155.668948 -313.673563) (xy 155.714964 -313.656111) (xy 155.763183 -313.646267)
			(xy 155.812358 -313.644286) (xy 155.861213 -313.650218) (xy 155.908484 -313.66391) (xy 155.952946 -313.685008)
			(xy 155.993449 -313.712964) (xy 156.028942 -313.747056) (xy 156.058507 -313.7864) (xy 156.081378 -313.829977)
			(xy 156.096962 -313.876658) (xy 156.104857 -313.925235) (xy 156.105352 -313.949842) (xy 156.4442 -313.949842)
			(xy 156.44816 -313.900788) (xy 156.459937 -313.853004) (xy 156.479228 -313.807728) (xy 156.505531 -313.766132)
			(xy 156.538166 -313.729295) (xy 156.576287 -313.69817) (xy 156.618908 -313.673563) (xy 156.664924 -313.656111)
			(xy 156.713143 -313.646267) (xy 156.762318 -313.644286) (xy 156.811173 -313.650218) (xy 156.858444 -313.66391)
			(xy 156.902906 -313.685008) (xy 156.943409 -313.712964) (xy 156.978902 -313.747056) (xy 157.008467 -313.7864)
			(xy 157.031338 -313.829977) (xy 157.046922 -313.876658) (xy 157.054817 -313.925235) (xy 157.055312 -313.949842)
			(xy 157.39416 -313.949842) (xy 157.39812 -313.900788) (xy 157.409897 -313.853004) (xy 157.429188 -313.807728)
			(xy 157.455491 -313.766132) (xy 157.488126 -313.729295) (xy 157.526247 -313.69817) (xy 157.568868 -313.673563)
			(xy 157.614884 -313.656111) (xy 157.663103 -313.646267) (xy 157.712278 -313.644286) (xy 157.761133 -313.650218)
			(xy 157.808404 -313.66391) (xy 157.852866 -313.685008) (xy 157.893369 -313.712964) (xy 157.928862 -313.747056)
			(xy 157.958427 -313.7864) (xy 157.981298 -313.829977) (xy 157.996882 -313.876658) (xy 158.004777 -313.925235)
			(xy 158.005272 -313.949842) (xy 158.34412 -313.949842) (xy 158.34808 -313.900788) (xy 158.359857 -313.853004)
			(xy 158.379148 -313.807728) (xy 158.405451 -313.766132) (xy 158.438086 -313.729295) (xy 158.476207 -313.69817)
			(xy 158.518828 -313.673563) (xy 158.564844 -313.656111) (xy 158.613063 -313.646267) (xy 158.662238 -313.644286)
			(xy 158.711093 -313.650218) (xy 158.758364 -313.66391) (xy 158.802826 -313.685008) (xy 158.843329 -313.712964)
			(xy 158.878822 -313.747056) (xy 158.908387 -313.7864) (xy 158.931258 -313.829977) (xy 158.946842 -313.876658)
			(xy 158.954737 -313.925235) (xy 158.955232 -313.949842) (xy 159.29408 -313.949842) (xy 159.29804 -313.900788)
			(xy 159.309817 -313.853004) (xy 159.329108 -313.807728) (xy 159.355411 -313.766132) (xy 159.388046 -313.729295)
			(xy 159.426167 -313.69817) (xy 159.468788 -313.673563) (xy 159.514804 -313.656111) (xy 159.563023 -313.646267)
			(xy 159.612198 -313.644286) (xy 159.661053 -313.650218) (xy 159.708324 -313.66391) (xy 159.752786 -313.685008)
			(xy 159.793289 -313.712964) (xy 159.828782 -313.747056) (xy 159.858347 -313.7864) (xy 159.881218 -313.829977)
			(xy 159.896802 -313.876658) (xy 159.904697 -313.925235) (xy 159.905192 -313.949842) (xy 160.24404 -313.949842)
			(xy 160.248 -313.900788) (xy 160.259777 -313.853004) (xy 160.279068 -313.807728) (xy 160.305371 -313.766132)
			(xy 160.338006 -313.729295) (xy 160.376127 -313.69817) (xy 160.418748 -313.673563) (xy 160.464764 -313.656111)
			(xy 160.512983 -313.646267) (xy 160.562158 -313.644286) (xy 160.611013 -313.650218) (xy 160.658284 -313.66391)
			(xy 160.702746 -313.685008) (xy 160.743249 -313.712964) (xy 160.778742 -313.747056) (xy 160.808307 -313.7864)
			(xy 160.831178 -313.829977) (xy 160.846762 -313.876658) (xy 160.854657 -313.925235) (xy 160.855152 -313.949842)
			(xy 161.194254 -313.949842) (xy 161.198214 -313.900788) (xy 161.209991 -313.853004) (xy 161.229282 -313.807728)
			(xy 161.255585 -313.766132) (xy 161.28822 -313.729295) (xy 161.326341 -313.69817) (xy 161.368962 -313.673563)
			(xy 161.414978 -313.656111) (xy 161.463197 -313.646267) (xy 161.512372 -313.644286) (xy 161.561227 -313.650218)
			(xy 161.608498 -313.66391) (xy 161.65296 -313.685008) (xy 161.693463 -313.712964) (xy 161.728956 -313.747056)
			(xy 161.758521 -313.7864) (xy 161.781392 -313.829977) (xy 161.796976 -313.876658) (xy 161.804871 -313.925235)
			(xy 161.805366 -313.949842) (xy 162.144214 -313.949842) (xy 162.148174 -313.900788) (xy 162.159951 -313.853004)
			(xy 162.179242 -313.807728) (xy 162.205545 -313.766132) (xy 162.23818 -313.729295) (xy 162.276301 -313.69817)
			(xy 162.318922 -313.673563) (xy 162.364938 -313.656111) (xy 162.413157 -313.646267) (xy 162.462332 -313.644286)
			(xy 162.511187 -313.650218) (xy 162.558458 -313.66391) (xy 162.60292 -313.685008) (xy 162.643423 -313.712964)
			(xy 162.678916 -313.747056) (xy 162.708481 -313.7864) (xy 162.731352 -313.829977) (xy 162.746936 -313.876658)
			(xy 162.754831 -313.925235) (xy 162.755326 -313.949842) (xy 163.094174 -313.949842) (xy 163.098134 -313.900788)
			(xy 163.109911 -313.853004) (xy 163.129202 -313.807728) (xy 163.155505 -313.766132) (xy 163.18814 -313.729295)
			(xy 163.226261 -313.69817) (xy 163.268882 -313.673563) (xy 163.314898 -313.656111) (xy 163.363117 -313.646267)
			(xy 163.412292 -313.644286) (xy 163.461147 -313.650218) (xy 163.508418 -313.66391) (xy 163.55288 -313.685008)
			(xy 163.593383 -313.712964) (xy 163.628876 -313.747056) (xy 163.658441 -313.7864) (xy 163.681312 -313.829977)
			(xy 163.696896 -313.876658) (xy 163.704791 -313.925235) (xy 163.705286 -313.949842) (xy 163.704791 -313.974449)
			(xy 163.696896 -314.023026) (xy 163.681312 -314.069707) (xy 163.658441 -314.113284) (xy 163.628876 -314.152628)
			(xy 163.593383 -314.18672) (xy 163.55288 -314.214676) (xy 163.508418 -314.235774) (xy 163.461147 -314.249466)
			(xy 163.412292 -314.255398) (xy 163.363117 -314.253417) (xy 163.314898 -314.243573) (xy 163.268882 -314.226121)
			(xy 163.226261 -314.201514) (xy 163.18814 -314.170389) (xy 163.155505 -314.133552) (xy 163.129202 -314.091956)
			(xy 163.109911 -314.04668) (xy 163.098134 -313.998896) (xy 163.094174 -313.949842) (xy 162.755326 -313.949842)
			(xy 162.754831 -313.974449) (xy 162.746936 -314.023026) (xy 162.731352 -314.069707) (xy 162.708481 -314.113284)
			(xy 162.678916 -314.152628) (xy 162.643423 -314.18672) (xy 162.60292 -314.214676) (xy 162.558458 -314.235774)
			(xy 162.511187 -314.249466) (xy 162.462332 -314.255398) (xy 162.413157 -314.253417) (xy 162.364938 -314.243573)
			(xy 162.318922 -314.226121) (xy 162.276301 -314.201514) (xy 162.23818 -314.170389) (xy 162.205545 -314.133552)
			(xy 162.179242 -314.091956) (xy 162.159951 -314.04668) (xy 162.148174 -313.998896) (xy 162.144214 -313.949842)
			(xy 161.805366 -313.949842) (xy 161.804871 -313.974449) (xy 161.796976 -314.023026) (xy 161.781392 -314.069707)
			(xy 161.758521 -314.113284) (xy 161.728956 -314.152628) (xy 161.693463 -314.18672) (xy 161.65296 -314.214676)
			(xy 161.608498 -314.235774) (xy 161.561227 -314.249466) (xy 161.512372 -314.255398) (xy 161.463197 -314.253417)
			(xy 161.414978 -314.243573) (xy 161.368962 -314.226121) (xy 161.326341 -314.201514) (xy 161.28822 -314.170389)
			(xy 161.255585 -314.133552) (xy 161.229282 -314.091956) (xy 161.209991 -314.04668) (xy 161.198214 -313.998896)
			(xy 161.194254 -313.949842) (xy 160.855152 -313.949842) (xy 160.854657 -313.974449) (xy 160.846762 -314.023026)
			(xy 160.831178 -314.069707) (xy 160.808307 -314.113284) (xy 160.778742 -314.152628) (xy 160.743249 -314.18672)
			(xy 160.702746 -314.214676) (xy 160.658284 -314.235774) (xy 160.611013 -314.249466) (xy 160.562158 -314.255398)
			(xy 160.512983 -314.253417) (xy 160.464764 -314.243573) (xy 160.418748 -314.226121) (xy 160.376127 -314.201514)
			(xy 160.338006 -314.170389) (xy 160.305371 -314.133552) (xy 160.279068 -314.091956) (xy 160.259777 -314.04668)
			(xy 160.248 -313.998896) (xy 160.24404 -313.949842) (xy 159.905192 -313.949842) (xy 159.904697 -313.974449)
			(xy 159.896802 -314.023026) (xy 159.881218 -314.069707) (xy 159.858347 -314.113284) (xy 159.828782 -314.152628)
			(xy 159.793289 -314.18672) (xy 159.752786 -314.214676) (xy 159.708324 -314.235774) (xy 159.661053 -314.249466)
			(xy 159.612198 -314.255398) (xy 159.563023 -314.253417) (xy 159.514804 -314.243573) (xy 159.468788 -314.226121)
			(xy 159.426167 -314.201514) (xy 159.388046 -314.170389) (xy 159.355411 -314.133552) (xy 159.329108 -314.091956)
			(xy 159.309817 -314.04668) (xy 159.29804 -313.998896) (xy 159.29408 -313.949842) (xy 158.955232 -313.949842)
			(xy 158.954737 -313.974449) (xy 158.946842 -314.023026) (xy 158.931258 -314.069707) (xy 158.908387 -314.113284)
			(xy 158.878822 -314.152628) (xy 158.843329 -314.18672) (xy 158.802826 -314.214676) (xy 158.758364 -314.235774)
			(xy 158.711093 -314.249466) (xy 158.662238 -314.255398) (xy 158.613063 -314.253417) (xy 158.564844 -314.243573)
			(xy 158.518828 -314.226121) (xy 158.476207 -314.201514) (xy 158.438086 -314.170389) (xy 158.405451 -314.133552)
			(xy 158.379148 -314.091956) (xy 158.359857 -314.04668) (xy 158.34808 -313.998896) (xy 158.34412 -313.949842)
			(xy 158.005272 -313.949842) (xy 158.004777 -313.974449) (xy 157.996882 -314.023026) (xy 157.981298 -314.069707)
			(xy 157.958427 -314.113284) (xy 157.928862 -314.152628) (xy 157.893369 -314.18672) (xy 157.852866 -314.214676)
			(xy 157.808404 -314.235774) (xy 157.761133 -314.249466) (xy 157.712278 -314.255398) (xy 157.663103 -314.253417)
			(xy 157.614884 -314.243573) (xy 157.568868 -314.226121) (xy 157.526247 -314.201514) (xy 157.488126 -314.170389)
			(xy 157.455491 -314.133552) (xy 157.429188 -314.091956) (xy 157.409897 -314.04668) (xy 157.39812 -313.998896)
			(xy 157.39416 -313.949842) (xy 157.055312 -313.949842) (xy 157.054817 -313.974449) (xy 157.046922 -314.023026)
			(xy 157.031338 -314.069707) (xy 157.008467 -314.113284) (xy 156.978902 -314.152628) (xy 156.943409 -314.18672)
			(xy 156.902906 -314.214676) (xy 156.858444 -314.235774) (xy 156.811173 -314.249466) (xy 156.762318 -314.255398)
			(xy 156.713143 -314.253417) (xy 156.664924 -314.243573) (xy 156.618908 -314.226121) (xy 156.576287 -314.201514)
			(xy 156.538166 -314.170389) (xy 156.505531 -314.133552) (xy 156.479228 -314.091956) (xy 156.459937 -314.04668)
			(xy 156.44816 -313.998896) (xy 156.4442 -313.949842) (xy 156.105352 -313.949842) (xy 156.104857 -313.974449)
			(xy 156.096962 -314.023026) (xy 156.081378 -314.069707) (xy 156.058507 -314.113284) (xy 156.028942 -314.152628)
			(xy 155.993449 -314.18672) (xy 155.952946 -314.214676) (xy 155.908484 -314.235774) (xy 155.861213 -314.249466)
			(xy 155.812358 -314.255398) (xy 155.763183 -314.253417) (xy 155.714964 -314.243573) (xy 155.668948 -314.226121)
			(xy 155.626327 -314.201514) (xy 155.588206 -314.170389) (xy 155.555571 -314.133552) (xy 155.529268 -314.091956)
			(xy 155.509977 -314.04668) (xy 155.4982 -313.998896) (xy 155.49424 -313.949842) (xy 155.155392 -313.949842)
			(xy 155.154897 -313.974449) (xy 155.147002 -314.023026) (xy 155.131418 -314.069707) (xy 155.108547 -314.113284)
			(xy 155.078982 -314.152628) (xy 155.043489 -314.18672) (xy 155.002986 -314.214676) (xy 154.958524 -314.235774)
			(xy 154.911253 -314.249466) (xy 154.862398 -314.255398) (xy 154.813223 -314.253417) (xy 154.765004 -314.243573)
			(xy 154.718988 -314.226121) (xy 154.676367 -314.201514) (xy 154.638246 -314.170389) (xy 154.605611 -314.133552)
			(xy 154.579308 -314.091956) (xy 154.560017 -314.04668) (xy 154.54824 -313.998896) (xy 154.54428 -313.949842)
			(xy 154.205178 -313.949842) (xy 154.204683 -313.974449) (xy 154.196788 -314.023026) (xy 154.181204 -314.069707)
			(xy 154.158333 -314.113284) (xy 154.128768 -314.152628) (xy 154.093275 -314.18672) (xy 154.052772 -314.214676)
			(xy 154.00831 -314.235774) (xy 153.961039 -314.249466) (xy 153.912184 -314.255398) (xy 153.863009 -314.253417)
			(xy 153.81479 -314.243573) (xy 153.768774 -314.226121) (xy 153.726153 -314.201514) (xy 153.688032 -314.170389)
			(xy 153.655397 -314.133552) (xy 153.629094 -314.091956) (xy 153.609803 -314.04668) (xy 153.598026 -313.998896)
			(xy 153.594066 -313.949842) (xy 153.255218 -313.949842) (xy 153.254723 -313.974449) (xy 153.246828 -314.023026)
			(xy 153.231244 -314.069707) (xy 153.208373 -314.113284) (xy 153.178808 -314.152628) (xy 153.143315 -314.18672)
			(xy 153.102812 -314.214676) (xy 153.05835 -314.235774) (xy 153.011079 -314.249466) (xy 152.962224 -314.255398)
			(xy 152.913049 -314.253417) (xy 152.86483 -314.243573) (xy 152.818814 -314.226121) (xy 152.776193 -314.201514)
			(xy 152.738072 -314.170389) (xy 152.705437 -314.133552) (xy 152.679134 -314.091956) (xy 152.659843 -314.04668)
			(xy 152.648066 -313.998896) (xy 152.644106 -313.949842) (xy 150.788307 -313.949842) (xy 150.751317 -313.980625)
			(xy 150.703711 -314.009679) (xy 150.652382 -314.031491) (xy 150.598425 -314.045597) (xy 150.542988 -314.051697)
			(xy 150.487254 -314.04966) (xy 150.432411 -314.03953) (xy 150.379627 -314.021523) (xy 150.330027 -313.996022)
			(xy 150.284669 -313.963571) (xy 150.24452 -313.924862) (xy 150.210434 -313.880719) (xy 150.183138 -313.832084)
			(xy 150.163215 -313.779993) (xy 150.151089 -313.725556) (xy 150.147018 -313.669934) (xy 118.832884 -313.669934)
			(xy 118.832884 -314.844684) (xy 118.834408 -314.856876) (xy 118.836694 -314.863988) (xy 118.84279 -314.87872)
			(xy 118.844561 -314.883348) (xy 118.846475 -314.89307) (xy 118.8466 -314.898024) (xy 118.8466 -314.899548)
			(xy 151.693638 -314.899548) (xy 151.697598 -314.850494) (xy 151.709375 -314.80271) (xy 151.728666 -314.757434)
			(xy 151.754969 -314.715838) (xy 151.787604 -314.679001) (xy 151.825725 -314.647876) (xy 151.868346 -314.623269)
			(xy 151.914362 -314.605817) (xy 151.962581 -314.595973) (xy 152.011756 -314.593992) (xy 152.060611 -314.599924)
			(xy 152.107882 -314.613616) (xy 152.152344 -314.634714) (xy 152.192847 -314.66267) (xy 152.22834 -314.696762)
			(xy 152.257905 -314.736106) (xy 152.280776 -314.779683) (xy 152.29636 -314.826364) (xy 152.304255 -314.874941)
			(xy 152.30475 -314.899548) (xy 152.304745 -314.899802) (xy 152.644106 -314.899802) (xy 152.648066 -314.850748)
			(xy 152.659843 -314.802964) (xy 152.679134 -314.757688) (xy 152.705437 -314.716092) (xy 152.738072 -314.679255)
			(xy 152.776193 -314.64813) (xy 152.818814 -314.623523) (xy 152.86483 -314.606071) (xy 152.913049 -314.596227)
			(xy 152.962224 -314.594246) (xy 153.011079 -314.600178) (xy 153.05835 -314.61387) (xy 153.102812 -314.634968)
			(xy 153.143315 -314.662924) (xy 153.178808 -314.697016) (xy 153.208373 -314.73636) (xy 153.231244 -314.779937)
			(xy 153.246828 -314.826618) (xy 153.254723 -314.875195) (xy 153.255218 -314.899802) (xy 153.594066 -314.899802)
			(xy 153.598026 -314.850748) (xy 153.609803 -314.802964) (xy 153.629094 -314.757688) (xy 153.655397 -314.716092)
			(xy 153.688032 -314.679255) (xy 153.726153 -314.64813) (xy 153.768774 -314.623523) (xy 153.81479 -314.606071)
			(xy 153.863009 -314.596227) (xy 153.912184 -314.594246) (xy 153.961039 -314.600178) (xy 154.00831 -314.61387)
			(xy 154.052772 -314.634968) (xy 154.093275 -314.662924) (xy 154.128768 -314.697016) (xy 154.158333 -314.73636)
			(xy 154.181204 -314.779937) (xy 154.196788 -314.826618) (xy 154.204683 -314.875195) (xy 154.205178 -314.899802)
			(xy 154.54428 -314.899802) (xy 154.54824 -314.850748) (xy 154.560017 -314.802964) (xy 154.579308 -314.757688)
			(xy 154.605611 -314.716092) (xy 154.638246 -314.679255) (xy 154.676367 -314.64813) (xy 154.718988 -314.623523)
			(xy 154.765004 -314.606071) (xy 154.813223 -314.596227) (xy 154.862398 -314.594246) (xy 154.911253 -314.600178)
			(xy 154.958524 -314.61387) (xy 155.002986 -314.634968) (xy 155.043489 -314.662924) (xy 155.078982 -314.697016)
			(xy 155.108547 -314.73636) (xy 155.131418 -314.779937) (xy 155.147002 -314.826618) (xy 155.154897 -314.875195)
			(xy 155.155392 -314.899802) (xy 155.49424 -314.899802) (xy 155.4982 -314.850748) (xy 155.509977 -314.802964)
			(xy 155.529268 -314.757688) (xy 155.555571 -314.716092) (xy 155.588206 -314.679255) (xy 155.626327 -314.64813)
			(xy 155.668948 -314.623523) (xy 155.714964 -314.606071) (xy 155.763183 -314.596227) (xy 155.812358 -314.594246)
			(xy 155.861213 -314.600178) (xy 155.908484 -314.61387) (xy 155.952946 -314.634968) (xy 155.993449 -314.662924)
			(xy 156.028942 -314.697016) (xy 156.058507 -314.73636) (xy 156.081378 -314.779937) (xy 156.096962 -314.826618)
			(xy 156.104857 -314.875195) (xy 156.105352 -314.899802) (xy 156.4442 -314.899802) (xy 156.44816 -314.850748)
			(xy 156.459937 -314.802964) (xy 156.479228 -314.757688) (xy 156.505531 -314.716092) (xy 156.538166 -314.679255)
			(xy 156.576287 -314.64813) (xy 156.618908 -314.623523) (xy 156.664924 -314.606071) (xy 156.713143 -314.596227)
			(xy 156.762318 -314.594246) (xy 156.811173 -314.600178) (xy 156.858444 -314.61387) (xy 156.902906 -314.634968)
			(xy 156.943409 -314.662924) (xy 156.978902 -314.697016) (xy 157.008467 -314.73636) (xy 157.031338 -314.779937)
			(xy 157.046922 -314.826618) (xy 157.054817 -314.875195) (xy 157.055312 -314.899802) (xy 157.39416 -314.899802)
			(xy 157.39812 -314.850748) (xy 157.409897 -314.802964) (xy 157.429188 -314.757688) (xy 157.455491 -314.716092)
			(xy 157.488126 -314.679255) (xy 157.526247 -314.64813) (xy 157.568868 -314.623523) (xy 157.614884 -314.606071)
			(xy 157.663103 -314.596227) (xy 157.712278 -314.594246) (xy 157.761133 -314.600178) (xy 157.808404 -314.61387)
			(xy 157.852866 -314.634968) (xy 157.893369 -314.662924) (xy 157.928862 -314.697016) (xy 157.958427 -314.73636)
			(xy 157.981298 -314.779937) (xy 157.996882 -314.826618) (xy 158.004777 -314.875195) (xy 158.005272 -314.899802)
			(xy 158.34412 -314.899802) (xy 158.34808 -314.850748) (xy 158.359857 -314.802964) (xy 158.379148 -314.757688)
			(xy 158.405451 -314.716092) (xy 158.438086 -314.679255) (xy 158.476207 -314.64813) (xy 158.518828 -314.623523)
			(xy 158.564844 -314.606071) (xy 158.613063 -314.596227) (xy 158.662238 -314.594246) (xy 158.711093 -314.600178)
			(xy 158.758364 -314.61387) (xy 158.802826 -314.634968) (xy 158.843329 -314.662924) (xy 158.878822 -314.697016)
			(xy 158.908387 -314.73636) (xy 158.931258 -314.779937) (xy 158.946842 -314.826618) (xy 158.954737 -314.875195)
			(xy 158.955232 -314.899802) (xy 159.29408 -314.899802) (xy 159.29804 -314.850748) (xy 159.309817 -314.802964)
			(xy 159.329108 -314.757688) (xy 159.355411 -314.716092) (xy 159.388046 -314.679255) (xy 159.426167 -314.64813)
			(xy 159.468788 -314.623523) (xy 159.514804 -314.606071) (xy 159.563023 -314.596227) (xy 159.612198 -314.594246)
			(xy 159.661053 -314.600178) (xy 159.708324 -314.61387) (xy 159.752786 -314.634968) (xy 159.793289 -314.662924)
			(xy 159.828782 -314.697016) (xy 159.858347 -314.73636) (xy 159.881218 -314.779937) (xy 159.896802 -314.826618)
			(xy 159.904697 -314.875195) (xy 159.905192 -314.899802) (xy 160.24404 -314.899802) (xy 160.248 -314.850748)
			(xy 160.259777 -314.802964) (xy 160.279068 -314.757688) (xy 160.305371 -314.716092) (xy 160.338006 -314.679255)
			(xy 160.376127 -314.64813) (xy 160.418748 -314.623523) (xy 160.464764 -314.606071) (xy 160.512983 -314.596227)
			(xy 160.562158 -314.594246) (xy 160.611013 -314.600178) (xy 160.658284 -314.61387) (xy 160.702746 -314.634968)
			(xy 160.743249 -314.662924) (xy 160.778742 -314.697016) (xy 160.808307 -314.73636) (xy 160.831178 -314.779937)
			(xy 160.846762 -314.826618) (xy 160.854657 -314.875195) (xy 160.855152 -314.899802) (xy 161.194254 -314.899802)
			(xy 161.198214 -314.850748) (xy 161.209991 -314.802964) (xy 161.229282 -314.757688) (xy 161.255585 -314.716092)
			(xy 161.28822 -314.679255) (xy 161.326341 -314.64813) (xy 161.368962 -314.623523) (xy 161.414978 -314.606071)
			(xy 161.463197 -314.596227) (xy 161.512372 -314.594246) (xy 161.561227 -314.600178) (xy 161.608498 -314.61387)
			(xy 161.65296 -314.634968) (xy 161.693463 -314.662924) (xy 161.728956 -314.697016) (xy 161.758521 -314.73636)
			(xy 161.781392 -314.779937) (xy 161.796976 -314.826618) (xy 161.804871 -314.875195) (xy 161.805366 -314.899802)
			(xy 162.144214 -314.899802) (xy 162.148174 -314.850748) (xy 162.159951 -314.802964) (xy 162.179242 -314.757688)
			(xy 162.205545 -314.716092) (xy 162.23818 -314.679255) (xy 162.276301 -314.64813) (xy 162.318922 -314.623523)
			(xy 162.364938 -314.606071) (xy 162.413157 -314.596227) (xy 162.462332 -314.594246) (xy 162.511187 -314.600178)
			(xy 162.558458 -314.61387) (xy 162.60292 -314.634968) (xy 162.643423 -314.662924) (xy 162.678916 -314.697016)
			(xy 162.708481 -314.73636) (xy 162.731352 -314.779937) (xy 162.746936 -314.826618) (xy 162.754831 -314.875195)
			(xy 162.755326 -314.899802) (xy 163.094174 -314.899802) (xy 163.098134 -314.850748) (xy 163.109911 -314.802964)
			(xy 163.129202 -314.757688) (xy 163.155505 -314.716092) (xy 163.18814 -314.679255) (xy 163.226261 -314.64813)
			(xy 163.268882 -314.623523) (xy 163.314898 -314.606071) (xy 163.363117 -314.596227) (xy 163.412292 -314.594246)
			(xy 163.461147 -314.600178) (xy 163.508418 -314.61387) (xy 163.55288 -314.634968) (xy 163.593383 -314.662924)
			(xy 163.628876 -314.697016) (xy 163.658441 -314.73636) (xy 163.681312 -314.779937) (xy 163.696896 -314.826618)
			(xy 163.704791 -314.875195) (xy 163.705286 -314.899802) (xy 163.704791 -314.924409) (xy 163.696896 -314.972986)
			(xy 163.681312 -315.019667) (xy 163.658441 -315.063244) (xy 163.628876 -315.102588) (xy 163.593383 -315.13668)
			(xy 163.55288 -315.164636) (xy 163.508418 -315.185734) (xy 163.461147 -315.199426) (xy 163.412292 -315.205358)
			(xy 163.363117 -315.203377) (xy 163.314898 -315.193533) (xy 163.268882 -315.176081) (xy 163.226261 -315.151474)
			(xy 163.18814 -315.120349) (xy 163.155505 -315.083512) (xy 163.129202 -315.041916) (xy 163.109911 -314.99664)
			(xy 163.098134 -314.948856) (xy 163.094174 -314.899802) (xy 162.755326 -314.899802) (xy 162.754831 -314.924409)
			(xy 162.746936 -314.972986) (xy 162.731352 -315.019667) (xy 162.708481 -315.063244) (xy 162.678916 -315.102588)
			(xy 162.643423 -315.13668) (xy 162.60292 -315.164636) (xy 162.558458 -315.185734) (xy 162.511187 -315.199426)
			(xy 162.462332 -315.205358) (xy 162.413157 -315.203377) (xy 162.364938 -315.193533) (xy 162.318922 -315.176081)
			(xy 162.276301 -315.151474) (xy 162.23818 -315.120349) (xy 162.205545 -315.083512) (xy 162.179242 -315.041916)
			(xy 162.159951 -314.99664) (xy 162.148174 -314.948856) (xy 162.144214 -314.899802) (xy 161.805366 -314.899802)
			(xy 161.804871 -314.924409) (xy 161.796976 -314.972986) (xy 161.781392 -315.019667) (xy 161.758521 -315.063244)
			(xy 161.728956 -315.102588) (xy 161.693463 -315.13668) (xy 161.65296 -315.164636) (xy 161.608498 -315.185734)
			(xy 161.561227 -315.199426) (xy 161.512372 -315.205358) (xy 161.463197 -315.203377) (xy 161.414978 -315.193533)
			(xy 161.368962 -315.176081) (xy 161.326341 -315.151474) (xy 161.28822 -315.120349) (xy 161.255585 -315.083512)
			(xy 161.229282 -315.041916) (xy 161.209991 -314.99664) (xy 161.198214 -314.948856) (xy 161.194254 -314.899802)
			(xy 160.855152 -314.899802) (xy 160.854657 -314.924409) (xy 160.846762 -314.972986) (xy 160.831178 -315.019667)
			(xy 160.808307 -315.063244) (xy 160.778742 -315.102588) (xy 160.743249 -315.13668) (xy 160.702746 -315.164636)
			(xy 160.658284 -315.185734) (xy 160.611013 -315.199426) (xy 160.562158 -315.205358) (xy 160.512983 -315.203377)
			(xy 160.464764 -315.193533) (xy 160.418748 -315.176081) (xy 160.376127 -315.151474) (xy 160.338006 -315.120349)
			(xy 160.305371 -315.083512) (xy 160.279068 -315.041916) (xy 160.259777 -314.99664) (xy 160.248 -314.948856)
			(xy 160.24404 -314.899802) (xy 159.905192 -314.899802) (xy 159.904697 -314.924409) (xy 159.896802 -314.972986)
			(xy 159.881218 -315.019667) (xy 159.858347 -315.063244) (xy 159.828782 -315.102588) (xy 159.793289 -315.13668)
			(xy 159.752786 -315.164636) (xy 159.708324 -315.185734) (xy 159.661053 -315.199426) (xy 159.612198 -315.205358)
			(xy 159.563023 -315.203377) (xy 159.514804 -315.193533) (xy 159.468788 -315.176081) (xy 159.426167 -315.151474)
			(xy 159.388046 -315.120349) (xy 159.355411 -315.083512) (xy 159.329108 -315.041916) (xy 159.309817 -314.99664)
			(xy 159.29804 -314.948856) (xy 159.29408 -314.899802) (xy 158.955232 -314.899802) (xy 158.954737 -314.924409)
			(xy 158.946842 -314.972986) (xy 158.931258 -315.019667) (xy 158.908387 -315.063244) (xy 158.878822 -315.102588)
			(xy 158.843329 -315.13668) (xy 158.802826 -315.164636) (xy 158.758364 -315.185734) (xy 158.711093 -315.199426)
			(xy 158.662238 -315.205358) (xy 158.613063 -315.203377) (xy 158.564844 -315.193533) (xy 158.518828 -315.176081)
			(xy 158.476207 -315.151474) (xy 158.438086 -315.120349) (xy 158.405451 -315.083512) (xy 158.379148 -315.041916)
			(xy 158.359857 -314.99664) (xy 158.34808 -314.948856) (xy 158.34412 -314.899802) (xy 158.005272 -314.899802)
			(xy 158.004777 -314.924409) (xy 157.996882 -314.972986) (xy 157.981298 -315.019667) (xy 157.958427 -315.063244)
			(xy 157.928862 -315.102588) (xy 157.893369 -315.13668) (xy 157.852866 -315.164636) (xy 157.808404 -315.185734)
			(xy 157.761133 -315.199426) (xy 157.712278 -315.205358) (xy 157.663103 -315.203377) (xy 157.614884 -315.193533)
			(xy 157.568868 -315.176081) (xy 157.526247 -315.151474) (xy 157.488126 -315.120349) (xy 157.455491 -315.083512)
			(xy 157.429188 -315.041916) (xy 157.409897 -314.99664) (xy 157.39812 -314.948856) (xy 157.39416 -314.899802)
			(xy 157.055312 -314.899802) (xy 157.054817 -314.924409) (xy 157.046922 -314.972986) (xy 157.031338 -315.019667)
			(xy 157.008467 -315.063244) (xy 156.978902 -315.102588) (xy 156.943409 -315.13668) (xy 156.902906 -315.164636)
			(xy 156.858444 -315.185734) (xy 156.811173 -315.199426) (xy 156.762318 -315.205358) (xy 156.713143 -315.203377)
			(xy 156.664924 -315.193533) (xy 156.618908 -315.176081) (xy 156.576287 -315.151474) (xy 156.538166 -315.120349)
			(xy 156.505531 -315.083512) (xy 156.479228 -315.041916) (xy 156.459937 -314.99664) (xy 156.44816 -314.948856)
			(xy 156.4442 -314.899802) (xy 156.105352 -314.899802) (xy 156.104857 -314.924409) (xy 156.096962 -314.972986)
			(xy 156.081378 -315.019667) (xy 156.058507 -315.063244) (xy 156.028942 -315.102588) (xy 155.993449 -315.13668)
			(xy 155.952946 -315.164636) (xy 155.908484 -315.185734) (xy 155.861213 -315.199426) (xy 155.812358 -315.205358)
			(xy 155.763183 -315.203377) (xy 155.714964 -315.193533) (xy 155.668948 -315.176081) (xy 155.626327 -315.151474)
			(xy 155.588206 -315.120349) (xy 155.555571 -315.083512) (xy 155.529268 -315.041916) (xy 155.509977 -314.99664)
			(xy 155.4982 -314.948856) (xy 155.49424 -314.899802) (xy 155.155392 -314.899802) (xy 155.154897 -314.924409)
			(xy 155.147002 -314.972986) (xy 155.131418 -315.019667) (xy 155.108547 -315.063244) (xy 155.078982 -315.102588)
			(xy 155.043489 -315.13668) (xy 155.002986 -315.164636) (xy 154.958524 -315.185734) (xy 154.911253 -315.199426)
			(xy 154.862398 -315.205358) (xy 154.813223 -315.203377) (xy 154.765004 -315.193533) (xy 154.718988 -315.176081)
			(xy 154.676367 -315.151474) (xy 154.638246 -315.120349) (xy 154.605611 -315.083512) (xy 154.579308 -315.041916)
			(xy 154.560017 -314.99664) (xy 154.54824 -314.948856) (xy 154.54428 -314.899802) (xy 154.205178 -314.899802)
			(xy 154.204683 -314.924409) (xy 154.196788 -314.972986) (xy 154.181204 -315.019667) (xy 154.158333 -315.063244)
			(xy 154.128768 -315.102588) (xy 154.093275 -315.13668) (xy 154.052772 -315.164636) (xy 154.00831 -315.185734)
			(xy 153.961039 -315.199426) (xy 153.912184 -315.205358) (xy 153.863009 -315.203377) (xy 153.81479 -315.193533)
			(xy 153.768774 -315.176081) (xy 153.726153 -315.151474) (xy 153.688032 -315.120349) (xy 153.655397 -315.083512)
			(xy 153.629094 -315.041916) (xy 153.609803 -314.99664) (xy 153.598026 -314.948856) (xy 153.594066 -314.899802)
			(xy 153.255218 -314.899802) (xy 153.254723 -314.924409) (xy 153.246828 -314.972986) (xy 153.231244 -315.019667)
			(xy 153.208373 -315.063244) (xy 153.178808 -315.102588) (xy 153.143315 -315.13668) (xy 153.102812 -315.164636)
			(xy 153.05835 -315.185734) (xy 153.011079 -315.199426) (xy 152.962224 -315.205358) (xy 152.913049 -315.203377)
			(xy 152.86483 -315.193533) (xy 152.818814 -315.176081) (xy 152.776193 -315.151474) (xy 152.738072 -315.120349)
			(xy 152.705437 -315.083512) (xy 152.679134 -315.041916) (xy 152.659843 -314.99664) (xy 152.648066 -314.948856)
			(xy 152.644106 -314.899802) (xy 152.304745 -314.899802) (xy 152.304255 -314.924155) (xy 152.29636 -314.972732)
			(xy 152.280776 -315.019413) (xy 152.257905 -315.06299) (xy 152.22834 -315.102334) (xy 152.192847 -315.136426)
			(xy 152.152344 -315.164382) (xy 152.107882 -315.18548) (xy 152.060611 -315.199172) (xy 152.011756 -315.205104)
			(xy 151.962581 -315.203123) (xy 151.914362 -315.193279) (xy 151.868346 -315.175827) (xy 151.825725 -315.15122)
			(xy 151.787604 -315.120095) (xy 151.754969 -315.083258) (xy 151.728666 -315.041662) (xy 151.709375 -314.996386)
			(xy 151.697598 -314.948602) (xy 151.693638 -314.899548) (xy 118.8466 -314.899548) (xy 118.8466 -315.849762)
			(xy 152.644106 -315.849762) (xy 152.648066 -315.800708) (xy 152.659843 -315.752924) (xy 152.679134 -315.707648)
			(xy 152.705437 -315.666052) (xy 152.738072 -315.629215) (xy 152.776193 -315.59809) (xy 152.818814 -315.573483)
			(xy 152.86483 -315.556031) (xy 152.913049 -315.546187) (xy 152.962224 -315.544206) (xy 153.011079 -315.550138)
			(xy 153.05835 -315.56383) (xy 153.102812 -315.584928) (xy 153.143315 -315.612884) (xy 153.178808 -315.646976)
			(xy 153.208373 -315.68632) (xy 153.231244 -315.729897) (xy 153.246828 -315.776578) (xy 153.254723 -315.825155)
			(xy 153.255218 -315.849762) (xy 153.594066 -315.849762) (xy 153.598026 -315.800708) (xy 153.609803 -315.752924)
			(xy 153.629094 -315.707648) (xy 153.655397 -315.666052) (xy 153.688032 -315.629215) (xy 153.726153 -315.59809)
			(xy 153.768774 -315.573483) (xy 153.81479 -315.556031) (xy 153.863009 -315.546187) (xy 153.912184 -315.544206)
			(xy 153.961039 -315.550138) (xy 154.00831 -315.56383) (xy 154.052772 -315.584928) (xy 154.093275 -315.612884)
			(xy 154.128768 -315.646976) (xy 154.158333 -315.68632) (xy 154.181204 -315.729897) (xy 154.196788 -315.776578)
			(xy 154.204683 -315.825155) (xy 154.205178 -315.849762) (xy 154.54428 -315.849762) (xy 154.54824 -315.800708)
			(xy 154.560017 -315.752924) (xy 154.579308 -315.707648) (xy 154.605611 -315.666052) (xy 154.638246 -315.629215)
			(xy 154.676367 -315.59809) (xy 154.718988 -315.573483) (xy 154.765004 -315.556031) (xy 154.813223 -315.546187)
			(xy 154.862398 -315.544206) (xy 154.911253 -315.550138) (xy 154.958524 -315.56383) (xy 155.002986 -315.584928)
			(xy 155.043489 -315.612884) (xy 155.078982 -315.646976) (xy 155.108547 -315.68632) (xy 155.131418 -315.729897)
			(xy 155.147002 -315.776578) (xy 155.154897 -315.825155) (xy 155.155392 -315.849762) (xy 155.49424 -315.849762)
			(xy 155.4982 -315.800708) (xy 155.509977 -315.752924) (xy 155.529268 -315.707648) (xy 155.555571 -315.666052)
			(xy 155.588206 -315.629215) (xy 155.626327 -315.59809) (xy 155.668948 -315.573483) (xy 155.714964 -315.556031)
			(xy 155.763183 -315.546187) (xy 155.812358 -315.544206) (xy 155.861213 -315.550138) (xy 155.908484 -315.56383)
			(xy 155.952946 -315.584928) (xy 155.993449 -315.612884) (xy 156.028942 -315.646976) (xy 156.058507 -315.68632)
			(xy 156.081378 -315.729897) (xy 156.096962 -315.776578) (xy 156.104857 -315.825155) (xy 156.105352 -315.849762)
			(xy 156.4442 -315.849762) (xy 156.44816 -315.800708) (xy 156.459937 -315.752924) (xy 156.479228 -315.707648)
			(xy 156.505531 -315.666052) (xy 156.538166 -315.629215) (xy 156.576287 -315.59809) (xy 156.618908 -315.573483)
			(xy 156.664924 -315.556031) (xy 156.713143 -315.546187) (xy 156.762318 -315.544206) (xy 156.811173 -315.550138)
			(xy 156.858444 -315.56383) (xy 156.902906 -315.584928) (xy 156.943409 -315.612884) (xy 156.978902 -315.646976)
			(xy 157.008467 -315.68632) (xy 157.031338 -315.729897) (xy 157.046922 -315.776578) (xy 157.054817 -315.825155)
			(xy 157.055312 -315.849762) (xy 157.39416 -315.849762) (xy 157.39812 -315.800708) (xy 157.409897 -315.752924)
			(xy 157.429188 -315.707648) (xy 157.455491 -315.666052) (xy 157.488126 -315.629215) (xy 157.526247 -315.59809)
			(xy 157.568868 -315.573483) (xy 157.614884 -315.556031) (xy 157.663103 -315.546187) (xy 157.712278 -315.544206)
			(xy 157.761133 -315.550138) (xy 157.808404 -315.56383) (xy 157.852866 -315.584928) (xy 157.893369 -315.612884)
			(xy 157.928862 -315.646976) (xy 157.958427 -315.68632) (xy 157.981298 -315.729897) (xy 157.996882 -315.776578)
			(xy 158.004777 -315.825155) (xy 158.005272 -315.849762) (xy 158.34412 -315.849762) (xy 158.34808 -315.800708)
			(xy 158.359857 -315.752924) (xy 158.379148 -315.707648) (xy 158.405451 -315.666052) (xy 158.438086 -315.629215)
			(xy 158.476207 -315.59809) (xy 158.518828 -315.573483) (xy 158.564844 -315.556031) (xy 158.613063 -315.546187)
			(xy 158.662238 -315.544206) (xy 158.711093 -315.550138) (xy 158.758364 -315.56383) (xy 158.802826 -315.584928)
			(xy 158.843329 -315.612884) (xy 158.878822 -315.646976) (xy 158.908387 -315.68632) (xy 158.931258 -315.729897)
			(xy 158.946842 -315.776578) (xy 158.954737 -315.825155) (xy 158.955232 -315.849762) (xy 159.29408 -315.849762)
			(xy 159.29804 -315.800708) (xy 159.309817 -315.752924) (xy 159.329108 -315.707648) (xy 159.355411 -315.666052)
			(xy 159.388046 -315.629215) (xy 159.426167 -315.59809) (xy 159.468788 -315.573483) (xy 159.514804 -315.556031)
			(xy 159.563023 -315.546187) (xy 159.612198 -315.544206) (xy 159.661053 -315.550138) (xy 159.708324 -315.56383)
			(xy 159.752786 -315.584928) (xy 159.793289 -315.612884) (xy 159.828782 -315.646976) (xy 159.858347 -315.68632)
			(xy 159.881218 -315.729897) (xy 159.896802 -315.776578) (xy 159.904697 -315.825155) (xy 159.905192 -315.849762)
			(xy 160.24404 -315.849762) (xy 160.248 -315.800708) (xy 160.259777 -315.752924) (xy 160.279068 -315.707648)
			(xy 160.305371 -315.666052) (xy 160.338006 -315.629215) (xy 160.376127 -315.59809) (xy 160.418748 -315.573483)
			(xy 160.464764 -315.556031) (xy 160.512983 -315.546187) (xy 160.562158 -315.544206) (xy 160.611013 -315.550138)
			(xy 160.658284 -315.56383) (xy 160.702746 -315.584928) (xy 160.743249 -315.612884) (xy 160.778742 -315.646976)
			(xy 160.808307 -315.68632) (xy 160.831178 -315.729897) (xy 160.846762 -315.776578) (xy 160.854657 -315.825155)
			(xy 160.855152 -315.849762) (xy 161.194254 -315.849762) (xy 161.198214 -315.800708) (xy 161.209991 -315.752924)
			(xy 161.229282 -315.707648) (xy 161.255585 -315.666052) (xy 161.28822 -315.629215) (xy 161.326341 -315.59809)
			(xy 161.368962 -315.573483) (xy 161.414978 -315.556031) (xy 161.463197 -315.546187) (xy 161.512372 -315.544206)
			(xy 161.561227 -315.550138) (xy 161.608498 -315.56383) (xy 161.65296 -315.584928) (xy 161.693463 -315.612884)
			(xy 161.728956 -315.646976) (xy 161.758521 -315.68632) (xy 161.781392 -315.729897) (xy 161.796976 -315.776578)
			(xy 161.804871 -315.825155) (xy 161.805366 -315.849762) (xy 162.144214 -315.849762) (xy 162.148174 -315.800708)
			(xy 162.159951 -315.752924) (xy 162.179242 -315.707648) (xy 162.205545 -315.666052) (xy 162.23818 -315.629215)
			(xy 162.276301 -315.59809) (xy 162.318922 -315.573483) (xy 162.364938 -315.556031) (xy 162.413157 -315.546187)
			(xy 162.462332 -315.544206) (xy 162.511187 -315.550138) (xy 162.558458 -315.56383) (xy 162.60292 -315.584928)
			(xy 162.643423 -315.612884) (xy 162.678916 -315.646976) (xy 162.708481 -315.68632) (xy 162.731352 -315.729897)
			(xy 162.746936 -315.776578) (xy 162.754831 -315.825155) (xy 162.755326 -315.849762) (xy 163.094174 -315.849762)
			(xy 163.098134 -315.800708) (xy 163.109911 -315.752924) (xy 163.129202 -315.707648) (xy 163.155505 -315.666052)
			(xy 163.18814 -315.629215) (xy 163.226261 -315.59809) (xy 163.268882 -315.573483) (xy 163.314898 -315.556031)
			(xy 163.363117 -315.546187) (xy 163.412292 -315.544206) (xy 163.461147 -315.550138) (xy 163.508418 -315.56383)
			(xy 163.55288 -315.584928) (xy 163.593383 -315.612884) (xy 163.628876 -315.646976) (xy 163.658441 -315.68632)
			(xy 163.681312 -315.729897) (xy 163.696896 -315.776578) (xy 163.704791 -315.825155) (xy 163.705286 -315.849762)
			(xy 163.704791 -315.874369) (xy 163.696896 -315.922946) (xy 163.681312 -315.969627) (xy 163.658441 -316.013204)
			(xy 163.628876 -316.052548) (xy 163.593383 -316.08664) (xy 163.55288 -316.114596) (xy 163.508418 -316.135694)
			(xy 163.461147 -316.149386) (xy 163.412292 -316.155318) (xy 163.363117 -316.153337) (xy 163.314898 -316.143493)
			(xy 163.268882 -316.126041) (xy 163.226261 -316.101434) (xy 163.18814 -316.070309) (xy 163.155505 -316.033472)
			(xy 163.129202 -315.991876) (xy 163.109911 -315.9466) (xy 163.098134 -315.898816) (xy 163.094174 -315.849762)
			(xy 162.755326 -315.849762) (xy 162.754831 -315.874369) (xy 162.746936 -315.922946) (xy 162.731352 -315.969627)
			(xy 162.708481 -316.013204) (xy 162.678916 -316.052548) (xy 162.643423 -316.08664) (xy 162.60292 -316.114596)
			(xy 162.558458 -316.135694) (xy 162.511187 -316.149386) (xy 162.462332 -316.155318) (xy 162.413157 -316.153337)
			(xy 162.364938 -316.143493) (xy 162.318922 -316.126041) (xy 162.276301 -316.101434) (xy 162.23818 -316.070309)
			(xy 162.205545 -316.033472) (xy 162.179242 -315.991876) (xy 162.159951 -315.9466) (xy 162.148174 -315.898816)
			(xy 162.144214 -315.849762) (xy 161.805366 -315.849762) (xy 161.804871 -315.874369) (xy 161.796976 -315.922946)
			(xy 161.781392 -315.969627) (xy 161.758521 -316.013204) (xy 161.728956 -316.052548) (xy 161.693463 -316.08664)
			(xy 161.65296 -316.114596) (xy 161.608498 -316.135694) (xy 161.561227 -316.149386) (xy 161.512372 -316.155318)
			(xy 161.463197 -316.153337) (xy 161.414978 -316.143493) (xy 161.368962 -316.126041) (xy 161.326341 -316.101434)
			(xy 161.28822 -316.070309) (xy 161.255585 -316.033472) (xy 161.229282 -315.991876) (xy 161.209991 -315.9466)
			(xy 161.198214 -315.898816) (xy 161.194254 -315.849762) (xy 160.855152 -315.849762) (xy 160.854657 -315.874369)
			(xy 160.846762 -315.922946) (xy 160.831178 -315.969627) (xy 160.808307 -316.013204) (xy 160.778742 -316.052548)
			(xy 160.743249 -316.08664) (xy 160.702746 -316.114596) (xy 160.658284 -316.135694) (xy 160.611013 -316.149386)
			(xy 160.562158 -316.155318) (xy 160.512983 -316.153337) (xy 160.464764 -316.143493) (xy 160.418748 -316.126041)
			(xy 160.376127 -316.101434) (xy 160.338006 -316.070309) (xy 160.305371 -316.033472) (xy 160.279068 -315.991876)
			(xy 160.259777 -315.9466) (xy 160.248 -315.898816) (xy 160.24404 -315.849762) (xy 159.905192 -315.849762)
			(xy 159.904697 -315.874369) (xy 159.896802 -315.922946) (xy 159.881218 -315.969627) (xy 159.858347 -316.013204)
			(xy 159.828782 -316.052548) (xy 159.793289 -316.08664) (xy 159.752786 -316.114596) (xy 159.708324 -316.135694)
			(xy 159.661053 -316.149386) (xy 159.612198 -316.155318) (xy 159.563023 -316.153337) (xy 159.514804 -316.143493)
			(xy 159.468788 -316.126041) (xy 159.426167 -316.101434) (xy 159.388046 -316.070309) (xy 159.355411 -316.033472)
			(xy 159.329108 -315.991876) (xy 159.309817 -315.9466) (xy 159.29804 -315.898816) (xy 159.29408 -315.849762)
			(xy 158.955232 -315.849762) (xy 158.954737 -315.874369) (xy 158.946842 -315.922946) (xy 158.931258 -315.969627)
			(xy 158.908387 -316.013204) (xy 158.878822 -316.052548) (xy 158.843329 -316.08664) (xy 158.802826 -316.114596)
			(xy 158.758364 -316.135694) (xy 158.711093 -316.149386) (xy 158.662238 -316.155318) (xy 158.613063 -316.153337)
			(xy 158.564844 -316.143493) (xy 158.518828 -316.126041) (xy 158.476207 -316.101434) (xy 158.438086 -316.070309)
			(xy 158.405451 -316.033472) (xy 158.379148 -315.991876) (xy 158.359857 -315.9466) (xy 158.34808 -315.898816)
			(xy 158.34412 -315.849762) (xy 158.005272 -315.849762) (xy 158.004777 -315.874369) (xy 157.996882 -315.922946)
			(xy 157.981298 -315.969627) (xy 157.958427 -316.013204) (xy 157.928862 -316.052548) (xy 157.893369 -316.08664)
			(xy 157.852866 -316.114596) (xy 157.808404 -316.135694) (xy 157.761133 -316.149386) (xy 157.712278 -316.155318)
			(xy 157.663103 -316.153337) (xy 157.614884 -316.143493) (xy 157.568868 -316.126041) (xy 157.526247 -316.101434)
			(xy 157.488126 -316.070309) (xy 157.455491 -316.033472) (xy 157.429188 -315.991876) (xy 157.409897 -315.9466)
			(xy 157.39812 -315.898816) (xy 157.39416 -315.849762) (xy 157.055312 -315.849762) (xy 157.054817 -315.874369)
			(xy 157.046922 -315.922946) (xy 157.031338 -315.969627) (xy 157.008467 -316.013204) (xy 156.978902 -316.052548)
			(xy 156.943409 -316.08664) (xy 156.902906 -316.114596) (xy 156.858444 -316.135694) (xy 156.811173 -316.149386)
			(xy 156.762318 -316.155318) (xy 156.713143 -316.153337) (xy 156.664924 -316.143493) (xy 156.618908 -316.126041)
			(xy 156.576287 -316.101434) (xy 156.538166 -316.070309) (xy 156.505531 -316.033472) (xy 156.479228 -315.991876)
			(xy 156.459937 -315.9466) (xy 156.44816 -315.898816) (xy 156.4442 -315.849762) (xy 156.105352 -315.849762)
			(xy 156.104857 -315.874369) (xy 156.096962 -315.922946) (xy 156.081378 -315.969627) (xy 156.058507 -316.013204)
			(xy 156.028942 -316.052548) (xy 155.993449 -316.08664) (xy 155.952946 -316.114596) (xy 155.908484 -316.135694)
			(xy 155.861213 -316.149386) (xy 155.812358 -316.155318) (xy 155.763183 -316.153337) (xy 155.714964 -316.143493)
			(xy 155.668948 -316.126041) (xy 155.626327 -316.101434) (xy 155.588206 -316.070309) (xy 155.555571 -316.033472)
			(xy 155.529268 -315.991876) (xy 155.509977 -315.9466) (xy 155.4982 -315.898816) (xy 155.49424 -315.849762)
			(xy 155.155392 -315.849762) (xy 155.154897 -315.874369) (xy 155.147002 -315.922946) (xy 155.131418 -315.969627)
			(xy 155.108547 -316.013204) (xy 155.078982 -316.052548) (xy 155.043489 -316.08664) (xy 155.002986 -316.114596)
			(xy 154.958524 -316.135694) (xy 154.911253 -316.149386) (xy 154.862398 -316.155318) (xy 154.813223 -316.153337)
			(xy 154.765004 -316.143493) (xy 154.718988 -316.126041) (xy 154.676367 -316.101434) (xy 154.638246 -316.070309)
			(xy 154.605611 -316.033472) (xy 154.579308 -315.991876) (xy 154.560017 -315.9466) (xy 154.54824 -315.898816)
			(xy 154.54428 -315.849762) (xy 154.205178 -315.849762) (xy 154.204683 -315.874369) (xy 154.196788 -315.922946)
			(xy 154.181204 -315.969627) (xy 154.158333 -316.013204) (xy 154.128768 -316.052548) (xy 154.093275 -316.08664)
			(xy 154.052772 -316.114596) (xy 154.00831 -316.135694) (xy 153.961039 -316.149386) (xy 153.912184 -316.155318)
			(xy 153.863009 -316.153337) (xy 153.81479 -316.143493) (xy 153.768774 -316.126041) (xy 153.726153 -316.101434)
			(xy 153.688032 -316.070309) (xy 153.655397 -316.033472) (xy 153.629094 -315.991876) (xy 153.609803 -315.9466)
			(xy 153.598026 -315.898816) (xy 153.594066 -315.849762) (xy 153.255218 -315.849762) (xy 153.254723 -315.874369)
			(xy 153.246828 -315.922946) (xy 153.231244 -315.969627) (xy 153.208373 -316.013204) (xy 153.178808 -316.052548)
			(xy 153.143315 -316.08664) (xy 153.102812 -316.114596) (xy 153.05835 -316.135694) (xy 153.011079 -316.149386)
			(xy 152.962224 -316.155318) (xy 152.913049 -316.153337) (xy 152.86483 -316.143493) (xy 152.818814 -316.126041)
			(xy 152.776193 -316.101434) (xy 152.738072 -316.070309) (xy 152.705437 -316.033472) (xy 152.679134 -315.991876)
			(xy 152.659843 -315.9466) (xy 152.648066 -315.898816) (xy 152.644106 -315.849762) (xy 118.8466 -315.849762)
			(xy 118.8466 -317.108078) (xy 118.847362 -317.116206) (xy 118.847362 -317.116714) (xy 118.848959 -317.124235)
			(xy 118.855928 -317.13793) (xy 118.861078 -317.143638) (xy 119.574818 -317.857378) (xy 119.5805 -317.862565)
			(xy 119.594208 -317.869533) (xy 119.601742 -317.871094) (xy 119.60225 -317.871094) (xy 119.610378 -317.871856)
			(xy 141.717522 -317.871856)
		)
		(stroke
			(width 0)
			(type solid)
		)
		(fill yes)
		(layer "In7.Cu")
		(net "P0V8_PEX1")
	)
	(gr_poly
		(pts
			(xy 373.925846 -317.871094) (xy 373.926354 -317.871094) (xy 373.933871 -317.86949) (xy 373.947554 -317.862509)
			(xy 373.953278 -317.857378) (xy 375.873772 -315.936884) (xy 375.88117 -315.93004) (xy 375.89977 -315.922318)
			(xy 375.90984 -315.921898) (xy 379.933962 -315.921898) (xy 379.944027 -315.922333) (xy 379.962615 -315.930063)
			(xy 379.97003 -315.936884) (xy 380.832614 -316.799468) (xy 383.89358 -316.799468) (xy 383.89754 -316.750414)
			(xy 383.909317 -316.70263) (xy 383.928608 -316.657354) (xy 383.954911 -316.615758) (xy 383.987546 -316.578921)
			(xy 384.025667 -316.547796) (xy 384.068288 -316.523189) (xy 384.114304 -316.505737) (xy 384.162523 -316.495893)
			(xy 384.211698 -316.493912) (xy 384.260553 -316.499844) (xy 384.307824 -316.513536) (xy 384.352286 -316.534634)
			(xy 384.392789 -316.56259) (xy 384.428282 -316.596682) (xy 384.457847 -316.636026) (xy 384.480718 -316.679603)
			(xy 384.496302 -316.726284) (xy 384.504197 -316.774861) (xy 384.504692 -316.799468) (xy 384.504687 -316.799722)
			(xy 384.844048 -316.799722) (xy 384.848008 -316.750668) (xy 384.859785 -316.702884) (xy 384.879076 -316.657608)
			(xy 384.905379 -316.616012) (xy 384.938014 -316.579175) (xy 384.976135 -316.54805) (xy 385.018756 -316.523443)
			(xy 385.064772 -316.505991) (xy 385.112991 -316.496147) (xy 385.162166 -316.494166) (xy 385.211021 -316.500098)
			(xy 385.258292 -316.51379) (xy 385.302754 -316.534888) (xy 385.343257 -316.562844) (xy 385.37875 -316.596936)
			(xy 385.408315 -316.63628) (xy 385.431186 -316.679857) (xy 385.44677 -316.726538) (xy 385.454665 -316.775115)
			(xy 385.45516 -316.799722) (xy 385.794008 -316.799722) (xy 385.797968 -316.750668) (xy 385.809745 -316.702884)
			(xy 385.829036 -316.657608) (xy 385.855339 -316.616012) (xy 385.887974 -316.579175) (xy 385.926095 -316.54805)
			(xy 385.968716 -316.523443) (xy 386.014732 -316.505991) (xy 386.062951 -316.496147) (xy 386.112126 -316.494166)
			(xy 386.160981 -316.500098) (xy 386.208252 -316.51379) (xy 386.252714 -316.534888) (xy 386.293217 -316.562844)
			(xy 386.32871 -316.596936) (xy 386.358275 -316.63628) (xy 386.381146 -316.679857) (xy 386.39673 -316.726538)
			(xy 386.404625 -316.775115) (xy 386.40512 -316.799722) (xy 386.744222 -316.799722) (xy 386.748182 -316.750668)
			(xy 386.759959 -316.702884) (xy 386.77925 -316.657608) (xy 386.805553 -316.616012) (xy 386.838188 -316.579175)
			(xy 386.876309 -316.54805) (xy 386.91893 -316.523443) (xy 386.964946 -316.505991) (xy 387.013165 -316.496147)
			(xy 387.06234 -316.494166) (xy 387.111195 -316.500098) (xy 387.158466 -316.51379) (xy 387.202928 -316.534888)
			(xy 387.243431 -316.562844) (xy 387.278924 -316.596936) (xy 387.308489 -316.63628) (xy 387.33136 -316.679857)
			(xy 387.346944 -316.726538) (xy 387.354839 -316.775115) (xy 387.355334 -316.799722) (xy 387.694182 -316.799722)
			(xy 387.698142 -316.750668) (xy 387.709919 -316.702884) (xy 387.72921 -316.657608) (xy 387.755513 -316.616012)
			(xy 387.788148 -316.579175) (xy 387.826269 -316.54805) (xy 387.86889 -316.523443) (xy 387.914906 -316.505991)
			(xy 387.963125 -316.496147) (xy 388.0123 -316.494166) (xy 388.061155 -316.500098) (xy 388.108426 -316.51379)
			(xy 388.152888 -316.534888) (xy 388.193391 -316.562844) (xy 388.228884 -316.596936) (xy 388.258449 -316.63628)
			(xy 388.28132 -316.679857) (xy 388.296904 -316.726538) (xy 388.304799 -316.775115) (xy 388.305294 -316.799722)
			(xy 388.644142 -316.799722) (xy 388.648102 -316.750668) (xy 388.659879 -316.702884) (xy 388.67917 -316.657608)
			(xy 388.705473 -316.616012) (xy 388.738108 -316.579175) (xy 388.776229 -316.54805) (xy 388.81885 -316.523443)
			(xy 388.864866 -316.505991) (xy 388.913085 -316.496147) (xy 388.96226 -316.494166) (xy 389.011115 -316.500098)
			(xy 389.058386 -316.51379) (xy 389.102848 -316.534888) (xy 389.143351 -316.562844) (xy 389.178844 -316.596936)
			(xy 389.208409 -316.63628) (xy 389.23128 -316.679857) (xy 389.246864 -316.726538) (xy 389.254759 -316.775115)
			(xy 389.255254 -316.799722) (xy 389.594102 -316.799722) (xy 389.598062 -316.750668) (xy 389.609839 -316.702884)
			(xy 389.62913 -316.657608) (xy 389.655433 -316.616012) (xy 389.688068 -316.579175) (xy 389.726189 -316.54805)
			(xy 389.76881 -316.523443) (xy 389.814826 -316.505991) (xy 389.863045 -316.496147) (xy 389.91222 -316.494166)
			(xy 389.961075 -316.500098) (xy 390.008346 -316.51379) (xy 390.052808 -316.534888) (xy 390.093311 -316.562844)
			(xy 390.128804 -316.596936) (xy 390.158369 -316.63628) (xy 390.18124 -316.679857) (xy 390.196824 -316.726538)
			(xy 390.204719 -316.775115) (xy 390.205214 -316.799722) (xy 390.544062 -316.799722) (xy 390.548022 -316.750668)
			(xy 390.559799 -316.702884) (xy 390.57909 -316.657608) (xy 390.605393 -316.616012) (xy 390.638028 -316.579175)
			(xy 390.676149 -316.54805) (xy 390.71877 -316.523443) (xy 390.764786 -316.505991) (xy 390.813005 -316.496147)
			(xy 390.86218 -316.494166) (xy 390.911035 -316.500098) (xy 390.958306 -316.51379) (xy 391.002768 -316.534888)
			(xy 391.043271 -316.562844) (xy 391.078764 -316.596936) (xy 391.108329 -316.63628) (xy 391.1312 -316.679857)
			(xy 391.146784 -316.726538) (xy 391.154679 -316.775115) (xy 391.155174 -316.799722) (xy 391.494022 -316.799722)
			(xy 391.497982 -316.750668) (xy 391.509759 -316.702884) (xy 391.52905 -316.657608) (xy 391.555353 -316.616012)
			(xy 391.587988 -316.579175) (xy 391.626109 -316.54805) (xy 391.66873 -316.523443) (xy 391.714746 -316.505991)
			(xy 391.762965 -316.496147) (xy 391.81214 -316.494166) (xy 391.860995 -316.500098) (xy 391.908266 -316.51379)
			(xy 391.952728 -316.534888) (xy 391.993231 -316.562844) (xy 392.028724 -316.596936) (xy 392.058289 -316.63628)
			(xy 392.08116 -316.679857) (xy 392.096744 -316.726538) (xy 392.104639 -316.775115) (xy 392.105134 -316.799722)
			(xy 392.443982 -316.799722) (xy 392.447942 -316.750668) (xy 392.459719 -316.702884) (xy 392.47901 -316.657608)
			(xy 392.505313 -316.616012) (xy 392.537948 -316.579175) (xy 392.576069 -316.54805) (xy 392.61869 -316.523443)
			(xy 392.664706 -316.505991) (xy 392.712925 -316.496147) (xy 392.7621 -316.494166) (xy 392.810955 -316.500098)
			(xy 392.858226 -316.51379) (xy 392.902688 -316.534888) (xy 392.943191 -316.562844) (xy 392.978684 -316.596936)
			(xy 393.008249 -316.63628) (xy 393.03112 -316.679857) (xy 393.046704 -316.726538) (xy 393.054599 -316.775115)
			(xy 393.055094 -316.799722) (xy 393.394196 -316.799722) (xy 393.398156 -316.750668) (xy 393.409933 -316.702884)
			(xy 393.429224 -316.657608) (xy 393.455527 -316.616012) (xy 393.488162 -316.579175) (xy 393.526283 -316.54805)
			(xy 393.568904 -316.523443) (xy 393.61492 -316.505991) (xy 393.663139 -316.496147) (xy 393.712314 -316.494166)
			(xy 393.761169 -316.500098) (xy 393.80844 -316.51379) (xy 393.852902 -316.534888) (xy 393.893405 -316.562844)
			(xy 393.928898 -316.596936) (xy 393.958463 -316.63628) (xy 393.981334 -316.679857) (xy 393.996918 -316.726538)
			(xy 394.004813 -316.775115) (xy 394.005308 -316.799722) (xy 394.344156 -316.799722) (xy 394.348116 -316.750668)
			(xy 394.359893 -316.702884) (xy 394.379184 -316.657608) (xy 394.405487 -316.616012) (xy 394.438122 -316.579175)
			(xy 394.476243 -316.54805) (xy 394.518864 -316.523443) (xy 394.56488 -316.505991) (xy 394.613099 -316.496147)
			(xy 394.662274 -316.494166) (xy 394.711129 -316.500098) (xy 394.7584 -316.51379) (xy 394.802862 -316.534888)
			(xy 394.843365 -316.562844) (xy 394.878858 -316.596936) (xy 394.908423 -316.63628) (xy 394.931294 -316.679857)
			(xy 394.946878 -316.726538) (xy 394.954773 -316.775115) (xy 394.955268 -316.799722) (xy 394.954773 -316.824329)
			(xy 394.946878 -316.872906) (xy 394.931294 -316.919587) (xy 394.908423 -316.963164) (xy 394.878858 -317.002508)
			(xy 394.843365 -317.0366) (xy 394.802862 -317.064556) (xy 394.7584 -317.085654) (xy 394.711129 -317.099346)
			(xy 394.662274 -317.105278) (xy 394.613099 -317.103297) (xy 394.56488 -317.093453) (xy 394.518864 -317.076001)
			(xy 394.476243 -317.051394) (xy 394.438122 -317.020269) (xy 394.405487 -316.983432) (xy 394.379184 -316.941836)
			(xy 394.359893 -316.89656) (xy 394.348116 -316.848776) (xy 394.344156 -316.799722) (xy 394.005308 -316.799722)
			(xy 394.004813 -316.824329) (xy 393.996918 -316.872906) (xy 393.981334 -316.919587) (xy 393.958463 -316.963164)
			(xy 393.928898 -317.002508) (xy 393.893405 -317.0366) (xy 393.852902 -317.064556) (xy 393.80844 -317.085654)
			(xy 393.761169 -317.099346) (xy 393.712314 -317.105278) (xy 393.663139 -317.103297) (xy 393.61492 -317.093453)
			(xy 393.568904 -317.076001) (xy 393.526283 -317.051394) (xy 393.488162 -317.020269) (xy 393.455527 -316.983432)
			(xy 393.429224 -316.941836) (xy 393.409933 -316.89656) (xy 393.398156 -316.848776) (xy 393.394196 -316.799722)
			(xy 393.055094 -316.799722) (xy 393.054599 -316.824329) (xy 393.046704 -316.872906) (xy 393.03112 -316.919587)
			(xy 393.008249 -316.963164) (xy 392.978684 -317.002508) (xy 392.943191 -317.0366) (xy 392.902688 -317.064556)
			(xy 392.858226 -317.085654) (xy 392.810955 -317.099346) (xy 392.7621 -317.105278) (xy 392.712925 -317.103297)
			(xy 392.664706 -317.093453) (xy 392.61869 -317.076001) (xy 392.576069 -317.051394) (xy 392.537948 -317.020269)
			(xy 392.505313 -316.983432) (xy 392.47901 -316.941836) (xy 392.459719 -316.89656) (xy 392.447942 -316.848776)
			(xy 392.443982 -316.799722) (xy 392.105134 -316.799722) (xy 392.104639 -316.824329) (xy 392.096744 -316.872906)
			(xy 392.08116 -316.919587) (xy 392.058289 -316.963164) (xy 392.028724 -317.002508) (xy 391.993231 -317.0366)
			(xy 391.952728 -317.064556) (xy 391.908266 -317.085654) (xy 391.860995 -317.099346) (xy 391.81214 -317.105278)
			(xy 391.762965 -317.103297) (xy 391.714746 -317.093453) (xy 391.66873 -317.076001) (xy 391.626109 -317.051394)
			(xy 391.587988 -317.020269) (xy 391.555353 -316.983432) (xy 391.52905 -316.941836) (xy 391.509759 -316.89656)
			(xy 391.497982 -316.848776) (xy 391.494022 -316.799722) (xy 391.155174 -316.799722) (xy 391.154679 -316.824329)
			(xy 391.146784 -316.872906) (xy 391.1312 -316.919587) (xy 391.108329 -316.963164) (xy 391.078764 -317.002508)
			(xy 391.043271 -317.0366) (xy 391.002768 -317.064556) (xy 390.958306 -317.085654) (xy 390.911035 -317.099346)
			(xy 390.86218 -317.105278) (xy 390.813005 -317.103297) (xy 390.764786 -317.093453) (xy 390.71877 -317.076001)
			(xy 390.676149 -317.051394) (xy 390.638028 -317.020269) (xy 390.605393 -316.983432) (xy 390.57909 -316.941836)
			(xy 390.559799 -316.89656) (xy 390.548022 -316.848776) (xy 390.544062 -316.799722) (xy 390.205214 -316.799722)
			(xy 390.204719 -316.824329) (xy 390.196824 -316.872906) (xy 390.18124 -316.919587) (xy 390.158369 -316.963164)
			(xy 390.128804 -317.002508) (xy 390.093311 -317.0366) (xy 390.052808 -317.064556) (xy 390.008346 -317.085654)
			(xy 389.961075 -317.099346) (xy 389.91222 -317.105278) (xy 389.863045 -317.103297) (xy 389.814826 -317.093453)
			(xy 389.76881 -317.076001) (xy 389.726189 -317.051394) (xy 389.688068 -317.020269) (xy 389.655433 -316.983432)
			(xy 389.62913 -316.941836) (xy 389.609839 -316.89656) (xy 389.598062 -316.848776) (xy 389.594102 -316.799722)
			(xy 389.255254 -316.799722) (xy 389.254759 -316.824329) (xy 389.246864 -316.872906) (xy 389.23128 -316.919587)
			(xy 389.208409 -316.963164) (xy 389.178844 -317.002508) (xy 389.143351 -317.0366) (xy 389.102848 -317.064556)
			(xy 389.058386 -317.085654) (xy 389.011115 -317.099346) (xy 388.96226 -317.105278) (xy 388.913085 -317.103297)
			(xy 388.864866 -317.093453) (xy 388.81885 -317.076001) (xy 388.776229 -317.051394) (xy 388.738108 -317.020269)
			(xy 388.705473 -316.983432) (xy 388.67917 -316.941836) (xy 388.659879 -316.89656) (xy 388.648102 -316.848776)
			(xy 388.644142 -316.799722) (xy 388.305294 -316.799722) (xy 388.304799 -316.824329) (xy 388.296904 -316.872906)
			(xy 388.28132 -316.919587) (xy 388.258449 -316.963164) (xy 388.228884 -317.002508) (xy 388.193391 -317.0366)
			(xy 388.152888 -317.064556) (xy 388.108426 -317.085654) (xy 388.061155 -317.099346) (xy 388.0123 -317.105278)
			(xy 387.963125 -317.103297) (xy 387.914906 -317.093453) (xy 387.86889 -317.076001) (xy 387.826269 -317.051394)
			(xy 387.788148 -317.020269) (xy 387.755513 -316.983432) (xy 387.72921 -316.941836) (xy 387.709919 -316.89656)
			(xy 387.698142 -316.848776) (xy 387.694182 -316.799722) (xy 387.355334 -316.799722) (xy 387.354839 -316.824329)
			(xy 387.346944 -316.872906) (xy 387.33136 -316.919587) (xy 387.308489 -316.963164) (xy 387.278924 -317.002508)
			(xy 387.243431 -317.0366) (xy 387.202928 -317.064556) (xy 387.158466 -317.085654) (xy 387.111195 -317.099346)
			(xy 387.06234 -317.105278) (xy 387.013165 -317.103297) (xy 386.964946 -317.093453) (xy 386.91893 -317.076001)
			(xy 386.876309 -317.051394) (xy 386.838188 -317.020269) (xy 386.805553 -316.983432) (xy 386.77925 -316.941836)
			(xy 386.759959 -316.89656) (xy 386.748182 -316.848776) (xy 386.744222 -316.799722) (xy 386.40512 -316.799722)
			(xy 386.404625 -316.824329) (xy 386.39673 -316.872906) (xy 386.381146 -316.919587) (xy 386.358275 -316.963164)
			(xy 386.32871 -317.002508) (xy 386.293217 -317.0366) (xy 386.252714 -317.064556) (xy 386.208252 -317.085654)
			(xy 386.160981 -317.099346) (xy 386.112126 -317.105278) (xy 386.062951 -317.103297) (xy 386.014732 -317.093453)
			(xy 385.968716 -317.076001) (xy 385.926095 -317.051394) (xy 385.887974 -317.020269) (xy 385.855339 -316.983432)
			(xy 385.829036 -316.941836) (xy 385.809745 -316.89656) (xy 385.797968 -316.848776) (xy 385.794008 -316.799722)
			(xy 385.45516 -316.799722) (xy 385.454665 -316.824329) (xy 385.44677 -316.872906) (xy 385.431186 -316.919587)
			(xy 385.408315 -316.963164) (xy 385.37875 -317.002508) (xy 385.343257 -317.0366) (xy 385.302754 -317.064556)
			(xy 385.258292 -317.085654) (xy 385.211021 -317.099346) (xy 385.162166 -317.105278) (xy 385.112991 -317.103297)
			(xy 385.064772 -317.093453) (xy 385.018756 -317.076001) (xy 384.976135 -317.051394) (xy 384.938014 -317.020269)
			(xy 384.905379 -316.983432) (xy 384.879076 -316.941836) (xy 384.859785 -316.89656) (xy 384.848008 -316.848776)
			(xy 384.844048 -316.799722) (xy 384.504687 -316.799722) (xy 384.504197 -316.824075) (xy 384.496302 -316.872652)
			(xy 384.480718 -316.919333) (xy 384.457847 -316.96291) (xy 384.428282 -317.002254) (xy 384.392789 -317.036346)
			(xy 384.352286 -317.064302) (xy 384.307824 -317.0854) (xy 384.260553 -317.099092) (xy 384.211698 -317.105024)
			(xy 384.162523 -317.103043) (xy 384.114304 -317.093199) (xy 384.068288 -317.075747) (xy 384.025667 -317.05114)
			(xy 383.987546 -317.020015) (xy 383.954911 -316.983178) (xy 383.928608 -316.941582) (xy 383.909317 -316.896306)
			(xy 383.89754 -316.848522) (xy 383.89358 -316.799468) (xy 380.832614 -316.799468) (xy 381.890524 -317.857378)
			(xy 381.896022 -317.862368) (xy 381.909188 -317.869215) (xy 381.916432 -317.87084) (xy 381.926084 -317.871856)
			(xy 384.226562 -317.871856) (xy 384.230972 -317.871767) (xy 384.239658 -317.870231) (xy 384.243834 -317.868808)
			(xy 384.248979 -317.866784) (xy 384.258331 -317.860892) (xy 384.262376 -317.857124) (xy 384.308096 -317.811404)
			(xy 384.30835 -317.811404) (xy 384.330956 -317.788798) (xy 384.338358 -317.781961) (xy 384.356956 -317.774247)
			(xy 384.367024 -317.773812) (xy 384.774694 -317.773812) (xy 384.784302 -317.773395) (xy 384.802181 -317.766345)
			(xy 384.809492 -317.760096) (xy 384.831336 -317.739776) (xy 384.837498 -317.733525) (xy 384.845541 -317.717938)
			(xy 384.847084 -317.709296) (xy 384.850805 -317.685169) (xy 384.86491 -317.638436) (xy 384.886268 -317.594541)
			(xy 384.914335 -317.554601) (xy 384.948396 -317.519633) (xy 384.987585 -317.490526) (xy 385.030904 -317.468022)
			(xy 385.07725 -317.452694) (xy 385.125444 -317.444931) (xy 385.17426 -317.444931) (xy 385.222454 -317.452694)
			(xy 385.2688 -317.468022) (xy 385.312119 -317.490526) (xy 385.351308 -317.519633) (xy 385.385369 -317.554601)
			(xy 385.413436 -317.594541) (xy 385.434794 -317.638436) (xy 385.448899 -317.685169) (xy 385.45262 -317.709296)
			(xy 385.454123 -317.717951) (xy 385.462175 -317.733547) (xy 385.468368 -317.739776) (xy 385.490212 -317.760096)
			(xy 385.497504 -317.766375) (xy 385.515395 -317.77342) (xy 385.52501 -317.773812) (xy 385.724654 -317.773812)
			(xy 385.734265 -317.773402) (xy 385.752153 -317.766362) (xy 385.759452 -317.760096) (xy 385.781296 -317.739776)
			(xy 385.787452 -317.733522) (xy 385.795486 -317.717934) (xy 385.797044 -317.709296) (xy 385.800765 -317.685169)
			(xy 385.81487 -317.638436) (xy 385.836228 -317.594541) (xy 385.864295 -317.554601) (xy 385.898356 -317.519633)
			(xy 385.937545 -317.490526) (xy 385.980864 -317.468022) (xy 386.02721 -317.452694) (xy 386.075404 -317.444931)
			(xy 386.12422 -317.444931) (xy 386.172414 -317.452694) (xy 386.21876 -317.468022) (xy 386.262079 -317.490526)
			(xy 386.301268 -317.519633) (xy 386.335329 -317.554601) (xy 386.363396 -317.594541) (xy 386.384754 -317.638436)
			(xy 386.398859 -317.685169) (xy 386.40258 -317.709296) (xy 386.404085 -317.717949) (xy 386.412144 -317.733539)
			(xy 386.418328 -317.739776) (xy 386.440172 -317.760096) (xy 386.447462 -317.766381) (xy 386.465352 -317.77344)
			(xy 386.47497 -317.773812) (xy 386.674868 -317.773812) (xy 386.684478 -317.7734) (xy 386.702363 -317.766356)
			(xy 386.709666 -317.760096) (xy 386.73151 -317.739776) (xy 386.737674 -317.733526) (xy 386.745722 -317.717939)
			(xy 386.747258 -317.709296) (xy 386.750979 -317.685169) (xy 386.765084 -317.638436) (xy 386.786442 -317.594541)
			(xy 386.814509 -317.554601) (xy 386.84857 -317.519633) (xy 386.887759 -317.490526) (xy 386.931078 -317.468022)
			(xy 386.977424 -317.452694) (xy 387.025618 -317.444931) (xy 387.074434 -317.444931) (xy 387.122628 -317.452694)
			(xy 387.168974 -317.468022) (xy 387.212293 -317.490526) (xy 387.251482 -317.519633) (xy 387.285543 -317.554601)
			(xy 387.31361 -317.594541) (xy 387.334968 -317.638436) (xy 387.349073 -317.685169) (xy 387.352794 -317.709296)
			(xy 387.3543 -317.717948) (xy 387.362361 -317.733537) (xy 387.368542 -317.739776) (xy 387.390386 -317.760096)
			(xy 387.397677 -317.766379) (xy 387.415567 -317.773433) (xy 387.425184 -317.773812) (xy 387.624828 -317.773812)
			(xy 387.634441 -317.773407) (xy 387.652336 -317.766373) (xy 387.659626 -317.760096) (xy 387.68147 -317.739776)
			(xy 387.687628 -317.733523) (xy 387.695666 -317.717935) (xy 387.697218 -317.709296) (xy 387.700939 -317.685169)
			(xy 387.715044 -317.638436) (xy 387.736402 -317.594541) (xy 387.764469 -317.554601) (xy 387.79853 -317.519633)
			(xy 387.837719 -317.490526) (xy 387.881038 -317.468022) (xy 387.927384 -317.452694) (xy 387.975578 -317.444931)
			(xy 388.024394 -317.444931) (xy 388.072588 -317.452694) (xy 388.118934 -317.468022) (xy 388.162253 -317.490526)
			(xy 388.201442 -317.519633) (xy 388.235503 -317.554601) (xy 388.26357 -317.594541) (xy 388.284928 -317.638436)
			(xy 388.299033 -317.685169) (xy 388.302754 -317.709296) (xy 388.304259 -317.71795) (xy 388.312314 -317.733542)
			(xy 388.318502 -317.739776) (xy 388.340346 -317.760096) (xy 388.34764 -317.76637) (xy 388.36553 -317.773403)
			(xy 388.375144 -317.773812) (xy 388.574788 -317.773812) (xy 388.584397 -317.773396) (xy 388.602277 -317.766347)
			(xy 388.609586 -317.760096) (xy 388.63143 -317.739776) (xy 388.637592 -317.733525) (xy 388.645637 -317.717938)
			(xy 388.647178 -317.709296) (xy 388.650899 -317.685169) (xy 388.665004 -317.638436) (xy 388.686362 -317.594541)
			(xy 388.714429 -317.554601) (xy 388.74849 -317.519633) (xy 388.787679 -317.490526) (xy 388.830998 -317.468022)
			(xy 388.877344 -317.452694) (xy 388.925538 -317.444931) (xy 388.974354 -317.444931) (xy 389.022548 -317.452694)
			(xy 389.068894 -317.468022) (xy 389.112213 -317.490526) (xy 389.151402 -317.519633) (xy 389.185463 -317.554601)
			(xy 389.21353 -317.594541) (xy 389.234888 -317.638436) (xy 389.248993 -317.685169) (xy 389.252714 -317.709296)
			(xy 389.254221 -317.717948) (xy 389.262283 -317.733534) (xy 389.268462 -317.739776) (xy 389.290306 -317.760096)
			(xy 389.297598 -317.766375) (xy 389.315488 -317.773423) (xy 389.325104 -317.773812) (xy 389.524748 -317.773812)
			(xy 389.53436 -317.773403) (xy 389.552249 -317.766364) (xy 389.559546 -317.760096) (xy 389.58139 -317.739776)
			(xy 389.587547 -317.733522) (xy 389.595581 -317.717934) (xy 389.597138 -317.709296) (xy 389.600859 -317.685169)
			(xy 389.614964 -317.638436) (xy 389.636322 -317.594541) (xy 389.664389 -317.554601) (xy 389.69845 -317.519633)
			(xy 389.737639 -317.490526) (xy 389.780958 -317.468022) (xy 389.827304 -317.452694) (xy 389.875498 -317.444931)
			(xy 389.924314 -317.444931) (xy 389.972508 -317.452694) (xy 390.018854 -317.468022) (xy 390.062173 -317.490526)
			(xy 390.101362 -317.519633) (xy 390.135423 -317.554601) (xy 390.16349 -317.594541) (xy 390.184848 -317.638436)
			(xy 390.198953 -317.685169) (xy 390.202674 -317.709296) (xy 390.204179 -317.717949) (xy 390.212237 -317.73354)
			(xy 390.218422 -317.739776) (xy 390.240266 -317.760096) (xy 390.247556 -317.766382) (xy 390.265446 -317.773443)
			(xy 390.275064 -317.773812) (xy 390.474708 -317.773812) (xy 390.484315 -317.773393) (xy 390.50219 -317.766339)
			(xy 390.509506 -317.760096) (xy 390.53135 -317.739776) (xy 390.53751 -317.733524) (xy 390.545551 -317.717937)
			(xy 390.547098 -317.709296) (xy 390.550819 -317.685169) (xy 390.564924 -317.638436) (xy 390.586282 -317.594541)
			(xy 390.614349 -317.554601) (xy 390.64841 -317.519633) (xy 390.687599 -317.490526) (xy 390.730918 -317.468022)
			(xy 390.777264 -317.452694) (xy 390.825458 -317.444931) (xy 390.874274 -317.444931) (xy 390.922468 -317.452694)
			(xy 390.968814 -317.468022) (xy 391.012133 -317.490526) (xy 391.051322 -317.519633) (xy 391.085383 -317.554601)
			(xy 391.11345 -317.594541) (xy 391.134808 -317.638436) (xy 391.148913 -317.685169) (xy 391.152634 -317.709296)
			(xy 391.154138 -317.71795) (xy 391.162191 -317.733545) (xy 391.168382 -317.739776) (xy 391.190226 -317.760096)
			(xy 391.197519 -317.766372) (xy 391.215409 -317.773413) (xy 391.225024 -317.773812) (xy 391.424668 -317.773812)
			(xy 391.434278 -317.7734) (xy 391.452163 -317.766356) (xy 391.459466 -317.760096) (xy 391.48131 -317.739776)
			(xy 391.487474 -317.733526) (xy 391.495522 -317.717939) (xy 391.497058 -317.709296) (xy 391.500779 -317.685169)
			(xy 391.514884 -317.638436) (xy 391.536242 -317.594541) (xy 391.564309 -317.554601) (xy 391.59837 -317.519633)
			(xy 391.637559 -317.490526) (xy 391.680878 -317.468022) (xy 391.727224 -317.452694) (xy 391.775418 -317.444931)
			(xy 391.824234 -317.444931) (xy 391.872428 -317.452694) (xy 391.918774 -317.468022) (xy 391.962093 -317.490526)
			(xy 392.001282 -317.519633) (xy 392.035343 -317.554601) (xy 392.06341 -317.594541) (xy 392.084768 -317.638436)
			(xy 392.098873 -317.685169) (xy 392.102594 -317.709296) (xy 392.1041 -317.717948) (xy 392.112161 -317.733537)
			(xy 392.118342 -317.739776) (xy 392.140186 -317.760096) (xy 392.147477 -317.766379) (xy 392.165367 -317.773433)
			(xy 392.174984 -317.773812) (xy 392.374628 -317.773812) (xy 392.384241 -317.773407) (xy 392.402136 -317.766373)
			(xy 392.409426 -317.760096) (xy 392.43127 -317.739776) (xy 392.437428 -317.733523) (xy 392.445466 -317.717935)
			(xy 392.447018 -317.709296) (xy 392.450739 -317.685169) (xy 392.464844 -317.638436) (xy 392.486202 -317.594541)
			(xy 392.514269 -317.554601) (xy 392.54833 -317.519633) (xy 392.587519 -317.490526) (xy 392.630838 -317.468022)
			(xy 392.677184 -317.452694) (xy 392.725378 -317.444931) (xy 392.774194 -317.444931) (xy 392.822388 -317.452694)
			(xy 392.868734 -317.468022) (xy 392.912053 -317.490526) (xy 392.951242 -317.519633) (xy 392.985303 -317.554601)
			(xy 393.01337 -317.594541) (xy 393.034728 -317.638436) (xy 393.048833 -317.685169) (xy 393.052554 -317.709296)
			(xy 393.054059 -317.71795) (xy 393.062114 -317.733542) (xy 393.068302 -317.739776) (xy 393.090146 -317.760096)
			(xy 393.09744 -317.76637) (xy 393.11533 -317.773403) (xy 393.124944 -317.773812) (xy 393.324842 -317.773812)
			(xy 393.334454 -317.773404) (xy 393.352345 -317.766367) (xy 393.35964 -317.760096) (xy 393.381484 -317.739776)
			(xy 393.387641 -317.733522) (xy 393.395677 -317.717935) (xy 393.397232 -317.709296) (xy 393.400953 -317.685169)
			(xy 393.415058 -317.638436) (xy 393.436416 -317.594541) (xy 393.464483 -317.554601) (xy 393.498544 -317.519633)
			(xy 393.537733 -317.490526) (xy 393.581052 -317.468022) (xy 393.627398 -317.452694) (xy 393.675592 -317.444931)
			(xy 393.724408 -317.444931) (xy 393.772602 -317.452694) (xy 393.818948 -317.468022) (xy 393.862267 -317.490526)
			(xy 393.901456 -317.519633) (xy 393.935517 -317.554601) (xy 393.963584 -317.594541) (xy 393.984942 -317.638436)
			(xy 393.999047 -317.685169) (xy 394.002768 -317.709296) (xy 394.004273 -317.717949) (xy 394.01233 -317.73354)
			(xy 394.018516 -317.739776) (xy 394.04036 -317.760096) (xy 394.04765 -317.766383) (xy 394.06554 -317.773446)
			(xy 394.075158 -317.773812) (xy 394.274802 -317.773812) (xy 394.28441 -317.773394) (xy 394.302286 -317.766341)
			(xy 394.3096 -317.760096) (xy 394.331444 -317.739776) (xy 394.337605 -317.733524) (xy 394.345647 -317.717937)
			(xy 394.347192 -317.709296) (xy 394.350913 -317.685169) (xy 394.365018 -317.638436) (xy 394.386376 -317.594541)
			(xy 394.414443 -317.554601) (xy 394.448504 -317.519633) (xy 394.487693 -317.490526) (xy 394.531012 -317.468022)
			(xy 394.577358 -317.452694) (xy 394.625552 -317.444931) (xy 394.674368 -317.444931) (xy 394.722562 -317.452694)
			(xy 394.768908 -317.468022) (xy 394.812227 -317.490526) (xy 394.851416 -317.519633) (xy 394.885477 -317.554601)
			(xy 394.913544 -317.594541) (xy 394.934902 -317.638436) (xy 394.949007 -317.685169) (xy 394.952728 -317.709296)
			(xy 394.954232 -317.71795) (xy 394.962285 -317.733546) (xy 394.968476 -317.739776) (xy 394.99032 -317.760096)
			(xy 394.997613 -317.766373) (xy 395.015503 -317.773416) (xy 395.025118 -317.773812) (xy 395.224762 -317.773812)
			(xy 395.234373 -317.773401) (xy 395.252259 -317.766358) (xy 395.25956 -317.760096) (xy 395.281404 -317.739776)
			(xy 395.287569 -317.733527) (xy 395.295618 -317.71794) (xy 395.297152 -317.709296) (xy 395.300847 -317.685308)
			(xy 395.314834 -317.638833) (xy 395.335992 -317.595154) (xy 395.363788 -317.555368) (xy 395.397524 -317.520476)
			(xy 395.436351 -317.491356) (xy 395.479293 -317.468739) (xy 395.52527 -317.453195) (xy 395.54912 -317.448692)
			(xy 395.54912 -317.448946) (xy 395.561725 -317.446944) (xy 395.587158 -317.444784) (xy 395.59992 -317.444628)
			(xy 395.614039 -317.444827) (xy 395.642151 -317.447496) (xy 395.656054 -317.449962) (xy 395.668754 -317.452248)
			(xy 395.680438 -317.448692) (xy 395.686276 -317.446686) (xy 395.696818 -317.440272) (xy 395.701266 -317.435992)
			(xy 395.730984 -317.40602) (xy 395.760702 -317.376302) (xy 395.764945 -317.371824) (xy 395.771365 -317.361296)
			(xy 395.773402 -317.355474) (xy 395.776958 -317.34379) (xy 395.774672 -317.33109) (xy 395.772186 -317.317125)
			(xy 395.769514 -317.288885) (xy 395.769338 -317.274702) (xy 395.769524 -317.26052) (xy 395.772197 -317.23228)
			(xy 395.774672 -317.218314) (xy 395.776958 -317.205868) (xy 395.773402 -317.194184) (xy 395.771388 -317.188351)
			(xy 395.764964 -317.177819) (xy 395.760702 -317.173356) (xy 395.730476 -317.14313) (xy 395.701266 -317.113666)
			(xy 395.696756 -317.109369) (xy 395.686093 -317.102938) (xy 395.680184 -317.100966) (xy 395.669262 -317.097664)
			(xy 395.656562 -317.09995) (xy 395.656054 -317.09995) (xy 395.642145 -317.102348) (xy 395.614033 -317.104891)
			(xy 395.59992 -317.10503) (xy 395.575097 -317.104546) (xy 395.526103 -317.096517) (xy 395.479055 -317.080667)
			(xy 395.43519 -317.057414) (xy 395.395665 -317.027371) (xy 395.361522 -316.991329) (xy 395.333659 -316.950238)
			(xy 395.312811 -316.905181) (xy 395.299528 -316.857344) (xy 395.294159 -316.807989) (xy 395.296846 -316.758415)
			(xy 395.307518 -316.709928) (xy 395.325894 -316.663808) (xy 395.351489 -316.621267) (xy 395.38363 -316.583429)
			(xy 395.421469 -316.551288) (xy 395.464009 -316.525693) (xy 395.51013 -316.507318) (xy 395.558617 -316.496646)
			(xy 395.608191 -316.493959) (xy 395.657546 -316.499329) (xy 395.705383 -316.512612) (xy 395.75044 -316.53346)
			(xy 395.791531 -316.561323) (xy 395.827573 -316.595467) (xy 395.857615 -316.634992) (xy 395.880868 -316.678856)
			(xy 395.896717 -316.725905) (xy 395.904746 -316.774899) (xy 395.905228 -316.799722) (xy 395.90504 -316.813904)
			(xy 395.902365 -316.842143) (xy 395.899894 -316.85611) (xy 395.897608 -316.868556) (xy 395.901164 -316.88024)
			(xy 395.903173 -316.886076) (xy 395.909592 -316.896614) (xy 395.913864 -316.901068) (xy 395.94409 -316.931294)
			(xy 395.9733 -316.960758) (xy 395.977814 -316.965047) (xy 395.988482 -316.971463) (xy 395.994382 -316.973458)
			(xy 396.005304 -316.97676) (xy 396.018004 -316.974474) (xy 396.018512 -316.974474) (xy 396.032421 -316.972075)
			(xy 396.060532 -316.969529) (xy 396.074646 -316.969394) (xy 396.088892 -316.969572) (xy 396.117259 -316.972244)
			(xy 396.131288 -316.974728) (xy 396.14348 -316.977014) (xy 396.155418 -316.973458) (xy 396.161305 -316.971438)
			(xy 396.171969 -316.965025) (xy 396.1765 -316.960758) (xy 396.235936 -316.901322) (xy 396.240178 -316.896844)
			(xy 396.246598 -316.886316) (xy 396.248636 -316.880494) (xy 396.252192 -316.868556) (xy 396.249906 -316.85611)
			(xy 396.24742 -316.842145) (xy 396.244746 -316.813905) (xy 396.244572 -316.799722) (xy 396.245017 -316.775727)
			(xy 396.25252 -316.728328) (xy 396.267347 -316.682686) (xy 396.289131 -316.639925) (xy 396.317335 -316.601099)
			(xy 396.351267 -316.567163) (xy 396.390089 -316.538953) (xy 396.432847 -316.517163) (xy 396.478487 -316.50233)
			(xy 396.525885 -316.49482) (xy 396.54988 -316.494414) (xy 396.58163 -316.495938) (xy 396.592806 -316.496954)
			(xy 396.602204 -316.493906) (xy 396.607223 -316.49209) (xy 396.616439 -316.486711) (xy 396.620492 -316.483238)
			(xy 396.676626 -316.432692) (xy 396.684138 -316.425149) (xy 396.6928 -316.405729) (xy 396.69339 -316.3951)
			(xy 396.69339 -316.324742) (xy 396.693552 -316.311088) (xy 396.69584 -316.283875) (xy 396.697962 -316.270386)
			(xy 396.69974 -316.258448) (xy 396.696438 -316.247526) (xy 396.694569 -316.24181) (xy 396.688539 -316.231408)
			(xy 396.6845 -316.226952) (xy 396.628112 -316.168024) (xy 396.624003 -316.164011) (xy 396.614384 -316.157739)
			(xy 396.609062 -316.155578) (xy 396.597886 -316.151514) (xy 396.585694 -316.153038) (xy 396.576772 -316.154)
			(xy 396.558854 -316.155015) (xy 396.54988 -316.15507) (xy 396.524629 -316.154547) (xy 396.474816 -316.146232)
			(xy 396.427051 -316.129831) (xy 396.382636 -316.105793) (xy 396.342784 -316.074772) (xy 396.308581 -316.037615)
			(xy 396.28096 -315.995336) (xy 396.260674 -315.949087) (xy 396.248277 -315.90013) (xy 396.244107 -315.8498)
			(xy 396.248277 -315.79947) (xy 396.260674 -315.750513) (xy 396.28096 -315.704264) (xy 396.308581 -315.661985)
			(xy 396.342784 -315.624828) (xy 396.382636 -315.593807) (xy 396.427051 -315.569769) (xy 396.474816 -315.553368)
			(xy 396.524629 -315.545053) (xy 396.54988 -315.544454) (xy 396.564063 -315.54464) (xy 396.592302 -315.547311)
			(xy 396.606268 -315.549788) (xy 396.618714 -315.552074) (xy 396.630398 -315.548518) (xy 396.63623 -315.546503)
			(xy 396.646757 -315.540074) (xy 396.651226 -315.535818) (xy 396.710916 -315.476128) (xy 396.71516 -315.471651)
			(xy 396.721583 -315.461124) (xy 396.723616 -315.4553) (xy 396.727172 -315.443616) (xy 396.724886 -315.43117)
			(xy 396.722402 -315.417205) (xy 396.719732 -315.388965) (xy 396.719552 -315.374782) (xy 396.719739 -315.3606)
			(xy 396.722414 -315.332361) (xy 396.724886 -315.318394) (xy 396.727172 -315.305948) (xy 396.723616 -315.294264)
			(xy 396.721607 -315.288428) (xy 396.715186 -315.277892) (xy 396.710916 -315.273436) (xy 396.651226 -315.213746)
			(xy 396.646747 -315.209505) (xy 396.636219 -315.203087) (xy 396.630398 -315.201046) (xy 396.618714 -315.19749)
			(xy 396.606268 -315.199776) (xy 396.592303 -315.20226) (xy 396.564063 -315.204931) (xy 396.54988 -315.20511)
			(xy 396.524626 -315.204587) (xy 396.474806 -315.19627) (xy 396.427035 -315.179868) (xy 396.382615 -315.155826)
			(xy 396.342757 -315.124802) (xy 396.30855 -315.08764) (xy 396.280925 -315.045355) (xy 396.260637 -314.9991)
			(xy 396.248238 -314.950136) (xy 396.244067 -314.8998) (xy 396.248238 -314.849464) (xy 396.260637 -314.8005)
			(xy 396.280925 -314.754245) (xy 396.30855 -314.71196) (xy 396.342757 -314.674798) (xy 396.382615 -314.643774)
			(xy 396.427035 -314.619732) (xy 396.474806 -314.60333) (xy 396.524626 -314.595013) (xy 396.54988 -314.594494)
			(xy 396.559048 -314.594586) (xy 396.577348 -314.595728) (xy 396.586456 -314.59678) (xy 396.58798 -314.597034)
			(xy 396.598394 -314.59805) (xy 396.609316 -314.59424) (xy 396.614895 -314.592076) (xy 396.624908 -314.585529)
			(xy 396.629128 -314.581286) (xy 396.657068 -314.552076) (xy 396.685516 -314.522104) (xy 396.689374 -314.517837)
			(xy 396.695276 -314.507967) (xy 396.6972 -314.502546) (xy 396.700756 -314.49137) (xy 396.699486 -314.484004)
			(xy 396.698724 -314.479178) (xy 396.696592 -314.46569) (xy 396.694303 -314.438477) (xy 396.694152 -314.424822)
			(xy 396.694315 -314.411168) (xy 396.696605 -314.383956) (xy 396.698724 -314.370466) (xy 396.699486 -314.36564)
			(xy 396.700756 -314.358274) (xy 396.6972 -314.347098) (xy 396.695295 -314.341668) (xy 396.689393 -314.331793)
			(xy 396.685516 -314.32754) (xy 396.657322 -314.297822) (xy 396.629128 -314.268358) (xy 396.624899 -314.264126)
			(xy 396.614889 -314.257579) (xy 396.609316 -314.255404) (xy 396.598394 -314.251594) (xy 396.58798 -314.25261)
			(xy 396.586456 -314.252864) (xy 396.577348 -314.253917) (xy 396.559048 -314.255058) (xy 396.54988 -314.25515)
			(xy 396.524622 -314.254627) (xy 396.474796 -314.246309) (xy 396.427019 -314.229904) (xy 396.382593 -314.20586)
			(xy 396.34273 -314.174831) (xy 396.308518 -314.137664) (xy 396.28089 -314.095374) (xy 396.260599 -314.049113)
			(xy 396.248198 -314.000143) (xy 396.244027 -313.9498) (xy 396.248198 -313.899457) (xy 396.260599 -313.850487)
			(xy 396.28089 -313.804226) (xy 396.308518 -313.761936) (xy 396.34273 -313.724769) (xy 396.382593 -313.69374)
			(xy 396.427019 -313.669696) (xy 396.474796 -313.653291) (xy 396.524622 -313.644973) (xy 396.54988 -313.644534)
			(xy 396.559048 -313.644626) (xy 396.577348 -313.645768) (xy 396.586456 -313.64682) (xy 396.58798 -313.647074)
			(xy 396.598394 -313.64809) (xy 396.609316 -313.64428) (xy 396.614896 -313.642118) (xy 396.624913 -313.635574)
			(xy 396.629128 -313.631326) (xy 396.657068 -313.602116) (xy 396.685516 -313.572144) (xy 396.689379 -313.567882)
			(xy 396.695271 -313.558006) (xy 396.6972 -313.552586) (xy 396.700756 -313.54141) (xy 396.699486 -313.534044)
			(xy 396.698724 -313.529218) (xy 396.696591 -313.51573) (xy 396.694298 -313.488517) (xy 396.694152 -313.474862)
			(xy 396.694313 -313.461208) (xy 396.6966 -313.433995) (xy 396.698724 -313.420506) (xy 396.699486 -313.41568)
			(xy 396.700756 -313.408314) (xy 396.6972 -313.397138) (xy 396.695299 -313.391706) (xy 396.689402 -313.381825)
			(xy 396.685516 -313.37758) (xy 396.657322 -313.347862) (xy 396.629128 -313.318398) (xy 396.624901 -313.314163)
			(xy 396.614893 -313.307611) (xy 396.609316 -313.305444) (xy 396.598394 -313.301634) (xy 396.58798 -313.30265)
			(xy 396.586456 -313.302904) (xy 396.577348 -313.303957) (xy 396.559048 -313.305098) (xy 396.54988 -313.30519)
			(xy 396.524627 -313.304667) (xy 396.474811 -313.296351) (xy 396.427043 -313.279949) (xy 396.382626 -313.255909)
			(xy 396.342771 -313.224887) (xy 396.308565 -313.187728) (xy 396.280942 -313.145445) (xy 396.260655 -313.099193)
			(xy 396.248258 -313.050233) (xy 396.244087 -312.9999) (xy 396.248258 -312.949567) (xy 396.260655 -312.900607)
			(xy 396.280942 -312.854355) (xy 396.308565 -312.812072) (xy 396.342771 -312.774913) (xy 396.382626 -312.743891)
			(xy 396.427043 -312.719851) (xy 396.474811 -312.703449) (xy 396.524627 -312.695133) (xy 396.54988 -312.694574)
			(xy 396.559048 -312.694666) (xy 396.577348 -312.695808) (xy 396.586456 -312.69686) (xy 396.58798 -312.697114)
			(xy 396.598394 -312.69813) (xy 396.609316 -312.69432) (xy 396.614895 -312.692155) (xy 396.624905 -312.685606)
			(xy 396.629128 -312.681366) (xy 396.657068 -312.652156) (xy 396.685516 -312.622184) (xy 396.689373 -312.617917)
			(xy 396.695271 -312.608045) (xy 396.6972 -312.602626) (xy 396.700756 -312.59145) (xy 396.699486 -312.584084)
			(xy 396.698724 -312.579258) (xy 396.696593 -312.56577) (xy 396.694305 -312.538557) (xy 396.694152 -312.524902)
			(xy 396.694315 -312.511248) (xy 396.696607 -312.484036) (xy 396.698724 -312.470546) (xy 396.699486 -312.46572)
			(xy 396.700756 -312.458354) (xy 396.6972 -312.447178) (xy 396.695293 -312.441749) (xy 396.689388 -312.431877)
			(xy 396.685516 -312.42762) (xy 396.657322 -312.397902) (xy 396.629128 -312.368438) (xy 396.624899 -312.364207)
			(xy 396.614888 -312.357662) (xy 396.609316 -312.355484) (xy 396.598394 -312.351674) (xy 396.58798 -312.35269)
			(xy 396.586456 -312.352944) (xy 396.577348 -312.353997) (xy 396.559048 -312.355138) (xy 396.54988 -312.35523)
			(xy 396.524624 -312.354707) (xy 396.474801 -312.34639) (xy 396.427027 -312.329986) (xy 396.382604 -312.305943)
			(xy 396.342744 -312.274916) (xy 396.308534 -312.237752) (xy 396.280907 -312.195464) (xy 396.260618 -312.149206)
			(xy 396.248218 -312.10024) (xy 396.244047 -312.0499) (xy 396.248218 -311.99956) (xy 396.260618 -311.950594)
			(xy 396.280907 -311.904336) (xy 396.308534 -311.862048) (xy 396.342744 -311.824884) (xy 396.382604 -311.793857)
			(xy 396.427027 -311.769814) (xy 396.474801 -311.75341) (xy 396.524624 -311.745093) (xy 396.54988 -311.744614)
			(xy 396.558917 -311.744661) (xy 396.576963 -311.745678) (xy 396.585948 -311.746646) (xy 396.59814 -311.74817)
			(xy 396.608808 -311.74436) (xy 396.614232 -311.742201) (xy 396.623985 -311.735789) (xy 396.628112 -311.73166)
			(xy 396.685008 -311.672478) (xy 396.688946 -311.668126) (xy 396.694849 -311.657985) (xy 396.696692 -311.652412)
			(xy 396.700248 -311.641236) (xy 396.698216 -311.629044) (xy 396.696086 -311.615556) (xy 396.693799 -311.588342)
			(xy 396.693644 -311.574688) (xy 396.693644 -311.504584) (xy 396.69318 -311.493928) (xy 396.684486 -311.474471)
			(xy 396.67688 -311.466992) (xy 396.620746 -311.416446) (xy 396.616657 -311.412924) (xy 396.607306 -311.407538)
			(xy 396.602204 -311.405778) (xy 396.592806 -311.40273) (xy 396.581884 -311.403746) (xy 396.54988 -311.40527)
			(xy 396.524629 -311.404747) (xy 396.474816 -311.396432) (xy 396.427051 -311.380031) (xy 396.382636 -311.355993)
			(xy 396.342784 -311.324972) (xy 396.308581 -311.287815) (xy 396.28096 -311.245536) (xy 396.260674 -311.199287)
			(xy 396.248277 -311.15033) (xy 396.244107 -311.1) (xy 396.248277 -311.04967) (xy 396.260674 -311.000713)
			(xy 396.28096 -310.954464) (xy 396.308581 -310.912185) (xy 396.342784 -310.875028) (xy 396.382636 -310.844007)
			(xy 396.427051 -310.819969) (xy 396.474816 -310.803568) (xy 396.524629 -310.795253) (xy 396.54988 -310.794654)
			(xy 396.581884 -310.796178) (xy 396.592806 -310.797194) (xy 396.602204 -310.794146) (xy 396.607297 -310.792366)
			(xy 396.616647 -310.786986) (xy 396.620746 -310.783478) (xy 396.67688 -310.732932) (xy 396.684392 -310.725388)
			(xy 396.69306 -310.705969) (xy 396.693644 -310.69534) (xy 396.693644 -310.624728) (xy 396.693806 -310.611074)
			(xy 396.696096 -310.583861) (xy 396.698216 -310.570372) (xy 396.698978 -310.565546) (xy 396.700248 -310.55818)
			(xy 396.696692 -310.547004) (xy 396.694787 -310.541574) (xy 396.688885 -310.531699) (xy 396.685008 -310.527446)
			(xy 396.660878 -310.502046) (xy 396.62862 -310.46801) (xy 396.624366 -310.463856) (xy 396.614358 -310.457442)
			(xy 396.608808 -310.45531) (xy 396.59814 -310.4515) (xy 396.586202 -310.453024) (xy 396.577155 -310.454012)
			(xy 396.558981 -310.455025) (xy 396.54988 -310.455056) (xy 396.524622 -310.454533) (xy 396.474795 -310.446216)
			(xy 396.427016 -310.42981) (xy 396.382589 -310.405765) (xy 396.342726 -310.374736) (xy 396.308513 -310.337568)
			(xy 396.280884 -310.295277) (xy 396.260593 -310.249015) (xy 396.248192 -310.200044) (xy 396.24402 -310.1497)
			(xy 396.248192 -310.099356) (xy 396.260593 -310.050385) (xy 396.280884 -310.004123) (xy 396.308513 -309.961832)
			(xy 396.342726 -309.924664) (xy 396.382589 -309.893635) (xy 396.427016 -309.86959) (xy 396.474795 -309.853184)
			(xy 396.524622 -309.844867) (xy 396.54988 -309.84444) (xy 396.564063 -309.844626) (xy 396.592302 -309.847297)
			(xy 396.606268 -309.849774) (xy 396.618714 -309.85206) (xy 396.630398 -309.848504) (xy 396.636232 -309.846492)
			(xy 396.646767 -309.840071) (xy 396.651226 -309.835804) (xy 396.710916 -309.776114) (xy 396.715159 -309.771636)
			(xy 396.721579 -309.761108) (xy 396.723616 -309.755286) (xy 396.727172 -309.743602) (xy 396.724886 -309.731156)
			(xy 396.722403 -309.717191) (xy 396.719734 -309.688951) (xy 396.719552 -309.674768) (xy 396.720074 -309.649513)
			(xy 396.728387 -309.599691) (xy 396.744788 -309.551917) (xy 396.768829 -309.507494) (xy 396.799853 -309.467634)
			(xy 396.837015 -309.433424) (xy 396.879301 -309.405798) (xy 396.925557 -309.385508) (xy 396.974522 -309.373108)
			(xy 397.02486 -309.368937) (xy 397.075198 -309.373108) (xy 397.124163 -309.385508) (xy 397.170419 -309.405798)
			(xy 397.212705 -309.433424) (xy 397.249867 -309.467634) (xy 397.280891 -309.507494) (xy 397.304932 -309.551917)
			(xy 397.321333 -309.599691) (xy 397.329646 -309.649513) (xy 397.330168 -309.674768) (xy 397.329983 -309.688951)
			(xy 397.327312 -309.71719) (xy 397.324834 -309.731156) (xy 397.322548 -309.743602) (xy 397.326104 -309.755286)
			(xy 397.328115 -309.761121) (xy 397.334536 -309.771657) (xy 397.338804 -309.776114) (xy 397.398494 -309.835804)
			(xy 397.402972 -309.840047) (xy 397.4135 -309.846468) (xy 397.419322 -309.848504) (xy 397.431006 -309.85206)
			(xy 397.443452 -309.849774) (xy 397.457417 -309.84729) (xy 397.485657 -309.844621) (xy 397.49984 -309.84444)
			(xy 397.509008 -309.844534) (xy 397.527308 -309.84568) (xy 397.536416 -309.846726) (xy 397.53794 -309.84698)
			(xy 397.548354 -309.847996) (xy 397.559022 -309.844186) (xy 397.564663 -309.842034) (xy 397.574801 -309.835483)
			(xy 397.579088 -309.831232) (xy 397.607028 -309.801768) (xy 397.635476 -309.772304) (xy 397.63936 -309.767985)
			(xy 397.64525 -309.757978) (xy 397.64716 -309.752492) (xy 397.650716 -309.741316) (xy 397.649446 -309.73395)
			(xy 397.648684 -309.729124) (xy 397.64502 -309.70428) (xy 397.644355 -309.654067) (xy 397.651289 -309.604331)
			(xy 397.665663 -309.556215) (xy 397.687146 -309.510825) (xy 397.715245 -309.469205) (xy 397.749313 -309.432312)
			(xy 397.788567 -309.400993) (xy 397.832105 -309.37597) (xy 397.878926 -309.357816) (xy 397.927953 -309.346949)
			(xy 397.952976 -309.344822) (xy 397.961612 -309.344314) (xy 397.985996 -309.333646) (xy 397.990341 -309.331717)
			(xy 397.998275 -309.326482) (xy 398.001744 -309.323232) (xy 398.016984 -309.308246) (xy 398.02394 -309.300823)
			(xy 398.031817 -309.282087) (xy 398.032224 -309.271924) (xy 398.032224 -309.127652) (xy 398.031875 -309.119199)
			(xy 398.026301 -309.103235) (xy 398.021302 -309.09641) (xy 398.017238 -309.091584) (xy 397.995394 -309.069994)
			(xy 397.991914 -309.066708) (xy 397.983987 -309.061343) (xy 397.979646 -309.059326) (xy 397.971264 -309.05577)
			(xy 397.961612 -309.055262) (xy 397.961358 -309.055262) (xy 397.936301 -309.053762) (xy 397.887039 -309.044137)
			(xy 397.839796 -309.027179) (xy 397.795658 -309.003277) (xy 397.755638 -308.972981) (xy 397.720656 -308.936985)
			(xy 397.691515 -308.896117) (xy 397.668883 -308.851314) (xy 397.653281 -308.803606) (xy 397.645067 -308.754089)
			(xy 397.64443 -308.703899) (xy 397.651384 -308.654188) (xy 397.665769 -308.6061) (xy 397.687256 -308.560737)
			(xy 397.71535 -308.519142) (xy 397.749407 -308.482269) (xy 397.788645 -308.450966) (xy 397.832161 -308.425951)
			(xy 397.878958 -308.4078) (xy 397.927961 -308.396927) (xy 397.952976 -308.394862) (xy 397.961612 -308.394354)
			(xy 397.985996 -308.383686) (xy 397.99034 -308.381755) (xy 397.99827 -308.376516) (xy 398.001744 -308.373272)
			(xy 398.016984 -308.358286) (xy 398.02393 -308.35086) (xy 398.031785 -308.332123) (xy 398.032224 -308.321964)
			(xy 398.032224 -308.177692) (xy 398.031865 -308.169243) (xy 398.026277 -308.15329) (xy 398.021302 -308.14645)
			(xy 398.017238 -308.141624) (xy 397.995394 -308.120034) (xy 397.991912 -308.116751) (xy 397.983983 -308.111392)
			(xy 397.979646 -308.109366) (xy 397.971264 -308.10581) (xy 397.961612 -308.105302) (xy 397.961358 -308.105302)
			(xy 397.934987 -308.103696) (xy 397.883221 -308.093152) (xy 397.833789 -308.074512) (xy 397.78795 -308.04825)
			(xy 397.74687 -308.015034) (xy 397.711592 -307.975709) (xy 397.683016 -307.931275) (xy 397.661868 -307.882864)
			(xy 397.648686 -307.831706) (xy 397.643805 -307.779102) (xy 397.64735 -307.726392) (xy 397.65923 -307.674916)
			(xy 397.679143 -307.625983) (xy 397.706582 -307.580839) (xy 397.74085 -307.540632) (xy 397.781075 -307.506384)
			(xy 397.826233 -307.478968) (xy 397.875176 -307.459079) (xy 397.926658 -307.447225) (xy 397.952976 -307.444902)
			(xy 397.961612 -307.444394) (xy 397.985996 -307.433726) (xy 397.99034 -307.431796) (xy 397.998273 -307.42656)
			(xy 398.001744 -307.423312) (xy 398.016984 -307.408326) (xy 398.023936 -307.400902) (xy 398.031806 -307.382166)
			(xy 398.032224 -307.372004) (xy 398.032224 -307.227732) (xy 398.031871 -307.21928) (xy 398.026293 -307.20332)
			(xy 398.021302 -307.19649) (xy 398.017238 -307.191664) (xy 397.995394 -307.170074) (xy 397.991913 -307.166789)
			(xy 397.983986 -307.161426) (xy 397.979646 -307.159406) (xy 397.971264 -307.15585) (xy 397.961612 -307.155342)
			(xy 397.961358 -307.155342) (xy 397.936303 -307.153842) (xy 397.887043 -307.144217) (xy 397.839803 -307.127261)
			(xy 397.795668 -307.10336) (xy 397.755651 -307.073065) (xy 397.720671 -307.037071) (xy 397.691531 -306.996205)
			(xy 397.668901 -306.951405) (xy 397.653301 -306.9037) (xy 397.645087 -306.854186) (xy 397.64445 -306.803999)
			(xy 397.651404 -306.754292) (xy 397.665788 -306.706206) (xy 397.687274 -306.660846) (xy 397.715367 -306.619253)
			(xy 397.749422 -306.582383) (xy 397.788657 -306.551082) (xy 397.832171 -306.526069) (xy 397.878965 -306.507918)
			(xy 397.927965 -306.497047) (xy 397.952976 -306.494942) (xy 397.961612 -306.494434) (xy 397.985996 -306.483766)
			(xy 397.990339 -306.481834) (xy 397.998268 -306.476594) (xy 398.001744 -306.473352) (xy 398.016984 -306.458366)
			(xy 398.023927 -306.450939) (xy 398.031774 -306.432202) (xy 398.032224 -306.422044) (xy 398.032224 -306.277772)
			(xy 398.031862 -306.269324) (xy 398.026269 -306.253375) (xy 398.021302 -306.24653) (xy 398.017238 -306.241704)
			(xy 397.995394 -306.220114) (xy 397.991918 -306.216822) (xy 397.983992 -306.211454) (xy 397.979646 -306.209446)
			(xy 397.971264 -306.20589) (xy 397.961612 -306.205382) (xy 397.961358 -306.205382) (xy 397.934989 -306.203776)
			(xy 397.883226 -306.193232) (xy 397.833797 -306.174593) (xy 397.787961 -306.148333) (xy 397.746883 -306.115119)
			(xy 397.711608 -306.075796) (xy 397.683033 -306.031365) (xy 397.661887 -305.982956) (xy 397.648706 -305.931801)
			(xy 397.643825 -305.879201) (xy 397.64737 -305.826494) (xy 397.659249 -305.775021) (xy 397.679161 -305.726091)
			(xy 397.706599 -305.68095) (xy 397.740865 -305.640745) (xy 397.781088 -305.6065) (xy 397.826243 -305.579085)
			(xy 397.875183 -305.559198) (xy 397.926662 -305.547345) (xy 397.952976 -305.544982) (xy 397.961612 -305.544474)
			(xy 397.985996 -305.533806) (xy 397.99034 -305.531876) (xy 397.998272 -305.526638) (xy 398.001744 -305.523392)
			(xy 398.016984 -305.508406) (xy 398.023933 -305.500981) (xy 398.031795 -305.482245) (xy 398.032224 -305.472084)
			(xy 398.032224 -305.327558) (xy 398.031876 -305.319105) (xy 398.026304 -305.303139) (xy 398.021302 -305.296316)
			(xy 398.017238 -305.29149) (xy 397.995394 -305.2699) (xy 397.991914 -305.266613) (xy 397.983988 -305.261248)
			(xy 397.979646 -305.259232) (xy 397.971264 -305.255676) (xy 397.961612 -305.255168) (xy 397.961358 -305.255168)
			(xy 397.936083 -305.253657) (xy 397.886397 -305.243913) (xy 397.838778 -305.22671) (xy 397.794337 -305.20245)
			(xy 397.754112 -305.171699) (xy 397.719044 -305.135178) (xy 397.689953 -305.093738) (xy 397.667517 -305.048349)
			(xy 397.652261 -305.00007) (xy 397.644542 -304.95003) (xy 397.644112 -304.924714) (xy 397.644594 -304.898725)
			(xy 397.652724 -304.847385) (xy 397.668785 -304.79795) (xy 397.692382 -304.751637) (xy 397.722935 -304.709585)
			(xy 397.75969 -304.672831) (xy 397.801742 -304.642279) (xy 397.848056 -304.618683) (xy 397.897491 -304.602622)
			(xy 397.948831 -304.594494) (xy 397.97482 -304.594006) (xy 397.975074 -304.594006) (xy 398.002811 -304.594563)
			(xy 398.057509 -304.603813) (xy 398.109891 -304.622073) (xy 398.158486 -304.648829) (xy 398.18056 -304.665634)
			(xy 398.18691 -304.670714) (xy 398.20977 -304.679096) (xy 398.21104 -304.679604) (xy 398.211548 -304.679604)
			(xy 398.2212 -304.68189) (xy 398.229582 -304.682144) (xy 398.244568 -304.681382) (xy 398.292828 -304.679096)
			(xy 398.301434 -304.677881) (xy 398.31715 -304.670485) (xy 398.323562 -304.664618) (xy 398.652746 -304.335434)
			(xy 398.657409 -304.331006) (xy 398.668471 -304.324457) (xy 398.67459 -304.32248) (xy 398.681194 -304.320448)
			(xy 398.686528 -304.317146) (xy 398.696942 -304.30851) (xy 398.71142 -304.29327) (xy 398.7165 -304.287936)
			(xy 398.723612 -304.26914) (xy 398.723358 -304.25898) (xy 398.722577 -304.248922) (xy 398.714203 -304.230585)
			(xy 398.707102 -304.22342) (xy 398.704054 -304.220372) (xy 398.703038 -304.21961) (xy 398.682941 -304.200679)
			(xy 398.648727 -304.157352) (xy 398.622191 -304.108941) (xy 398.60407 -304.056792) (xy 398.594869 -304.002357)
			(xy 398.594326 -303.974754) (xy 398.594836 -303.948767) (xy 398.602966 -303.897432) (xy 398.619027 -303.848002)
			(xy 398.642623 -303.801692) (xy 398.673173 -303.759644) (xy 398.709924 -303.722893) (xy 398.751972 -303.692343)
			(xy 398.798282 -303.668747) (xy 398.847712 -303.652686) (xy 398.899047 -303.644556) (xy 398.951021 -303.644556)
			(xy 399.002356 -303.652686) (xy 399.051786 -303.668747) (xy 399.098096 -303.692343) (xy 399.140144 -303.722893)
			(xy 399.176895 -303.759644) (xy 399.207445 -303.801692) (xy 399.231041 -303.848002) (xy 399.247102 -303.897432)
			(xy 399.255232 -303.948767) (xy 399.255742 -303.974754) (xy 399.255742 -303.975008) (xy 399.255282 -303.999825)
			(xy 399.247831 -304.048898) (xy 399.23313 -304.096307) (xy 399.211507 -304.140985) (xy 399.19783 -304.161698)
			(xy 399.191672 -304.171965) (xy 399.18861 -304.19568) (xy 399.191988 -304.207164) (xy 399.19402 -304.212244)
			(xy 399.238724 -304.296318) (xy 399.242039 -304.301419) (xy 399.250646 -304.310012) (xy 399.255742 -304.313336)
			(xy 399.262346 -304.3174) (xy 399.268696 -304.318924) (xy 399.530316 -304.318924) (xy 399.540018 -304.316061)
			(xy 399.556241 -304.304002) (xy 399.561812 -304.295556) (xy 399.563082 -304.29327) (xy 399.564352 -304.290984)
			(xy 399.56486 -304.289714) (xy 399.604992 -304.214022) (xy 399.608744 -304.206273) (xy 399.611338 -304.189264)
			(xy 399.610072 -304.180748) (xy 399.608294 -304.171096) (xy 399.601944 -304.161698) (xy 399.588305 -304.140971)
			(xy 399.566733 -304.096289) (xy 399.552091 -304.048881) (xy 399.544709 -303.999817) (xy 399.544286 -303.975008)
			(xy 399.544286 -303.974754) (xy 399.544796 -303.948767) (xy 399.552926 -303.897432) (xy 399.568987 -303.848002)
			(xy 399.592583 -303.801692) (xy 399.623133 -303.759644) (xy 399.659884 -303.722893) (xy 399.701932 -303.692343)
			(xy 399.748242 -303.668747) (xy 399.797672 -303.652686) (xy 399.849007 -303.644556) (xy 399.900981 -303.644556)
			(xy 399.952316 -303.652686) (xy 400.001746 -303.668747) (xy 400.048056 -303.692343) (xy 400.090104 -303.722893)
			(xy 400.126855 -303.759644) (xy 400.157405 -303.801692) (xy 400.181001 -303.848002) (xy 400.197062 -303.897432)
			(xy 400.205192 -303.948767) (xy 400.205702 -303.974754) (xy 400.205702 -303.975008) (xy 400.205242 -303.999826)
			(xy 400.197793 -304.048899) (xy 400.183093 -304.096309) (xy 400.161474 -304.140989) (xy 400.14779 -304.161698)
			(xy 400.141636 -304.171966) (xy 400.138576 -304.195679) (xy 400.141948 -304.207164) (xy 400.14398 -304.212244)
			(xy 400.188684 -304.296318) (xy 400.191997 -304.301421) (xy 400.2006 -304.31002) (xy 400.205702 -304.313336)
			(xy 400.212306 -304.3174) (xy 400.218656 -304.318924) (xy 400.480276 -304.318924) (xy 400.489983 -304.316067)
			(xy 400.506216 -304.304014) (xy 400.511772 -304.295556) (xy 400.513042 -304.29327) (xy 400.514312 -304.290984)
			(xy 400.51482 -304.289714) (xy 400.554952 -304.214022) (xy 400.558706 -304.206274) (xy 400.561302 -304.189264)
			(xy 400.560032 -304.180748) (xy 400.558254 -304.171096) (xy 400.551904 -304.161698) (xy 400.538262 -304.140971)
			(xy 400.516687 -304.09629) (xy 400.502042 -304.048883) (xy 400.494659 -303.999817) (xy 400.494246 -303.975008)
			(xy 400.494246 -303.974754) (xy 400.494756 -303.948767) (xy 400.502886 -303.897432) (xy 400.518947 -303.848002)
			(xy 400.542543 -303.801692) (xy 400.573093 -303.759644) (xy 400.609844 -303.722893) (xy 400.651892 -303.692343)
			(xy 400.698202 -303.668747) (xy 400.747632 -303.652686) (xy 400.798967 -303.644556) (xy 400.850941 -303.644556)
			(xy 400.902276 -303.652686) (xy 400.951706 -303.668747) (xy 400.998016 -303.692343) (xy 401.040064 -303.722893)
			(xy 401.076815 -303.759644) (xy 401.107365 -303.801692) (xy 401.130961 -303.848002) (xy 401.147022 -303.897432)
			(xy 401.155152 -303.948767) (xy 401.155662 -303.974754) (xy 401.155662 -303.975008) (xy 401.155202 -303.999825)
			(xy 401.147752 -304.048899) (xy 401.133051 -304.096307) (xy 401.111429 -304.140986) (xy 401.09775 -304.161698)
			(xy 401.09159 -304.171965) (xy 401.088527 -304.19568) (xy 401.091908 -304.207164) (xy 401.09394 -304.212244)
			(xy 401.138644 -304.296318) (xy 401.141955 -304.301424) (xy 401.150555 -304.310028) (xy 401.155662 -304.313336)
			(xy 401.162266 -304.3174) (xy 401.168616 -304.318924) (xy 401.430236 -304.318924) (xy 401.439947 -304.316072)
			(xy 401.456192 -304.304026) (xy 401.461732 -304.295556) (xy 401.463002 -304.29327) (xy 401.464272 -304.290984)
			(xy 401.46478 -304.289714) (xy 401.504912 -304.214022) (xy 401.508663 -304.206273) (xy 401.511255 -304.189264)
			(xy 401.509992 -304.180748) (xy 401.508214 -304.171096) (xy 401.501864 -304.161698) (xy 401.488224 -304.140971)
			(xy 401.466651 -304.096289) (xy 401.452008 -304.048882) (xy 401.444626 -303.999817) (xy 401.444206 -303.975008)
			(xy 401.444206 -303.974754) (xy 401.444716 -303.948767) (xy 401.452846 -303.897432) (xy 401.468907 -303.848002)
			(xy 401.492503 -303.801692) (xy 401.523053 -303.759644) (xy 401.559804 -303.722893) (xy 401.601852 -303.692343)
			(xy 401.648162 -303.668747) (xy 401.697592 -303.652686) (xy 401.748927 -303.644556) (xy 401.800901 -303.644556)
			(xy 401.852236 -303.652686) (xy 401.901666 -303.668747) (xy 401.947976 -303.692343) (xy 401.990024 -303.722893)
			(xy 402.026775 -303.759644) (xy 402.057325 -303.801692) (xy 402.080921 -303.848002) (xy 402.096982 -303.897432)
			(xy 402.105112 -303.948767) (xy 402.105622 -303.974754) (xy 402.105622 -303.975008) (xy 402.105161 -303.999825)
			(xy 402.097711 -304.048898) (xy 402.083008 -304.096306) (xy 402.061384 -304.140983) (xy 402.04771 -304.161698)
			(xy 402.041554 -304.171966) (xy 402.038493 -304.19568) (xy 402.041868 -304.207164) (xy 402.0439 -304.212244)
			(xy 402.088604 -304.296318) (xy 402.091918 -304.30142) (xy 402.100523 -304.310016) (xy 402.105622 -304.313336)
			(xy 402.112226 -304.3174) (xy 402.118576 -304.318924) (xy 402.380196 -304.318924) (xy 402.389901 -304.316064)
			(xy 402.406129 -304.304008) (xy 402.411692 -304.295556) (xy 402.412962 -304.29327) (xy 402.414232 -304.290984)
			(xy 402.41474 -304.289714) (xy 402.454872 -304.214022) (xy 402.458626 -304.206273) (xy 402.46122 -304.189264)
			(xy 402.459952 -304.180748) (xy 402.458174 -304.171096) (xy 402.451824 -304.161698) (xy 402.438182 -304.140972)
			(xy 402.416605 -304.096291) (xy 402.401959 -304.048883) (xy 402.394575 -303.999817) (xy 402.394166 -303.975008)
			(xy 402.394166 -303.974754) (xy 402.394676 -303.948767) (xy 402.402806 -303.897432) (xy 402.418867 -303.848002)
			(xy 402.442463 -303.801692) (xy 402.473013 -303.759644) (xy 402.509764 -303.722893) (xy 402.551812 -303.692343)
			(xy 402.598122 -303.668747) (xy 402.647552 -303.652686) (xy 402.698887 -303.644556) (xy 402.750861 -303.644556)
			(xy 402.802196 -303.652686) (xy 402.851626 -303.668747) (xy 402.897936 -303.692343) (xy 402.939984 -303.722893)
			(xy 402.976735 -303.759644) (xy 403.007285 -303.801692) (xy 403.030881 -303.848002) (xy 403.046942 -303.897432)
			(xy 403.055072 -303.948767) (xy 403.055582 -303.974754) (xy 403.055582 -303.975008) (xy 403.055122 -303.999826)
			(xy 403.047672 -304.048899) (xy 403.032972 -304.096308) (xy 403.011351 -304.140987) (xy 402.99767 -304.161698)
			(xy 402.991518 -304.171967) (xy 402.988459 -304.195679) (xy 402.991828 -304.207164) (xy 402.99386 -304.212244)
			(xy 403.038564 -304.296318) (xy 403.041876 -304.301422) (xy 403.050478 -304.310024) (xy 403.055582 -304.313336)
			(xy 403.062186 -304.3174) (xy 403.068536 -304.318924) (xy 403.330156 -304.318924) (xy 403.339865 -304.31607)
			(xy 403.356104 -304.30402) (xy 403.361652 -304.295556) (xy 403.362922 -304.29327) (xy 403.364192 -304.290984)
			(xy 403.3647 -304.289714) (xy 403.404832 -304.214022) (xy 403.408588 -304.206274) (xy 403.411184 -304.189264)
			(xy 403.409912 -304.180748) (xy 403.408134 -304.171096) (xy 403.401784 -304.161698) (xy 403.388143 -304.140971)
			(xy 403.366569 -304.09629) (xy 403.351925 -304.048882) (xy 403.344542 -303.999817) (xy 403.344126 -303.975008)
			(xy 403.344126 -303.974754) (xy 403.344636 -303.948767) (xy 403.352766 -303.897432) (xy 403.368827 -303.848002)
			(xy 403.392423 -303.801692) (xy 403.422973 -303.759644) (xy 403.459724 -303.722893) (xy 403.501772 -303.692343)
			(xy 403.548082 -303.668747) (xy 403.597512 -303.652686) (xy 403.648847 -303.644556) (xy 403.700821 -303.644556)
			(xy 403.752156 -303.652686) (xy 403.801586 -303.668747) (xy 403.847896 -303.692343) (xy 403.889944 -303.722893)
			(xy 403.926695 -303.759644) (xy 403.957245 -303.801692) (xy 403.980841 -303.848002) (xy 403.996902 -303.897432)
			(xy 404.005032 -303.948767) (xy 404.005542 -303.974754) (xy 404.005542 -303.975008) (xy 404.005082 -303.999825)
			(xy 403.997631 -304.048898) (xy 403.98293 -304.096307) (xy 403.961307 -304.140985) (xy 403.94763 -304.161698)
			(xy 403.941472 -304.171965) (xy 403.93841 -304.19568) (xy 403.941788 -304.207164) (xy 403.94382 -304.212244)
			(xy 403.988524 -304.296318) (xy 403.991839 -304.301419) (xy 404.000446 -304.310012) (xy 404.005542 -304.313336)
			(xy 404.012146 -304.3174) (xy 404.018496 -304.318924) (xy 404.280116 -304.318924) (xy 404.289818 -304.316061)
			(xy 404.306041 -304.304002) (xy 404.311612 -304.295556) (xy 404.312882 -304.29327) (xy 404.314152 -304.290984)
			(xy 404.31466 -304.289714) (xy 404.354792 -304.214022) (xy 404.358544 -304.206273) (xy 404.361138 -304.189264)
			(xy 404.359872 -304.180748) (xy 404.358094 -304.171096) (xy 404.351744 -304.161698) (xy 404.338105 -304.140971)
			(xy 404.316533 -304.096289) (xy 404.301891 -304.048881) (xy 404.294509 -303.999817) (xy 404.294086 -303.975008)
			(xy 404.294086 -303.974754) (xy 404.294596 -303.948767) (xy 404.302726 -303.897432) (xy 404.318787 -303.848002)
			(xy 404.342383 -303.801692) (xy 404.372933 -303.759644) (xy 404.409684 -303.722893) (xy 404.451732 -303.692343)
			(xy 404.498042 -303.668747) (xy 404.547472 -303.652686) (xy 404.598807 -303.644556) (xy 404.650781 -303.644556)
			(xy 404.702116 -303.652686) (xy 404.751546 -303.668747) (xy 404.797856 -303.692343) (xy 404.839904 -303.722893)
			(xy 404.876655 -303.759644) (xy 404.907205 -303.801692) (xy 404.930801 -303.848002) (xy 404.946862 -303.897432)
			(xy 404.954992 -303.948767) (xy 404.955502 -303.974754) (xy 404.955502 -303.975008) (xy 404.955042 -303.999826)
			(xy 404.947593 -304.048899) (xy 404.932893 -304.096309) (xy 404.911274 -304.140989) (xy 404.89759 -304.161698)
			(xy 404.891436 -304.171966) (xy 404.888376 -304.195679) (xy 404.891748 -304.207164) (xy 404.89378 -304.212244)
			(xy 404.938484 -304.296318) (xy 404.941797 -304.301421) (xy 404.9504 -304.31002) (xy 404.955502 -304.313336)
			(xy 404.962106 -304.3174) (xy 404.968456 -304.318924) (xy 405.23033 -304.318924) (xy 405.240042 -304.316073)
			(xy 405.256288 -304.304028) (xy 405.261826 -304.295556) (xy 405.263096 -304.29327) (xy 405.264366 -304.290984)
			(xy 405.264874 -304.289714) (xy 405.305006 -304.214022) (xy 405.308757 -304.206273) (xy 405.31135 -304.189264)
			(xy 405.310086 -304.180748) (xy 405.308308 -304.171096) (xy 405.301958 -304.161698) (xy 405.288318 -304.140971)
			(xy 405.266745 -304.096289) (xy 405.252103 -304.048882) (xy 405.244721 -303.999817) (xy 405.2443 -303.975008)
			(xy 405.2443 -303.974754) (xy 405.24481 -303.948767) (xy 405.25294 -303.897432) (xy 405.269001 -303.848002)
			(xy 405.292597 -303.801692) (xy 405.323147 -303.759644) (xy 405.359898 -303.722893) (xy 405.401946 -303.692343)
			(xy 405.448256 -303.668747) (xy 405.497686 -303.652686) (xy 405.549021 -303.644556) (xy 405.600995 -303.644556)
			(xy 405.65233 -303.652686) (xy 405.70176 -303.668747) (xy 405.74807 -303.692343) (xy 405.790118 -303.722893)
			(xy 405.826869 -303.759644) (xy 405.857419 -303.801692) (xy 405.881015 -303.848002) (xy 405.897076 -303.897432)
			(xy 405.905206 -303.948767) (xy 405.905716 -303.974754) (xy 405.905716 -303.975008) (xy 405.905255 -303.999825)
			(xy 405.897805 -304.048898) (xy 405.883102 -304.096306) (xy 405.861478 -304.140983) (xy 405.847804 -304.161698)
			(xy 405.841649 -304.171966) (xy 405.838588 -304.195679) (xy 405.841962 -304.207164) (xy 405.843994 -304.212244)
			(xy 405.888698 -304.296318) (xy 405.892012 -304.301421) (xy 405.900616 -304.310017) (xy 405.905716 -304.313336)
			(xy 405.91232 -304.3174) (xy 405.91867 -304.318924) (xy 406.18029 -304.318924) (xy 406.189995 -304.316065)
			(xy 406.206225 -304.30401) (xy 406.211786 -304.295556) (xy 406.213056 -304.29327) (xy 406.214326 -304.290984)
			(xy 406.214834 -304.289714) (xy 406.254966 -304.214022) (xy 406.25872 -304.206274) (xy 406.261315 -304.189264)
			(xy 406.260046 -304.180748) (xy 406.258268 -304.171096) (xy 406.251918 -304.161698) (xy 406.238276 -304.140972)
			(xy 406.216699 -304.096291) (xy 406.202054 -304.048883) (xy 406.19467 -303.999817) (xy 406.19426 -303.975008)
			(xy 406.19426 -303.974754) (xy 406.19477 -303.948767) (xy 406.2029 -303.897432) (xy 406.218961 -303.848002)
			(xy 406.242557 -303.801692) (xy 406.273107 -303.759644) (xy 406.309858 -303.722893) (xy 406.351906 -303.692343)
			(xy 406.398216 -303.668747) (xy 406.447646 -303.652686) (xy 406.498981 -303.644556) (xy 406.550955 -303.644556)
			(xy 406.60229 -303.652686) (xy 406.65172 -303.668747) (xy 406.69803 -303.692343) (xy 406.740078 -303.722893)
			(xy 406.776829 -303.759644) (xy 406.807379 -303.801692) (xy 406.830975 -303.848002) (xy 406.847036 -303.897432)
			(xy 406.855166 -303.948767) (xy 406.855676 -303.974754) (xy 406.855676 -303.975008) (xy 406.855216 -303.999826)
			(xy 406.847766 -304.048899) (xy 406.833066 -304.096308) (xy 406.811445 -304.140987) (xy 406.797764 -304.161698)
			(xy 406.791603 -304.171964) (xy 406.788538 -304.195681) (xy 406.791922 -304.207164) (xy 406.793954 -304.212244)
			(xy 406.838658 -304.296318) (xy 406.84197 -304.301423) (xy 406.850571 -304.310025) (xy 406.855676 -304.313336)
			(xy 406.86228 -304.3174) (xy 406.86863 -304.318924) (xy 408.08021 -304.318924) (xy 408.089913 -304.316062)
			(xy 408.106137 -304.304003) (xy 408.111706 -304.295556) (xy 408.112976 -304.29327) (xy 408.114246 -304.290984)
			(xy 408.114754 -304.289714) (xy 408.154886 -304.214022) (xy 408.158639 -304.206273) (xy 408.161232 -304.189264)
			(xy 408.159966 -304.180748) (xy 408.158188 -304.171096) (xy 408.151838 -304.161698) (xy 408.138199 -304.140971)
			(xy 408.116628 -304.096288) (xy 408.101986 -304.048881) (xy 408.094604 -303.999817) (xy 408.09418 -303.975008)
			(xy 408.09418 -303.974754) (xy 408.09469 -303.948767) (xy 408.10282 -303.897432) (xy 408.118881 -303.848002)
			(xy 408.142477 -303.801692) (xy 408.173027 -303.759644) (xy 408.209778 -303.722893) (xy 408.251826 -303.692343)
			(xy 408.298136 -303.668747) (xy 408.347566 -303.652686) (xy 408.398901 -303.644556) (xy 408.450875 -303.644556)
			(xy 408.50221 -303.652686) (xy 408.55164 -303.668747) (xy 408.59795 -303.692343) (xy 408.639998 -303.722893)
			(xy 408.676749 -303.759644) (xy 408.707299 -303.801692) (xy 408.730895 -303.848002) (xy 408.746956 -303.897432)
			(xy 408.755086 -303.948767) (xy 408.755596 -303.974754) (xy 408.755596 -303.975008) (xy 408.755136 -303.999826)
			(xy 408.747687 -304.048899) (xy 408.732987 -304.096309) (xy 408.711367 -304.140989) (xy 408.697684 -304.161698)
			(xy 408.69153 -304.171966) (xy 408.68847 -304.195679) (xy 408.691842 -304.207164) (xy 408.693874 -304.212244)
			(xy 408.738578 -304.296318) (xy 408.741891 -304.301422) (xy 408.750493 -304.310021) (xy 408.755596 -304.313336)
			(xy 408.7622 -304.3174) (xy 408.76855 -304.318924) (xy 409.03017 -304.318924) (xy 409.039878 -304.316068)
			(xy 409.056113 -304.304016) (xy 409.061666 -304.295556) (xy 409.062936 -304.29327) (xy 409.064206 -304.290984)
			(xy 409.064714 -304.289714) (xy 409.104846 -304.214022) (xy 409.108601 -304.206274) (xy 409.111197 -304.189264)
			(xy 409.109926 -304.180748) (xy 409.108148 -304.171096) (xy 409.101798 -304.161698) (xy 409.088157 -304.140971)
			(xy 409.066581 -304.09629) (xy 409.051937 -304.048883) (xy 409.044554 -303.999817) (xy 409.04414 -303.975008)
			(xy 409.04414 -303.974754) (xy 409.04465 -303.948767) (xy 409.05278 -303.897432) (xy 409.068841 -303.848002)
			(xy 409.092437 -303.801692) (xy 409.122987 -303.759644) (xy 409.159738 -303.722893) (xy 409.201786 -303.692343)
			(xy 409.248096 -303.668747) (xy 409.297526 -303.652686) (xy 409.348861 -303.644556) (xy 409.400835 -303.644556)
			(xy 409.45217 -303.652686) (xy 409.5016 -303.668747) (xy 409.54791 -303.692343) (xy 409.589958 -303.722893)
			(xy 409.626709 -303.759644) (xy 409.657259 -303.801692) (xy 409.680855 -303.848002) (xy 409.696916 -303.897432)
			(xy 409.705046 -303.948767) (xy 409.705556 -303.974754) (xy 409.705556 -303.975008) (xy 409.705096 -303.999825)
			(xy 409.697646 -304.048899) (xy 409.682945 -304.096307) (xy 409.661322 -304.140986) (xy 409.647644 -304.161698)
			(xy 409.641485 -304.171965) (xy 409.638422 -304.19568) (xy 409.641802 -304.207164) (xy 409.643834 -304.212244)
			(xy 409.688538 -304.296318) (xy 409.691848 -304.301424) (xy 409.700448 -304.310029) (xy 409.705556 -304.313336)
			(xy 409.71216 -304.3174) (xy 409.71851 -304.318924) (xy 409.98013 -304.318924) (xy 409.989842 -304.316073)
			(xy 410.006088 -304.304028) (xy 410.011626 -304.295556) (xy 410.012896 -304.29327) (xy 410.014166 -304.290984)
			(xy 410.014674 -304.289714) (xy 410.054806 -304.214022) (xy 410.058557 -304.206273) (xy 410.06115 -304.189264)
			(xy 410.059886 -304.180748) (xy 410.058108 -304.171096) (xy 410.051758 -304.161698) (xy 410.038118 -304.140971)
			(xy 410.016545 -304.096289) (xy 410.001903 -304.048882) (xy 409.994521 -303.999817) (xy 409.9941 -303.975008)
			(xy 409.9941 -303.974754) (xy 409.99461 -303.948767) (xy 410.00274 -303.897432) (xy 410.018801 -303.848002)
			(xy 410.042397 -303.801692) (xy 410.072947 -303.759644) (xy 410.109698 -303.722893) (xy 410.151746 -303.692343)
			(xy 410.198056 -303.668747) (xy 410.247486 -303.652686) (xy 410.298821 -303.644556) (xy 410.350795 -303.644556)
			(xy 410.40213 -303.652686) (xy 410.45156 -303.668747) (xy 410.49787 -303.692343) (xy 410.539918 -303.722893)
			(xy 410.576669 -303.759644) (xy 410.607219 -303.801692) (xy 410.630815 -303.848002) (xy 410.646876 -303.897432)
			(xy 410.655006 -303.948767) (xy 410.655516 -303.974754) (xy 410.655516 -303.975008) (xy 410.655055 -303.999825)
			(xy 410.647605 -304.048898) (xy 410.632902 -304.096306) (xy 410.611278 -304.140983) (xy 410.597604 -304.161698)
			(xy 410.591449 -304.171966) (xy 410.588388 -304.195679) (xy 410.591762 -304.207164) (xy 410.593794 -304.212244)
			(xy 410.638498 -304.296318) (xy 410.641812 -304.301421) (xy 410.650416 -304.310017) (xy 410.655516 -304.313336)
			(xy 410.66212 -304.3174) (xy 410.66847 -304.318924) (xy 410.930344 -304.318924) (xy 410.940055 -304.316072)
			(xy 410.956297 -304.304024) (xy 410.96184 -304.295556) (xy 410.96311 -304.29327) (xy 410.96438 -304.290984)
			(xy 410.964888 -304.289714) (xy 411.00502 -304.214022) (xy 411.008777 -304.206274) (xy 411.011374 -304.189264)
			(xy 411.0101 -304.180748) (xy 411.008322 -304.171096) (xy 411.001972 -304.161698) (xy 410.988332 -304.140971)
			(xy 410.966758 -304.096289) (xy 410.952115 -304.048882) (xy 410.944732 -303.999817) (xy 410.944314 -303.975008)
			(xy 410.944314 -303.974754) (xy 410.944824 -303.948767) (xy 410.952954 -303.897432) (xy 410.969015 -303.848002)
			(xy 410.992611 -303.801692) (xy 411.023161 -303.759644) (xy 411.059912 -303.722893) (xy 411.10196 -303.692343)
			(xy 411.14827 -303.668747) (xy 411.1977 -303.652686) (xy 411.249035 -303.644556) (xy 411.301009 -303.644556)
			(xy 411.352344 -303.652686) (xy 411.401774 -303.668747) (xy 411.448084 -303.692343) (xy 411.490132 -303.722893)
			(xy 411.526883 -303.759644) (xy 411.557433 -303.801692) (xy 411.581029 -303.848002) (xy 411.59709 -303.897432)
			(xy 411.60522 -303.948767) (xy 411.60573 -303.974754) (xy 411.60573 -303.975008) (xy 411.60527 -303.999825)
			(xy 411.597819 -304.048898) (xy 411.583117 -304.096306) (xy 411.561493 -304.140984) (xy 411.547818 -304.161698)
			(xy 411.541661 -304.171965) (xy 411.538599 -304.19568) (xy 411.541976 -304.207164) (xy 411.544008 -304.212244)
			(xy 411.588712 -304.296318) (xy 411.592026 -304.30142) (xy 411.600632 -304.310015) (xy 411.60573 -304.313336)
			(xy 411.612334 -304.3174) (xy 411.618684 -304.318924) (xy 411.880304 -304.318924) (xy 411.890008 -304.316063)
			(xy 411.906233 -304.304005) (xy 411.9118 -304.295556) (xy 411.91307 -304.29327) (xy 411.91434 -304.290984)
			(xy 411.914848 -304.289714) (xy 411.95498 -304.214022) (xy 411.958733 -304.206273) (xy 411.961327 -304.189264)
			(xy 411.96006 -304.180748) (xy 411.958282 -304.171096) (xy 411.951932 -304.161698) (xy 411.938289 -304.140972)
			(xy 411.916712 -304.096291) (xy 411.902066 -304.048883) (xy 411.894682 -303.999818) (xy 411.894274 -303.975008)
			(xy 411.894274 -303.974754) (xy 411.894784 -303.948767) (xy 411.902914 -303.897432) (xy 411.918975 -303.848002)
			(xy 411.942571 -303.801692) (xy 411.973121 -303.759644) (xy 412.009872 -303.722893) (xy 412.05192 -303.692343)
			(xy 412.09823 -303.668747) (xy 412.14766 -303.652686) (xy 412.198995 -303.644556) (xy 412.250969 -303.644556)
			(xy 412.302304 -303.652686) (xy 412.351734 -303.668747) (xy 412.398044 -303.692343) (xy 412.440092 -303.722893)
			(xy 412.476843 -303.759644) (xy 412.507393 -303.801692) (xy 412.530989 -303.848002) (xy 412.54705 -303.897432)
			(xy 412.55518 -303.948767) (xy 412.55569 -303.974754) (xy 412.55569 -303.975008) (xy 412.55523 -303.999826)
			(xy 412.54778 -304.048899) (xy 412.533081 -304.096308) (xy 412.51146 -304.140988) (xy 412.497778 -304.161698)
			(xy 412.491625 -304.171966) (xy 412.488565 -304.195679) (xy 412.491936 -304.207164) (xy 412.493968 -304.212244)
			(xy 412.538672 -304.296318) (xy 412.541984 -304.301422) (xy 412.550587 -304.310022) (xy 412.55569 -304.313336)
			(xy 412.562294 -304.3174) (xy 412.568644 -304.318924) (xy 412.830264 -304.318924) (xy 412.839972 -304.316069)
			(xy 412.856209 -304.304018) (xy 412.86176 -304.295556) (xy 412.86303 -304.29327) (xy 412.8643 -304.290984)
			(xy 412.864808 -304.289714) (xy 412.90494 -304.214022) (xy 412.908695 -304.206274) (xy 412.911291 -304.189264)
			(xy 412.91002 -304.180748) (xy 412.908242 -304.171096) (xy 412.901892 -304.161698) (xy 412.888251 -304.140971)
			(xy 412.866676 -304.09629) (xy 412.852032 -304.048882) (xy 412.844649 -303.999817) (xy 412.844234 -303.975008)
			(xy 412.844234 -303.974754) (xy 412.844744 -303.948767) (xy 412.852874 -303.897432) (xy 412.868935 -303.848002)
			(xy 412.892531 -303.801692) (xy 412.923081 -303.759644) (xy 412.959832 -303.722893) (xy 413.00188 -303.692343)
			(xy 413.04819 -303.668747) (xy 413.09762 -303.652686) (xy 413.148955 -303.644556) (xy 413.200929 -303.644556)
			(xy 413.252264 -303.652686) (xy 413.301694 -303.668747) (xy 413.348004 -303.692343) (xy 413.390052 -303.722893)
			(xy 413.426803 -303.759644) (xy 413.457353 -303.801692) (xy 413.480949 -303.848002) (xy 413.49701 -303.897432)
			(xy 413.50514 -303.948767) (xy 413.50565 -303.974754) (xy 413.50565 -303.975008) (xy 413.50519 -303.999825)
			(xy 413.49774 -304.048899) (xy 413.483038 -304.096307) (xy 413.461416 -304.140985) (xy 413.447738 -304.161698)
			(xy 413.44158 -304.171965) (xy 413.438517 -304.19568) (xy 413.441896 -304.207164) (xy 413.443928 -304.212244)
			(xy 413.488632 -304.296318) (xy 413.491942 -304.301424) (xy 413.500541 -304.310031) (xy 413.50565 -304.313336)
			(xy 413.512254 -304.3174) (xy 413.518604 -304.318924) (xy 413.780224 -304.318924) (xy 413.789925 -304.316059)
			(xy 413.806145 -304.303999) (xy 413.81172 -304.295556) (xy 413.81299 -304.29327) (xy 413.81426 -304.290984)
			(xy 413.814768 -304.289714) (xy 413.8549 -304.214022) (xy 413.858652 -304.206273) (xy 413.861245 -304.189264)
			(xy 413.85998 -304.180748) (xy 413.858202 -304.171096) (xy 413.851852 -304.161698) (xy 413.838212 -304.140971)
			(xy 413.81664 -304.096289) (xy 413.801998 -304.048882) (xy 413.794616 -303.999817) (xy 413.794194 -303.975008)
			(xy 413.794194 -303.974754) (xy 413.794704 -303.948767) (xy 413.802834 -303.897432) (xy 413.818895 -303.848002)
			(xy 413.842491 -303.801692) (xy 413.873041 -303.759644) (xy 413.909792 -303.722893) (xy 413.95184 -303.692343)
			(xy 413.99815 -303.668747) (xy 414.04758 -303.652686) (xy 414.098915 -303.644556) (xy 414.150889 -303.644556)
			(xy 414.202224 -303.652686) (xy 414.251654 -303.668747) (xy 414.297964 -303.692343) (xy 414.340012 -303.722893)
			(xy 414.376763 -303.759644) (xy 414.407313 -303.801692) (xy 414.430909 -303.848002) (xy 414.44697 -303.897432)
			(xy 414.4551 -303.948767) (xy 414.45561 -303.974754) (xy 414.45561 -303.975008) (xy 414.45515 -303.999826)
			(xy 414.447701 -304.0489) (xy 414.433002 -304.096309) (xy 414.411382 -304.14099) (xy 414.397698 -304.161698)
			(xy 414.391543 -304.171966) (xy 414.388483 -304.195679) (xy 414.391856 -304.207164) (xy 414.393888 -304.212244)
			(xy 414.438592 -304.296318) (xy 414.441905 -304.301421) (xy 414.450509 -304.310019) (xy 414.45561 -304.313336)
			(xy 414.462214 -304.3174) (xy 414.468564 -304.318924) (xy 414.730184 -304.318924) (xy 414.73989 -304.316066)
			(xy 414.756121 -304.304011) (xy 414.76168 -304.295556) (xy 414.76295 -304.29327) (xy 414.76422 -304.290984)
			(xy 414.764728 -304.289714) (xy 414.80486 -304.214022) (xy 414.808614 -304.206274) (xy 414.811209 -304.189264)
			(xy 414.80994 -304.180748) (xy 414.808162 -304.171096) (xy 414.801812 -304.161698) (xy 414.78817 -304.140972)
			(xy 414.766594 -304.09629) (xy 414.751949 -304.048883) (xy 414.744565 -303.999817) (xy 414.744154 -303.975008)
			(xy 414.744154 -303.974754) (xy 414.744664 -303.948767) (xy 414.752794 -303.897432) (xy 414.768855 -303.848002)
			(xy 414.792451 -303.801692) (xy 414.823001 -303.759644) (xy 414.859752 -303.722893) (xy 414.9018 -303.692343)
			(xy 414.94811 -303.668747) (xy 414.99754 -303.652686) (xy 415.048875 -303.644556) (xy 415.100849 -303.644556)
			(xy 415.152184 -303.652686) (xy 415.201614 -303.668747) (xy 415.247924 -303.692343) (xy 415.289972 -303.722893)
			(xy 415.326723 -303.759644) (xy 415.357273 -303.801692) (xy 415.380869 -303.848002) (xy 415.39693 -303.897432)
			(xy 415.40506 -303.948767) (xy 415.40557 -303.974754) (xy 415.40557 -303.975008) (xy 415.40511 -303.999826)
			(xy 415.39766 -304.048899) (xy 415.382959 -304.096308) (xy 415.361338 -304.140987) (xy 415.347658 -304.161698)
			(xy 415.341497 -304.171965) (xy 415.338433 -304.195681) (xy 415.341816 -304.207164) (xy 415.343848 -304.212244)
			(xy 415.388552 -304.296318) (xy 415.391863 -304.301423) (xy 415.400464 -304.310026) (xy 415.40557 -304.313336)
			(xy 415.412174 -304.3174) (xy 415.418524 -304.318924) (xy 415.680144 -304.318924) (xy 415.689855 -304.316072)
			(xy 415.706097 -304.304024) (xy 415.71164 -304.295556) (xy 415.71291 -304.29327) (xy 415.71418 -304.290984)
			(xy 415.714688 -304.289714) (xy 415.75482 -304.214022) (xy 415.758577 -304.206274) (xy 415.761174 -304.189264)
			(xy 415.7599 -304.180748) (xy 415.758122 -304.171096) (xy 415.751772 -304.161698) (xy 415.738132 -304.140971)
			(xy 415.716558 -304.096289) (xy 415.701915 -304.048882) (xy 415.694532 -303.999817) (xy 415.694114 -303.975008)
			(xy 415.694114 -303.974754) (xy 415.694624 -303.948767) (xy 415.702754 -303.897432) (xy 415.718815 -303.848002)
			(xy 415.742411 -303.801692) (xy 415.772961 -303.759644) (xy 415.809712 -303.722893) (xy 415.85176 -303.692343)
			(xy 415.89807 -303.668747) (xy 415.9475 -303.652686) (xy 415.998835 -303.644556) (xy 416.050809 -303.644556)
			(xy 416.102144 -303.652686) (xy 416.151574 -303.668747) (xy 416.197884 -303.692343) (xy 416.239932 -303.722893)
			(xy 416.276683 -303.759644) (xy 416.307233 -303.801692) (xy 416.330829 -303.848002) (xy 416.34689 -303.897432)
			(xy 416.35502 -303.948767) (xy 416.35553 -303.974754) (xy 416.35553 -303.975008) (xy 416.35507 -303.999825)
			(xy 416.347619 -304.048898) (xy 416.332917 -304.096306) (xy 416.311293 -304.140984) (xy 416.297618 -304.161698)
			(xy 416.291461 -304.171965) (xy 416.288399 -304.19568) (xy 416.291776 -304.207164) (xy 416.293808 -304.212244)
			(xy 416.338512 -304.296318) (xy 416.341826 -304.30142) (xy 416.350432 -304.310015) (xy 416.35553 -304.313336)
			(xy 416.362134 -304.3174) (xy 416.368484 -304.318924) (xy 416.564318 -304.318924) (xy 416.570912 -304.317135)
			(xy 416.58289 -304.310572) (xy 416.58794 -304.30597) (xy 416.690048 -304.203862) (xy 416.697414 -304.194464)
			(xy 416.697414 -304.141886) (xy 416.692588 -304.132996) (xy 416.678991 -304.107986) (xy 416.659655 -304.054448)
			(xy 416.649786 -303.998388) (xy 416.649154 -303.969928) (xy 416.64966 -303.943951) (xy 416.657779 -303.892635)
			(xy 416.673822 -303.84322) (xy 416.697394 -303.796921) (xy 416.727914 -303.754877) (xy 416.764634 -303.718123)
			(xy 416.806648 -303.687561) (xy 416.852924 -303.663945) (xy 416.902324 -303.647854) (xy 416.953631 -303.639686)
			(xy 416.979608 -303.63922) (xy 416.980116 -303.63922) (xy 417.00577 -303.639982) (xy 417.016438 -303.640744)
			(xy 417.02609 -303.637442) (xy 417.030918 -303.635588) (xy 417.039749 -303.630209) (xy 417.043616 -303.626774)
			(xy 417.085018 -303.588674) (xy 417.09848 -303.576228) (xy 417.105824 -303.56876) (xy 417.114236 -303.549604)
			(xy 417.114736 -303.539144) (xy 417.114736 -303.455324) (xy 417.11424 -303.445512) (xy 417.106801 -303.427346)
			(xy 417.100258 -303.420018) (xy 417.042854 -303.367186) (xy 417.03893 -303.363734) (xy 417.029965 -303.358364)
			(xy 417.025074 -303.356518) (xy 417.015168 -303.353216) (xy 417.004246 -303.354232) (xy 416.974782 -303.355502)
			(xy 416.948796 -303.354991) (xy 416.897465 -303.346858) (xy 416.848038 -303.330796) (xy 416.801731 -303.3072)
			(xy 416.759686 -303.27665) (xy 416.722938 -303.2399) (xy 416.692391 -303.197853) (xy 416.668797 -303.151546)
			(xy 416.652737 -303.102118) (xy 416.644607 -303.050786) (xy 416.644607 -302.998814) (xy 416.652737 -302.947482)
			(xy 416.668797 -302.898054) (xy 416.692391 -302.851747) (xy 416.722938 -302.8097) (xy 416.759686 -302.77295)
			(xy 416.801731 -302.7424) (xy 416.848038 -302.718804) (xy 416.897465 -302.702742) (xy 416.948796 -302.694609)
			(xy 416.974782 -302.694086) (xy 417.004246 -302.695356) (xy 417.015168 -302.696372) (xy 417.025074 -302.69307)
			(xy 417.029962 -302.691222) (xy 417.038918 -302.68584) (xy 417.042854 -302.682402) (xy 417.098226 -302.631602)
			(xy 417.105665 -302.624106) (xy 417.11419 -302.604811) (xy 417.114736 -302.594264) (xy 417.114736 -302.505364)
			(xy 417.114229 -302.495556) (xy 417.106776 -302.477406) (xy 417.100258 -302.470058) (xy 417.042854 -302.417226)
			(xy 417.038931 -302.413771) (xy 417.029967 -302.408397) (xy 417.025074 -302.406558) (xy 417.015168 -302.403256)
			(xy 417.004246 -302.404272) (xy 416.974782 -302.405542) (xy 416.948793 -302.405031) (xy 416.897456 -302.396897)
			(xy 416.848022 -302.380833) (xy 416.801711 -302.357234) (xy 416.759661 -302.326681) (xy 416.722908 -302.289926)
			(xy 416.692357 -302.247874) (xy 416.66876 -302.201561) (xy 416.652698 -302.152127) (xy 416.644568 -302.100789)
			(xy 416.644568 -302.048811) (xy 416.652698 -301.997473) (xy 416.66876 -301.948039) (xy 416.692357 -301.901726)
			(xy 416.722908 -301.859674) (xy 416.759661 -301.822919) (xy 416.801711 -301.792366) (xy 416.848022 -301.768767)
			(xy 416.897456 -301.752703) (xy 416.948793 -301.744569) (xy 416.974782 -301.744126) (xy 417.004246 -301.745396)
			(xy 417.015168 -301.746412) (xy 417.025074 -301.74311) (xy 417.029963 -301.741264) (xy 417.038922 -301.735885)
			(xy 417.042854 -301.732442) (xy 417.098226 -301.681642) (xy 417.105672 -301.674149) (xy 417.114212 -301.654854)
			(xy 417.114736 -301.644304) (xy 417.114736 -301.555404) (xy 417.114236 -301.545593) (xy 417.106793 -301.527432)
			(xy 417.100258 -301.520098) (xy 417.042854 -301.467266) (xy 417.038929 -301.463815) (xy 417.029963 -301.458447)
			(xy 417.025074 -301.456598) (xy 417.015168 -301.453296) (xy 417.004246 -301.454312) (xy 416.974782 -301.455582)
			(xy 416.948798 -301.455071) (xy 416.89747 -301.446939) (xy 416.848045 -301.430878) (xy 416.801742 -301.407283)
			(xy 416.759699 -301.376735) (xy 416.722953 -301.339987) (xy 416.692408 -301.297943) (xy 416.668815 -301.251638)
			(xy 416.652757 -301.202213) (xy 416.644627 -301.150884) (xy 416.644627 -301.098916) (xy 416.652757 -301.047587)
			(xy 416.668815 -300.998162) (xy 416.692408 -300.951857) (xy 416.722953 -300.909813) (xy 416.759699 -300.873065)
			(xy 416.801742 -300.842517) (xy 416.848045 -300.818922) (xy 416.89747 -300.802861) (xy 416.948798 -300.794729)
			(xy 416.974782 -300.794166) (xy 417.004246 -300.795436) (xy 417.015168 -300.796452) (xy 417.025074 -300.79315)
			(xy 417.029962 -300.791301) (xy 417.038916 -300.785918) (xy 417.042854 -300.782482) (xy 417.098226 -300.731682)
			(xy 417.105662 -300.724185) (xy 417.114179 -300.70489) (xy 417.114736 -300.694344) (xy 417.114736 -300.605444)
			(xy 417.114243 -300.59563) (xy 417.10681 -300.577459) (xy 417.100258 -300.570138) (xy 417.042854 -300.517306)
			(xy 417.03893 -300.513852) (xy 417.029966 -300.50848) (xy 417.025074 -300.506638) (xy 417.015168 -300.503336)
			(xy 417.004246 -300.504352) (xy 416.974782 -300.505622) (xy 416.948795 -300.505111) (xy 416.89746 -300.496978)
			(xy 416.84803 -300.480915) (xy 416.801721 -300.457317) (xy 416.759674 -300.426765) (xy 416.722923 -300.390013)
			(xy 416.692374 -300.347964) (xy 416.668778 -300.301653) (xy 416.652718 -300.252222) (xy 416.644588 -300.200887)
			(xy 416.644588 -300.148913) (xy 416.652718 -300.097578) (xy 416.668778 -300.048147) (xy 416.692374 -300.001836)
			(xy 416.722923 -299.959787) (xy 416.759674 -299.923035) (xy 416.801721 -299.892483) (xy 416.84803 -299.868885)
			(xy 416.89746 -299.852822) (xy 416.948795 -299.844689) (xy 416.974782 -299.844206) (xy 417.004246 -299.845476)
			(xy 417.015168 -299.846492) (xy 417.025074 -299.84319) (xy 417.029963 -299.841343) (xy 417.03892 -299.835962)
			(xy 417.042854 -299.832522) (xy 417.098226 -299.781722) (xy 417.105669 -299.774228) (xy 417.114201 -299.754933)
			(xy 417.114736 -299.744384) (xy 417.114736 -299.655484) (xy 417.114233 -299.645675) (xy 417.106784 -299.627519)
			(xy 417.100258 -299.620178) (xy 417.042854 -299.567346) (xy 417.038932 -299.56389) (xy 417.029969 -299.558514)
			(xy 417.025074 -299.556678) (xy 417.015168 -299.553376) (xy 417.004246 -299.554392) (xy 416.974782 -299.555662)
			(xy 416.948799 -299.555151) (xy 416.897474 -299.547019) (xy 416.848053 -299.530959) (xy 416.801753 -299.507365)
			(xy 416.759713 -299.476819) (xy 416.722969 -299.440073) (xy 416.692425 -299.398032) (xy 416.668834 -299.35173)
			(xy 416.652777 -299.302308) (xy 416.644648 -299.250983) (xy 416.644648 -299.199017) (xy 416.652777 -299.147692)
			(xy 416.668834 -299.09827) (xy 416.692425 -299.051968) (xy 416.722969 -299.009927) (xy 416.759713 -298.973181)
			(xy 416.801753 -298.942635) (xy 416.848053 -298.919041) (xy 416.897474 -298.902981) (xy 416.948799 -298.894849)
			(xy 416.974782 -298.894246) (xy 417.004246 -298.895516) (xy 417.015168 -298.896532) (xy 417.025074 -298.89323)
			(xy 417.029964 -298.891384) (xy 417.038924 -298.886007) (xy 417.042854 -298.882562) (xy 417.098226 -298.831762)
			(xy 417.105659 -298.824264) (xy 417.114169 -298.804969) (xy 417.114736 -298.794424) (xy 417.114736 -298.70527)
			(xy 417.11423 -298.695462) (xy 417.106778 -298.67731) (xy 417.100258 -298.669964) (xy 417.042854 -298.617132)
			(xy 417.038931 -298.613677) (xy 417.029968 -298.608302) (xy 417.025074 -298.606464) (xy 417.015168 -298.603162)
			(xy 417.004246 -298.604178) (xy 416.974782 -298.605448) (xy 416.948793 -298.604937) (xy 416.897454 -298.596803)
			(xy 416.84802 -298.580739) (xy 416.801707 -298.557139) (xy 416.759657 -298.526585) (xy 416.722903 -298.48983)
			(xy 416.692352 -298.447777) (xy 416.668754 -298.401463) (xy 416.652693 -298.352028) (xy 416.644562 -298.300689)
			(xy 416.644562 -298.248711) (xy 416.652693 -298.197372) (xy 416.668754 -298.147937) (xy 416.692352 -298.101623)
			(xy 416.722903 -298.05957) (xy 416.759657 -298.022815) (xy 416.801707 -297.992261) (xy 416.84802 -297.968661)
			(xy 416.897454 -297.952597) (xy 416.948793 -297.944463) (xy 416.974782 -297.944032) (xy 417.004246 -297.945302)
			(xy 417.015168 -297.946318) (xy 417.025074 -297.943016) (xy 417.029963 -297.94117) (xy 417.038922 -297.935792)
			(xy 417.042854 -297.932348) (xy 417.098226 -297.881548) (xy 417.105673 -297.874055) (xy 417.114215 -297.85476)
			(xy 417.114736 -297.84421) (xy 417.114736 -297.75531) (xy 417.114237 -297.745499) (xy 417.106795 -297.727336)
			(xy 417.100258 -297.720004) (xy 417.042854 -297.667172) (xy 417.038929 -297.66372) (xy 417.029964 -297.658352)
			(xy 417.025074 -297.656504) (xy 417.015168 -297.653202) (xy 417.004246 -297.654218) (xy 416.974782 -297.655488)
			(xy 416.948797 -297.654977) (xy 416.897468 -297.646845) (xy 416.848043 -297.630783) (xy 416.801739 -297.607188)
			(xy 416.759696 -297.57664) (xy 416.722949 -297.539891) (xy 416.692403 -297.497846) (xy 416.66881 -297.45154)
			(xy 416.652751 -297.402114) (xy 416.644621 -297.350785) (xy 416.644621 -297.298815) (xy 416.652751 -297.247486)
			(xy 416.66881 -297.19806) (xy 416.692403 -297.151754) (xy 416.722949 -297.109709) (xy 416.759696 -297.07296)
			(xy 416.801739 -297.042412) (xy 416.848043 -297.018817) (xy 416.897468 -297.002755) (xy 416.948797 -296.994623)
			(xy 416.974782 -296.994072) (xy 417.004246 -296.995342) (xy 417.015168 -296.996358) (xy 417.025074 -296.993056)
			(xy 417.029962 -296.991208) (xy 417.038917 -296.985824) (xy 417.042854 -296.982388) (xy 417.098226 -296.931588)
			(xy 417.105663 -296.924091) (xy 417.114183 -296.904797) (xy 417.114736 -296.89425) (xy 417.114736 -296.80535)
			(xy 417.114244 -296.795536) (xy 417.106813 -296.777363) (xy 417.100258 -296.770044) (xy 417.042854 -296.717212)
			(xy 417.038931 -296.713758) (xy 417.029966 -296.708386) (xy 417.025074 -296.706544) (xy 417.015168 -296.703242)
			(xy 417.004246 -296.704258) (xy 416.974782 -296.705528) (xy 416.948794 -296.705017) (xy 416.897459 -296.696884)
			(xy 416.848028 -296.68082) (xy 416.801718 -296.657222) (xy 416.75967 -296.62667) (xy 416.722918 -296.589917)
			(xy 416.692369 -296.547867) (xy 416.668773 -296.501556) (xy 416.652712 -296.452124) (xy 416.644582 -296.400788)
			(xy 416.644582 -296.348812) (xy 416.652712 -296.297476) (xy 416.668773 -296.248044) (xy 416.692369 -296.201733)
			(xy 416.722918 -296.159683) (xy 416.75967 -296.12293) (xy 416.801718 -296.092378) (xy 416.848028 -296.06878)
			(xy 416.897459 -296.052716) (xy 416.948794 -296.044583) (xy 416.974782 -296.044112) (xy 417.004246 -296.045382)
			(xy 417.015168 -296.046398) (xy 417.025074 -296.043096) (xy 417.029963 -296.041249) (xy 417.03892 -296.035869)
			(xy 417.042854 -296.032428) (xy 417.098226 -295.981628) (xy 417.10567 -295.974134) (xy 417.114204 -295.954839)
			(xy 417.114736 -295.94429) (xy 417.114736 -294.90543) (xy 417.114241 -294.895617) (xy 417.106804 -294.87745)
			(xy 417.100258 -294.870124) (xy 417.042854 -294.817292) (xy 417.03893 -294.813839) (xy 417.029965 -294.808469)
			(xy 417.025074 -294.806624) (xy 417.015168 -294.803322) (xy 417.004246 -294.804338) (xy 416.974782 -294.805608)
			(xy 416.948796 -294.805097) (xy 416.897463 -294.796964) (xy 416.848035 -294.780902) (xy 416.801728 -294.757305)
			(xy 416.759683 -294.726755) (xy 416.722933 -294.690004) (xy 416.692386 -294.647956) (xy 416.668791 -294.601648)
			(xy 416.652731 -294.552219) (xy 416.644601 -294.500886) (xy 416.644601 -294.448914) (xy 416.652731 -294.397581)
			(xy 416.668791 -294.348152) (xy 416.692386 -294.301844) (xy 416.722933 -294.259796) (xy 416.759683 -294.223045)
			(xy 416.801728 -294.192495) (xy 416.848035 -294.168898) (xy 416.897463 -294.152836) (xy 416.948796 -294.144703)
			(xy 416.974782 -294.144192) (xy 417.004246 -294.145462) (xy 417.015168 -294.146478) (xy 417.025074 -294.143176)
			(xy 417.029962 -294.141328) (xy 417.038918 -294.135947) (xy 417.042854 -294.132508) (xy 417.098226 -294.081708)
			(xy 417.105667 -294.074213) (xy 417.114194 -294.054918) (xy 417.114736 -294.04437) (xy 417.114736 -293.95547)
			(xy 417.11423 -293.945662) (xy 417.106778 -293.92751) (xy 417.100258 -293.920164) (xy 417.042854 -293.867332)
			(xy 417.038931 -293.863877) (xy 417.029968 -293.858502) (xy 417.025074 -293.856664) (xy 417.015168 -293.853362)
			(xy 417.004246 -293.854378) (xy 416.974782 -293.855648) (xy 416.948793 -293.855137) (xy 416.897454 -293.847003)
			(xy 416.84802 -293.830939) (xy 416.801707 -293.807339) (xy 416.759657 -293.776785) (xy 416.722903 -293.74003)
			(xy 416.692352 -293.697977) (xy 416.668754 -293.651663) (xy 416.652693 -293.602228) (xy 416.644562 -293.550889)
			(xy 416.644562 -293.498911) (xy 416.652693 -293.447572) (xy 416.668754 -293.398137) (xy 416.692352 -293.351823)
			(xy 416.722903 -293.30977) (xy 416.759657 -293.273015) (xy 416.801707 -293.242461) (xy 416.84802 -293.218861)
			(xy 416.897454 -293.202797) (xy 416.948793 -293.194663) (xy 416.974782 -293.194232) (xy 417.004246 -293.195502)
			(xy 417.015168 -293.196518) (xy 417.025074 -293.193216) (xy 417.029963 -293.19137) (xy 417.038922 -293.185992)
			(xy 417.042854 -293.182548) (xy 417.098226 -293.131748) (xy 417.105673 -293.124255) (xy 417.114215 -293.10496)
			(xy 417.114736 -293.09441) (xy 417.114736 -293.005256) (xy 417.114228 -292.995449) (xy 417.106772 -292.9773)
			(xy 417.100258 -292.96995) (xy 417.042854 -292.917118) (xy 417.038931 -292.913664) (xy 417.029967 -292.908291)
			(xy 417.025074 -292.90645) (xy 417.015168 -292.903148) (xy 417.004246 -292.904164) (xy 416.974782 -292.905434)
			(xy 416.948794 -292.904923) (xy 416.897457 -292.89679) (xy 416.848025 -292.880726) (xy 416.801715 -292.857127)
			(xy 416.759666 -292.826575) (xy 416.722914 -292.789821) (xy 416.692363 -292.74777) (xy 416.668767 -292.701458)
			(xy 416.652706 -292.652025) (xy 416.644576 -292.600688) (xy 416.644576 -292.548712) (xy 416.652706 -292.497375)
			(xy 416.668767 -292.447942) (xy 416.692363 -292.40163) (xy 416.722914 -292.359579) (xy 416.759666 -292.322825)
			(xy 416.801715 -292.292273) (xy 416.848025 -292.268674) (xy 416.897457 -292.25261) (xy 416.948794 -292.244477)
			(xy 416.974782 -292.244018) (xy 417.004246 -292.245288) (xy 417.015168 -292.246304) (xy 417.025074 -292.243002)
			(xy 417.029963 -292.241155) (xy 417.038921 -292.235776) (xy 417.042854 -292.232334) (xy 417.098226 -292.181534)
			(xy 417.105671 -292.17404) (xy 417.114208 -292.154745) (xy 417.114736 -292.144196) (xy 417.114736 -292.055296)
			(xy 417.114235 -292.045486) (xy 417.106789 -292.027327) (xy 417.100258 -292.01999) (xy 417.042854 -291.967158)
			(xy 417.038929 -291.963707) (xy 417.029963 -291.95834) (xy 417.025074 -291.95649) (xy 417.015168 -291.953188)
			(xy 417.004246 -291.954204) (xy 416.974782 -291.955474) (xy 416.948798 -291.954963) (xy 416.897471 -291.946831)
			(xy 416.848048 -291.93077) (xy 416.801746 -291.907176) (xy 416.759705 -291.876629) (xy 416.722959 -291.839882)
			(xy 416.692415 -291.797839) (xy 416.668823 -291.751535) (xy 416.652765 -291.702111) (xy 416.644635 -291.650784)
			(xy 416.644635 -291.598816) (xy 416.652765 -291.547489) (xy 416.668823 -291.498065) (xy 416.692415 -291.451761)
			(xy 416.722959 -291.409718) (xy 416.759705 -291.372971) (xy 416.801746 -291.342424) (xy 416.848048 -291.31883)
			(xy 416.897471 -291.302769) (xy 416.948798 -291.294637) (xy 416.974782 -291.294058) (xy 417.004246 -291.295328)
			(xy 417.015168 -291.296344) (xy 417.025074 -291.293042) (xy 417.029961 -291.291193) (xy 417.038915 -291.285809)
			(xy 417.042854 -291.282374) (xy 417.098226 -291.231574) (xy 417.105661 -291.224077) (xy 417.114175 -291.204782)
			(xy 417.114736 -291.194236) (xy 417.114736 -291.105336) (xy 417.114242 -291.095523) (xy 417.106807 -291.077354)
			(xy 417.100258 -291.07003) (xy 417.042854 -291.017198) (xy 417.03893 -291.013745) (xy 417.029965 -291.008374)
			(xy 417.025074 -291.00653) (xy 417.015168 -291.003228) (xy 417.004246 -291.004244) (xy 416.974782 -291.005514)
			(xy 416.948795 -291.005003) (xy 416.897462 -290.99687) (xy 416.848033 -290.980807) (xy 416.801725 -290.95721)
			(xy 416.759679 -290.926659) (xy 416.722929 -290.889908) (xy 416.692381 -290.847859) (xy 416.668786 -290.80155)
			(xy 416.652726 -290.75212) (xy 416.644595 -290.700787) (xy 416.644595 -290.648813) (xy 416.652726 -290.59748)
			(xy 416.668786 -290.54805) (xy 416.692381 -290.501741) (xy 416.722929 -290.459692) (xy 416.759679 -290.422941)
			(xy 416.801725 -290.39239) (xy 416.848033 -290.368793) (xy 416.897462 -290.35273) (xy 416.948795 -290.344597)
			(xy 416.974782 -290.344098) (xy 417.004246 -290.345368) (xy 417.015168 -290.346384) (xy 417.025074 -290.343082)
			(xy 417.029962 -290.341234) (xy 417.038919 -290.335853) (xy 417.042854 -290.332414) (xy 417.098226 -290.281614)
			(xy 417.105668 -290.274119) (xy 417.114197 -290.254824) (xy 417.114736 -290.244276) (xy 417.114736 -290.155376)
			(xy 417.114231 -290.145567) (xy 417.106781 -290.127414) (xy 417.100258 -290.12007) (xy 417.042854 -290.067238)
			(xy 417.038931 -290.063783) (xy 417.029968 -290.058407) (xy 417.025074 -290.05657) (xy 417.015168 -290.053268)
			(xy 417.004246 -290.054284) (xy 416.974782 -290.055554) (xy 416.948792 -290.055043) (xy 416.897453 -290.046909)
			(xy 416.848018 -290.030844) (xy 416.801704 -290.007244) (xy 416.759653 -289.97669) (xy 416.722898 -289.939934)
			(xy 416.692346 -289.89788) (xy 416.668749 -289.851566) (xy 416.652687 -289.80213) (xy 416.644556 -289.75079)
			(xy 416.644556 -289.69881) (xy 416.652687 -289.64747) (xy 416.668749 -289.598034) (xy 416.692346 -289.55172)
			(xy 416.722898 -289.509666) (xy 416.759653 -289.47291) (xy 416.801704 -289.442356) (xy 416.848018 -289.418756)
			(xy 416.897453 -289.402691) (xy 416.948792 -289.394557) (xy 416.974782 -289.394138) (xy 417.004246 -289.395408)
			(xy 417.015168 -289.396424) (xy 417.025074 -289.393122) (xy 417.029963 -289.391276) (xy 417.038923 -289.385898)
			(xy 417.042854 -289.382454) (xy 417.098226 -289.331654) (xy 417.105674 -289.324161) (xy 417.114218 -289.304867)
			(xy 417.114736 -289.294316) (xy 417.114736 -289.205416) (xy 417.114238 -289.195604) (xy 417.106798 -289.17744)
			(xy 417.100258 -289.17011) (xy 417.042854 -289.117278) (xy 417.038929 -289.113826) (xy 417.029964 -289.108457)
			(xy 417.025074 -289.10661) (xy 417.015168 -289.103308) (xy 417.004246 -289.104324) (xy 416.974782 -289.105594)
			(xy 416.948797 -289.105083) (xy 416.897467 -289.096951) (xy 416.848041 -289.080889) (xy 416.801736 -289.057293)
			(xy 416.759692 -289.026744) (xy 416.722944 -288.989995) (xy 416.692398 -288.947949) (xy 416.668804 -288.901643)
			(xy 416.652745 -288.852216) (xy 416.644615 -288.800885) (xy 416.644615 -288.748915) (xy 416.652745 -288.697584)
			(xy 416.668804 -288.648157) (xy 416.692398 -288.601851) (xy 416.722944 -288.559805) (xy 416.759692 -288.523056)
			(xy 416.801736 -288.492507) (xy 416.848041 -288.468911) (xy 416.897467 -288.452849) (xy 416.948797 -288.444717)
			(xy 416.974782 -288.444178) (xy 417.004246 -288.445448) (xy 417.015168 -288.446464) (xy 417.025074 -288.443162)
			(xy 417.029962 -288.441314) (xy 417.038917 -288.435931) (xy 417.042854 -288.432494) (xy 417.098226 -288.381694)
			(xy 417.105664 -288.374198) (xy 417.114186 -288.354903) (xy 417.114736 -288.344356) (xy 417.114736 -288.255456)
			(xy 417.114228 -288.245649) (xy 417.106772 -288.2275) (xy 417.100258 -288.22015) (xy 417.042854 -288.167318)
			(xy 417.038931 -288.163864) (xy 417.029967 -288.158491) (xy 417.025074 -288.15665) (xy 417.015168 -288.153348)
			(xy 417.004246 -288.154364) (xy 416.974782 -288.155634) (xy 416.948795 -288.155123) (xy 416.897461 -288.14699)
			(xy 416.848031 -288.130928) (xy 416.801722 -288.107332) (xy 416.759675 -288.076782) (xy 416.722923 -288.040031)
			(xy 416.692372 -287.997984) (xy 416.668775 -287.951676) (xy 416.652711 -287.902247) (xy 416.644577 -287.850913)
			(xy 416.644074 -287.824926) (xy 416.644571 -287.799073) (xy 416.652611 -287.747996) (xy 416.6685 -287.698791)
			(xy 416.69185 -287.652658) (xy 416.722094 -287.610719) (xy 416.758494 -287.573996) (xy 416.800164 -287.543383)
			(xy 416.82289 -287.531048) (xy 416.830002 -287.527492) (xy 416.83686 -287.520634) (xy 416.843191 -287.513157)
			(xy 416.850173 -287.494869) (xy 416.849817 -287.475298) (xy 416.842177 -287.457276) (xy 416.83559 -287.450022)
			(xy 416.819334 -287.433766) (xy 416.816485 -287.431057) (xy 416.81011 -287.426458) (xy 416.806634 -287.424622)
			(xy 416.801207 -287.42204) (xy 416.789527 -287.419221) (xy 416.78352 -287.419034) (xy 416.61334 -287.419034)
			(xy 416.607752 -287.419542) (xy 416.606228 -287.419542) (xy 416.583114 -287.420812) (xy 416.385502 -287.420812)
			(xy 416.358832 -287.419542) (xy 416.354006 -287.419288) (xy 416.331654 -287.419288) (xy 416.321701 -287.419824)
			(xy 416.303322 -287.427486) (xy 416.289212 -287.441536) (xy 416.284918 -287.45053) (xy 416.24885 -287.53689)
			(xy 416.245542 -287.545849) (xy 416.245122 -287.564928) (xy 416.251683 -287.582849) (xy 416.25774 -287.59023)
			(xy 416.275937 -287.608966) (xy 416.306778 -287.651113) (xy 416.330602 -287.697588) (xy 416.346816 -287.747234)
			(xy 416.355015 -287.798813) (xy 416.35553 -287.824926) (xy 416.35502 -287.850913) (xy 416.34689 -287.902248)
			(xy 416.330829 -287.951678) (xy 416.307233 -287.997988) (xy 416.276683 -288.040036) (xy 416.239932 -288.076787)
			(xy 416.197884 -288.107337) (xy 416.151574 -288.130933) (xy 416.102144 -288.146994) (xy 416.050809 -288.155124)
			(xy 415.998835 -288.155124) (xy 415.9475 -288.146994) (xy 415.89807 -288.130933) (xy 415.85176 -288.107337)
			(xy 415.809712 -288.076787) (xy 415.772961 -288.040036) (xy 415.742411 -287.997988) (xy 415.718815 -287.951678)
			(xy 415.702754 -287.902248) (xy 415.694624 -287.850913) (xy 415.694114 -287.824926) (xy 415.694614 -287.798814)
			(xy 415.702836 -287.747243) (xy 415.719064 -287.697605) (xy 415.742895 -287.651136) (xy 415.773735 -287.608992)
			(xy 415.791904 -287.59023) (xy 415.797939 -287.582832) (xy 415.804515 -287.564923) (xy 415.804094 -287.54585)
			(xy 415.800794 -287.53689) (xy 415.764726 -287.45053) (xy 415.760462 -287.441512) (xy 415.746367 -287.427424)
			(xy 415.727954 -287.419802) (xy 415.71799 -287.419288) (xy 415.695638 -287.419288) (xy 415.690812 -287.419542)
			(xy 415.664142 -287.420812) (xy 415.435542 -287.420812) (xy 415.408872 -287.419542) (xy 415.404046 -287.419288)
			(xy 415.381694 -287.419288) (xy 415.371737 -287.419817) (xy 415.353346 -287.427471) (xy 415.339223 -287.441519)
			(xy 415.334958 -287.45053) (xy 415.29889 -287.53689) (xy 415.295584 -287.54585) (xy 415.295166 -287.564929)
			(xy 415.30172 -287.582852) (xy 415.30778 -287.59023) (xy 415.325975 -287.608967) (xy 415.356812 -287.651115)
			(xy 415.380634 -287.697591) (xy 415.396845 -287.747236) (xy 415.405043 -287.798813) (xy 415.40557 -287.824926)
			(xy 415.40506 -287.850913) (xy 415.39693 -287.902248) (xy 415.380869 -287.951678) (xy 415.357273 -287.997988)
			(xy 415.326723 -288.040036) (xy 415.289972 -288.076787) (xy 415.247924 -288.107337) (xy 415.201614 -288.130933)
			(xy 415.152184 -288.146994) (xy 415.100849 -288.155124) (xy 415.048875 -288.155124) (xy 414.99754 -288.146994)
			(xy 414.94811 -288.130933) (xy 414.9018 -288.107337) (xy 414.859752 -288.076787) (xy 414.823001 -288.040036)
			(xy 414.792451 -287.997988) (xy 414.768855 -287.951678) (xy 414.752794 -287.902248) (xy 414.744664 -287.850913)
			(xy 414.744154 -287.824926) (xy 414.744653 -287.798814) (xy 414.752874 -287.747241) (xy 414.7691 -287.697601)
			(xy 414.792928 -287.65113) (xy 414.823765 -287.608981) (xy 414.841944 -287.59023) (xy 414.847975 -287.582831)
			(xy 414.854546 -287.564923) (xy 414.854125 -287.545852) (xy 414.850834 -287.53689) (xy 414.814766 -287.45053)
			(xy 414.810504 -287.441507) (xy 414.796411 -287.427408) (xy 414.777997 -287.419772) (xy 414.76803 -287.419288)
			(xy 414.745678 -287.419288) (xy 414.740852 -287.419542) (xy 414.714182 -287.420812) (xy 414.485582 -287.420812)
			(xy 414.458912 -287.419542) (xy 414.454086 -287.419288) (xy 414.431734 -287.419288) (xy 414.421784 -287.419828)
			(xy 414.403411 -287.427494) (xy 414.389306 -287.441544) (xy 414.384998 -287.45053) (xy 414.34893 -287.53689)
			(xy 414.345623 -287.545849) (xy 414.345203 -287.564928) (xy 414.351762 -287.58285) (xy 414.35782 -287.59023)
			(xy 414.376017 -287.608965) (xy 414.40686 -287.651112) (xy 414.430686 -287.697587) (xy 414.446901 -287.747233)
			(xy 414.4551 -287.798812) (xy 414.45561 -287.824926) (xy 414.4551 -287.850913) (xy 414.44697 -287.902248)
			(xy 414.430909 -287.951678) (xy 414.407313 -287.997988) (xy 414.376763 -288.040036) (xy 414.340012 -288.076787)
			(xy 414.297964 -288.107337) (xy 414.251654 -288.130933) (xy 414.202224 -288.146994) (xy 414.150889 -288.155124)
			(xy 414.098915 -288.155124) (xy 414.04758 -288.146994) (xy 413.99815 -288.130933) (xy 413.95184 -288.107337)
			(xy 413.909792 -288.076787) (xy 413.873041 -288.040036) (xy 413.842491 -287.997988) (xy 413.818895 -287.951678)
			(xy 413.802834 -287.902248) (xy 413.794704 -287.850913) (xy 413.794194 -287.824926) (xy 413.794693 -287.798814)
			(xy 413.802915 -287.747242) (xy 413.819143 -287.697604) (xy 413.842972 -287.651134) (xy 413.873812 -287.608988)
			(xy 413.891984 -287.59023) (xy 413.898021 -287.582833) (xy 413.9046 -287.564923) (xy 413.904178 -287.545849)
			(xy 413.900874 -287.53689) (xy 413.864806 -287.45053) (xy 413.860545 -287.441503) (xy 413.846455 -287.427393)
			(xy 413.82804 -287.419743) (xy 413.81807 -287.419288) (xy 413.795718 -287.419288) (xy 413.790892 -287.419542)
			(xy 413.764222 -287.420812) (xy 413.535622 -287.420812) (xy 413.508952 -287.419542) (xy 413.504126 -287.419288)
			(xy 413.481774 -287.419288) (xy 413.471819 -287.419821) (xy 413.453434 -287.427479) (xy 413.439317 -287.441528)
			(xy 413.435038 -287.45053) (xy 413.39897 -287.53689) (xy 413.395661 -287.545848) (xy 413.395241 -287.564928)
			(xy 413.401804 -287.582848) (xy 413.40786 -287.59023) (xy 413.426056 -287.608966) (xy 413.456895 -287.651114)
			(xy 413.480718 -287.69759) (xy 413.496931 -287.747235) (xy 413.505129 -287.798813) (xy 413.50565 -287.824926)
			(xy 413.50514 -287.850913) (xy 413.49701 -287.902248) (xy 413.480949 -287.951678) (xy 413.457353 -287.997988)
			(xy 413.426803 -288.040036) (xy 413.390052 -288.076787) (xy 413.348004 -288.107337) (xy 413.301694 -288.130933)
			(xy 413.252264 -288.146994) (xy 413.200929 -288.155124) (xy 413.148955 -288.155124) (xy 413.09762 -288.146994)
			(xy 413.04819 -288.130933) (xy 413.00188 -288.107337) (xy 412.959832 -288.076787) (xy 412.923081 -288.040036)
			(xy 412.892531 -287.997988) (xy 412.868935 -287.951678) (xy 412.852874 -287.902248) (xy 412.844744 -287.850913)
			(xy 412.844234 -287.824926) (xy 412.844734 -287.798815) (xy 412.852956 -287.747243) (xy 412.869185 -287.697606)
			(xy 412.893017 -287.651138) (xy 412.923859 -287.608995) (xy 412.942024 -287.59023) (xy 412.948057 -287.582832)
			(xy 412.954631 -287.564923) (xy 412.95421 -287.545851) (xy 412.950914 -287.53689) (xy 412.914846 -287.45053)
			(xy 412.910582 -287.441509) (xy 412.896489 -287.427416) (xy 412.878075 -287.419787) (xy 412.86811 -287.419288)
			(xy 412.845758 -287.419288) (xy 412.840932 -287.419542) (xy 412.814262 -287.420812) (xy 412.585662 -287.420812)
			(xy 412.558992 -287.419542) (xy 412.554166 -287.419288) (xy 412.531814 -287.419288) (xy 412.521866 -287.419831)
			(xy 412.503499 -287.427502) (xy 412.489401 -287.441552) (xy 412.485078 -287.45053) (xy 412.44901 -287.53689)
			(xy 412.445704 -287.545849) (xy 412.445285 -287.564929) (xy 412.451841 -287.582851) (xy 412.4579 -287.59023)
			(xy 412.476098 -287.608965) (xy 412.506943 -287.651111) (xy 412.53077 -287.697586) (xy 412.546986 -287.747233)
			(xy 412.555186 -287.798812) (xy 412.55569 -287.824926) (xy 412.55518 -287.850913) (xy 412.54705 -287.902248)
			(xy 412.530989 -287.951678) (xy 412.507393 -287.997988) (xy 412.476843 -288.040036) (xy 412.440092 -288.076787)
			(xy 412.398044 -288.107337) (xy 412.351734 -288.130933) (xy 412.302304 -288.146994) (xy 412.250969 -288.155124)
			(xy 412.198995 -288.155124) (xy 412.14766 -288.146994) (xy 412.09823 -288.130933) (xy 412.05192 -288.107337)
			(xy 412.009872 -288.076787) (xy 411.973121 -288.040036) (xy 411.942571 -287.997988) (xy 411.918975 -287.951678)
			(xy 411.902914 -287.902248) (xy 411.894784 -287.850913) (xy 411.894274 -287.824926) (xy 411.894773 -287.798814)
			(xy 411.902994 -287.747241) (xy 411.919221 -287.697602) (xy 411.94305 -287.651132) (xy 411.973888 -287.608985)
			(xy 411.992064 -287.59023) (xy 411.998093 -287.58283) (xy 412.004661 -287.564922) (xy 412.004241 -287.545853)
			(xy 412.000954 -287.53689) (xy 411.964886 -287.45053) (xy 411.960624 -287.441505) (xy 411.946533 -287.427401)
			(xy 411.928118 -287.419758) (xy 411.91815 -287.419288) (xy 411.895798 -287.419288) (xy 411.890972 -287.419542)
			(xy 411.864302 -287.420812) (xy 411.635702 -287.420812) (xy 411.609032 -287.419542) (xy 411.604206 -287.419288)
			(xy 411.581854 -287.419288) (xy 411.571901 -287.419824) (xy 411.553522 -287.427486) (xy 411.539412 -287.441536)
			(xy 411.535118 -287.45053) (xy 411.49905 -287.53689) (xy 411.495742 -287.545849) (xy 411.495322 -287.564928)
			(xy 411.501883 -287.582849) (xy 411.50794 -287.59023) (xy 411.526137 -287.608966) (xy 411.556978 -287.651113)
			(xy 411.580802 -287.697588) (xy 411.597016 -287.747234) (xy 411.605215 -287.798813) (xy 411.60573 -287.824926)
			(xy 411.60522 -287.850913) (xy 411.59709 -287.902248) (xy 411.581029 -287.951678) (xy 411.557433 -287.997988)
			(xy 411.526883 -288.040036) (xy 411.490132 -288.076787) (xy 411.448084 -288.107337) (xy 411.401774 -288.130933)
			(xy 411.352344 -288.146994) (xy 411.301009 -288.155124) (xy 411.249035 -288.155124) (xy 411.1977 -288.146994)
			(xy 411.14827 -288.130933) (xy 411.10196 -288.107337) (xy 411.059912 -288.076787) (xy 411.023161 -288.040036)
			(xy 410.992611 -287.997988) (xy 410.969015 -287.951678) (xy 410.952954 -287.902248) (xy 410.944824 -287.850913)
			(xy 410.944314 -287.824926) (xy 410.944814 -287.798814) (xy 410.953036 -287.747243) (xy 410.969264 -287.697605)
			(xy 410.993095 -287.651136) (xy 411.023935 -287.608992) (xy 411.042104 -287.59023) (xy 411.048139 -287.582832)
			(xy 411.054715 -287.564923) (xy 411.054294 -287.54585) (xy 411.050994 -287.53689) (xy 411.014926 -287.45053)
			(xy 411.010662 -287.441512) (xy 410.996567 -287.427424) (xy 410.978154 -287.419802) (xy 410.96819 -287.419288)
			(xy 410.945838 -287.419288) (xy 410.941012 -287.419542) (xy 410.914342 -287.420812) (xy 410.685488 -287.420812)
			(xy 410.658818 -287.419542) (xy 410.653992 -287.419288) (xy 410.63164 -287.419288) (xy 410.621689 -287.419827)
			(xy 410.603314 -287.427492) (xy 410.589208 -287.441541) (xy 410.584904 -287.45053) (xy 410.548836 -287.53689)
			(xy 410.545528 -287.545849) (xy 410.545109 -287.564928) (xy 410.551668 -287.58285) (xy 410.557726 -287.59023)
			(xy 410.575923 -287.608965) (xy 410.606766 -287.651112) (xy 410.630591 -287.697588) (xy 410.646806 -287.747234)
			(xy 410.655005 -287.798812) (xy 410.655516 -287.824926) (xy 410.655006 -287.850913) (xy 410.646876 -287.902248)
			(xy 410.630815 -287.951678) (xy 410.607219 -287.997988) (xy 410.576669 -288.040036) (xy 410.539918 -288.076787)
			(xy 410.49787 -288.107337) (xy 410.45156 -288.130933) (xy 410.40213 -288.146994) (xy 410.350795 -288.155124)
			(xy 410.298821 -288.155124) (xy 410.247486 -288.146994) (xy 410.198056 -288.130933) (xy 410.151746 -288.107337)
			(xy 410.109698 -288.076787) (xy 410.072947 -288.040036) (xy 410.042397 -287.997988) (xy 410.018801 -287.951678)
			(xy 410.00274 -287.902248) (xy 409.99461 -287.850913) (xy 409.9941 -287.824926) (xy 409.994599 -287.798814)
			(xy 410.002821 -287.747242) (xy 410.019049 -287.697604) (xy 410.042879 -287.651134) (xy 410.073719 -287.608989)
			(xy 410.09189 -287.59023) (xy 410.097927 -287.582833) (xy 410.104504 -287.564923) (xy 410.104083 -287.545849)
			(xy 410.10078 -287.53689) (xy 410.064712 -287.45053) (xy 410.060505 -287.441474) (xy 410.04639 -287.427372)
			(xy 410.027953 -287.419744) (xy 410.017976 -287.419288) (xy 409.995624 -287.419288) (xy 409.990798 -287.419542)
			(xy 409.964128 -287.420812) (xy 409.735528 -287.420812) (xy 409.708858 -287.419542) (xy 409.704032 -287.419288)
			(xy 409.68168 -287.419288) (xy 409.671724 -287.41982) (xy 409.653338 -287.427476) (xy 409.639219 -287.441525)
			(xy 409.634944 -287.45053) (xy 409.598876 -287.53689) (xy 409.595567 -287.545848) (xy 409.595147 -287.564928)
			(xy 409.60171 -287.582847) (xy 409.607766 -287.59023) (xy 409.625961 -287.608966) (xy 409.6568 -287.651114)
			(xy 409.680623 -287.69759) (xy 409.696835 -287.747235) (xy 409.705033 -287.798813) (xy 409.705556 -287.824926)
			(xy 409.705046 -287.850913) (xy 409.696916 -287.902248) (xy 409.680855 -287.951678) (xy 409.657259 -287.997988)
			(xy 409.626709 -288.040036) (xy 409.589958 -288.076787) (xy 409.54791 -288.107337) (xy 409.5016 -288.130933)
			(xy 409.45217 -288.146994) (xy 409.400835 -288.155124) (xy 409.348861 -288.155124) (xy 409.297526 -288.146994)
			(xy 409.248096 -288.130933) (xy 409.201786 -288.107337) (xy 409.159738 -288.076787) (xy 409.122987 -288.040036)
			(xy 409.092437 -287.997988) (xy 409.068841 -287.951678) (xy 409.05278 -287.902248) (xy 409.04465 -287.850913)
			(xy 409.04414 -287.824926) (xy 409.04464 -287.798815) (xy 409.052862 -287.747243) (xy 409.069092 -287.697606)
			(xy 409.092924 -287.651139) (xy 409.123766 -287.608996) (xy 409.14193 -287.59023) (xy 409.147963 -287.582831)
			(xy 409.154535 -287.564923) (xy 409.154114 -287.545851) (xy 409.15082 -287.53689) (xy 409.114752 -287.45053)
			(xy 409.110489 -287.441509) (xy 409.096395 -287.427414) (xy 409.077982 -287.419783) (xy 409.068016 -287.419288)
			(xy 409.045664 -287.419288) (xy 409.040838 -287.419542) (xy 409.014168 -287.420812) (xy 408.785568 -287.420812)
			(xy 408.758898 -287.419542) (xy 408.754072 -287.419288) (xy 408.095704 -287.419288) (xy 408.090878 -287.419542)
			(xy 408.064208 -287.420812) (xy 406.93086 -287.420812) (xy 406.922049 -287.423397) (xy 406.906949 -287.433819)
			(xy 406.901396 -287.441132) (xy 406.876504 -287.480248) (xy 406.858978 -287.50768) (xy 406.8553 -287.513872)
			(xy 406.851175 -287.527664) (xy 406.85085 -287.534858) (xy 406.85085 -287.562544) (xy 406.854914 -287.572196)
			(xy 406.863026 -287.592464) (xy 406.874444 -287.634601) (xy 406.880211 -287.677876) (xy 406.880568 -287.699704)
			(xy 406.880568 -287.699958) (xy 406.880058 -287.725945) (xy 406.871928 -287.77728) (xy 406.855867 -287.82671)
			(xy 406.832271 -287.87302) (xy 406.812773 -287.899856) (xy 408.119084 -287.899856) (xy 408.123044 -287.850802)
			(xy 408.134821 -287.803018) (xy 408.154112 -287.757742) (xy 408.180415 -287.716146) (xy 408.21305 -287.679309)
			(xy 408.251171 -287.648184) (xy 408.293792 -287.623577) (xy 408.339808 -287.606125) (xy 408.388027 -287.596281)
			(xy 408.437202 -287.5943) (xy 408.486057 -287.600232) (xy 408.533328 -287.613924) (xy 408.57779 -287.635022)
			(xy 408.618293 -287.662978) (xy 408.653786 -287.69707) (xy 408.683351 -287.736414) (xy 408.706222 -287.779991)
			(xy 408.721806 -287.826672) (xy 408.729701 -287.875249) (xy 408.730196 -287.899856) (xy 408.729701 -287.924463)
			(xy 408.721806 -287.97304) (xy 408.706222 -288.019721) (xy 408.683351 -288.063298) (xy 408.653786 -288.102642)
			(xy 408.618293 -288.136734) (xy 408.57779 -288.16469) (xy 408.533328 -288.185788) (xy 408.486057 -288.19948)
			(xy 408.437202 -288.205412) (xy 408.388027 -288.203431) (xy 408.339808 -288.193587) (xy 408.293792 -288.176135)
			(xy 408.251171 -288.151528) (xy 408.21305 -288.120403) (xy 408.180415 -288.083566) (xy 408.154112 -288.04197)
			(xy 408.134821 -287.996694) (xy 408.123044 -287.94891) (xy 408.119084 -287.899856) (xy 406.812773 -287.899856)
			(xy 406.801721 -287.915068) (xy 406.76497 -287.951819) (xy 406.722922 -287.982369) (xy 406.676612 -288.005965)
			(xy 406.627182 -288.022026) (xy 406.575847 -288.030156) (xy 406.523873 -288.030156) (xy 406.472538 -288.022026)
			(xy 406.423108 -288.005965) (xy 406.376798 -287.982369) (xy 406.33475 -287.951819) (xy 406.297999 -287.915068)
			(xy 406.267449 -287.87302) (xy 406.243853 -287.82671) (xy 406.227792 -287.77728) (xy 406.219662 -287.725945)
			(xy 406.219152 -287.699958) (xy 406.219152 -287.699704) (xy 406.219593 -287.676251) (xy 406.226297 -287.629824)
			(xy 406.239511 -287.584816) (xy 406.24887 -287.563306) (xy 406.24887 -287.562798) (xy 406.249124 -287.562798)
			(xy 406.25146 -287.556996) (xy 406.253511 -287.544661) (xy 406.253188 -287.538414) (xy 406.252426 -287.525968)
			(xy 406.19807 -287.440878) (xy 406.192555 -287.433652) (xy 406.177584 -287.423366) (xy 406.16886 -287.420812)
			(xy 405.935688 -287.420812) (xy 405.909018 -287.419542) (xy 405.904192 -287.419288) (xy 405.88184 -287.419288)
			(xy 405.871889 -287.419827) (xy 405.853514 -287.427492) (xy 405.839408 -287.441541) (xy 405.835104 -287.45053)
			(xy 405.799036 -287.53689) (xy 405.795728 -287.545849) (xy 405.795309 -287.564928) (xy 405.801868 -287.58285)
			(xy 405.807926 -287.59023) (xy 405.826123 -287.608965) (xy 405.856966 -287.651112) (xy 405.880791 -287.697588)
			(xy 405.897006 -287.747234) (xy 405.905205 -287.798812) (xy 405.905716 -287.824926) (xy 405.905206 -287.850913)
			(xy 405.897076 -287.902248) (xy 405.881015 -287.951678) (xy 405.857419 -287.997988) (xy 405.826869 -288.040036)
			(xy 405.790118 -288.076787) (xy 405.74807 -288.107337) (xy 405.70176 -288.130933) (xy 405.65233 -288.146994)
			(xy 405.600995 -288.155124) (xy 405.549021 -288.155124) (xy 405.497686 -288.146994) (xy 405.448256 -288.130933)
			(xy 405.401946 -288.107337) (xy 405.359898 -288.076787) (xy 405.323147 -288.040036) (xy 405.292597 -287.997988)
			(xy 405.269001 -287.951678) (xy 405.25294 -287.902248) (xy 405.24481 -287.850913) (xy 405.2443 -287.824926)
			(xy 405.244799 -287.798814) (xy 405.253021 -287.747242) (xy 405.269249 -287.697604) (xy 405.293079 -287.651134)
			(xy 405.323919 -287.608989) (xy 405.34209 -287.59023) (xy 405.348127 -287.582833) (xy 405.354704 -287.564923)
			(xy 405.354283 -287.545849) (xy 405.35098 -287.53689) (xy 405.314912 -287.45053) (xy 405.310705 -287.441474)
			(xy 405.29659 -287.427372) (xy 405.278153 -287.419744) (xy 405.268176 -287.419288) (xy 405.245824 -287.419288)
			(xy 405.240998 -287.419542) (xy 405.214328 -287.420812) (xy 404.985474 -287.420812) (xy 404.958804 -287.419542)
			(xy 404.953978 -287.419288) (xy 404.931626 -287.419288) (xy 404.921676 -287.419829) (xy 404.903306 -287.427497)
			(xy 404.889204 -287.441547) (xy 404.88489 -287.45053) (xy 404.848822 -287.53689) (xy 404.845515 -287.545849)
			(xy 404.845096 -287.564928) (xy 404.851653 -287.58285) (xy 404.857712 -287.59023) (xy 404.87591 -287.608965)
			(xy 404.906753 -287.651112) (xy 404.93058 -287.697587) (xy 404.946795 -287.747233) (xy 404.954995 -287.798812)
			(xy 404.955502 -287.824926) (xy 404.954992 -287.850913) (xy 404.946862 -287.902248) (xy 404.930801 -287.951678)
			(xy 404.907205 -287.997988) (xy 404.876655 -288.040036) (xy 404.839904 -288.076787) (xy 404.797856 -288.107337)
			(xy 404.751546 -288.130933) (xy 404.702116 -288.146994) (xy 404.650781 -288.155124) (xy 404.598807 -288.155124)
			(xy 404.547472 -288.146994) (xy 404.498042 -288.130933) (xy 404.451732 -288.107337) (xy 404.409684 -288.076787)
			(xy 404.372933 -288.040036) (xy 404.342383 -287.997988) (xy 404.318787 -287.951678) (xy 404.302726 -287.902248)
			(xy 404.294596 -287.850913) (xy 404.294086 -287.824926) (xy 404.294585 -287.798814) (xy 404.302807 -287.747242)
			(xy 404.319034 -287.697603) (xy 404.342863 -287.651133) (xy 404.373702 -287.608987) (xy 404.391876 -287.59023)
			(xy 404.397904 -287.58283) (xy 404.404471 -287.564922) (xy 404.40405 -287.545853) (xy 404.400766 -287.53689)
			(xy 404.364698 -287.45053) (xy 404.360437 -287.441504) (xy 404.346346 -287.427396) (xy 404.327931 -287.419749)
			(xy 404.317962 -287.419288) (xy 404.29561 -287.419288) (xy 404.290784 -287.419542) (xy 404.264114 -287.420812)
			(xy 404.035514 -287.420812) (xy 404.008844 -287.419542) (xy 404.004018 -287.419288) (xy 403.981666 -287.419288)
			(xy 403.971712 -287.419822) (xy 403.95333 -287.427482) (xy 403.939215 -287.441531) (xy 403.93493 -287.45053)
			(xy 403.898862 -287.53689) (xy 403.895553 -287.545849) (xy 403.895134 -287.564928) (xy 403.901696 -287.582848)
			(xy 403.907752 -287.59023) (xy 403.925948 -287.608966) (xy 403.956788 -287.651114) (xy 403.980612 -287.697589)
			(xy 403.996825 -287.747235) (xy 404.005024 -287.798813) (xy 404.005542 -287.824926) (xy 404.005032 -287.850913)
			(xy 403.996902 -287.902248) (xy 403.980841 -287.951678) (xy 403.957245 -287.997988) (xy 403.926695 -288.040036)
			(xy 403.889944 -288.076787) (xy 403.847896 -288.107337) (xy 403.801586 -288.130933) (xy 403.752156 -288.146994)
			(xy 403.700821 -288.155124) (xy 403.648847 -288.155124) (xy 403.597512 -288.146994) (xy 403.548082 -288.130933)
			(xy 403.501772 -288.107337) (xy 403.459724 -288.076787) (xy 403.422973 -288.040036) (xy 403.392423 -287.997988)
			(xy 403.368827 -287.951678) (xy 403.352766 -287.902248) (xy 403.344636 -287.850913) (xy 403.344126 -287.824926)
			(xy 403.344626 -287.798815) (xy 403.352848 -287.747243) (xy 403.369077 -287.697606) (xy 403.392908 -287.651137)
			(xy 403.42375 -287.608994) (xy 403.441916 -287.59023) (xy 403.44795 -287.582832) (xy 403.454525 -287.564923)
			(xy 403.454103 -287.54585) (xy 403.450806 -287.53689) (xy 403.414738 -287.45053) (xy 403.410474 -287.44151)
			(xy 403.39638 -287.427419) (xy 403.377967 -287.419793) (xy 403.368002 -287.419288) (xy 403.34565 -287.419288)
			(xy 403.340824 -287.419542) (xy 403.314154 -287.420812) (xy 403.085554 -287.420812) (xy 403.058884 -287.419542)
			(xy 403.054058 -287.419288) (xy 403.031706 -287.419288) (xy 403.021748 -287.419815) (xy 403.003353 -287.427466)
			(xy 402.989227 -287.441515) (xy 402.98497 -287.45053) (xy 402.948902 -287.53689) (xy 402.945596 -287.545849)
			(xy 402.945177 -287.564929) (xy 402.951733 -287.582851) (xy 402.957792 -287.59023) (xy 402.975991 -287.608965)
			(xy 403.006836 -287.651111) (xy 403.030664 -287.697586) (xy 403.04688 -287.747232) (xy 403.055081 -287.798812)
			(xy 403.055582 -287.824926) (xy 403.055072 -287.850913) (xy 403.046942 -287.902248) (xy 403.030881 -287.951678)
			(xy 403.007285 -287.997988) (xy 402.976735 -288.040036) (xy 402.939984 -288.076787) (xy 402.897936 -288.107337)
			(xy 402.851626 -288.130933) (xy 402.802196 -288.146994) (xy 402.750861 -288.155124) (xy 402.698887 -288.155124)
			(xy 402.647552 -288.146994) (xy 402.598122 -288.130933) (xy 402.551812 -288.107337) (xy 402.509764 -288.076787)
			(xy 402.473013 -288.040036) (xy 402.442463 -287.997988) (xy 402.418867 -287.951678) (xy 402.402806 -287.902248)
			(xy 402.394676 -287.850913) (xy 402.394166 -287.824926) (xy 402.394665 -287.798814) (xy 402.402886 -287.747241)
			(xy 402.419113 -287.697602) (xy 402.442941 -287.651131) (xy 402.473779 -287.608983) (xy 402.491956 -287.59023)
			(xy 402.497986 -287.58283) (xy 402.504555 -287.564922) (xy 402.504134 -287.545852) (xy 402.500846 -287.53689)
			(xy 402.464778 -287.45053) (xy 402.460516 -287.441506) (xy 402.446424 -287.427404) (xy 402.42801 -287.419764)
			(xy 402.418042 -287.419288) (xy 402.39569 -287.419288) (xy 402.390864 -287.419542) (xy 402.364194 -287.420812)
			(xy 402.135594 -287.420812) (xy 402.108924 -287.419542) (xy 402.104098 -287.419288) (xy 402.081746 -287.419288)
			(xy 402.071794 -287.419826) (xy 402.053418 -287.42749) (xy 402.03931 -287.441539) (xy 402.03501 -287.45053)
			(xy 401.998942 -287.53689) (xy 401.995634 -287.545849) (xy 401.995215 -287.564928) (xy 402.001774 -287.582849)
			(xy 402.007832 -287.59023) (xy 402.026029 -287.608965) (xy 402.056871 -287.651112) (xy 402.080696 -287.697588)
			(xy 402.09691 -287.747234) (xy 402.105109 -287.798813) (xy 402.105622 -287.824926) (xy 402.105112 -287.850913)
			(xy 402.096982 -287.902248) (xy 402.080921 -287.951678) (xy 402.057325 -287.997988) (xy 402.026775 -288.040036)
			(xy 401.990024 -288.076787) (xy 401.947976 -288.107337) (xy 401.901666 -288.130933) (xy 401.852236 -288.146994)
			(xy 401.800901 -288.155124) (xy 401.748927 -288.155124) (xy 401.697592 -288.146994) (xy 401.648162 -288.130933)
			(xy 401.601852 -288.107337) (xy 401.559804 -288.076787) (xy 401.523053 -288.040036) (xy 401.492503 -287.997988)
			(xy 401.468907 -287.951678) (xy 401.452846 -287.902248) (xy 401.444716 -287.850913) (xy 401.444206 -287.824926)
			(xy 401.444705 -287.798814) (xy 401.452927 -287.747242) (xy 401.469155 -287.697604) (xy 401.492986 -287.651135)
			(xy 401.523826 -287.60899) (xy 401.541996 -287.59023) (xy 401.548032 -287.582832) (xy 401.554609 -287.564923)
			(xy 401.554187 -287.545849) (xy 401.550886 -287.53689) (xy 401.514818 -287.45053) (xy 401.510611 -287.441474)
			(xy 401.496497 -287.427369) (xy 401.478059 -287.41974) (xy 401.468082 -287.419288) (xy 401.44573 -287.419288)
			(xy 401.440904 -287.419542) (xy 401.414234 -287.420812) (xy 401.185634 -287.420812) (xy 401.158964 -287.419542)
			(xy 401.154138 -287.419288) (xy 401.131786 -287.419288) (xy 401.12183 -287.419819) (xy 401.103441 -287.427474)
			(xy 401.089321 -287.441523) (xy 401.08505 -287.45053) (xy 401.048982 -287.53689) (xy 401.045672 -287.545848)
			(xy 401.045252 -287.564928) (xy 401.051817 -287.582847) (xy 401.057872 -287.59023) (xy 401.076067 -287.608966)
			(xy 401.106905 -287.651115) (xy 401.130727 -287.69759) (xy 401.146939 -287.747235) (xy 401.155138 -287.798813)
			(xy 401.155662 -287.824926) (xy 401.155152 -287.850913) (xy 401.147022 -287.902248) (xy 401.130961 -287.951678)
			(xy 401.107365 -287.997988) (xy 401.076815 -288.040036) (xy 401.040064 -288.076787) (xy 400.998016 -288.107337)
			(xy 400.951706 -288.130933) (xy 400.902276 -288.146994) (xy 400.850941 -288.155124) (xy 400.798967 -288.155124)
			(xy 400.747632 -288.146994) (xy 400.698202 -288.130933) (xy 400.651892 -288.107337) (xy 400.609844 -288.076787)
			(xy 400.573093 -288.040036) (xy 400.542543 -287.997988) (xy 400.518947 -287.951678) (xy 400.502886 -287.902248)
			(xy 400.494756 -287.850913) (xy 400.494246 -287.824926) (xy 400.494746 -287.798815) (xy 400.502969 -287.747243)
			(xy 400.519198 -287.697607) (xy 400.543031 -287.651139) (xy 400.573873 -287.608997) (xy 400.592036 -287.59023)
			(xy 400.598068 -287.582831) (xy 400.60464 -287.564923) (xy 400.604219 -287.545851) (xy 400.600926 -287.53689)
			(xy 400.564858 -287.45053) (xy 400.560595 -287.441508) (xy 400.546502 -287.427411) (xy 400.528088 -287.419778)
			(xy 400.518122 -287.419288) (xy 400.49577 -287.419288) (xy 400.490944 -287.419542) (xy 400.464274 -287.420812)
			(xy 400.235674 -287.420812) (xy 400.209004 -287.419542) (xy 400.204178 -287.419288) (xy 400.181826 -287.419288)
			(xy 400.171876 -287.419829) (xy 400.153506 -287.427497) (xy 400.139404 -287.441547) (xy 400.13509 -287.45053)
			(xy 400.099022 -287.53689) (xy 400.095715 -287.545849) (xy 400.095296 -287.564928) (xy 400.101853 -287.58285)
			(xy 400.107912 -287.59023) (xy 400.12611 -287.608965) (xy 400.156953 -287.651112) (xy 400.18078 -287.697587)
			(xy 400.196995 -287.747233) (xy 400.205195 -287.798812) (xy 400.205702 -287.824926) (xy 400.205192 -287.850913)
			(xy 400.197062 -287.902248) (xy 400.181001 -287.951678) (xy 400.157405 -287.997988) (xy 400.126855 -288.040036)
			(xy 400.090104 -288.076787) (xy 400.048056 -288.107337) (xy 400.001746 -288.130933) (xy 399.952316 -288.146994)
			(xy 399.900981 -288.155124) (xy 399.849007 -288.155124) (xy 399.797672 -288.146994) (xy 399.748242 -288.130933)
			(xy 399.701932 -288.107337) (xy 399.659884 -288.076787) (xy 399.623133 -288.040036) (xy 399.592583 -287.997988)
			(xy 399.568987 -287.951678) (xy 399.552926 -287.902248) (xy 399.544796 -287.850913) (xy 399.544286 -287.824926)
			(xy 399.544785 -287.798814) (xy 399.553007 -287.747242) (xy 399.569234 -287.697603) (xy 399.593063 -287.651133)
			(xy 399.623902 -287.608987) (xy 399.642076 -287.59023) (xy 399.648104 -287.58283) (xy 399.654671 -287.564922)
			(xy 399.65425 -287.545853) (xy 399.650966 -287.53689) (xy 399.614898 -287.45053) (xy 399.610637 -287.441504)
			(xy 399.596546 -287.427396) (xy 399.578131 -287.419749) (xy 399.568162 -287.419288) (xy 399.54581 -287.419288)
			(xy 399.540984 -287.419542) (xy 399.514314 -287.420812) (xy 399.285714 -287.420812) (xy 399.259044 -287.419542)
			(xy 399.254218 -287.419288) (xy 399.231866 -287.419288) (xy 399.221912 -287.419822) (xy 399.20353 -287.427482)
			(xy 399.189415 -287.441531) (xy 399.18513 -287.45053) (xy 399.149062 -287.53689) (xy 399.145753 -287.545849)
			(xy 399.145334 -287.564928) (xy 399.151896 -287.582848) (xy 399.157952 -287.59023) (xy 399.176148 -287.608966)
			(xy 399.206988 -287.651114) (xy 399.230812 -287.697589) (xy 399.247025 -287.747235) (xy 399.255224 -287.798813)
			(xy 399.255742 -287.824926) (xy 399.255232 -287.850913) (xy 399.247102 -287.902248) (xy 399.231041 -287.951678)
			(xy 399.207445 -287.997988) (xy 399.176895 -288.040036) (xy 399.140144 -288.076787) (xy 399.098096 -288.107337)
			(xy 399.051786 -288.130933) (xy 399.002356 -288.146994) (xy 398.951021 -288.155124) (xy 398.899047 -288.155124)
			(xy 398.847712 -288.146994) (xy 398.798282 -288.130933) (xy 398.751972 -288.107337) (xy 398.709924 -288.076787)
			(xy 398.673173 -288.040036) (xy 398.642623 -287.997988) (xy 398.619027 -287.951678) (xy 398.602966 -287.902248)
			(xy 398.594836 -287.850913) (xy 398.594326 -287.824926) (xy 398.594826 -287.798815) (xy 398.603048 -287.747243)
			(xy 398.619277 -287.697606) (xy 398.643108 -287.651137) (xy 398.67395 -287.608994) (xy 398.692116 -287.59023)
			(xy 398.69815 -287.582832) (xy 398.704725 -287.564923) (xy 398.704303 -287.54585) (xy 398.701006 -287.53689)
			(xy 398.664938 -287.45053) (xy 398.660674 -287.44151) (xy 398.64658 -287.427419) (xy 398.628167 -287.419793)
			(xy 398.618202 -287.419288) (xy 398.59585 -287.419288) (xy 398.591024 -287.419542) (xy 398.564354 -287.420812)
			(xy 398.354042 -287.420812) (xy 398.348454 -287.420558) (xy 398.335754 -287.419034) (xy 398.281652 -287.419034)
			(xy 398.274161 -287.419338) (xy 398.25983 -287.42372) (xy 398.253458 -287.42767) (xy 398.247449 -287.432041)
			(xy 398.238038 -287.443532) (xy 398.234916 -287.450276) (xy 398.209008 -287.512506) (xy 398.198848 -287.536636)
			(xy 398.195413 -287.545918) (xy 398.195177 -287.565688) (xy 398.202481 -287.58406) (xy 398.209008 -287.5915)
			(xy 398.20977 -287.592262) (xy 398.227596 -287.610953) (xy 398.257806 -287.652845) (xy 398.281126 -287.698928)
			(xy 398.29699 -287.74808) (xy 398.305009 -287.799102) (xy 398.305528 -287.824926) (xy 398.305018 -287.850913)
			(xy 398.296888 -287.902248) (xy 398.280827 -287.951678) (xy 398.257231 -287.997988) (xy 398.226681 -288.040036)
			(xy 398.18993 -288.076787) (xy 398.147882 -288.107337) (xy 398.101572 -288.130933) (xy 398.052142 -288.146994)
			(xy 398.000807 -288.155124) (xy 397.948833 -288.155124) (xy 397.897498 -288.146994) (xy 397.848068 -288.130933)
			(xy 397.801758 -288.107337) (xy 397.75971 -288.076787) (xy 397.722959 -288.040036) (xy 397.692409 -287.997988)
			(xy 397.668813 -287.951678) (xy 397.652752 -287.902248) (xy 397.644622 -287.850913) (xy 397.644112 -287.824926)
			(xy 397.644615 -287.799103) (xy 397.652658 -287.748088) (xy 397.668536 -287.698944) (xy 397.691863 -287.652867)
			(xy 397.722071 -287.610978) (xy 397.73987 -287.592262) (xy 397.740632 -287.5915) (xy 397.747125 -287.584043)
			(xy 397.754385 -287.565673) (xy 397.754189 -287.545921) (xy 397.750792 -287.536636) (xy 397.740632 -287.512506)
			(xy 397.714724 -287.450276) (xy 397.711637 -287.443511) (xy 397.702213 -287.432019) (xy 397.696182 -287.42767)
			(xy 397.689819 -287.423702) (xy 397.675483 -287.419327) (xy 397.667988 -287.419034) (xy 397.613378 -287.419034)
			(xy 397.60779 -287.419542) (xy 397.606266 -287.419542) (xy 397.583152 -287.420812) (xy 397.404082 -287.420812)
			(xy 397.398494 -287.420558) (xy 397.385794 -287.419034) (xy 397.331692 -287.419034) (xy 397.324204 -287.419346)
			(xy 397.309882 -287.423742) (xy 397.303498 -287.42767) (xy 397.297485 -287.432038) (xy 397.288067 -287.443526)
			(xy 397.284956 -287.450276) (xy 397.259048 -287.512506) (xy 397.248888 -287.536636) (xy 397.245451 -287.545917)
			(xy 397.245215 -287.565687) (xy 397.252523 -287.584057) (xy 397.259048 -287.5915) (xy 397.25981 -287.592262)
			(xy 397.277634 -287.610954) (xy 397.30784 -287.652847) (xy 397.331158 -287.698931) (xy 397.347019 -287.748082)
			(xy 397.355038 -287.799102) (xy 397.355568 -287.824926) (xy 397.355058 -287.850913) (xy 397.346928 -287.902248)
			(xy 397.330867 -287.951678) (xy 397.307271 -287.997988) (xy 397.276721 -288.040036) (xy 397.23997 -288.076787)
			(xy 397.197922 -288.107337) (xy 397.151612 -288.130933) (xy 397.102182 -288.146994) (xy 397.050847 -288.155124)
			(xy 396.998873 -288.155124) (xy 396.947538 -288.146994) (xy 396.898108 -288.130933) (xy 396.851798 -288.107337)
			(xy 396.80975 -288.076787) (xy 396.772999 -288.040036) (xy 396.742449 -287.997988) (xy 396.718853 -287.951678)
			(xy 396.702792 -287.902248) (xy 396.694662 -287.850913) (xy 396.694152 -287.824926) (xy 396.694655 -287.799103)
			(xy 396.702697 -287.748087) (xy 396.718572 -287.698941) (xy 396.741896 -287.652861) (xy 396.772101 -287.610969)
			(xy 396.78991 -287.592262) (xy 396.790672 -287.5915) (xy 396.797161 -287.584042) (xy 396.804415 -287.565672)
			(xy 396.804219 -287.545923) (xy 396.800832 -287.536636) (xy 396.790672 -287.512506) (xy 396.764764 -287.450276)
			(xy 396.761679 -287.44351) (xy 396.752259 -287.432011) (xy 396.746222 -287.42767) (xy 396.73986 -287.423696)
			(xy 396.725524 -287.41931) (xy 396.718028 -287.419034) (xy 396.663418 -287.419034) (xy 396.661386 -287.419288)
			(xy 396.64767 -287.420558) (xy 396.642844 -287.420812) (xy 396.608554 -287.420812) (xy 396.60576 -287.420304)
			(xy 396.5575 -287.420304) (xy 396.554198 -287.419034) (xy 396.381732 -287.419034) (xy 396.374242 -287.419341)
			(xy 396.359914 -287.423727) (xy 396.353538 -287.42767) (xy 396.34753 -287.432042) (xy 396.338123 -287.443535)
			(xy 396.334996 -287.450276) (xy 396.309088 -287.512506) (xy 396.298928 -287.536636) (xy 396.295489 -287.545916)
			(xy 396.295252 -287.565686) (xy 396.302566 -287.584055) (xy 396.309088 -287.5915) (xy 396.30985 -287.592262)
			(xy 396.327677 -287.610952) (xy 396.357888 -287.652844) (xy 396.38121 -287.698927) (xy 396.397075 -287.748079)
			(xy 396.405095 -287.799101) (xy 396.405608 -287.824926) (xy 396.405098 -287.850913) (xy 396.396968 -287.902248)
			(xy 396.380907 -287.951678) (xy 396.357311 -287.997988) (xy 396.326761 -288.040036) (xy 396.29001 -288.076787)
			(xy 396.247962 -288.107337) (xy 396.201652 -288.130933) (xy 396.152222 -288.146994) (xy 396.100887 -288.155124)
			(xy 396.048913 -288.155124) (xy 395.997578 -288.146994) (xy 395.948148 -288.130933) (xy 395.901838 -288.107337)
			(xy 395.85979 -288.076787) (xy 395.823039 -288.040036) (xy 395.792489 -287.997988) (xy 395.768893 -287.951678)
			(xy 395.752832 -287.902248) (xy 395.744702 -287.850913) (xy 395.744192 -287.824926) (xy 395.744695 -287.799103)
			(xy 395.752737 -287.748088) (xy 395.768615 -287.698943) (xy 395.791941 -287.652865) (xy 395.822148 -287.610975)
			(xy 395.83995 -287.592262) (xy 395.840712 -287.5915) (xy 395.847196 -287.58404) (xy 395.854445 -287.565672)
			(xy 395.854249 -287.545926) (xy 395.850872 -287.536636) (xy 395.840712 -287.512506) (xy 395.814804 -287.450276)
			(xy 395.811716 -287.443512) (xy 395.80229 -287.432023) (xy 395.796262 -287.42767) (xy 395.789901 -287.423691)
			(xy 395.775566 -287.419294) (xy 395.768068 -287.419034) (xy 395.431772 -287.419034) (xy 395.42428 -287.419335)
			(xy 395.409946 -287.423712) (xy 395.403578 -287.42767) (xy 395.397567 -287.432039) (xy 395.388153 -287.443529)
			(xy 395.385036 -287.450276) (xy 395.359128 -287.512506) (xy 395.348968 -287.536636) (xy 395.345532 -287.545917)
			(xy 395.345296 -287.565687) (xy 395.352602 -287.584059) (xy 395.359128 -287.5915) (xy 395.35989 -287.592262)
			(xy 395.377715 -287.610953) (xy 395.407923 -287.652846) (xy 395.431242 -287.698929) (xy 395.447104 -287.748081)
			(xy 395.455123 -287.799102) (xy 395.455648 -287.824926) (xy 395.455138 -287.850913) (xy 395.447008 -287.902248)
			(xy 395.430947 -287.951678) (xy 395.407351 -287.997988) (xy 395.376801 -288.040036) (xy 395.34005 -288.076787)
			(xy 395.298002 -288.107337) (xy 395.251692 -288.130933) (xy 395.202262 -288.146994) (xy 395.150927 -288.155124)
			(xy 395.098953 -288.155124) (xy 395.047618 -288.146994) (xy 394.998188 -288.130933) (xy 394.951878 -288.107337)
			(xy 394.90983 -288.076787) (xy 394.873079 -288.040036) (xy 394.842529 -287.997988) (xy 394.818933 -287.951678)
			(xy 394.802872 -287.902248) (xy 394.794742 -287.850913) (xy 394.794232 -287.824926) (xy 394.794735 -287.799104)
			(xy 394.802778 -287.748089) (xy 394.818657 -287.698945) (xy 394.841985 -287.652869) (xy 394.872195 -287.610982)
			(xy 394.88999 -287.592262) (xy 394.890752 -287.5915) (xy 394.897242 -287.584043) (xy 394.9045 -287.565673)
			(xy 394.904304 -287.545922) (xy 394.900912 -287.536636) (xy 394.890752 -287.512506) (xy 394.864844 -287.450276)
			(xy 394.861758 -287.44351) (xy 394.852336 -287.432015) (xy 394.846302 -287.42767) (xy 394.839939 -287.423699)
			(xy 394.825604 -287.419319) (xy 394.818108 -287.419034) (xy 394.481812 -287.419034) (xy 394.471866 -287.419579)
			(xy 394.453506 -287.427253) (xy 394.439419 -287.441308) (xy 394.435076 -287.450276) (xy 394.417042 -287.49371)
			(xy 394.399008 -287.53689) (xy 394.395875 -287.545318) (xy 394.395122 -287.563271) (xy 394.400637 -287.580373)
			(xy 394.405866 -287.58769) (xy 394.40739 -287.589722) (xy 394.409422 -287.591754) (xy 394.427337 -287.61046)
			(xy 394.457707 -287.652414) (xy 394.481155 -287.698594) (xy 394.497108 -287.747869) (xy 394.505173 -287.79903)
			(xy 394.505688 -287.824926) (xy 394.505178 -287.850913) (xy 394.497048 -287.902248) (xy 394.480987 -287.951678)
			(xy 394.457391 -287.997988) (xy 394.426841 -288.040036) (xy 394.39009 -288.076787) (xy 394.348042 -288.107337)
			(xy 394.301732 -288.130933) (xy 394.252302 -288.146994) (xy 394.200967 -288.155124) (xy 394.148993 -288.155124)
			(xy 394.097658 -288.146994) (xy 394.048228 -288.130933) (xy 394.001918 -288.107337) (xy 393.95987 -288.076787)
			(xy 393.923119 -288.040036) (xy 393.892569 -287.997988) (xy 393.868973 -287.951678) (xy 393.852912 -287.902248)
			(xy 393.844782 -287.850913) (xy 393.844272 -287.824926) (xy 393.844775 -287.799103) (xy 393.852817 -287.748087)
			(xy 393.868693 -287.698942) (xy 393.892018 -287.652863) (xy 393.922224 -287.610972) (xy 393.94003 -287.592262)
			(xy 393.940792 -287.5915) (xy 393.947278 -287.584041) (xy 393.95453 -287.565672) (xy 393.954334 -287.545924)
			(xy 393.950952 -287.536636) (xy 393.940792 -287.512506) (xy 393.914884 -287.450276) (xy 393.9118 -287.443508)
			(xy 393.902383 -287.432007) (xy 393.896342 -287.42767) (xy 393.889981 -287.423694) (xy 393.875645 -287.419302)
			(xy 393.868148 -287.419034) (xy 393.531852 -287.419034) (xy 393.521902 -287.419572) (xy 393.503529 -287.427238)
			(xy 393.48943 -287.441292) (xy 393.485116 -287.450276) (xy 393.467082 -287.49371) (xy 393.449048 -287.53689)
			(xy 393.445917 -287.545319) (xy 393.445166 -287.563272) (xy 393.450675 -287.580375) (xy 393.455906 -287.58769)
			(xy 393.45743 -287.589722) (xy 393.459462 -287.591754) (xy 393.477376 -287.610461) (xy 393.507741 -287.652416)
			(xy 393.531187 -287.698597) (xy 393.547137 -287.747871) (xy 393.555201 -287.79903) (xy 393.555728 -287.824926)
			(xy 393.555218 -287.850913) (xy 393.547088 -287.902248) (xy 393.531027 -287.951678) (xy 393.507431 -287.997988)
			(xy 393.476881 -288.040036) (xy 393.44013 -288.076787) (xy 393.398082 -288.107337) (xy 393.351772 -288.130933)
			(xy 393.302342 -288.146994) (xy 393.251007 -288.155124) (xy 393.199033 -288.155124) (xy 393.147698 -288.146994)
			(xy 393.098268 -288.130933) (xy 393.051958 -288.107337) (xy 393.00991 -288.076787) (xy 392.973159 -288.040036)
			(xy 392.942609 -287.997988) (xy 392.919013 -287.951678) (xy 392.902952 -287.902248) (xy 392.894822 -287.850913)
			(xy 392.894312 -287.824926) (xy 392.894815 -287.799103) (xy 392.902858 -287.748088) (xy 392.918736 -287.698944)
			(xy 392.942063 -287.652867) (xy 392.972271 -287.610978) (xy 392.99007 -287.592262) (xy 392.990832 -287.5915)
			(xy 392.997325 -287.584043) (xy 393.004585 -287.565673) (xy 393.004389 -287.545921) (xy 393.000992 -287.536636)
			(xy 392.990832 -287.512506) (xy 392.964924 -287.450276) (xy 392.961837 -287.443511) (xy 392.952413 -287.432019)
			(xy 392.946382 -287.42767) (xy 392.940019 -287.423702) (xy 392.925683 -287.419327) (xy 392.918188 -287.419034)
			(xy 389.731758 -287.419034) (xy 389.721807 -287.419571) (xy 389.703433 -287.427236) (xy 389.689332 -287.44129)
			(xy 389.685022 -287.450276) (xy 389.666988 -287.49371) (xy 389.648954 -287.53689) (xy 389.645824 -287.545319)
			(xy 389.645072 -287.563272) (xy 389.650582 -287.580374) (xy 389.655812 -287.58769) (xy 389.657336 -287.589722)
			(xy 389.659368 -287.591754) (xy 389.677281 -287.610461) (xy 389.707647 -287.652416) (xy 389.731092 -287.698597)
			(xy 389.747042 -287.747871) (xy 389.755106 -287.79903) (xy 389.755634 -287.824926) (xy 389.755124 -287.850913)
			(xy 389.746994 -287.902248) (xy 389.730933 -287.951678) (xy 389.707337 -287.997988) (xy 389.676787 -288.040036)
			(xy 389.640036 -288.076787) (xy 389.597988 -288.107337) (xy 389.551678 -288.130933) (xy 389.502248 -288.146994)
			(xy 389.450913 -288.155124) (xy 389.398939 -288.155124) (xy 389.347604 -288.146994) (xy 389.298174 -288.130933)
			(xy 389.251864 -288.107337) (xy 389.209816 -288.076787) (xy 389.173065 -288.040036) (xy 389.142515 -287.997988)
			(xy 389.118919 -287.951678) (xy 389.102858 -287.902248) (xy 389.094728 -287.850913) (xy 389.094218 -287.824926)
			(xy 389.094721 -287.799104) (xy 389.102764 -287.748088) (xy 389.118642 -287.698945) (xy 389.141969 -287.652868)
			(xy 389.172178 -287.610979) (xy 389.189976 -287.592262) (xy 389.190738 -287.5915) (xy 389.19723 -287.584043)
			(xy 389.20449 -287.565673) (xy 389.204293 -287.545921) (xy 389.200898 -287.536636) (xy 389.190738 -287.512506)
			(xy 389.16483 -287.450276) (xy 389.161743 -287.443511) (xy 389.15232 -287.432018) (xy 389.146288 -287.42767)
			(xy 389.139925 -287.423701) (xy 389.125589 -287.419325) (xy 389.118094 -287.419034) (xy 386.881878 -287.419034)
			(xy 386.871925 -287.419567) (xy 386.853544 -287.427228) (xy 386.839437 -287.441282) (xy 386.835142 -287.450276)
			(xy 386.817108 -287.49371) (xy 386.799074 -287.53689) (xy 386.795943 -287.545319) (xy 386.79519 -287.563271)
			(xy 386.800702 -287.580374) (xy 386.805932 -287.58769) (xy 386.807456 -287.589722) (xy 386.809488 -287.591754)
			(xy 386.8274 -287.610461) (xy 386.857764 -287.652417) (xy 386.881207 -287.698598) (xy 386.897156 -287.747872)
			(xy 386.90522 -287.799031) (xy 386.905754 -287.824926) (xy 386.905244 -287.850913) (xy 386.897114 -287.902248)
			(xy 386.881053 -287.951678) (xy 386.857457 -287.997988) (xy 386.826907 -288.040036) (xy 386.790156 -288.076787)
			(xy 386.748108 -288.107337) (xy 386.701798 -288.130933) (xy 386.652368 -288.146994) (xy 386.601033 -288.155124)
			(xy 386.549059 -288.155124) (xy 386.497724 -288.146994) (xy 386.448294 -288.130933) (xy 386.401984 -288.107337)
			(xy 386.359936 -288.076787) (xy 386.323185 -288.040036) (xy 386.292635 -287.997988) (xy 386.269039 -287.951678)
			(xy 386.252978 -287.902248) (xy 386.244848 -287.850913) (xy 386.244338 -287.824926) (xy 386.244841 -287.799104)
			(xy 386.252884 -287.748089) (xy 386.268763 -287.698946) (xy 386.292092 -287.65287) (xy 386.322302 -287.610983)
			(xy 386.340096 -287.592262) (xy 386.340858 -287.5915) (xy 386.347348 -287.584042) (xy 386.354605 -287.565673)
			(xy 386.354408 -287.545923) (xy 386.351018 -287.536636) (xy 386.340858 -287.512506) (xy 386.31495 -287.450276)
			(xy 386.311864 -287.44351) (xy 386.302443 -287.432014) (xy 386.296408 -287.42767) (xy 386.290045 -287.423698)
			(xy 386.27571 -287.419317) (xy 386.268214 -287.419034) (xy 385.931664 -287.419034) (xy 385.921712 -287.41957)
			(xy 385.903336 -287.427233) (xy 385.889233 -287.441287) (xy 385.884928 -287.450276) (xy 385.866894 -287.49371)
			(xy 385.84886 -287.53689) (xy 385.845729 -287.545319) (xy 385.844977 -287.563271) (xy 385.850488 -287.580374)
			(xy 385.855718 -287.58769) (xy 385.857242 -287.589722) (xy 385.859274 -287.591754) (xy 385.877187 -287.610461)
			(xy 385.907552 -287.652417) (xy 385.930996 -287.698597) (xy 385.946946 -287.747871) (xy 385.95501 -287.79903)
			(xy 385.95554 -287.824926) (xy 385.95503 -287.850913) (xy 385.9469 -287.902248) (xy 385.930839 -287.951678)
			(xy 385.907243 -287.997988) (xy 385.876693 -288.040036) (xy 385.839942 -288.076787) (xy 385.797894 -288.107337)
			(xy 385.751584 -288.130933) (xy 385.702154 -288.146994) (xy 385.650819 -288.155124) (xy 385.598845 -288.155124)
			(xy 385.54751 -288.146994) (xy 385.49808 -288.130933) (xy 385.45177 -288.107337) (xy 385.409722 -288.076787)
			(xy 385.372971 -288.040036) (xy 385.342421 -287.997988) (xy 385.318825 -287.951678) (xy 385.302764 -287.902248)
			(xy 385.294634 -287.850913) (xy 385.294124 -287.824926) (xy 385.294627 -287.799104) (xy 385.30267 -287.748089)
			(xy 385.318549 -287.698945) (xy 385.341876 -287.652868) (xy 385.372085 -287.61098) (xy 385.389882 -287.592262)
			(xy 385.390644 -287.5915) (xy 385.397135 -287.584043) (xy 385.404394 -287.565673) (xy 385.404198 -287.545922)
			(xy 385.400804 -287.536636) (xy 385.390644 -287.512506) (xy 385.364736 -287.450276) (xy 385.361649 -287.443511)
			(xy 385.352227 -287.432016) (xy 385.346194 -287.42767) (xy 385.339831 -287.4237) (xy 385.325495 -287.419322)
			(xy 385.318 -287.419034) (xy 384.981704 -287.419034) (xy 384.971748 -287.419563) (xy 384.95336 -287.427218)
			(xy 384.939245 -287.441271) (xy 384.934968 -287.450276) (xy 384.916934 -287.49371) (xy 384.8989 -287.53689)
			(xy 384.895767 -287.545318) (xy 384.895014 -287.563271) (xy 384.900529 -287.580373) (xy 384.905758 -287.58769)
			(xy 384.907282 -287.589722) (xy 384.909314 -287.591754) (xy 384.927225 -287.610462) (xy 384.957586 -287.652419)
			(xy 384.981028 -287.6986) (xy 384.996976 -287.747873) (xy 385.005038 -287.799031) (xy 385.00558 -287.824926)
			(xy 385.00507 -287.850913) (xy 384.99694 -287.902248) (xy 384.980879 -287.951678) (xy 384.957283 -287.997988)
			(xy 384.926733 -288.040036) (xy 384.889982 -288.076787) (xy 384.847934 -288.107337) (xy 384.801624 -288.130933)
			(xy 384.752194 -288.146994) (xy 384.700859 -288.155124) (xy 384.648885 -288.155124) (xy 384.59755 -288.146994)
			(xy 384.54812 -288.130933) (xy 384.50181 -288.107337) (xy 384.459762 -288.076787) (xy 384.423011 -288.040036)
			(xy 384.392461 -287.997988) (xy 384.368865 -287.951678) (xy 384.352804 -287.902248) (xy 384.344674 -287.850913)
			(xy 384.344164 -287.824926) (xy 384.344667 -287.799103) (xy 384.352709 -287.748087) (xy 384.368585 -287.698942)
			(xy 384.391909 -287.652863) (xy 384.422115 -287.610971) (xy 384.439922 -287.592262) (xy 384.440684 -287.5915)
			(xy 384.447171 -287.584041) (xy 384.454424 -287.565672) (xy 384.454228 -287.545924) (xy 384.450844 -287.536636)
			(xy 384.440684 -287.512506) (xy 384.414776 -287.450276) (xy 384.411692 -287.443509) (xy 384.402274 -287.432008)
			(xy 384.396234 -287.42767) (xy 384.389873 -287.423695) (xy 384.375537 -287.419305) (xy 384.36804 -287.419034)
			(xy 382.523492 -287.419034) (xy 382.510538 -287.420812) (xy 382.491742 -287.425638) (xy 382.486154 -287.428686)
			(xy 382.457932 -287.443377) (xy 382.397817 -287.464201) (xy 382.335083 -287.474782) (xy 382.303274 -287.475422)
			(xy 382.293622 -287.475422) (xy 382.2634 -287.474081) (xy 382.203927 -287.463021) (xy 382.146949 -287.442702)
			(xy 382.12014 -287.428686) (xy 382.114298 -287.425638) (xy 382.095502 -287.420812) (xy 382.082548 -287.419034)
			(xy 381.637032 -287.419034) (xy 381.624078 -287.420812) (xy 381.605282 -287.425638) (xy 381.599694 -287.428686)
			(xy 381.571471 -287.443372) (xy 381.511355 -287.464187) (xy 381.448622 -287.474758) (xy 381.416814 -287.475422)
			(xy 381.407162 -287.475422) (xy 381.376939 -287.474084) (xy 381.317463 -287.46303) (xy 381.260482 -287.442716)
			(xy 381.23368 -287.428686) (xy 381.227838 -287.425638) (xy 381.209042 -287.420812) (xy 381.196088 -287.419034)
			(xy 380.240032 -287.419034) (xy 380.227078 -287.420812) (xy 380.208282 -287.425638) (xy 380.202694 -287.428686)
			(xy 380.174471 -287.443372) (xy 380.114355 -287.464187) (xy 380.051622 -287.474758) (xy 380.019814 -287.475422)
			(xy 380.010162 -287.475422) (xy 379.979939 -287.474084) (xy 379.920463 -287.46303) (xy 379.863482 -287.442716)
			(xy 379.83668 -287.428686) (xy 379.830838 -287.425638) (xy 379.812042 -287.420812) (xy 379.799088 -287.419034)
			(xy 369.10772 -287.419034) (xy 369.099027 -287.419377) (xy 369.082653 -287.425216) (xy 369.075716 -287.430464)
			(xy 369.071906 -287.433766) (xy 368.564922 -287.94075) (xy 368.562214 -287.9436) (xy 368.557617 -287.949976)
			(xy 368.555778 -287.95345) (xy 368.553197 -287.958877) (xy 368.550376 -287.970557) (xy 368.55019 -287.976564)
			(xy 368.55019 -288.230056) (xy 374.111518 -288.230056) (xy 374.115589 -288.174434) (xy 374.127715 -288.119997)
			(xy 374.147638 -288.067906) (xy 374.174934 -288.019271) (xy 374.20902 -287.975128) (xy 374.249169 -287.936419)
			(xy 374.294527 -287.903968) (xy 374.344127 -287.878467) (xy 374.396911 -287.86046) (xy 374.451754 -287.85033)
			(xy 374.507488 -287.848293) (xy 374.562925 -287.854393) (xy 374.616882 -287.868499) (xy 374.668211 -287.890311)
			(xy 374.715817 -287.919365) (xy 374.758685 -287.95504) (xy 374.795902 -287.996577) (xy 374.826675 -288.04309)
			(xy 374.850347 -288.093587) (xy 374.866415 -288.146994) (xy 374.874535 -288.20217) (xy 374.875044 -288.230056)
			(xy 375.596656 -288.230056) (xy 375.600727 -288.174434) (xy 375.612853 -288.119997) (xy 375.632776 -288.067906)
			(xy 375.660072 -288.019271) (xy 375.694158 -287.975128) (xy 375.734307 -287.936419) (xy 375.779665 -287.903968)
			(xy 375.829265 -287.878467) (xy 375.882049 -287.86046) (xy 375.936892 -287.85033) (xy 375.992626 -287.848293)
			(xy 376.048063 -287.854393) (xy 376.10202 -287.868499) (xy 376.153349 -287.890311) (xy 376.200955 -287.919365)
			(xy 376.243823 -287.95504) (xy 376.28104 -287.996577) (xy 376.311813 -288.04309) (xy 376.335485 -288.093587)
			(xy 376.351553 -288.146994) (xy 376.359673 -288.20217) (xy 376.360182 -288.230056) (xy 376.359673 -288.257942)
			(xy 376.351553 -288.313118) (xy 376.335485 -288.366525) (xy 376.311813 -288.417022) (xy 376.28104 -288.463535)
			(xy 376.243823 -288.505072) (xy 376.200955 -288.540747) (xy 376.153349 -288.569801) (xy 376.10202 -288.591613)
			(xy 376.048063 -288.605719) (xy 375.992626 -288.611819) (xy 375.936892 -288.609782) (xy 375.882049 -288.599652)
			(xy 375.829265 -288.581645) (xy 375.779665 -288.556144) (xy 375.734307 -288.523693) (xy 375.694158 -288.484984)
			(xy 375.660072 -288.440841) (xy 375.632776 -288.392206) (xy 375.612853 -288.340115) (xy 375.600727 -288.285678)
			(xy 375.596656 -288.230056) (xy 374.875044 -288.230056) (xy 374.874535 -288.257942) (xy 374.866415 -288.313118)
			(xy 374.850347 -288.366525) (xy 374.826675 -288.417022) (xy 374.795902 -288.463535) (xy 374.758685 -288.505072)
			(xy 374.715817 -288.540747) (xy 374.668211 -288.569801) (xy 374.616882 -288.591613) (xy 374.562925 -288.605719)
			(xy 374.507488 -288.611819) (xy 374.451754 -288.609782) (xy 374.396911 -288.599652) (xy 374.344127 -288.581645)
			(xy 374.294527 -288.556144) (xy 374.249169 -288.523693) (xy 374.20902 -288.484984) (xy 374.174934 -288.440841)
			(xy 374.147638 -288.392206) (xy 374.127715 -288.340115) (xy 374.115589 -288.285678) (xy 374.111518 -288.230056)
			(xy 368.55019 -288.230056) (xy 368.55019 -288.774886) (xy 384.369068 -288.774886) (xy 384.373028 -288.725832)
			(xy 384.384805 -288.678048) (xy 384.404096 -288.632772) (xy 384.430399 -288.591176) (xy 384.463034 -288.554339)
			(xy 384.501155 -288.523214) (xy 384.543776 -288.498607) (xy 384.589792 -288.481155) (xy 384.638011 -288.471311)
			(xy 384.687186 -288.46933) (xy 384.736041 -288.475262) (xy 384.783312 -288.488954) (xy 384.827774 -288.510052)
			(xy 384.868277 -288.538008) (xy 384.90377 -288.5721) (xy 384.933335 -288.611444) (xy 384.956206 -288.655021)
			(xy 384.97179 -288.701702) (xy 384.979685 -288.750279) (xy 384.98018 -288.774886) (xy 385.319028 -288.774886)
			(xy 385.322988 -288.725832) (xy 385.334765 -288.678048) (xy 385.354056 -288.632772) (xy 385.380359 -288.591176)
			(xy 385.412994 -288.554339) (xy 385.451115 -288.523214) (xy 385.493736 -288.498607) (xy 385.539752 -288.481155)
			(xy 385.587971 -288.471311) (xy 385.637146 -288.46933) (xy 385.686001 -288.475262) (xy 385.733272 -288.488954)
			(xy 385.777734 -288.510052) (xy 385.818237 -288.538008) (xy 385.85373 -288.5721) (xy 385.883295 -288.611444)
			(xy 385.906166 -288.655021) (xy 385.92175 -288.701702) (xy 385.929645 -288.750279) (xy 385.93014 -288.774886)
			(xy 386.269242 -288.774886) (xy 386.273202 -288.725832) (xy 386.284979 -288.678048) (xy 386.30427 -288.632772)
			(xy 386.330573 -288.591176) (xy 386.363208 -288.554339) (xy 386.401329 -288.523214) (xy 386.44395 -288.498607)
			(xy 386.489966 -288.481155) (xy 386.538185 -288.471311) (xy 386.58736 -288.46933) (xy 386.636215 -288.475262)
			(xy 386.683486 -288.488954) (xy 386.727948 -288.510052) (xy 386.768451 -288.538008) (xy 386.803944 -288.5721)
			(xy 386.833509 -288.611444) (xy 386.85638 -288.655021) (xy 386.871964 -288.701702) (xy 386.879859 -288.750279)
			(xy 386.880354 -288.774886) (xy 391.019042 -288.774886) (xy 391.023002 -288.725832) (xy 391.034779 -288.678048)
			(xy 391.05407 -288.632772) (xy 391.080373 -288.591176) (xy 391.113008 -288.554339) (xy 391.151129 -288.523214)
			(xy 391.19375 -288.498607) (xy 391.239766 -288.481155) (xy 391.287985 -288.471311) (xy 391.33716 -288.46933)
			(xy 391.386015 -288.475262) (xy 391.433286 -288.488954) (xy 391.477748 -288.510052) (xy 391.518251 -288.538008)
			(xy 391.553744 -288.5721) (xy 391.583309 -288.611444) (xy 391.60618 -288.655021) (xy 391.621764 -288.701702)
			(xy 391.629659 -288.750279) (xy 391.630154 -288.774886) (xy 391.969002 -288.774886) (xy 391.972962 -288.725832)
			(xy 391.984739 -288.678048) (xy 392.00403 -288.632772) (xy 392.030333 -288.591176) (xy 392.062968 -288.554339)
			(xy 392.101089 -288.523214) (xy 392.14371 -288.498607) (xy 392.189726 -288.481155) (xy 392.237945 -288.471311)
			(xy 392.28712 -288.46933) (xy 392.335975 -288.475262) (xy 392.383246 -288.488954) (xy 392.427708 -288.510052)
			(xy 392.468211 -288.538008) (xy 392.503704 -288.5721) (xy 392.533269 -288.611444) (xy 392.55614 -288.655021)
			(xy 392.571724 -288.701702) (xy 392.579619 -288.750279) (xy 392.580114 -288.774886) (xy 392.919216 -288.774886)
			(xy 392.923176 -288.725832) (xy 392.934953 -288.678048) (xy 392.954244 -288.632772) (xy 392.980547 -288.591176)
			(xy 393.013182 -288.554339) (xy 393.051303 -288.523214) (xy 393.093924 -288.498607) (xy 393.13994 -288.481155)
			(xy 393.188159 -288.471311) (xy 393.237334 -288.46933) (xy 393.286189 -288.475262) (xy 393.33346 -288.488954)
			(xy 393.377922 -288.510052) (xy 393.418425 -288.538008) (xy 393.453918 -288.5721) (xy 393.483483 -288.611444)
			(xy 393.506354 -288.655021) (xy 393.521938 -288.701702) (xy 393.529833 -288.750279) (xy 393.530328 -288.774886)
			(xy 393.869176 -288.774886) (xy 393.873136 -288.725832) (xy 393.884913 -288.678048) (xy 393.904204 -288.632772)
			(xy 393.930507 -288.591176) (xy 393.963142 -288.554339) (xy 394.001263 -288.523214) (xy 394.043884 -288.498607)
			(xy 394.0899 -288.481155) (xy 394.138119 -288.471311) (xy 394.187294 -288.46933) (xy 394.236149 -288.475262)
			(xy 394.28342 -288.488954) (xy 394.327882 -288.510052) (xy 394.368385 -288.538008) (xy 394.403878 -288.5721)
			(xy 394.433443 -288.611444) (xy 394.456314 -288.655021) (xy 394.471898 -288.701702) (xy 394.479793 -288.750279)
			(xy 394.480288 -288.774886) (xy 394.819136 -288.774886) (xy 394.823096 -288.725832) (xy 394.834873 -288.678048)
			(xy 394.854164 -288.632772) (xy 394.880467 -288.591176) (xy 394.913102 -288.554339) (xy 394.951223 -288.523214)
			(xy 394.993844 -288.498607) (xy 395.03986 -288.481155) (xy 395.088079 -288.471311) (xy 395.137254 -288.46933)
			(xy 395.186109 -288.475262) (xy 395.23338 -288.488954) (xy 395.277842 -288.510052) (xy 395.318345 -288.538008)
			(xy 395.353838 -288.5721) (xy 395.383403 -288.611444) (xy 395.406274 -288.655021) (xy 395.421858 -288.701702)
			(xy 395.429753 -288.750279) (xy 395.430248 -288.774886) (xy 395.769096 -288.774886) (xy 395.773056 -288.725832)
			(xy 395.784833 -288.678048) (xy 395.804124 -288.632772) (xy 395.830427 -288.591176) (xy 395.863062 -288.554339)
			(xy 395.901183 -288.523214) (xy 395.943804 -288.498607) (xy 395.98982 -288.481155) (xy 396.038039 -288.471311)
			(xy 396.087214 -288.46933) (xy 396.136069 -288.475262) (xy 396.18334 -288.488954) (xy 396.227802 -288.510052)
			(xy 396.268305 -288.538008) (xy 396.303798 -288.5721) (xy 396.333363 -288.611444) (xy 396.356234 -288.655021)
			(xy 396.371818 -288.701702) (xy 396.379713 -288.750279) (xy 396.380208 -288.774886) (xy 396.719056 -288.774886)
			(xy 396.723016 -288.725832) (xy 396.734793 -288.678048) (xy 396.754084 -288.632772) (xy 396.780387 -288.591176)
			(xy 396.813022 -288.554339) (xy 396.851143 -288.523214) (xy 396.893764 -288.498607) (xy 396.93978 -288.481155)
			(xy 396.987999 -288.471311) (xy 397.037174 -288.46933) (xy 397.086029 -288.475262) (xy 397.1333 -288.488954)
			(xy 397.177762 -288.510052) (xy 397.218265 -288.538008) (xy 397.253758 -288.5721) (xy 397.283323 -288.611444)
			(xy 397.306194 -288.655021) (xy 397.321778 -288.701702) (xy 397.329673 -288.750279) (xy 397.330168 -288.774886)
			(xy 397.669016 -288.774886) (xy 397.672976 -288.725832) (xy 397.684753 -288.678048) (xy 397.704044 -288.632772)
			(xy 397.730347 -288.591176) (xy 397.762982 -288.554339) (xy 397.801103 -288.523214) (xy 397.843724 -288.498607)
			(xy 397.88974 -288.481155) (xy 397.937959 -288.471311) (xy 397.987134 -288.46933) (xy 398.035989 -288.475262)
			(xy 398.08326 -288.488954) (xy 398.127722 -288.510052) (xy 398.168225 -288.538008) (xy 398.203718 -288.5721)
			(xy 398.233283 -288.611444) (xy 398.256154 -288.655021) (xy 398.271738 -288.701702) (xy 398.279633 -288.750279)
			(xy 398.280128 -288.774886) (xy 398.61923 -288.774886) (xy 398.62319 -288.725832) (xy 398.634967 -288.678048)
			(xy 398.654258 -288.632772) (xy 398.680561 -288.591176) (xy 398.713196 -288.554339) (xy 398.751317 -288.523214)
			(xy 398.793938 -288.498607) (xy 398.839954 -288.481155) (xy 398.888173 -288.471311) (xy 398.937348 -288.46933)
			(xy 398.986203 -288.475262) (xy 399.033474 -288.488954) (xy 399.077936 -288.510052) (xy 399.118439 -288.538008)
			(xy 399.153932 -288.5721) (xy 399.183497 -288.611444) (xy 399.206368 -288.655021) (xy 399.221952 -288.701702)
			(xy 399.229847 -288.750279) (xy 399.230342 -288.774886) (xy 399.56919 -288.774886) (xy 399.57315 -288.725832)
			(xy 399.584927 -288.678048) (xy 399.604218 -288.632772) (xy 399.630521 -288.591176) (xy 399.663156 -288.554339)
			(xy 399.701277 -288.523214) (xy 399.743898 -288.498607) (xy 399.789914 -288.481155) (xy 399.838133 -288.471311)
			(xy 399.887308 -288.46933) (xy 399.936163 -288.475262) (xy 399.983434 -288.488954) (xy 400.027896 -288.510052)
			(xy 400.068399 -288.538008) (xy 400.103892 -288.5721) (xy 400.133457 -288.611444) (xy 400.156328 -288.655021)
			(xy 400.171912 -288.701702) (xy 400.179807 -288.750279) (xy 400.180302 -288.774886) (xy 400.51915 -288.774886)
			(xy 400.52311 -288.725832) (xy 400.534887 -288.678048) (xy 400.554178 -288.632772) (xy 400.580481 -288.591176)
			(xy 400.613116 -288.554339) (xy 400.651237 -288.523214) (xy 400.693858 -288.498607) (xy 400.739874 -288.481155)
			(xy 400.788093 -288.471311) (xy 400.837268 -288.46933) (xy 400.886123 -288.475262) (xy 400.933394 -288.488954)
			(xy 400.977856 -288.510052) (xy 401.018359 -288.538008) (xy 401.053852 -288.5721) (xy 401.083417 -288.611444)
			(xy 401.106288 -288.655021) (xy 401.121872 -288.701702) (xy 401.129767 -288.750279) (xy 401.130262 -288.774886)
			(xy 401.46911 -288.774886) (xy 401.47307 -288.725832) (xy 401.484847 -288.678048) (xy 401.504138 -288.632772)
			(xy 401.530441 -288.591176) (xy 401.563076 -288.554339) (xy 401.601197 -288.523214) (xy 401.643818 -288.498607)
			(xy 401.689834 -288.481155) (xy 401.738053 -288.471311) (xy 401.787228 -288.46933) (xy 401.836083 -288.475262)
			(xy 401.883354 -288.488954) (xy 401.927816 -288.510052) (xy 401.968319 -288.538008) (xy 402.003812 -288.5721)
			(xy 402.033377 -288.611444) (xy 402.056248 -288.655021) (xy 402.071832 -288.701702) (xy 402.079727 -288.750279)
			(xy 402.080222 -288.774886) (xy 402.41907 -288.774886) (xy 402.42303 -288.725832) (xy 402.434807 -288.678048)
			(xy 402.454098 -288.632772) (xy 402.480401 -288.591176) (xy 402.513036 -288.554339) (xy 402.551157 -288.523214)
			(xy 402.593778 -288.498607) (xy 402.639794 -288.481155) (xy 402.688013 -288.471311) (xy 402.737188 -288.46933)
			(xy 402.786043 -288.475262) (xy 402.833314 -288.488954) (xy 402.877776 -288.510052) (xy 402.918279 -288.538008)
			(xy 402.953772 -288.5721) (xy 402.983337 -288.611444) (xy 403.006208 -288.655021) (xy 403.021792 -288.701702)
			(xy 403.029687 -288.750279) (xy 403.030182 -288.774886) (xy 403.36903 -288.774886) (xy 403.37299 -288.725832)
			(xy 403.384767 -288.678048) (xy 403.404058 -288.632772) (xy 403.430361 -288.591176) (xy 403.462996 -288.554339)
			(xy 403.501117 -288.523214) (xy 403.543738 -288.498607) (xy 403.589754 -288.481155) (xy 403.637973 -288.471311)
			(xy 403.687148 -288.46933) (xy 403.736003 -288.475262) (xy 403.783274 -288.488954) (xy 403.827736 -288.510052)
			(xy 403.868239 -288.538008) (xy 403.903732 -288.5721) (xy 403.933297 -288.611444) (xy 403.956168 -288.655021)
			(xy 403.971752 -288.701702) (xy 403.979647 -288.750279) (xy 403.980142 -288.774886) (xy 404.31899 -288.774886)
			(xy 404.32295 -288.725832) (xy 404.334727 -288.678048) (xy 404.354018 -288.632772) (xy 404.380321 -288.591176)
			(xy 404.412956 -288.554339) (xy 404.451077 -288.523214) (xy 404.493698 -288.498607) (xy 404.539714 -288.481155)
			(xy 404.587933 -288.471311) (xy 404.637108 -288.46933) (xy 404.685963 -288.475262) (xy 404.733234 -288.488954)
			(xy 404.777696 -288.510052) (xy 404.818199 -288.538008) (xy 404.853692 -288.5721) (xy 404.883257 -288.611444)
			(xy 404.906128 -288.655021) (xy 404.921712 -288.701702) (xy 404.929607 -288.750279) (xy 404.930102 -288.774886)
			(xy 405.269204 -288.774886) (xy 405.273164 -288.725832) (xy 405.284941 -288.678048) (xy 405.304232 -288.632772)
			(xy 405.330535 -288.591176) (xy 405.36317 -288.554339) (xy 405.401291 -288.523214) (xy 405.443912 -288.498607)
			(xy 405.489928 -288.481155) (xy 405.538147 -288.471311) (xy 405.587322 -288.46933) (xy 405.636177 -288.475262)
			(xy 405.683448 -288.488954) (xy 405.72791 -288.510052) (xy 405.768413 -288.538008) (xy 405.803906 -288.5721)
			(xy 405.833471 -288.611444) (xy 405.856342 -288.655021) (xy 405.871926 -288.701702) (xy 405.879821 -288.750279)
			(xy 405.880316 -288.774886) (xy 406.219164 -288.774886) (xy 406.223124 -288.725832) (xy 406.234901 -288.678048)
			(xy 406.254192 -288.632772) (xy 406.280495 -288.591176) (xy 406.31313 -288.554339) (xy 406.351251 -288.523214)
			(xy 406.393872 -288.498607) (xy 406.439888 -288.481155) (xy 406.488107 -288.471311) (xy 406.537282 -288.46933)
			(xy 406.586137 -288.475262) (xy 406.633408 -288.488954) (xy 406.67787 -288.510052) (xy 406.718373 -288.538008)
			(xy 406.753866 -288.5721) (xy 406.783431 -288.611444) (xy 406.806302 -288.655021) (xy 406.821886 -288.701702)
			(xy 406.829781 -288.750279) (xy 406.830276 -288.774886) (xy 408.119084 -288.774886) (xy 408.123044 -288.725832)
			(xy 408.134821 -288.678048) (xy 408.154112 -288.632772) (xy 408.180415 -288.591176) (xy 408.21305 -288.554339)
			(xy 408.251171 -288.523214) (xy 408.293792 -288.498607) (xy 408.339808 -288.481155) (xy 408.388027 -288.471311)
			(xy 408.437202 -288.46933) (xy 408.486057 -288.475262) (xy 408.533328 -288.488954) (xy 408.57779 -288.510052)
			(xy 408.618293 -288.538008) (xy 408.653786 -288.5721) (xy 408.683351 -288.611444) (xy 408.706222 -288.655021)
			(xy 408.721806 -288.701702) (xy 408.729701 -288.750279) (xy 408.730196 -288.774886) (xy 409.069044 -288.774886)
			(xy 409.073004 -288.725832) (xy 409.084781 -288.678048) (xy 409.104072 -288.632772) (xy 409.130375 -288.591176)
			(xy 409.16301 -288.554339) (xy 409.201131 -288.523214) (xy 409.243752 -288.498607) (xy 409.289768 -288.481155)
			(xy 409.337987 -288.471311) (xy 409.387162 -288.46933) (xy 409.436017 -288.475262) (xy 409.483288 -288.488954)
			(xy 409.52775 -288.510052) (xy 409.568253 -288.538008) (xy 409.603746 -288.5721) (xy 409.633311 -288.611444)
			(xy 409.656182 -288.655021) (xy 409.671766 -288.701702) (xy 409.679661 -288.750279) (xy 409.680156 -288.774886)
			(xy 410.019004 -288.774886) (xy 410.022964 -288.725832) (xy 410.034741 -288.678048) (xy 410.054032 -288.632772)
			(xy 410.080335 -288.591176) (xy 410.11297 -288.554339) (xy 410.151091 -288.523214) (xy 410.193712 -288.498607)
			(xy 410.239728 -288.481155) (xy 410.287947 -288.471311) (xy 410.337122 -288.46933) (xy 410.385977 -288.475262)
			(xy 410.433248 -288.488954) (xy 410.47771 -288.510052) (xy 410.518213 -288.538008) (xy 410.553706 -288.5721)
			(xy 410.583271 -288.611444) (xy 410.606142 -288.655021) (xy 410.621726 -288.701702) (xy 410.629621 -288.750279)
			(xy 410.630116 -288.774886) (xy 410.969218 -288.774886) (xy 410.973178 -288.725832) (xy 410.984955 -288.678048)
			(xy 411.004246 -288.632772) (xy 411.030549 -288.591176) (xy 411.063184 -288.554339) (xy 411.101305 -288.523214)
			(xy 411.143926 -288.498607) (xy 411.189942 -288.481155) (xy 411.238161 -288.471311) (xy 411.287336 -288.46933)
			(xy 411.336191 -288.475262) (xy 411.383462 -288.488954) (xy 411.427924 -288.510052) (xy 411.468427 -288.538008)
			(xy 411.50392 -288.5721) (xy 411.533485 -288.611444) (xy 411.556356 -288.655021) (xy 411.57194 -288.701702)
			(xy 411.579835 -288.750279) (xy 411.58033 -288.774886) (xy 411.919178 -288.774886) (xy 411.923138 -288.725832)
			(xy 411.934915 -288.678048) (xy 411.954206 -288.632772) (xy 411.980509 -288.591176) (xy 412.013144 -288.554339)
			(xy 412.051265 -288.523214) (xy 412.093886 -288.498607) (xy 412.139902 -288.481155) (xy 412.188121 -288.471311)
			(xy 412.237296 -288.46933) (xy 412.286151 -288.475262) (xy 412.333422 -288.488954) (xy 412.377884 -288.510052)
			(xy 412.418387 -288.538008) (xy 412.45388 -288.5721) (xy 412.483445 -288.611444) (xy 412.506316 -288.655021)
			(xy 412.5219 -288.701702) (xy 412.529795 -288.750279) (xy 412.53029 -288.774886) (xy 412.869138 -288.774886)
			(xy 412.873098 -288.725832) (xy 412.884875 -288.678048) (xy 412.904166 -288.632772) (xy 412.930469 -288.591176)
			(xy 412.963104 -288.554339) (xy 413.001225 -288.523214) (xy 413.043846 -288.498607) (xy 413.089862 -288.481155)
			(xy 413.138081 -288.471311) (xy 413.187256 -288.46933) (xy 413.236111 -288.475262) (xy 413.283382 -288.488954)
			(xy 413.327844 -288.510052) (xy 413.368347 -288.538008) (xy 413.40384 -288.5721) (xy 413.433405 -288.611444)
			(xy 413.456276 -288.655021) (xy 413.47186 -288.701702) (xy 413.479755 -288.750279) (xy 413.48025 -288.774886)
			(xy 413.819098 -288.774886) (xy 413.823058 -288.725832) (xy 413.834835 -288.678048) (xy 413.854126 -288.632772)
			(xy 413.880429 -288.591176) (xy 413.913064 -288.554339) (xy 413.951185 -288.523214) (xy 413.993806 -288.498607)
			(xy 414.039822 -288.481155) (xy 414.088041 -288.471311) (xy 414.137216 -288.46933) (xy 414.186071 -288.475262)
			(xy 414.233342 -288.488954) (xy 414.277804 -288.510052) (xy 414.318307 -288.538008) (xy 414.3538 -288.5721)
			(xy 414.383365 -288.611444) (xy 414.406236 -288.655021) (xy 414.42182 -288.701702) (xy 414.429715 -288.750279)
			(xy 414.43021 -288.774886) (xy 414.769058 -288.774886) (xy 414.773018 -288.725832) (xy 414.784795 -288.678048)
			(xy 414.804086 -288.632772) (xy 414.830389 -288.591176) (xy 414.863024 -288.554339) (xy 414.901145 -288.523214)
			(xy 414.943766 -288.498607) (xy 414.989782 -288.481155) (xy 415.038001 -288.471311) (xy 415.087176 -288.46933)
			(xy 415.136031 -288.475262) (xy 415.183302 -288.488954) (xy 415.227764 -288.510052) (xy 415.268267 -288.538008)
			(xy 415.30376 -288.5721) (xy 415.333325 -288.611444) (xy 415.356196 -288.655021) (xy 415.37178 -288.701702)
			(xy 415.379675 -288.750279) (xy 415.38017 -288.774886) (xy 415.719018 -288.774886) (xy 415.722978 -288.725832)
			(xy 415.734755 -288.678048) (xy 415.754046 -288.632772) (xy 415.780349 -288.591176) (xy 415.812984 -288.554339)
			(xy 415.851105 -288.523214) (xy 415.893726 -288.498607) (xy 415.939742 -288.481155) (xy 415.987961 -288.471311)
			(xy 416.037136 -288.46933) (xy 416.085991 -288.475262) (xy 416.133262 -288.488954) (xy 416.177724 -288.510052)
			(xy 416.218227 -288.538008) (xy 416.25372 -288.5721) (xy 416.283285 -288.611444) (xy 416.306156 -288.655021)
			(xy 416.32174 -288.701702) (xy 416.329635 -288.750279) (xy 416.33013 -288.774886) (xy 416.329635 -288.799493)
			(xy 416.32174 -288.84807) (xy 416.306156 -288.894751) (xy 416.283285 -288.938328) (xy 416.25372 -288.977672)
			(xy 416.218227 -289.011764) (xy 416.177724 -289.03972) (xy 416.133262 -289.060818) (xy 416.085991 -289.07451)
			(xy 416.037136 -289.080442) (xy 415.987961 -289.078461) (xy 415.939742 -289.068617) (xy 415.893726 -289.051165)
			(xy 415.851105 -289.026558) (xy 415.812984 -288.995433) (xy 415.780349 -288.958596) (xy 415.754046 -288.917)
			(xy 415.734755 -288.871724) (xy 415.722978 -288.82394) (xy 415.719018 -288.774886) (xy 415.38017 -288.774886)
			(xy 415.379675 -288.799493) (xy 415.37178 -288.84807) (xy 415.356196 -288.894751) (xy 415.333325 -288.938328)
			(xy 415.30376 -288.977672) (xy 415.268267 -289.011764) (xy 415.227764 -289.03972) (xy 415.183302 -289.060818)
			(xy 415.136031 -289.07451) (xy 415.087176 -289.080442) (xy 415.038001 -289.078461) (xy 414.989782 -289.068617)
			(xy 414.943766 -289.051165) (xy 414.901145 -289.026558) (xy 414.863024 -288.995433) (xy 414.830389 -288.958596)
			(xy 414.804086 -288.917) (xy 414.784795 -288.871724) (xy 414.773018 -288.82394) (xy 414.769058 -288.774886)
			(xy 414.43021 -288.774886) (xy 414.429715 -288.799493) (xy 414.42182 -288.84807) (xy 414.406236 -288.894751)
			(xy 414.383365 -288.938328) (xy 414.3538 -288.977672) (xy 414.318307 -289.011764) (xy 414.277804 -289.03972)
			(xy 414.233342 -289.060818) (xy 414.186071 -289.07451) (xy 414.137216 -289.080442) (xy 414.088041 -289.078461)
			(xy 414.039822 -289.068617) (xy 413.993806 -289.051165) (xy 413.951185 -289.026558) (xy 413.913064 -288.995433)
			(xy 413.880429 -288.958596) (xy 413.854126 -288.917) (xy 413.834835 -288.871724) (xy 413.823058 -288.82394)
			(xy 413.819098 -288.774886) (xy 413.48025 -288.774886) (xy 413.479755 -288.799493) (xy 413.47186 -288.84807)
			(xy 413.456276 -288.894751) (xy 413.433405 -288.938328) (xy 413.40384 -288.977672) (xy 413.368347 -289.011764)
			(xy 413.327844 -289.03972) (xy 413.283382 -289.060818) (xy 413.236111 -289.07451) (xy 413.187256 -289.080442)
			(xy 413.138081 -289.078461) (xy 413.089862 -289.068617) (xy 413.043846 -289.051165) (xy 413.001225 -289.026558)
			(xy 412.963104 -288.995433) (xy 412.930469 -288.958596) (xy 412.904166 -288.917) (xy 412.884875 -288.871724)
			(xy 412.873098 -288.82394) (xy 412.869138 -288.774886) (xy 412.53029 -288.774886) (xy 412.529795 -288.799493)
			(xy 412.5219 -288.84807) (xy 412.506316 -288.894751) (xy 412.483445 -288.938328) (xy 412.45388 -288.977672)
			(xy 412.418387 -289.011764) (xy 412.377884 -289.03972) (xy 412.333422 -289.060818) (xy 412.286151 -289.07451)
			(xy 412.237296 -289.080442) (xy 412.188121 -289.078461) (xy 412.139902 -289.068617) (xy 412.093886 -289.051165)
			(xy 412.051265 -289.026558) (xy 412.013144 -288.995433) (xy 411.980509 -288.958596) (xy 411.954206 -288.917)
			(xy 411.934915 -288.871724) (xy 411.923138 -288.82394) (xy 411.919178 -288.774886) (xy 411.58033 -288.774886)
			(xy 411.579835 -288.799493) (xy 411.57194 -288.84807) (xy 411.556356 -288.894751) (xy 411.533485 -288.938328)
			(xy 411.50392 -288.977672) (xy 411.468427 -289.011764) (xy 411.427924 -289.03972) (xy 411.383462 -289.060818)
			(xy 411.336191 -289.07451) (xy 411.287336 -289.080442) (xy 411.238161 -289.078461) (xy 411.189942 -289.068617)
			(xy 411.143926 -289.051165) (xy 411.101305 -289.026558) (xy 411.063184 -288.995433) (xy 411.030549 -288.958596)
			(xy 411.004246 -288.917) (xy 410.984955 -288.871724) (xy 410.973178 -288.82394) (xy 410.969218 -288.774886)
			(xy 410.630116 -288.774886) (xy 410.629621 -288.799493) (xy 410.621726 -288.84807) (xy 410.606142 -288.894751)
			(xy 410.583271 -288.938328) (xy 410.553706 -288.977672) (xy 410.518213 -289.011764) (xy 410.47771 -289.03972)
			(xy 410.433248 -289.060818) (xy 410.385977 -289.07451) (xy 410.337122 -289.080442) (xy 410.287947 -289.078461)
			(xy 410.239728 -289.068617) (xy 410.193712 -289.051165) (xy 410.151091 -289.026558) (xy 410.11297 -288.995433)
			(xy 410.080335 -288.958596) (xy 410.054032 -288.917) (xy 410.034741 -288.871724) (xy 410.022964 -288.82394)
			(xy 410.019004 -288.774886) (xy 409.680156 -288.774886) (xy 409.679661 -288.799493) (xy 409.671766 -288.84807)
			(xy 409.656182 -288.894751) (xy 409.633311 -288.938328) (xy 409.603746 -288.977672) (xy 409.568253 -289.011764)
			(xy 409.52775 -289.03972) (xy 409.483288 -289.060818) (xy 409.436017 -289.07451) (xy 409.387162 -289.080442)
			(xy 409.337987 -289.078461) (xy 409.289768 -289.068617) (xy 409.243752 -289.051165) (xy 409.201131 -289.026558)
			(xy 409.16301 -288.995433) (xy 409.130375 -288.958596) (xy 409.104072 -288.917) (xy 409.084781 -288.871724)
			(xy 409.073004 -288.82394) (xy 409.069044 -288.774886) (xy 408.730196 -288.774886) (xy 408.729701 -288.799493)
			(xy 408.721806 -288.84807) (xy 408.706222 -288.894751) (xy 408.683351 -288.938328) (xy 408.653786 -288.977672)
			(xy 408.618293 -289.011764) (xy 408.57779 -289.03972) (xy 408.533328 -289.060818) (xy 408.486057 -289.07451)
			(xy 408.437202 -289.080442) (xy 408.388027 -289.078461) (xy 408.339808 -289.068617) (xy 408.293792 -289.051165)
			(xy 408.251171 -289.026558) (xy 408.21305 -288.995433) (xy 408.180415 -288.958596) (xy 408.154112 -288.917)
			(xy 408.134821 -288.871724) (xy 408.123044 -288.82394) (xy 408.119084 -288.774886) (xy 406.830276 -288.774886)
			(xy 406.829781 -288.799493) (xy 406.821886 -288.84807) (xy 406.806302 -288.894751) (xy 406.783431 -288.938328)
			(xy 406.753866 -288.977672) (xy 406.718373 -289.011764) (xy 406.67787 -289.03972) (xy 406.633408 -289.060818)
			(xy 406.586137 -289.07451) (xy 406.537282 -289.080442) (xy 406.488107 -289.078461) (xy 406.439888 -289.068617)
			(xy 406.393872 -289.051165) (xy 406.351251 -289.026558) (xy 406.31313 -288.995433) (xy 406.280495 -288.958596)
			(xy 406.254192 -288.917) (xy 406.234901 -288.871724) (xy 406.223124 -288.82394) (xy 406.219164 -288.774886)
			(xy 405.880316 -288.774886) (xy 405.879821 -288.799493) (xy 405.871926 -288.84807) (xy 405.856342 -288.894751)
			(xy 405.833471 -288.938328) (xy 405.803906 -288.977672) (xy 405.768413 -289.011764) (xy 405.72791 -289.03972)
			(xy 405.683448 -289.060818) (xy 405.636177 -289.07451) (xy 405.587322 -289.080442) (xy 405.538147 -289.078461)
			(xy 405.489928 -289.068617) (xy 405.443912 -289.051165) (xy 405.401291 -289.026558) (xy 405.36317 -288.995433)
			(xy 405.330535 -288.958596) (xy 405.304232 -288.917) (xy 405.284941 -288.871724) (xy 405.273164 -288.82394)
			(xy 405.269204 -288.774886) (xy 404.930102 -288.774886) (xy 404.929607 -288.799493) (xy 404.921712 -288.84807)
			(xy 404.906128 -288.894751) (xy 404.883257 -288.938328) (xy 404.853692 -288.977672) (xy 404.818199 -289.011764)
			(xy 404.777696 -289.03972) (xy 404.733234 -289.060818) (xy 404.685963 -289.07451) (xy 404.637108 -289.080442)
			(xy 404.587933 -289.078461) (xy 404.539714 -289.068617) (xy 404.493698 -289.051165) (xy 404.451077 -289.026558)
			(xy 404.412956 -288.995433) (xy 404.380321 -288.958596) (xy 404.354018 -288.917) (xy 404.334727 -288.871724)
			(xy 404.32295 -288.82394) (xy 404.31899 -288.774886) (xy 403.980142 -288.774886) (xy 403.979647 -288.799493)
			(xy 403.971752 -288.84807) (xy 403.956168 -288.894751) (xy 403.933297 -288.938328) (xy 403.903732 -288.977672)
			(xy 403.868239 -289.011764) (xy 403.827736 -289.03972) (xy 403.783274 -289.060818) (xy 403.736003 -289.07451)
			(xy 403.687148 -289.080442) (xy 403.637973 -289.078461) (xy 403.589754 -289.068617) (xy 403.543738 -289.051165)
			(xy 403.501117 -289.026558) (xy 403.462996 -288.995433) (xy 403.430361 -288.958596) (xy 403.404058 -288.917)
			(xy 403.384767 -288.871724) (xy 403.37299 -288.82394) (xy 403.36903 -288.774886) (xy 403.030182 -288.774886)
			(xy 403.029687 -288.799493) (xy 403.021792 -288.84807) (xy 403.006208 -288.894751) (xy 402.983337 -288.938328)
			(xy 402.953772 -288.977672) (xy 402.918279 -289.011764) (xy 402.877776 -289.03972) (xy 402.833314 -289.060818)
			(xy 402.786043 -289.07451) (xy 402.737188 -289.080442) (xy 402.688013 -289.078461) (xy 402.639794 -289.068617)
			(xy 402.593778 -289.051165) (xy 402.551157 -289.026558) (xy 402.513036 -288.995433) (xy 402.480401 -288.958596)
			(xy 402.454098 -288.917) (xy 402.434807 -288.871724) (xy 402.42303 -288.82394) (xy 402.41907 -288.774886)
			(xy 402.080222 -288.774886) (xy 402.079727 -288.799493) (xy 402.071832 -288.84807) (xy 402.056248 -288.894751)
			(xy 402.033377 -288.938328) (xy 402.003812 -288.977672) (xy 401.968319 -289.011764) (xy 401.927816 -289.03972)
			(xy 401.883354 -289.060818) (xy 401.836083 -289.07451) (xy 401.787228 -289.080442) (xy 401.738053 -289.078461)
			(xy 401.689834 -289.068617) (xy 401.643818 -289.051165) (xy 401.601197 -289.026558) (xy 401.563076 -288.995433)
			(xy 401.530441 -288.958596) (xy 401.504138 -288.917) (xy 401.484847 -288.871724) (xy 401.47307 -288.82394)
			(xy 401.46911 -288.774886) (xy 401.130262 -288.774886) (xy 401.129767 -288.799493) (xy 401.121872 -288.84807)
			(xy 401.106288 -288.894751) (xy 401.083417 -288.938328) (xy 401.053852 -288.977672) (xy 401.018359 -289.011764)
			(xy 400.977856 -289.03972) (xy 400.933394 -289.060818) (xy 400.886123 -289.07451) (xy 400.837268 -289.080442)
			(xy 400.788093 -289.078461) (xy 400.739874 -289.068617) (xy 400.693858 -289.051165) (xy 400.651237 -289.026558)
			(xy 400.613116 -288.995433) (xy 400.580481 -288.958596) (xy 400.554178 -288.917) (xy 400.534887 -288.871724)
			(xy 400.52311 -288.82394) (xy 400.51915 -288.774886) (xy 400.180302 -288.774886) (xy 400.179807 -288.799493)
			(xy 400.171912 -288.84807) (xy 400.156328 -288.894751) (xy 400.133457 -288.938328) (xy 400.103892 -288.977672)
			(xy 400.068399 -289.011764) (xy 400.027896 -289.03972) (xy 399.983434 -289.060818) (xy 399.936163 -289.07451)
			(xy 399.887308 -289.080442) (xy 399.838133 -289.078461) (xy 399.789914 -289.068617) (xy 399.743898 -289.051165)
			(xy 399.701277 -289.026558) (xy 399.663156 -288.995433) (xy 399.630521 -288.958596) (xy 399.604218 -288.917)
			(xy 399.584927 -288.871724) (xy 399.57315 -288.82394) (xy 399.56919 -288.774886) (xy 399.230342 -288.774886)
			(xy 399.229847 -288.799493) (xy 399.221952 -288.84807) (xy 399.206368 -288.894751) (xy 399.183497 -288.938328)
			(xy 399.153932 -288.977672) (xy 399.118439 -289.011764) (xy 399.077936 -289.03972) (xy 399.033474 -289.060818)
			(xy 398.986203 -289.07451) (xy 398.937348 -289.080442) (xy 398.888173 -289.078461) (xy 398.839954 -289.068617)
			(xy 398.793938 -289.051165) (xy 398.751317 -289.026558) (xy 398.713196 -288.995433) (xy 398.680561 -288.958596)
			(xy 398.654258 -288.917) (xy 398.634967 -288.871724) (xy 398.62319 -288.82394) (xy 398.61923 -288.774886)
			(xy 398.280128 -288.774886) (xy 398.279633 -288.799493) (xy 398.271738 -288.84807) (xy 398.256154 -288.894751)
			(xy 398.233283 -288.938328) (xy 398.203718 -288.977672) (xy 398.168225 -289.011764) (xy 398.127722 -289.03972)
			(xy 398.08326 -289.060818) (xy 398.035989 -289.07451) (xy 397.987134 -289.080442) (xy 397.937959 -289.078461)
			(xy 397.88974 -289.068617) (xy 397.843724 -289.051165) (xy 397.801103 -289.026558) (xy 397.762982 -288.995433)
			(xy 397.730347 -288.958596) (xy 397.704044 -288.917) (xy 397.684753 -288.871724) (xy 397.672976 -288.82394)
			(xy 397.669016 -288.774886) (xy 397.330168 -288.774886) (xy 397.329673 -288.799493) (xy 397.321778 -288.84807)
			(xy 397.306194 -288.894751) (xy 397.283323 -288.938328) (xy 397.253758 -288.977672) (xy 397.218265 -289.011764)
			(xy 397.177762 -289.03972) (xy 397.1333 -289.060818) (xy 397.086029 -289.07451) (xy 397.037174 -289.080442)
			(xy 396.987999 -289.078461) (xy 396.93978 -289.068617) (xy 396.893764 -289.051165) (xy 396.851143 -289.026558)
			(xy 396.813022 -288.995433) (xy 396.780387 -288.958596) (xy 396.754084 -288.917) (xy 396.734793 -288.871724)
			(xy 396.723016 -288.82394) (xy 396.719056 -288.774886) (xy 396.380208 -288.774886) (xy 396.379713 -288.799493)
			(xy 396.371818 -288.84807) (xy 396.356234 -288.894751) (xy 396.333363 -288.938328) (xy 396.303798 -288.977672)
			(xy 396.268305 -289.011764) (xy 396.227802 -289.03972) (xy 396.18334 -289.060818) (xy 396.136069 -289.07451)
			(xy 396.087214 -289.080442) (xy 396.038039 -289.078461) (xy 395.98982 -289.068617) (xy 395.943804 -289.051165)
			(xy 395.901183 -289.026558) (xy 395.863062 -288.995433) (xy 395.830427 -288.958596) (xy 395.804124 -288.917)
			(xy 395.784833 -288.871724) (xy 395.773056 -288.82394) (xy 395.769096 -288.774886) (xy 395.430248 -288.774886)
			(xy 395.429753 -288.799493) (xy 395.421858 -288.84807) (xy 395.406274 -288.894751) (xy 395.383403 -288.938328)
			(xy 395.353838 -288.977672) (xy 395.318345 -289.011764) (xy 395.277842 -289.03972) (xy 395.23338 -289.060818)
			(xy 395.186109 -289.07451) (xy 395.137254 -289.080442) (xy 395.088079 -289.078461) (xy 395.03986 -289.068617)
			(xy 394.993844 -289.051165) (xy 394.951223 -289.026558) (xy 394.913102 -288.995433) (xy 394.880467 -288.958596)
			(xy 394.854164 -288.917) (xy 394.834873 -288.871724) (xy 394.823096 -288.82394) (xy 394.819136 -288.774886)
			(xy 394.480288 -288.774886) (xy 394.479793 -288.799493) (xy 394.471898 -288.84807) (xy 394.456314 -288.894751)
			(xy 394.433443 -288.938328) (xy 394.403878 -288.977672) (xy 394.368385 -289.011764) (xy 394.327882 -289.03972)
			(xy 394.28342 -289.060818) (xy 394.236149 -289.07451) (xy 394.187294 -289.080442) (xy 394.138119 -289.078461)
			(xy 394.0899 -289.068617) (xy 394.043884 -289.051165) (xy 394.001263 -289.026558) (xy 393.963142 -288.995433)
			(xy 393.930507 -288.958596) (xy 393.904204 -288.917) (xy 393.884913 -288.871724) (xy 393.873136 -288.82394)
			(xy 393.869176 -288.774886) (xy 393.530328 -288.774886) (xy 393.529833 -288.799493) (xy 393.521938 -288.84807)
			(xy 393.506354 -288.894751) (xy 393.483483 -288.938328) (xy 393.453918 -288.977672) (xy 393.418425 -289.011764)
			(xy 393.377922 -289.03972) (xy 393.33346 -289.060818) (xy 393.286189 -289.07451) (xy 393.237334 -289.080442)
			(xy 393.188159 -289.078461) (xy 393.13994 -289.068617) (xy 393.093924 -289.051165) (xy 393.051303 -289.026558)
			(xy 393.013182 -288.995433) (xy 392.980547 -288.958596) (xy 392.954244 -288.917) (xy 392.934953 -288.871724)
			(xy 392.923176 -288.82394) (xy 392.919216 -288.774886) (xy 392.580114 -288.774886) (xy 392.579619 -288.799493)
			(xy 392.571724 -288.84807) (xy 392.55614 -288.894751) (xy 392.533269 -288.938328) (xy 392.503704 -288.977672)
			(xy 392.468211 -289.011764) (xy 392.427708 -289.03972) (xy 392.383246 -289.060818) (xy 392.335975 -289.07451)
			(xy 392.28712 -289.080442) (xy 392.237945 -289.078461) (xy 392.189726 -289.068617) (xy 392.14371 -289.051165)
			(xy 392.101089 -289.026558) (xy 392.062968 -288.995433) (xy 392.030333 -288.958596) (xy 392.00403 -288.917)
			(xy 391.984739 -288.871724) (xy 391.972962 -288.82394) (xy 391.969002 -288.774886) (xy 391.630154 -288.774886)
			(xy 391.629659 -288.799493) (xy 391.621764 -288.84807) (xy 391.60618 -288.894751) (xy 391.583309 -288.938328)
			(xy 391.553744 -288.977672) (xy 391.518251 -289.011764) (xy 391.477748 -289.03972) (xy 391.433286 -289.060818)
			(xy 391.386015 -289.07451) (xy 391.33716 -289.080442) (xy 391.287985 -289.078461) (xy 391.239766 -289.068617)
			(xy 391.19375 -289.051165) (xy 391.151129 -289.026558) (xy 391.113008 -288.995433) (xy 391.080373 -288.958596)
			(xy 391.05407 -288.917) (xy 391.034779 -288.871724) (xy 391.023002 -288.82394) (xy 391.019042 -288.774886)
			(xy 386.880354 -288.774886) (xy 386.879859 -288.799493) (xy 386.871964 -288.84807) (xy 386.85638 -288.894751)
			(xy 386.833509 -288.938328) (xy 386.803944 -288.977672) (xy 386.768451 -289.011764) (xy 386.727948 -289.03972)
			(xy 386.683486 -289.060818) (xy 386.636215 -289.07451) (xy 386.58736 -289.080442) (xy 386.538185 -289.078461)
			(xy 386.489966 -289.068617) (xy 386.44395 -289.051165) (xy 386.401329 -289.026558) (xy 386.363208 -288.995433)
			(xy 386.330573 -288.958596) (xy 386.30427 -288.917) (xy 386.284979 -288.871724) (xy 386.273202 -288.82394)
			(xy 386.269242 -288.774886) (xy 385.93014 -288.774886) (xy 385.929645 -288.799493) (xy 385.92175 -288.84807)
			(xy 385.906166 -288.894751) (xy 385.883295 -288.938328) (xy 385.85373 -288.977672) (xy 385.818237 -289.011764)
			(xy 385.777734 -289.03972) (xy 385.733272 -289.060818) (xy 385.686001 -289.07451) (xy 385.637146 -289.080442)
			(xy 385.587971 -289.078461) (xy 385.539752 -289.068617) (xy 385.493736 -289.051165) (xy 385.451115 -289.026558)
			(xy 385.412994 -288.995433) (xy 385.380359 -288.958596) (xy 385.354056 -288.917) (xy 385.334765 -288.871724)
			(xy 385.322988 -288.82394) (xy 385.319028 -288.774886) (xy 384.98018 -288.774886) (xy 384.979685 -288.799493)
			(xy 384.97179 -288.84807) (xy 384.956206 -288.894751) (xy 384.933335 -288.938328) (xy 384.90377 -288.977672)
			(xy 384.868277 -289.011764) (xy 384.827774 -289.03972) (xy 384.783312 -289.060818) (xy 384.736041 -289.07451)
			(xy 384.687186 -289.080442) (xy 384.638011 -289.078461) (xy 384.589792 -289.068617) (xy 384.543776 -289.051165)
			(xy 384.501155 -289.026558) (xy 384.463034 -288.995433) (xy 384.430399 -288.958596) (xy 384.404096 -288.917)
			(xy 384.384805 -288.871724) (xy 384.373028 -288.82394) (xy 384.369068 -288.774886) (xy 368.55019 -288.774886)
			(xy 368.55019 -289.532314) (xy 374.111518 -289.532314) (xy 374.115589 -289.476692) (xy 374.127715 -289.422255)
			(xy 374.147638 -289.370164) (xy 374.174934 -289.321529) (xy 374.20902 -289.277386) (xy 374.249169 -289.238677)
			(xy 374.294527 -289.206226) (xy 374.344127 -289.180725) (xy 374.396911 -289.162718) (xy 374.451754 -289.152588)
			(xy 374.507488 -289.150551) (xy 374.562925 -289.156651) (xy 374.616882 -289.170757) (xy 374.668211 -289.192569)
			(xy 374.715817 -289.221623) (xy 374.758685 -289.257298) (xy 374.795902 -289.298835) (xy 374.826675 -289.345348)
			(xy 374.850347 -289.395845) (xy 374.866415 -289.449252) (xy 374.874535 -289.504428) (xy 374.875044 -289.532314)
			(xy 375.587004 -289.532314) (xy 375.591075 -289.476692) (xy 375.603201 -289.422255) (xy 375.623124 -289.370164)
			(xy 375.65042 -289.321529) (xy 375.684506 -289.277386) (xy 375.724655 -289.238677) (xy 375.770013 -289.206226)
			(xy 375.819613 -289.180725) (xy 375.872397 -289.162718) (xy 375.92724 -289.152588) (xy 375.982974 -289.150551)
			(xy 376.038411 -289.156651) (xy 376.092368 -289.170757) (xy 376.143697 -289.192569) (xy 376.191303 -289.221623)
			(xy 376.234171 -289.257298) (xy 376.271388 -289.298835) (xy 376.302161 -289.345348) (xy 376.325833 -289.395845)
			(xy 376.341901 -289.449252) (xy 376.350021 -289.504428) (xy 376.35053 -289.532314) (xy 376.476004 -289.532314)
			(xy 376.480075 -289.476692) (xy 376.492201 -289.422255) (xy 376.512124 -289.370164) (xy 376.53942 -289.321529)
			(xy 376.573506 -289.277386) (xy 376.613655 -289.238677) (xy 376.659013 -289.206226) (xy 376.708613 -289.180725)
			(xy 376.761397 -289.162718) (xy 376.81624 -289.152588) (xy 376.871974 -289.150551) (xy 376.927411 -289.156651)
			(xy 376.981368 -289.170757) (xy 377.032697 -289.192569) (xy 377.080303 -289.221623) (xy 377.123171 -289.257298)
			(xy 377.160388 -289.298835) (xy 377.191161 -289.345348) (xy 377.214833 -289.395845) (xy 377.230901 -289.449252)
			(xy 377.239021 -289.504428) (xy 377.23953 -289.532314) (xy 377.239021 -289.5602) (xy 377.230901 -289.615376)
			(xy 377.214833 -289.668783) (xy 377.191161 -289.71928) (xy 377.160388 -289.765793) (xy 377.123171 -289.80733)
			(xy 377.080303 -289.843005) (xy 377.032697 -289.872059) (xy 376.981368 -289.893871) (xy 376.927411 -289.907977)
			(xy 376.871974 -289.914077) (xy 376.81624 -289.91204) (xy 376.761397 -289.90191) (xy 376.708613 -289.883903)
			(xy 376.659013 -289.858402) (xy 376.613655 -289.825951) (xy 376.573506 -289.787242) (xy 376.53942 -289.743099)
			(xy 376.512124 -289.694464) (xy 376.492201 -289.642373) (xy 376.480075 -289.587936) (xy 376.476004 -289.532314)
			(xy 376.35053 -289.532314) (xy 376.350021 -289.5602) (xy 376.341901 -289.615376) (xy 376.325833 -289.668783)
			(xy 376.302161 -289.71928) (xy 376.271388 -289.765793) (xy 376.234171 -289.80733) (xy 376.191303 -289.843005)
			(xy 376.143697 -289.872059) (xy 376.092368 -289.893871) (xy 376.038411 -289.907977) (xy 375.982974 -289.914077)
			(xy 375.92724 -289.91204) (xy 375.872397 -289.90191) (xy 375.819613 -289.883903) (xy 375.770013 -289.858402)
			(xy 375.724655 -289.825951) (xy 375.684506 -289.787242) (xy 375.65042 -289.743099) (xy 375.623124 -289.694464)
			(xy 375.603201 -289.642373) (xy 375.591075 -289.587936) (xy 375.587004 -289.532314) (xy 374.875044 -289.532314)
			(xy 374.874535 -289.5602) (xy 374.866415 -289.615376) (xy 374.850347 -289.668783) (xy 374.826675 -289.71928)
			(xy 374.795902 -289.765793) (xy 374.758685 -289.80733) (xy 374.715817 -289.843005) (xy 374.668211 -289.872059)
			(xy 374.616882 -289.893871) (xy 374.562925 -289.907977) (xy 374.507488 -289.914077) (xy 374.451754 -289.91204)
			(xy 374.396911 -289.90191) (xy 374.344127 -289.883903) (xy 374.294527 -289.858402) (xy 374.249169 -289.825951)
			(xy 374.20902 -289.787242) (xy 374.174934 -289.743099) (xy 374.147638 -289.694464) (xy 374.127715 -289.642373)
			(xy 374.115589 -289.587936) (xy 374.111518 -289.532314) (xy 368.55019 -289.532314) (xy 368.55019 -290.294314)
			(xy 379.638052 -290.294314) (xy 379.638619 -290.264933) (xy 379.647646 -290.206868) (xy 379.665474 -290.150875)
			(xy 379.691681 -290.09828) (xy 379.725646 -290.050328) (xy 379.766565 -290.008154) (xy 379.78969 -289.990022)
			(xy 379.798622 -289.98255) (xy 379.809075 -289.961769) (xy 379.809756 -289.950144) (xy 379.811026 -289.858196)
			(xy 379.80112 -289.837114) (xy 379.791976 -289.829748) (xy 379.770116 -289.811556) (xy 379.731578 -289.769734)
			(xy 379.699673 -289.722655) (xy 379.675108 -289.671363) (xy 379.658427 -289.616993) (xy 379.65 -289.56075)
			(xy 379.649482 -289.532314) (xy 379.649968 -289.505063) (xy 379.657724 -289.451115) (xy 379.673079 -289.39882)
			(xy 379.695721 -289.349243) (xy 379.725187 -289.303393) (xy 379.760878 -289.262202) (xy 379.802069 -289.226511)
			(xy 379.847919 -289.197045) (xy 379.897496 -289.174403) (xy 379.949791 -289.159048) (xy 380.003739 -289.151292)
			(xy 380.058241 -289.151292) (xy 380.112189 -289.159048) (xy 380.164484 -289.174403) (xy 380.214061 -289.197045)
			(xy 380.259911 -289.226511) (xy 380.301102 -289.262202) (xy 380.336793 -289.303393) (xy 380.366259 -289.349243)
			(xy 380.388901 -289.39882) (xy 380.404256 -289.451115) (xy 380.412012 -289.505063) (xy 380.412498 -289.532314)
			(xy 380.411971 -289.561697) (xy 380.402938 -289.619764) (xy 380.385103 -289.675759) (xy 380.360637 -289.724846)
			(xy 384.369068 -289.724846) (xy 384.373028 -289.675792) (xy 384.384805 -289.628008) (xy 384.404096 -289.582732)
			(xy 384.430399 -289.541136) (xy 384.463034 -289.504299) (xy 384.501155 -289.473174) (xy 384.543776 -289.448567)
			(xy 384.589792 -289.431115) (xy 384.638011 -289.421271) (xy 384.687186 -289.41929) (xy 384.736041 -289.425222)
			(xy 384.783312 -289.438914) (xy 384.827774 -289.460012) (xy 384.868277 -289.487968) (xy 384.90377 -289.52206)
			(xy 384.933335 -289.561404) (xy 384.956206 -289.604981) (xy 384.97179 -289.651662) (xy 384.979685 -289.700239)
			(xy 384.98018 -289.724846) (xy 385.319028 -289.724846) (xy 385.322988 -289.675792) (xy 385.334765 -289.628008)
			(xy 385.354056 -289.582732) (xy 385.380359 -289.541136) (xy 385.412994 -289.504299) (xy 385.451115 -289.473174)
			(xy 385.493736 -289.448567) (xy 385.539752 -289.431115) (xy 385.587971 -289.421271) (xy 385.637146 -289.41929)
			(xy 385.686001 -289.425222) (xy 385.733272 -289.438914) (xy 385.777734 -289.460012) (xy 385.818237 -289.487968)
			(xy 385.85373 -289.52206) (xy 385.883295 -289.561404) (xy 385.906166 -289.604981) (xy 385.92175 -289.651662)
			(xy 385.929645 -289.700239) (xy 385.93014 -289.724846) (xy 386.269242 -289.724846) (xy 386.273202 -289.675792)
			(xy 386.284979 -289.628008) (xy 386.30427 -289.582732) (xy 386.330573 -289.541136) (xy 386.363208 -289.504299)
			(xy 386.401329 -289.473174) (xy 386.44395 -289.448567) (xy 386.489966 -289.431115) (xy 386.538185 -289.421271)
			(xy 386.58736 -289.41929) (xy 386.636215 -289.425222) (xy 386.683486 -289.438914) (xy 386.727948 -289.460012)
			(xy 386.768451 -289.487968) (xy 386.803944 -289.52206) (xy 386.833509 -289.561404) (xy 386.85638 -289.604981)
			(xy 386.871964 -289.651662) (xy 386.879859 -289.700239) (xy 386.880354 -289.724846) (xy 387.219202 -289.724846)
			(xy 387.223162 -289.675792) (xy 387.234939 -289.628008) (xy 387.25423 -289.582732) (xy 387.280533 -289.541136)
			(xy 387.313168 -289.504299) (xy 387.351289 -289.473174) (xy 387.39391 -289.448567) (xy 387.439926 -289.431115)
			(xy 387.488145 -289.421271) (xy 387.53732 -289.41929) (xy 387.586175 -289.425222) (xy 387.633446 -289.438914)
			(xy 387.677908 -289.460012) (xy 387.718411 -289.487968) (xy 387.753904 -289.52206) (xy 387.783469 -289.561404)
			(xy 387.80634 -289.604981) (xy 387.821924 -289.651662) (xy 387.829819 -289.700239) (xy 387.830314 -289.724846)
			(xy 388.169162 -289.724846) (xy 388.173122 -289.675792) (xy 388.184899 -289.628008) (xy 388.20419 -289.582732)
			(xy 388.230493 -289.541136) (xy 388.263128 -289.504299) (xy 388.301249 -289.473174) (xy 388.34387 -289.448567)
			(xy 388.389886 -289.431115) (xy 388.438105 -289.421271) (xy 388.48728 -289.41929) (xy 388.536135 -289.425222)
			(xy 388.583406 -289.438914) (xy 388.627868 -289.460012) (xy 388.668371 -289.487968) (xy 388.703864 -289.52206)
			(xy 388.733429 -289.561404) (xy 388.7563 -289.604981) (xy 388.771884 -289.651662) (xy 388.779779 -289.700239)
			(xy 388.780274 -289.724846) (xy 389.119122 -289.724846) (xy 389.123082 -289.675792) (xy 389.134859 -289.628008)
			(xy 389.15415 -289.582732) (xy 389.180453 -289.541136) (xy 389.213088 -289.504299) (xy 389.251209 -289.473174)
			(xy 389.29383 -289.448567) (xy 389.339846 -289.431115) (xy 389.388065 -289.421271) (xy 389.43724 -289.41929)
			(xy 389.486095 -289.425222) (xy 389.533366 -289.438914) (xy 389.577828 -289.460012) (xy 389.618331 -289.487968)
			(xy 389.653824 -289.52206) (xy 389.683389 -289.561404) (xy 389.70626 -289.604981) (xy 389.721844 -289.651662)
			(xy 389.729739 -289.700239) (xy 389.730234 -289.724846) (xy 390.069082 -289.724846) (xy 390.073042 -289.675792)
			(xy 390.084819 -289.628008) (xy 390.10411 -289.582732) (xy 390.130413 -289.541136) (xy 390.163048 -289.504299)
			(xy 390.201169 -289.473174) (xy 390.24379 -289.448567) (xy 390.289806 -289.431115) (xy 390.338025 -289.421271)
			(xy 390.3872 -289.41929) (xy 390.436055 -289.425222) (xy 390.483326 -289.438914) (xy 390.527788 -289.460012)
			(xy 390.568291 -289.487968) (xy 390.603784 -289.52206) (xy 390.633349 -289.561404) (xy 390.65622 -289.604981)
			(xy 390.671804 -289.651662) (xy 390.679699 -289.700239) (xy 390.680194 -289.724846) (xy 391.019042 -289.724846)
			(xy 391.023002 -289.675792) (xy 391.034779 -289.628008) (xy 391.05407 -289.582732) (xy 391.080373 -289.541136)
			(xy 391.113008 -289.504299) (xy 391.151129 -289.473174) (xy 391.19375 -289.448567) (xy 391.239766 -289.431115)
			(xy 391.287985 -289.421271) (xy 391.33716 -289.41929) (xy 391.386015 -289.425222) (xy 391.433286 -289.438914)
			(xy 391.477748 -289.460012) (xy 391.518251 -289.487968) (xy 391.553744 -289.52206) (xy 391.583309 -289.561404)
			(xy 391.60618 -289.604981) (xy 391.621764 -289.651662) (xy 391.629659 -289.700239) (xy 391.630154 -289.724846)
			(xy 391.969002 -289.724846) (xy 391.972962 -289.675792) (xy 391.984739 -289.628008) (xy 392.00403 -289.582732)
			(xy 392.030333 -289.541136) (xy 392.062968 -289.504299) (xy 392.101089 -289.473174) (xy 392.14371 -289.448567)
			(xy 392.189726 -289.431115) (xy 392.237945 -289.421271) (xy 392.28712 -289.41929) (xy 392.335975 -289.425222)
			(xy 392.383246 -289.438914) (xy 392.427708 -289.460012) (xy 392.468211 -289.487968) (xy 392.503704 -289.52206)
			(xy 392.533269 -289.561404) (xy 392.55614 -289.604981) (xy 392.571724 -289.651662) (xy 392.579619 -289.700239)
			(xy 392.580114 -289.724846) (xy 392.919216 -289.724846) (xy 392.923176 -289.675792) (xy 392.934953 -289.628008)
			(xy 392.954244 -289.582732) (xy 392.980547 -289.541136) (xy 393.013182 -289.504299) (xy 393.051303 -289.473174)
			(xy 393.093924 -289.448567) (xy 393.13994 -289.431115) (xy 393.188159 -289.421271) (xy 393.237334 -289.41929)
			(xy 393.286189 -289.425222) (xy 393.33346 -289.438914) (xy 393.377922 -289.460012) (xy 393.418425 -289.487968)
			(xy 393.453918 -289.52206) (xy 393.483483 -289.561404) (xy 393.506354 -289.604981) (xy 393.521938 -289.651662)
			(xy 393.529833 -289.700239) (xy 393.530328 -289.724846) (xy 393.869176 -289.724846) (xy 393.873136 -289.675792)
			(xy 393.884913 -289.628008) (xy 393.904204 -289.582732) (xy 393.930507 -289.541136) (xy 393.963142 -289.504299)
			(xy 394.001263 -289.473174) (xy 394.043884 -289.448567) (xy 394.0899 -289.431115) (xy 394.138119 -289.421271)
			(xy 394.187294 -289.41929) (xy 394.236149 -289.425222) (xy 394.28342 -289.438914) (xy 394.327882 -289.460012)
			(xy 394.368385 -289.487968) (xy 394.403878 -289.52206) (xy 394.433443 -289.561404) (xy 394.456314 -289.604981)
			(xy 394.471898 -289.651662) (xy 394.479793 -289.700239) (xy 394.480288 -289.724846) (xy 394.819136 -289.724846)
			(xy 394.823096 -289.675792) (xy 394.834873 -289.628008) (xy 394.854164 -289.582732) (xy 394.880467 -289.541136)
			(xy 394.913102 -289.504299) (xy 394.951223 -289.473174) (xy 394.993844 -289.448567) (xy 395.03986 -289.431115)
			(xy 395.088079 -289.421271) (xy 395.137254 -289.41929) (xy 395.186109 -289.425222) (xy 395.23338 -289.438914)
			(xy 395.277842 -289.460012) (xy 395.318345 -289.487968) (xy 395.353838 -289.52206) (xy 395.383403 -289.561404)
			(xy 395.406274 -289.604981) (xy 395.421858 -289.651662) (xy 395.429753 -289.700239) (xy 395.430248 -289.724846)
			(xy 395.769096 -289.724846) (xy 395.773056 -289.675792) (xy 395.784833 -289.628008) (xy 395.804124 -289.582732)
			(xy 395.830427 -289.541136) (xy 395.863062 -289.504299) (xy 395.901183 -289.473174) (xy 395.943804 -289.448567)
			(xy 395.98982 -289.431115) (xy 396.038039 -289.421271) (xy 396.087214 -289.41929) (xy 396.136069 -289.425222)
			(xy 396.18334 -289.438914) (xy 396.227802 -289.460012) (xy 396.268305 -289.487968) (xy 396.303798 -289.52206)
			(xy 396.333363 -289.561404) (xy 396.356234 -289.604981) (xy 396.371818 -289.651662) (xy 396.379713 -289.700239)
			(xy 396.380208 -289.724846) (xy 396.719056 -289.724846) (xy 396.723016 -289.675792) (xy 396.734793 -289.628008)
			(xy 396.754084 -289.582732) (xy 396.780387 -289.541136) (xy 396.813022 -289.504299) (xy 396.851143 -289.473174)
			(xy 396.893764 -289.448567) (xy 396.93978 -289.431115) (xy 396.987999 -289.421271) (xy 397.037174 -289.41929)
			(xy 397.086029 -289.425222) (xy 397.1333 -289.438914) (xy 397.177762 -289.460012) (xy 397.218265 -289.487968)
			(xy 397.253758 -289.52206) (xy 397.283323 -289.561404) (xy 397.306194 -289.604981) (xy 397.321778 -289.651662)
			(xy 397.329673 -289.700239) (xy 397.330168 -289.724846) (xy 397.669016 -289.724846) (xy 397.672976 -289.675792)
			(xy 397.684753 -289.628008) (xy 397.704044 -289.582732) (xy 397.730347 -289.541136) (xy 397.762982 -289.504299)
			(xy 397.801103 -289.473174) (xy 397.843724 -289.448567) (xy 397.88974 -289.431115) (xy 397.937959 -289.421271)
			(xy 397.987134 -289.41929) (xy 398.035989 -289.425222) (xy 398.08326 -289.438914) (xy 398.127722 -289.460012)
			(xy 398.168225 -289.487968) (xy 398.203718 -289.52206) (xy 398.233283 -289.561404) (xy 398.256154 -289.604981)
			(xy 398.271738 -289.651662) (xy 398.279633 -289.700239) (xy 398.280128 -289.724846) (xy 398.61923 -289.724846)
			(xy 398.62319 -289.675792) (xy 398.634967 -289.628008) (xy 398.654258 -289.582732) (xy 398.680561 -289.541136)
			(xy 398.713196 -289.504299) (xy 398.751317 -289.473174) (xy 398.793938 -289.448567) (xy 398.839954 -289.431115)
			(xy 398.888173 -289.421271) (xy 398.937348 -289.41929) (xy 398.986203 -289.425222) (xy 399.033474 -289.438914)
			(xy 399.077936 -289.460012) (xy 399.118439 -289.487968) (xy 399.153932 -289.52206) (xy 399.183497 -289.561404)
			(xy 399.206368 -289.604981) (xy 399.221952 -289.651662) (xy 399.229847 -289.700239) (xy 399.230342 -289.724846)
			(xy 399.56919 -289.724846) (xy 399.57315 -289.675792) (xy 399.584927 -289.628008) (xy 399.604218 -289.582732)
			(xy 399.630521 -289.541136) (xy 399.663156 -289.504299) (xy 399.701277 -289.473174) (xy 399.743898 -289.448567)
			(xy 399.789914 -289.431115) (xy 399.838133 -289.421271) (xy 399.887308 -289.41929) (xy 399.936163 -289.425222)
			(xy 399.983434 -289.438914) (xy 400.027896 -289.460012) (xy 400.068399 -289.487968) (xy 400.103892 -289.52206)
			(xy 400.133457 -289.561404) (xy 400.156328 -289.604981) (xy 400.171912 -289.651662) (xy 400.179807 -289.700239)
			(xy 400.180302 -289.724846) (xy 400.51915 -289.724846) (xy 400.52311 -289.675792) (xy 400.534887 -289.628008)
			(xy 400.554178 -289.582732) (xy 400.580481 -289.541136) (xy 400.613116 -289.504299) (xy 400.651237 -289.473174)
			(xy 400.693858 -289.448567) (xy 400.739874 -289.431115) (xy 400.788093 -289.421271) (xy 400.837268 -289.41929)
			(xy 400.886123 -289.425222) (xy 400.933394 -289.438914) (xy 400.977856 -289.460012) (xy 401.018359 -289.487968)
			(xy 401.053852 -289.52206) (xy 401.083417 -289.561404) (xy 401.106288 -289.604981) (xy 401.121872 -289.651662)
			(xy 401.129767 -289.700239) (xy 401.130262 -289.724846) (xy 401.46911 -289.724846) (xy 401.47307 -289.675792)
			(xy 401.484847 -289.628008) (xy 401.504138 -289.582732) (xy 401.530441 -289.541136) (xy 401.563076 -289.504299)
			(xy 401.601197 -289.473174) (xy 401.643818 -289.448567) (xy 401.689834 -289.431115) (xy 401.738053 -289.421271)
			(xy 401.787228 -289.41929) (xy 401.836083 -289.425222) (xy 401.883354 -289.438914) (xy 401.927816 -289.460012)
			(xy 401.968319 -289.487968) (xy 402.003812 -289.52206) (xy 402.033377 -289.561404) (xy 402.056248 -289.604981)
			(xy 402.071832 -289.651662) (xy 402.079727 -289.700239) (xy 402.080222 -289.724846) (xy 402.41907 -289.724846)
			(xy 402.42303 -289.675792) (xy 402.434807 -289.628008) (xy 402.454098 -289.582732) (xy 402.480401 -289.541136)
			(xy 402.513036 -289.504299) (xy 402.551157 -289.473174) (xy 402.593778 -289.448567) (xy 402.639794 -289.431115)
			(xy 402.688013 -289.421271) (xy 402.737188 -289.41929) (xy 402.786043 -289.425222) (xy 402.833314 -289.438914)
			(xy 402.877776 -289.460012) (xy 402.918279 -289.487968) (xy 402.953772 -289.52206) (xy 402.983337 -289.561404)
			(xy 403.006208 -289.604981) (xy 403.021792 -289.651662) (xy 403.029687 -289.700239) (xy 403.030182 -289.724846)
			(xy 403.36903 -289.724846) (xy 403.37299 -289.675792) (xy 403.384767 -289.628008) (xy 403.404058 -289.582732)
			(xy 403.430361 -289.541136) (xy 403.462996 -289.504299) (xy 403.501117 -289.473174) (xy 403.543738 -289.448567)
			(xy 403.589754 -289.431115) (xy 403.637973 -289.421271) (xy 403.687148 -289.41929) (xy 403.736003 -289.425222)
			(xy 403.783274 -289.438914) (xy 403.827736 -289.460012) (xy 403.868239 -289.487968) (xy 403.903732 -289.52206)
			(xy 403.933297 -289.561404) (xy 403.956168 -289.604981) (xy 403.971752 -289.651662) (xy 403.979647 -289.700239)
			(xy 403.980142 -289.724846) (xy 404.31899 -289.724846) (xy 404.32295 -289.675792) (xy 404.334727 -289.628008)
			(xy 404.354018 -289.582732) (xy 404.380321 -289.541136) (xy 404.412956 -289.504299) (xy 404.451077 -289.473174)
			(xy 404.493698 -289.448567) (xy 404.539714 -289.431115) (xy 404.587933 -289.421271) (xy 404.637108 -289.41929)
			(xy 404.685963 -289.425222) (xy 404.733234 -289.438914) (xy 404.777696 -289.460012) (xy 404.818199 -289.487968)
			(xy 404.853692 -289.52206) (xy 404.883257 -289.561404) (xy 404.906128 -289.604981) (xy 404.921712 -289.651662)
			(xy 404.929607 -289.700239) (xy 404.930102 -289.724846) (xy 405.269204 -289.724846) (xy 405.273164 -289.675792)
			(xy 405.284941 -289.628008) (xy 405.304232 -289.582732) (xy 405.330535 -289.541136) (xy 405.36317 -289.504299)
			(xy 405.401291 -289.473174) (xy 405.443912 -289.448567) (xy 405.489928 -289.431115) (xy 405.538147 -289.421271)
			(xy 405.587322 -289.41929) (xy 405.636177 -289.425222) (xy 405.683448 -289.438914) (xy 405.72791 -289.460012)
			(xy 405.768413 -289.487968) (xy 405.803906 -289.52206) (xy 405.833471 -289.561404) (xy 405.856342 -289.604981)
			(xy 405.871926 -289.651662) (xy 405.879821 -289.700239) (xy 405.880316 -289.724846) (xy 406.219164 -289.724846)
			(xy 406.223124 -289.675792) (xy 406.234901 -289.628008) (xy 406.254192 -289.582732) (xy 406.280495 -289.541136)
			(xy 406.31313 -289.504299) (xy 406.351251 -289.473174) (xy 406.393872 -289.448567) (xy 406.439888 -289.431115)
			(xy 406.488107 -289.421271) (xy 406.537282 -289.41929) (xy 406.586137 -289.425222) (xy 406.633408 -289.438914)
			(xy 406.67787 -289.460012) (xy 406.718373 -289.487968) (xy 406.753866 -289.52206) (xy 406.783431 -289.561404)
			(xy 406.806302 -289.604981) (xy 406.821886 -289.651662) (xy 406.829781 -289.700239) (xy 406.830276 -289.724846)
			(xy 408.119084 -289.724846) (xy 408.123044 -289.675792) (xy 408.134821 -289.628008) (xy 408.154112 -289.582732)
			(xy 408.180415 -289.541136) (xy 408.21305 -289.504299) (xy 408.251171 -289.473174) (xy 408.293792 -289.448567)
			(xy 408.339808 -289.431115) (xy 408.388027 -289.421271) (xy 408.437202 -289.41929) (xy 408.486057 -289.425222)
			(xy 408.533328 -289.438914) (xy 408.57779 -289.460012) (xy 408.618293 -289.487968) (xy 408.653786 -289.52206)
			(xy 408.683351 -289.561404) (xy 408.706222 -289.604981) (xy 408.721806 -289.651662) (xy 408.729701 -289.700239)
			(xy 408.730196 -289.724846) (xy 409.069044 -289.724846) (xy 409.073004 -289.675792) (xy 409.084781 -289.628008)
			(xy 409.104072 -289.582732) (xy 409.130375 -289.541136) (xy 409.16301 -289.504299) (xy 409.201131 -289.473174)
			(xy 409.243752 -289.448567) (xy 409.289768 -289.431115) (xy 409.337987 -289.421271) (xy 409.387162 -289.41929)
			(xy 409.436017 -289.425222) (xy 409.483288 -289.438914) (xy 409.52775 -289.460012) (xy 409.568253 -289.487968)
			(xy 409.603746 -289.52206) (xy 409.633311 -289.561404) (xy 409.656182 -289.604981) (xy 409.671766 -289.651662)
			(xy 409.679661 -289.700239) (xy 409.680156 -289.724846) (xy 410.019004 -289.724846) (xy 410.022964 -289.675792)
			(xy 410.034741 -289.628008) (xy 410.054032 -289.582732) (xy 410.080335 -289.541136) (xy 410.11297 -289.504299)
			(xy 410.151091 -289.473174) (xy 410.193712 -289.448567) (xy 410.239728 -289.431115) (xy 410.287947 -289.421271)
			(xy 410.337122 -289.41929) (xy 410.385977 -289.425222) (xy 410.433248 -289.438914) (xy 410.47771 -289.460012)
			(xy 410.518213 -289.487968) (xy 410.553706 -289.52206) (xy 410.583271 -289.561404) (xy 410.606142 -289.604981)
			(xy 410.621726 -289.651662) (xy 410.629621 -289.700239) (xy 410.630116 -289.724846) (xy 410.969218 -289.724846)
			(xy 410.973178 -289.675792) (xy 410.984955 -289.628008) (xy 411.004246 -289.582732) (xy 411.030549 -289.541136)
			(xy 411.063184 -289.504299) (xy 411.101305 -289.473174) (xy 411.143926 -289.448567) (xy 411.189942 -289.431115)
			(xy 411.238161 -289.421271) (xy 411.287336 -289.41929) (xy 411.336191 -289.425222) (xy 411.383462 -289.438914)
			(xy 411.427924 -289.460012) (xy 411.468427 -289.487968) (xy 411.50392 -289.52206) (xy 411.533485 -289.561404)
			(xy 411.556356 -289.604981) (xy 411.57194 -289.651662) (xy 411.579835 -289.700239) (xy 411.58033 -289.724846)
			(xy 411.919178 -289.724846) (xy 411.923138 -289.675792) (xy 411.934915 -289.628008) (xy 411.954206 -289.582732)
			(xy 411.980509 -289.541136) (xy 412.013144 -289.504299) (xy 412.051265 -289.473174) (xy 412.093886 -289.448567)
			(xy 412.139902 -289.431115) (xy 412.188121 -289.421271) (xy 412.237296 -289.41929) (xy 412.286151 -289.425222)
			(xy 412.333422 -289.438914) (xy 412.377884 -289.460012) (xy 412.418387 -289.487968) (xy 412.45388 -289.52206)
			(xy 412.483445 -289.561404) (xy 412.506316 -289.604981) (xy 412.5219 -289.651662) (xy 412.529795 -289.700239)
			(xy 412.53029 -289.724846) (xy 412.869138 -289.724846) (xy 412.873098 -289.675792) (xy 412.884875 -289.628008)
			(xy 412.904166 -289.582732) (xy 412.930469 -289.541136) (xy 412.963104 -289.504299) (xy 413.001225 -289.473174)
			(xy 413.043846 -289.448567) (xy 413.089862 -289.431115) (xy 413.138081 -289.421271) (xy 413.187256 -289.41929)
			(xy 413.236111 -289.425222) (xy 413.283382 -289.438914) (xy 413.327844 -289.460012) (xy 413.368347 -289.487968)
			(xy 413.40384 -289.52206) (xy 413.433405 -289.561404) (xy 413.456276 -289.604981) (xy 413.47186 -289.651662)
			(xy 413.479755 -289.700239) (xy 413.48025 -289.724846) (xy 413.819098 -289.724846) (xy 413.823058 -289.675792)
			(xy 413.834835 -289.628008) (xy 413.854126 -289.582732) (xy 413.880429 -289.541136) (xy 413.913064 -289.504299)
			(xy 413.951185 -289.473174) (xy 413.993806 -289.448567) (xy 414.039822 -289.431115) (xy 414.088041 -289.421271)
			(xy 414.137216 -289.41929) (xy 414.186071 -289.425222) (xy 414.233342 -289.438914) (xy 414.277804 -289.460012)
			(xy 414.318307 -289.487968) (xy 414.3538 -289.52206) (xy 414.383365 -289.561404) (xy 414.406236 -289.604981)
			(xy 414.42182 -289.651662) (xy 414.429715 -289.700239) (xy 414.43021 -289.724846) (xy 414.769058 -289.724846)
			(xy 414.773018 -289.675792) (xy 414.784795 -289.628008) (xy 414.804086 -289.582732) (xy 414.830389 -289.541136)
			(xy 414.863024 -289.504299) (xy 414.901145 -289.473174) (xy 414.943766 -289.448567) (xy 414.989782 -289.431115)
			(xy 415.038001 -289.421271) (xy 415.087176 -289.41929) (xy 415.136031 -289.425222) (xy 415.183302 -289.438914)
			(xy 415.227764 -289.460012) (xy 415.268267 -289.487968) (xy 415.30376 -289.52206) (xy 415.333325 -289.561404)
			(xy 415.356196 -289.604981) (xy 415.37178 -289.651662) (xy 415.379675 -289.700239) (xy 415.38017 -289.724846)
			(xy 415.719018 -289.724846) (xy 415.722978 -289.675792) (xy 415.734755 -289.628008) (xy 415.754046 -289.582732)
			(xy 415.780349 -289.541136) (xy 415.812984 -289.504299) (xy 415.851105 -289.473174) (xy 415.893726 -289.448567)
			(xy 415.939742 -289.431115) (xy 415.987961 -289.421271) (xy 416.037136 -289.41929) (xy 416.085991 -289.425222)
			(xy 416.133262 -289.438914) (xy 416.177724 -289.460012) (xy 416.218227 -289.487968) (xy 416.25372 -289.52206)
			(xy 416.283285 -289.561404) (xy 416.306156 -289.604981) (xy 416.32174 -289.651662) (xy 416.329635 -289.700239)
			(xy 416.33013 -289.724846) (xy 416.329635 -289.749453) (xy 416.32174 -289.79803) (xy 416.306156 -289.844711)
			(xy 416.283285 -289.888288) (xy 416.25372 -289.927632) (xy 416.218227 -289.961724) (xy 416.177724 -289.98968)
			(xy 416.133262 -290.010778) (xy 416.085991 -290.02447) (xy 416.037136 -290.030402) (xy 415.987961 -290.028421)
			(xy 415.939742 -290.018577) (xy 415.893726 -290.001125) (xy 415.851105 -289.976518) (xy 415.812984 -289.945393)
			(xy 415.780349 -289.908556) (xy 415.754046 -289.86696) (xy 415.734755 -289.821684) (xy 415.722978 -289.7739)
			(xy 415.719018 -289.724846) (xy 415.38017 -289.724846) (xy 415.379675 -289.749453) (xy 415.37178 -289.79803)
			(xy 415.356196 -289.844711) (xy 415.333325 -289.888288) (xy 415.30376 -289.927632) (xy 415.268267 -289.961724)
			(xy 415.227764 -289.98968) (xy 415.183302 -290.010778) (xy 415.136031 -290.02447) (xy 415.087176 -290.030402)
			(xy 415.038001 -290.028421) (xy 414.989782 -290.018577) (xy 414.943766 -290.001125) (xy 414.901145 -289.976518)
			(xy 414.863024 -289.945393) (xy 414.830389 -289.908556) (xy 414.804086 -289.86696) (xy 414.784795 -289.821684)
			(xy 414.773018 -289.7739) (xy 414.769058 -289.724846) (xy 414.43021 -289.724846) (xy 414.429715 -289.749453)
			(xy 414.42182 -289.79803) (xy 414.406236 -289.844711) (xy 414.383365 -289.888288) (xy 414.3538 -289.927632)
			(xy 414.318307 -289.961724) (xy 414.277804 -289.98968) (xy 414.233342 -290.010778) (xy 414.186071 -290.02447)
			(xy 414.137216 -290.030402) (xy 414.088041 -290.028421) (xy 414.039822 -290.018577) (xy 413.993806 -290.001125)
			(xy 413.951185 -289.976518) (xy 413.913064 -289.945393) (xy 413.880429 -289.908556) (xy 413.854126 -289.86696)
			(xy 413.834835 -289.821684) (xy 413.823058 -289.7739) (xy 413.819098 -289.724846) (xy 413.48025 -289.724846)
			(xy 413.479755 -289.749453) (xy 413.47186 -289.79803) (xy 413.456276 -289.844711) (xy 413.433405 -289.888288)
			(xy 413.40384 -289.927632) (xy 413.368347 -289.961724) (xy 413.327844 -289.98968) (xy 413.283382 -290.010778)
			(xy 413.236111 -290.02447) (xy 413.187256 -290.030402) (xy 413.138081 -290.028421) (xy 413.089862 -290.018577)
			(xy 413.043846 -290.001125) (xy 413.001225 -289.976518) (xy 412.963104 -289.945393) (xy 412.930469 -289.908556)
			(xy 412.904166 -289.86696) (xy 412.884875 -289.821684) (xy 412.873098 -289.7739) (xy 412.869138 -289.724846)
			(xy 412.53029 -289.724846) (xy 412.529795 -289.749453) (xy 412.5219 -289.79803) (xy 412.506316 -289.844711)
			(xy 412.483445 -289.888288) (xy 412.45388 -289.927632) (xy 412.418387 -289.961724) (xy 412.377884 -289.98968)
			(xy 412.333422 -290.010778) (xy 412.286151 -290.02447) (xy 412.237296 -290.030402) (xy 412.188121 -290.028421)
			(xy 412.139902 -290.018577) (xy 412.093886 -290.001125) (xy 412.051265 -289.976518) (xy 412.013144 -289.945393)
			(xy 411.980509 -289.908556) (xy 411.954206 -289.86696) (xy 411.934915 -289.821684) (xy 411.923138 -289.7739)
			(xy 411.919178 -289.724846) (xy 411.58033 -289.724846) (xy 411.579835 -289.749453) (xy 411.57194 -289.79803)
			(xy 411.556356 -289.844711) (xy 411.533485 -289.888288) (xy 411.50392 -289.927632) (xy 411.468427 -289.961724)
			(xy 411.427924 -289.98968) (xy 411.383462 -290.010778) (xy 411.336191 -290.02447) (xy 411.287336 -290.030402)
			(xy 411.238161 -290.028421) (xy 411.189942 -290.018577) (xy 411.143926 -290.001125) (xy 411.101305 -289.976518)
			(xy 411.063184 -289.945393) (xy 411.030549 -289.908556) (xy 411.004246 -289.86696) (xy 410.984955 -289.821684)
			(xy 410.973178 -289.7739) (xy 410.969218 -289.724846) (xy 410.630116 -289.724846) (xy 410.629621 -289.749453)
			(xy 410.621726 -289.79803) (xy 410.606142 -289.844711) (xy 410.583271 -289.888288) (xy 410.553706 -289.927632)
			(xy 410.518213 -289.961724) (xy 410.47771 -289.98968) (xy 410.433248 -290.010778) (xy 410.385977 -290.02447)
			(xy 410.337122 -290.030402) (xy 410.287947 -290.028421) (xy 410.239728 -290.018577) (xy 410.193712 -290.001125)
			(xy 410.151091 -289.976518) (xy 410.11297 -289.945393) (xy 410.080335 -289.908556) (xy 410.054032 -289.86696)
			(xy 410.034741 -289.821684) (xy 410.022964 -289.7739) (xy 410.019004 -289.724846) (xy 409.680156 -289.724846)
			(xy 409.679661 -289.749453) (xy 409.671766 -289.79803) (xy 409.656182 -289.844711) (xy 409.633311 -289.888288)
			(xy 409.603746 -289.927632) (xy 409.568253 -289.961724) (xy 409.52775 -289.98968) (xy 409.483288 -290.010778)
			(xy 409.436017 -290.02447) (xy 409.387162 -290.030402) (xy 409.337987 -290.028421) (xy 409.289768 -290.018577)
			(xy 409.243752 -290.001125) (xy 409.201131 -289.976518) (xy 409.16301 -289.945393) (xy 409.130375 -289.908556)
			(xy 409.104072 -289.86696) (xy 409.084781 -289.821684) (xy 409.073004 -289.7739) (xy 409.069044 -289.724846)
			(xy 408.730196 -289.724846) (xy 408.729701 -289.749453) (xy 408.721806 -289.79803) (xy 408.706222 -289.844711)
			(xy 408.683351 -289.888288) (xy 408.653786 -289.927632) (xy 408.618293 -289.961724) (xy 408.57779 -289.98968)
			(xy 408.533328 -290.010778) (xy 408.486057 -290.02447) (xy 408.437202 -290.030402) (xy 408.388027 -290.028421)
			(xy 408.339808 -290.018577) (xy 408.293792 -290.001125) (xy 408.251171 -289.976518) (xy 408.21305 -289.945393)
			(xy 408.180415 -289.908556) (xy 408.154112 -289.86696) (xy 408.134821 -289.821684) (xy 408.123044 -289.7739)
			(xy 408.119084 -289.724846) (xy 406.830276 -289.724846) (xy 406.829781 -289.749453) (xy 406.821886 -289.79803)
			(xy 406.806302 -289.844711) (xy 406.783431 -289.888288) (xy 406.753866 -289.927632) (xy 406.718373 -289.961724)
			(xy 406.67787 -289.98968) (xy 406.633408 -290.010778) (xy 406.586137 -290.02447) (xy 406.537282 -290.030402)
			(xy 406.488107 -290.028421) (xy 406.439888 -290.018577) (xy 406.393872 -290.001125) (xy 406.351251 -289.976518)
			(xy 406.31313 -289.945393) (xy 406.280495 -289.908556) (xy 406.254192 -289.86696) (xy 406.234901 -289.821684)
			(xy 406.223124 -289.7739) (xy 406.219164 -289.724846) (xy 405.880316 -289.724846) (xy 405.879821 -289.749453)
			(xy 405.871926 -289.79803) (xy 405.856342 -289.844711) (xy 405.833471 -289.888288) (xy 405.803906 -289.927632)
			(xy 405.768413 -289.961724) (xy 405.72791 -289.98968) (xy 405.683448 -290.010778) (xy 405.636177 -290.02447)
			(xy 405.587322 -290.030402) (xy 405.538147 -290.028421) (xy 405.489928 -290.018577) (xy 405.443912 -290.001125)
			(xy 405.401291 -289.976518) (xy 405.36317 -289.945393) (xy 405.330535 -289.908556) (xy 405.304232 -289.86696)
			(xy 405.284941 -289.821684) (xy 405.273164 -289.7739) (xy 405.269204 -289.724846) (xy 404.930102 -289.724846)
			(xy 404.929607 -289.749453) (xy 404.921712 -289.79803) (xy 404.906128 -289.844711) (xy 404.883257 -289.888288)
			(xy 404.853692 -289.927632) (xy 404.818199 -289.961724) (xy 404.777696 -289.98968) (xy 404.733234 -290.010778)
			(xy 404.685963 -290.02447) (xy 404.637108 -290.030402) (xy 404.587933 -290.028421) (xy 404.539714 -290.018577)
			(xy 404.493698 -290.001125) (xy 404.451077 -289.976518) (xy 404.412956 -289.945393) (xy 404.380321 -289.908556)
			(xy 404.354018 -289.86696) (xy 404.334727 -289.821684) (xy 404.32295 -289.7739) (xy 404.31899 -289.724846)
			(xy 403.980142 -289.724846) (xy 403.979647 -289.749453) (xy 403.971752 -289.79803) (xy 403.956168 -289.844711)
			(xy 403.933297 -289.888288) (xy 403.903732 -289.927632) (xy 403.868239 -289.961724) (xy 403.827736 -289.98968)
			(xy 403.783274 -290.010778) (xy 403.736003 -290.02447) (xy 403.687148 -290.030402) (xy 403.637973 -290.028421)
			(xy 403.589754 -290.018577) (xy 403.543738 -290.001125) (xy 403.501117 -289.976518) (xy 403.462996 -289.945393)
			(xy 403.430361 -289.908556) (xy 403.404058 -289.86696) (xy 403.384767 -289.821684) (xy 403.37299 -289.7739)
			(xy 403.36903 -289.724846) (xy 403.030182 -289.724846) (xy 403.029687 -289.749453) (xy 403.021792 -289.79803)
			(xy 403.006208 -289.844711) (xy 402.983337 -289.888288) (xy 402.953772 -289.927632) (xy 402.918279 -289.961724)
			(xy 402.877776 -289.98968) (xy 402.833314 -290.010778) (xy 402.786043 -290.02447) (xy 402.737188 -290.030402)
			(xy 402.688013 -290.028421) (xy 402.639794 -290.018577) (xy 402.593778 -290.001125) (xy 402.551157 -289.976518)
			(xy 402.513036 -289.945393) (xy 402.480401 -289.908556) (xy 402.454098 -289.86696) (xy 402.434807 -289.821684)
			(xy 402.42303 -289.7739) (xy 402.41907 -289.724846) (xy 402.080222 -289.724846) (xy 402.079727 -289.749453)
			(xy 402.071832 -289.79803) (xy 402.056248 -289.844711) (xy 402.033377 -289.888288) (xy 402.003812 -289.927632)
			(xy 401.968319 -289.961724) (xy 401.927816 -289.98968) (xy 401.883354 -290.010778) (xy 401.836083 -290.02447)
			(xy 401.787228 -290.030402) (xy 401.738053 -290.028421) (xy 401.689834 -290.018577) (xy 401.643818 -290.001125)
			(xy 401.601197 -289.976518) (xy 401.563076 -289.945393) (xy 401.530441 -289.908556) (xy 401.504138 -289.86696)
			(xy 401.484847 -289.821684) (xy 401.47307 -289.7739) (xy 401.46911 -289.724846) (xy 401.130262 -289.724846)
			(xy 401.129767 -289.749453) (xy 401.121872 -289.79803) (xy 401.106288 -289.844711) (xy 401.083417 -289.888288)
			(xy 401.053852 -289.927632) (xy 401.018359 -289.961724) (xy 400.977856 -289.98968) (xy 400.933394 -290.010778)
			(xy 400.886123 -290.02447) (xy 400.837268 -290.030402) (xy 400.788093 -290.028421) (xy 400.739874 -290.018577)
			(xy 400.693858 -290.001125) (xy 400.651237 -289.976518) (xy 400.613116 -289.945393) (xy 400.580481 -289.908556)
			(xy 400.554178 -289.86696) (xy 400.534887 -289.821684) (xy 400.52311 -289.7739) (xy 400.51915 -289.724846)
			(xy 400.180302 -289.724846) (xy 400.179807 -289.749453) (xy 400.171912 -289.79803) (xy 400.156328 -289.844711)
			(xy 400.133457 -289.888288) (xy 400.103892 -289.927632) (xy 400.068399 -289.961724) (xy 400.027896 -289.98968)
			(xy 399.983434 -290.010778) (xy 399.936163 -290.02447) (xy 399.887308 -290.030402) (xy 399.838133 -290.028421)
			(xy 399.789914 -290.018577) (xy 399.743898 -290.001125) (xy 399.701277 -289.976518) (xy 399.663156 -289.945393)
			(xy 399.630521 -289.908556) (xy 399.604218 -289.86696) (xy 399.584927 -289.821684) (xy 399.57315 -289.7739)
			(xy 399.56919 -289.724846) (xy 399.230342 -289.724846) (xy 399.229847 -289.749453) (xy 399.221952 -289.79803)
			(xy 399.206368 -289.844711) (xy 399.183497 -289.888288) (xy 399.153932 -289.927632) (xy 399.118439 -289.961724)
			(xy 399.077936 -289.98968) (xy 399.033474 -290.010778) (xy 398.986203 -290.02447) (xy 398.937348 -290.030402)
			(xy 398.888173 -290.028421) (xy 398.839954 -290.018577) (xy 398.793938 -290.001125) (xy 398.751317 -289.976518)
			(xy 398.713196 -289.945393) (xy 398.680561 -289.908556) (xy 398.654258 -289.86696) (xy 398.634967 -289.821684)
			(xy 398.62319 -289.7739) (xy 398.61923 -289.724846) (xy 398.280128 -289.724846) (xy 398.279633 -289.749453)
			(xy 398.271738 -289.79803) (xy 398.256154 -289.844711) (xy 398.233283 -289.888288) (xy 398.203718 -289.927632)
			(xy 398.168225 -289.961724) (xy 398.127722 -289.98968) (xy 398.08326 -290.010778) (xy 398.035989 -290.02447)
			(xy 397.987134 -290.030402) (xy 397.937959 -290.028421) (xy 397.88974 -290.018577) (xy 397.843724 -290.001125)
			(xy 397.801103 -289.976518) (xy 397.762982 -289.945393) (xy 397.730347 -289.908556) (xy 397.704044 -289.86696)
			(xy 397.684753 -289.821684) (xy 397.672976 -289.7739) (xy 397.669016 -289.724846) (xy 397.330168 -289.724846)
			(xy 397.329673 -289.749453) (xy 397.321778 -289.79803) (xy 397.306194 -289.844711) (xy 397.283323 -289.888288)
			(xy 397.253758 -289.927632) (xy 397.218265 -289.961724) (xy 397.177762 -289.98968) (xy 397.1333 -290.010778)
			(xy 397.086029 -290.02447) (xy 397.037174 -290.030402) (xy 396.987999 -290.028421) (xy 396.93978 -290.018577)
			(xy 396.893764 -290.001125) (xy 396.851143 -289.976518) (xy 396.813022 -289.945393) (xy 396.780387 -289.908556)
			(xy 396.754084 -289.86696) (xy 396.734793 -289.821684) (xy 396.723016 -289.7739) (xy 396.719056 -289.724846)
			(xy 396.380208 -289.724846) (xy 396.379713 -289.749453) (xy 396.371818 -289.79803) (xy 396.356234 -289.844711)
			(xy 396.333363 -289.888288) (xy 396.303798 -289.927632) (xy 396.268305 -289.961724) (xy 396.227802 -289.98968)
			(xy 396.18334 -290.010778) (xy 396.136069 -290.02447) (xy 396.087214 -290.030402) (xy 396.038039 -290.028421)
			(xy 395.98982 -290.018577) (xy 395.943804 -290.001125) (xy 395.901183 -289.976518) (xy 395.863062 -289.945393)
			(xy 395.830427 -289.908556) (xy 395.804124 -289.86696) (xy 395.784833 -289.821684) (xy 395.773056 -289.7739)
			(xy 395.769096 -289.724846) (xy 395.430248 -289.724846) (xy 395.429753 -289.749453) (xy 395.421858 -289.79803)
			(xy 395.406274 -289.844711) (xy 395.383403 -289.888288) (xy 395.353838 -289.927632) (xy 395.318345 -289.961724)
			(xy 395.277842 -289.98968) (xy 395.23338 -290.010778) (xy 395.186109 -290.02447) (xy 395.137254 -290.030402)
			(xy 395.088079 -290.028421) (xy 395.03986 -290.018577) (xy 394.993844 -290.001125) (xy 394.951223 -289.976518)
			(xy 394.913102 -289.945393) (xy 394.880467 -289.908556) (xy 394.854164 -289.86696) (xy 394.834873 -289.821684)
			(xy 394.823096 -289.7739) (xy 394.819136 -289.724846) (xy 394.480288 -289.724846) (xy 394.479793 -289.749453)
			(xy 394.471898 -289.79803) (xy 394.456314 -289.844711) (xy 394.433443 -289.888288) (xy 394.403878 -289.927632)
			(xy 394.368385 -289.961724) (xy 394.327882 -289.98968) (xy 394.28342 -290.010778) (xy 394.236149 -290.02447)
			(xy 394.187294 -290.030402) (xy 394.138119 -290.028421) (xy 394.0899 -290.018577) (xy 394.043884 -290.001125)
			(xy 394.001263 -289.976518) (xy 393.963142 -289.945393) (xy 393.930507 -289.908556) (xy 393.904204 -289.86696)
			(xy 393.884913 -289.821684) (xy 393.873136 -289.7739) (xy 393.869176 -289.724846) (xy 393.530328 -289.724846)
			(xy 393.529833 -289.749453) (xy 393.521938 -289.79803) (xy 393.506354 -289.844711) (xy 393.483483 -289.888288)
			(xy 393.453918 -289.927632) (xy 393.418425 -289.961724) (xy 393.377922 -289.98968) (xy 393.33346 -290.010778)
			(xy 393.286189 -290.02447) (xy 393.237334 -290.030402) (xy 393.188159 -290.028421) (xy 393.13994 -290.018577)
			(xy 393.093924 -290.001125) (xy 393.051303 -289.976518) (xy 393.013182 -289.945393) (xy 392.980547 -289.908556)
			(xy 392.954244 -289.86696) (xy 392.934953 -289.821684) (xy 392.923176 -289.7739) (xy 392.919216 -289.724846)
			(xy 392.580114 -289.724846) (xy 392.579619 -289.749453) (xy 392.571724 -289.79803) (xy 392.55614 -289.844711)
			(xy 392.533269 -289.888288) (xy 392.503704 -289.927632) (xy 392.468211 -289.961724) (xy 392.427708 -289.98968)
			(xy 392.383246 -290.010778) (xy 392.335975 -290.02447) (xy 392.28712 -290.030402) (xy 392.237945 -290.028421)
			(xy 392.189726 -290.018577) (xy 392.14371 -290.001125) (xy 392.101089 -289.976518) (xy 392.062968 -289.945393)
			(xy 392.030333 -289.908556) (xy 392.00403 -289.86696) (xy 391.984739 -289.821684) (xy 391.972962 -289.7739)
			(xy 391.969002 -289.724846) (xy 391.630154 -289.724846) (xy 391.629659 -289.749453) (xy 391.621764 -289.79803)
			(xy 391.60618 -289.844711) (xy 391.583309 -289.888288) (xy 391.553744 -289.927632) (xy 391.518251 -289.961724)
			(xy 391.477748 -289.98968) (xy 391.433286 -290.010778) (xy 391.386015 -290.02447) (xy 391.33716 -290.030402)
			(xy 391.287985 -290.028421) (xy 391.239766 -290.018577) (xy 391.19375 -290.001125) (xy 391.151129 -289.976518)
			(xy 391.113008 -289.945393) (xy 391.080373 -289.908556) (xy 391.05407 -289.86696) (xy 391.034779 -289.821684)
			(xy 391.023002 -289.7739) (xy 391.019042 -289.724846) (xy 390.680194 -289.724846) (xy 390.679699 -289.749453)
			(xy 390.671804 -289.79803) (xy 390.65622 -289.844711) (xy 390.633349 -289.888288) (xy 390.603784 -289.927632)
			(xy 390.568291 -289.961724) (xy 390.527788 -289.98968) (xy 390.483326 -290.010778) (xy 390.436055 -290.02447)
			(xy 390.3872 -290.030402) (xy 390.338025 -290.028421) (xy 390.289806 -290.018577) (xy 390.24379 -290.001125)
			(xy 390.201169 -289.976518) (xy 390.163048 -289.945393) (xy 390.130413 -289.908556) (xy 390.10411 -289.86696)
			(xy 390.084819 -289.821684) (xy 390.073042 -289.7739) (xy 390.069082 -289.724846) (xy 389.730234 -289.724846)
			(xy 389.729739 -289.749453) (xy 389.721844 -289.79803) (xy 389.70626 -289.844711) (xy 389.683389 -289.888288)
			(xy 389.653824 -289.927632) (xy 389.618331 -289.961724) (xy 389.577828 -289.98968) (xy 389.533366 -290.010778)
			(xy 389.486095 -290.02447) (xy 389.43724 -290.030402) (xy 389.388065 -290.028421) (xy 389.339846 -290.018577)
			(xy 389.29383 -290.001125) (xy 389.251209 -289.976518) (xy 389.213088 -289.945393) (xy 389.180453 -289.908556)
			(xy 389.15415 -289.86696) (xy 389.134859 -289.821684) (xy 389.123082 -289.7739) (xy 389.119122 -289.724846)
			(xy 388.780274 -289.724846) (xy 388.779779 -289.749453) (xy 388.771884 -289.79803) (xy 388.7563 -289.844711)
			(xy 388.733429 -289.888288) (xy 388.703864 -289.927632) (xy 388.668371 -289.961724) (xy 388.627868 -289.98968)
			(xy 388.583406 -290.010778) (xy 388.536135 -290.02447) (xy 388.48728 -290.030402) (xy 388.438105 -290.028421)
			(xy 388.389886 -290.018577) (xy 388.34387 -290.001125) (xy 388.301249 -289.976518) (xy 388.263128 -289.945393)
			(xy 388.230493 -289.908556) (xy 388.20419 -289.86696) (xy 388.184899 -289.821684) (xy 388.173122 -289.7739)
			(xy 388.169162 -289.724846) (xy 387.830314 -289.724846) (xy 387.829819 -289.749453) (xy 387.821924 -289.79803)
			(xy 387.80634 -289.844711) (xy 387.783469 -289.888288) (xy 387.753904 -289.927632) (xy 387.718411 -289.961724)
			(xy 387.677908 -289.98968) (xy 387.633446 -290.010778) (xy 387.586175 -290.02447) (xy 387.53732 -290.030402)
			(xy 387.488145 -290.028421) (xy 387.439926 -290.018577) (xy 387.39391 -290.001125) (xy 387.351289 -289.976518)
			(xy 387.313168 -289.945393) (xy 387.280533 -289.908556) (xy 387.25423 -289.86696) (xy 387.234939 -289.821684)
			(xy 387.223162 -289.7739) (xy 387.219202 -289.724846) (xy 386.880354 -289.724846) (xy 386.879859 -289.749453)
			(xy 386.871964 -289.79803) (xy 386.85638 -289.844711) (xy 386.833509 -289.888288) (xy 386.803944 -289.927632)
			(xy 386.768451 -289.961724) (xy 386.727948 -289.98968) (xy 386.683486 -290.010778) (xy 386.636215 -290.02447)
			(xy 386.58736 -290.030402) (xy 386.538185 -290.028421) (xy 386.489966 -290.018577) (xy 386.44395 -290.001125)
			(xy 386.401329 -289.976518) (xy 386.363208 -289.945393) (xy 386.330573 -289.908556) (xy 386.30427 -289.86696)
			(xy 386.284979 -289.821684) (xy 386.273202 -289.7739) (xy 386.269242 -289.724846) (xy 385.93014 -289.724846)
			(xy 385.929645 -289.749453) (xy 385.92175 -289.79803) (xy 385.906166 -289.844711) (xy 385.883295 -289.888288)
			(xy 385.85373 -289.927632) (xy 385.818237 -289.961724) (xy 385.777734 -289.98968) (xy 385.733272 -290.010778)
			(xy 385.686001 -290.02447) (xy 385.637146 -290.030402) (xy 385.587971 -290.028421) (xy 385.539752 -290.018577)
			(xy 385.493736 -290.001125) (xy 385.451115 -289.976518) (xy 385.412994 -289.945393) (xy 385.380359 -289.908556)
			(xy 385.354056 -289.86696) (xy 385.334765 -289.821684) (xy 385.322988 -289.7739) (xy 385.319028 -289.724846)
			(xy 384.98018 -289.724846) (xy 384.979685 -289.749453) (xy 384.97179 -289.79803) (xy 384.956206 -289.844711)
			(xy 384.933335 -289.888288) (xy 384.90377 -289.927632) (xy 384.868277 -289.961724) (xy 384.827774 -289.98968)
			(xy 384.783312 -290.010778) (xy 384.736041 -290.02447) (xy 384.687186 -290.030402) (xy 384.638011 -290.028421)
			(xy 384.589792 -290.018577) (xy 384.543776 -290.001125) (xy 384.501155 -289.976518) (xy 384.463034 -289.945393)
			(xy 384.430399 -289.908556) (xy 384.404096 -289.86696) (xy 384.384805 -289.821684) (xy 384.373028 -289.7739)
			(xy 384.369068 -289.724846) (xy 380.360637 -289.724846) (xy 380.358889 -289.728354) (xy 380.324916 -289.776305)
			(xy 380.283989 -289.818476) (xy 380.26086 -289.836606) (xy 380.251924 -289.844075) (xy 380.241471 -289.864857)
			(xy 380.240794 -289.876484) (xy 380.239524 -289.968432) (xy 380.24943 -289.989514) (xy 380.258574 -289.99688)
			(xy 380.280389 -290.015124) (xy 380.318933 -290.056934) (xy 380.350844 -290.104001) (xy 380.375417 -290.155284)
			(xy 380.392107 -290.209645) (xy 380.400545 -290.265881) (xy 380.401068 -290.294314) (xy 381.034542 -290.294314)
			(xy 381.038613 -290.238692) (xy 381.050739 -290.184255) (xy 381.070662 -290.132164) (xy 381.097958 -290.083529)
			(xy 381.132044 -290.039386) (xy 381.172193 -290.000677) (xy 381.217551 -289.968226) (xy 381.267151 -289.942725)
			(xy 381.319935 -289.924718) (xy 381.374778 -289.914588) (xy 381.430512 -289.912551) (xy 381.485949 -289.918651)
			(xy 381.539906 -289.932757) (xy 381.591235 -289.954569) (xy 381.638841 -289.983623) (xy 381.681709 -290.019298)
			(xy 381.718926 -290.060835) (xy 381.749699 -290.107348) (xy 381.773371 -290.157845) (xy 381.789439 -290.211252)
			(xy 381.797559 -290.266428) (xy 381.798068 -290.294314) (xy 381.921002 -290.294314) (xy 381.925073 -290.238692)
			(xy 381.937199 -290.184255) (xy 381.957122 -290.132164) (xy 381.984418 -290.083529) (xy 382.018504 -290.039386)
			(xy 382.058653 -290.000677) (xy 382.104011 -289.968226) (xy 382.153611 -289.942725) (xy 382.206395 -289.924718)
			(xy 382.261238 -289.914588) (xy 382.316972 -289.912551) (xy 382.372409 -289.918651) (xy 382.426366 -289.932757)
			(xy 382.477695 -289.954569) (xy 382.525301 -289.983623) (xy 382.568169 -290.019298) (xy 382.605386 -290.060835)
			(xy 382.636159 -290.107348) (xy 382.659831 -290.157845) (xy 382.675899 -290.211252) (xy 382.684019 -290.266428)
			(xy 382.684528 -290.294314) (xy 382.684019 -290.3222) (xy 382.675899 -290.377376) (xy 382.659831 -290.430783)
			(xy 382.636159 -290.48128) (xy 382.605386 -290.527793) (xy 382.568169 -290.56933) (xy 382.525301 -290.605005)
			(xy 382.477695 -290.634059) (xy 382.426366 -290.655871) (xy 382.372409 -290.669977) (xy 382.328523 -290.674806)
			(xy 384.369068 -290.674806) (xy 384.373028 -290.625752) (xy 384.384805 -290.577968) (xy 384.404096 -290.532692)
			(xy 384.430399 -290.491096) (xy 384.463034 -290.454259) (xy 384.501155 -290.423134) (xy 384.543776 -290.398527)
			(xy 384.589792 -290.381075) (xy 384.638011 -290.371231) (xy 384.687186 -290.36925) (xy 384.736041 -290.375182)
			(xy 384.783312 -290.388874) (xy 384.827774 -290.409972) (xy 384.868277 -290.437928) (xy 384.90377 -290.47202)
			(xy 384.933335 -290.511364) (xy 384.956206 -290.554941) (xy 384.97179 -290.601622) (xy 384.979685 -290.650199)
			(xy 384.98018 -290.674806) (xy 385.319028 -290.674806) (xy 385.322988 -290.625752) (xy 385.334765 -290.577968)
			(xy 385.354056 -290.532692) (xy 385.380359 -290.491096) (xy 385.412994 -290.454259) (xy 385.451115 -290.423134)
			(xy 385.493736 -290.398527) (xy 385.539752 -290.381075) (xy 385.587971 -290.371231) (xy 385.637146 -290.36925)
			(xy 385.686001 -290.375182) (xy 385.733272 -290.388874) (xy 385.777734 -290.409972) (xy 385.818237 -290.437928)
			(xy 385.85373 -290.47202) (xy 385.883295 -290.511364) (xy 385.906166 -290.554941) (xy 385.92175 -290.601622)
			(xy 385.929645 -290.650199) (xy 385.93014 -290.674806) (xy 386.269242 -290.674806) (xy 386.273202 -290.625752)
			(xy 386.284979 -290.577968) (xy 386.30427 -290.532692) (xy 386.330573 -290.491096) (xy 386.363208 -290.454259)
			(xy 386.401329 -290.423134) (xy 386.44395 -290.398527) (xy 386.489966 -290.381075) (xy 386.538185 -290.371231)
			(xy 386.58736 -290.36925) (xy 386.636215 -290.375182) (xy 386.683486 -290.388874) (xy 386.727948 -290.409972)
			(xy 386.768451 -290.437928) (xy 386.803944 -290.47202) (xy 386.833509 -290.511364) (xy 386.85638 -290.554941)
			(xy 386.871964 -290.601622) (xy 386.879859 -290.650199) (xy 386.880354 -290.674806) (xy 389.119122 -290.674806)
			(xy 389.123082 -290.625752) (xy 389.134859 -290.577968) (xy 389.15415 -290.532692) (xy 389.180453 -290.491096)
			(xy 389.213088 -290.454259) (xy 389.251209 -290.423134) (xy 389.29383 -290.398527) (xy 389.339846 -290.381075)
			(xy 389.388065 -290.371231) (xy 389.43724 -290.36925) (xy 389.486095 -290.375182) (xy 389.533366 -290.388874)
			(xy 389.577828 -290.409972) (xy 389.618331 -290.437928) (xy 389.653824 -290.47202) (xy 389.683389 -290.511364)
			(xy 389.70626 -290.554941) (xy 389.721844 -290.601622) (xy 389.729739 -290.650199) (xy 389.730234 -290.674806)
			(xy 390.069082 -290.674806) (xy 390.073042 -290.625752) (xy 390.084819 -290.577968) (xy 390.10411 -290.532692)
			(xy 390.130413 -290.491096) (xy 390.163048 -290.454259) (xy 390.201169 -290.423134) (xy 390.24379 -290.398527)
			(xy 390.289806 -290.381075) (xy 390.338025 -290.371231) (xy 390.3872 -290.36925) (xy 390.436055 -290.375182)
			(xy 390.483326 -290.388874) (xy 390.527788 -290.409972) (xy 390.568291 -290.437928) (xy 390.603784 -290.47202)
			(xy 390.633349 -290.511364) (xy 390.65622 -290.554941) (xy 390.671804 -290.601622) (xy 390.679699 -290.650199)
			(xy 390.680194 -290.674806) (xy 391.019042 -290.674806) (xy 391.023002 -290.625752) (xy 391.034779 -290.577968)
			(xy 391.05407 -290.532692) (xy 391.080373 -290.491096) (xy 391.113008 -290.454259) (xy 391.151129 -290.423134)
			(xy 391.19375 -290.398527) (xy 391.239766 -290.381075) (xy 391.287985 -290.371231) (xy 391.33716 -290.36925)
			(xy 391.386015 -290.375182) (xy 391.433286 -290.388874) (xy 391.477748 -290.409972) (xy 391.518251 -290.437928)
			(xy 391.553744 -290.47202) (xy 391.583309 -290.511364) (xy 391.60618 -290.554941) (xy 391.621764 -290.601622)
			(xy 391.629659 -290.650199) (xy 391.630154 -290.674806) (xy 391.969002 -290.674806) (xy 391.972962 -290.625752)
			(xy 391.984739 -290.577968) (xy 392.00403 -290.532692) (xy 392.030333 -290.491096) (xy 392.062968 -290.454259)
			(xy 392.101089 -290.423134) (xy 392.14371 -290.398527) (xy 392.189726 -290.381075) (xy 392.237945 -290.371231)
			(xy 392.28712 -290.36925) (xy 392.335975 -290.375182) (xy 392.383246 -290.388874) (xy 392.427708 -290.409972)
			(xy 392.468211 -290.437928) (xy 392.503704 -290.47202) (xy 392.533269 -290.511364) (xy 392.55614 -290.554941)
			(xy 392.571724 -290.601622) (xy 392.579619 -290.650199) (xy 392.580114 -290.674806) (xy 392.919216 -290.674806)
			(xy 392.923176 -290.625752) (xy 392.934953 -290.577968) (xy 392.954244 -290.532692) (xy 392.980547 -290.491096)
			(xy 393.013182 -290.454259) (xy 393.051303 -290.423134) (xy 393.093924 -290.398527) (xy 393.13994 -290.381075)
			(xy 393.188159 -290.371231) (xy 393.237334 -290.36925) (xy 393.286189 -290.375182) (xy 393.33346 -290.388874)
			(xy 393.377922 -290.409972) (xy 393.418425 -290.437928) (xy 393.453918 -290.47202) (xy 393.483483 -290.511364)
			(xy 393.506354 -290.554941) (xy 393.521938 -290.601622) (xy 393.529833 -290.650199) (xy 393.530328 -290.674806)
			(xy 393.869176 -290.674806) (xy 393.873136 -290.625752) (xy 393.884913 -290.577968) (xy 393.904204 -290.532692)
			(xy 393.930507 -290.491096) (xy 393.963142 -290.454259) (xy 394.001263 -290.423134) (xy 394.043884 -290.398527)
			(xy 394.0899 -290.381075) (xy 394.138119 -290.371231) (xy 394.187294 -290.36925) (xy 394.236149 -290.375182)
			(xy 394.28342 -290.388874) (xy 394.327882 -290.409972) (xy 394.368385 -290.437928) (xy 394.403878 -290.47202)
			(xy 394.433443 -290.511364) (xy 394.456314 -290.554941) (xy 394.471898 -290.601622) (xy 394.479793 -290.650199)
			(xy 394.480288 -290.674806) (xy 394.819136 -290.674806) (xy 394.823096 -290.625752) (xy 394.834873 -290.577968)
			(xy 394.854164 -290.532692) (xy 394.880467 -290.491096) (xy 394.913102 -290.454259) (xy 394.951223 -290.423134)
			(xy 394.993844 -290.398527) (xy 395.03986 -290.381075) (xy 395.088079 -290.371231) (xy 395.137254 -290.36925)
			(xy 395.186109 -290.375182) (xy 395.23338 -290.388874) (xy 395.277842 -290.409972) (xy 395.318345 -290.437928)
			(xy 395.353838 -290.47202) (xy 395.383403 -290.511364) (xy 395.406274 -290.554941) (xy 395.421858 -290.601622)
			(xy 395.429753 -290.650199) (xy 395.430248 -290.674806) (xy 395.769096 -290.674806) (xy 395.773056 -290.625752)
			(xy 395.784833 -290.577968) (xy 395.804124 -290.532692) (xy 395.830427 -290.491096) (xy 395.863062 -290.454259)
			(xy 395.901183 -290.423134) (xy 395.943804 -290.398527) (xy 395.98982 -290.381075) (xy 396.038039 -290.371231)
			(xy 396.087214 -290.36925) (xy 396.136069 -290.375182) (xy 396.18334 -290.388874) (xy 396.227802 -290.409972)
			(xy 396.268305 -290.437928) (xy 396.303798 -290.47202) (xy 396.333363 -290.511364) (xy 396.356234 -290.554941)
			(xy 396.371818 -290.601622) (xy 396.379713 -290.650199) (xy 396.380208 -290.674806) (xy 397.669016 -290.674806)
			(xy 397.672976 -290.625752) (xy 397.684753 -290.577968) (xy 397.704044 -290.532692) (xy 397.730347 -290.491096)
			(xy 397.762982 -290.454259) (xy 397.801103 -290.423134) (xy 397.843724 -290.398527) (xy 397.88974 -290.381075)
			(xy 397.937959 -290.371231) (xy 397.987134 -290.36925) (xy 398.035989 -290.375182) (xy 398.08326 -290.388874)
			(xy 398.127722 -290.409972) (xy 398.168225 -290.437928) (xy 398.203718 -290.47202) (xy 398.233283 -290.511364)
			(xy 398.256154 -290.554941) (xy 398.271738 -290.601622) (xy 398.279633 -290.650199) (xy 398.280128 -290.674806)
			(xy 398.61923 -290.674806) (xy 398.62319 -290.625752) (xy 398.634967 -290.577968) (xy 398.654258 -290.532692)
			(xy 398.680561 -290.491096) (xy 398.713196 -290.454259) (xy 398.751317 -290.423134) (xy 398.793938 -290.398527)
			(xy 398.839954 -290.381075) (xy 398.888173 -290.371231) (xy 398.937348 -290.36925) (xy 398.986203 -290.375182)
			(xy 399.033474 -290.388874) (xy 399.077936 -290.409972) (xy 399.118439 -290.437928) (xy 399.153932 -290.47202)
			(xy 399.183497 -290.511364) (xy 399.206368 -290.554941) (xy 399.221952 -290.601622) (xy 399.229847 -290.650199)
			(xy 399.230342 -290.674806) (xy 399.56919 -290.674806) (xy 399.57315 -290.625752) (xy 399.584927 -290.577968)
			(xy 399.604218 -290.532692) (xy 399.630521 -290.491096) (xy 399.663156 -290.454259) (xy 399.701277 -290.423134)
			(xy 399.743898 -290.398527) (xy 399.789914 -290.381075) (xy 399.838133 -290.371231) (xy 399.887308 -290.36925)
			(xy 399.936163 -290.375182) (xy 399.983434 -290.388874) (xy 400.027896 -290.409972) (xy 400.068399 -290.437928)
			(xy 400.103892 -290.47202) (xy 400.133457 -290.511364) (xy 400.156328 -290.554941) (xy 400.171912 -290.601622)
			(xy 400.179807 -290.650199) (xy 400.180302 -290.674806) (xy 400.51915 -290.674806) (xy 400.52311 -290.625752)
			(xy 400.534887 -290.577968) (xy 400.554178 -290.532692) (xy 400.580481 -290.491096) (xy 400.613116 -290.454259)
			(xy 400.651237 -290.423134) (xy 400.693858 -290.398527) (xy 400.739874 -290.381075) (xy 400.788093 -290.371231)
			(xy 400.837268 -290.36925) (xy 400.886123 -290.375182) (xy 400.933394 -290.388874) (xy 400.977856 -290.409972)
			(xy 401.018359 -290.437928) (xy 401.053852 -290.47202) (xy 401.083417 -290.511364) (xy 401.106288 -290.554941)
			(xy 401.121872 -290.601622) (xy 401.129767 -290.650199) (xy 401.130262 -290.674806) (xy 401.46911 -290.674806)
			(xy 401.47307 -290.625752) (xy 401.484847 -290.577968) (xy 401.504138 -290.532692) (xy 401.530441 -290.491096)
			(xy 401.563076 -290.454259) (xy 401.601197 -290.423134) (xy 401.643818 -290.398527) (xy 401.689834 -290.381075)
			(xy 401.738053 -290.371231) (xy 401.787228 -290.36925) (xy 401.836083 -290.375182) (xy 401.883354 -290.388874)
			(xy 401.927816 -290.409972) (xy 401.968319 -290.437928) (xy 402.003812 -290.47202) (xy 402.033377 -290.511364)
			(xy 402.056248 -290.554941) (xy 402.071832 -290.601622) (xy 402.079727 -290.650199) (xy 402.080222 -290.674806)
			(xy 402.41907 -290.674806) (xy 402.42303 -290.625752) (xy 402.434807 -290.577968) (xy 402.454098 -290.532692)
			(xy 402.480401 -290.491096) (xy 402.513036 -290.454259) (xy 402.551157 -290.423134) (xy 402.593778 -290.398527)
			(xy 402.639794 -290.381075) (xy 402.688013 -290.371231) (xy 402.737188 -290.36925) (xy 402.786043 -290.375182)
			(xy 402.833314 -290.388874) (xy 402.877776 -290.409972) (xy 402.918279 -290.437928) (xy 402.953772 -290.47202)
			(xy 402.983337 -290.511364) (xy 403.006208 -290.554941) (xy 403.021792 -290.601622) (xy 403.029687 -290.650199)
			(xy 403.030182 -290.674806) (xy 403.36903 -290.674806) (xy 403.37299 -290.625752) (xy 403.384767 -290.577968)
			(xy 403.404058 -290.532692) (xy 403.430361 -290.491096) (xy 403.462996 -290.454259) (xy 403.501117 -290.423134)
			(xy 403.543738 -290.398527) (xy 403.589754 -290.381075) (xy 403.637973 -290.371231) (xy 403.687148 -290.36925)
			(xy 403.736003 -290.375182) (xy 403.783274 -290.388874) (xy 403.827736 -290.409972) (xy 403.868239 -290.437928)
			(xy 403.903732 -290.47202) (xy 403.933297 -290.511364) (xy 403.956168 -290.554941) (xy 403.971752 -290.601622)
			(xy 403.979647 -290.650199) (xy 403.980142 -290.674806) (xy 404.31899 -290.674806) (xy 404.32295 -290.625752)
			(xy 404.334727 -290.577968) (xy 404.354018 -290.532692) (xy 404.380321 -290.491096) (xy 404.412956 -290.454259)
			(xy 404.451077 -290.423134) (xy 404.493698 -290.398527) (xy 404.539714 -290.381075) (xy 404.587933 -290.371231)
			(xy 404.637108 -290.36925) (xy 404.685963 -290.375182) (xy 404.733234 -290.388874) (xy 404.777696 -290.409972)
			(xy 404.818199 -290.437928) (xy 404.853692 -290.47202) (xy 404.883257 -290.511364) (xy 404.906128 -290.554941)
			(xy 404.921712 -290.601622) (xy 404.929607 -290.650199) (xy 404.930102 -290.674806) (xy 405.269204 -290.674806)
			(xy 405.273164 -290.625752) (xy 405.284941 -290.577968) (xy 405.304232 -290.532692) (xy 405.330535 -290.491096)
			(xy 405.36317 -290.454259) (xy 405.401291 -290.423134) (xy 405.443912 -290.398527) (xy 405.489928 -290.381075)
			(xy 405.538147 -290.371231) (xy 405.587322 -290.36925) (xy 405.636177 -290.375182) (xy 405.683448 -290.388874)
			(xy 405.72791 -290.409972) (xy 405.768413 -290.437928) (xy 405.803906 -290.47202) (xy 405.833471 -290.511364)
			(xy 405.856342 -290.554941) (xy 405.871926 -290.601622) (xy 405.879821 -290.650199) (xy 405.880316 -290.674806)
			(xy 406.219164 -290.674806) (xy 406.223124 -290.625752) (xy 406.234901 -290.577968) (xy 406.254192 -290.532692)
			(xy 406.280495 -290.491096) (xy 406.31313 -290.454259) (xy 406.351251 -290.423134) (xy 406.393872 -290.398527)
			(xy 406.439888 -290.381075) (xy 406.488107 -290.371231) (xy 406.537282 -290.36925) (xy 406.586137 -290.375182)
			(xy 406.633408 -290.388874) (xy 406.67787 -290.409972) (xy 406.718373 -290.437928) (xy 406.753866 -290.47202)
			(xy 406.783431 -290.511364) (xy 406.806302 -290.554941) (xy 406.821886 -290.601622) (xy 406.829781 -290.650199)
			(xy 406.830276 -290.674806) (xy 408.119084 -290.674806) (xy 408.123044 -290.625752) (xy 408.134821 -290.577968)
			(xy 408.154112 -290.532692) (xy 408.180415 -290.491096) (xy 408.21305 -290.454259) (xy 408.251171 -290.423134)
			(xy 408.293792 -290.398527) (xy 408.339808 -290.381075) (xy 408.388027 -290.371231) (xy 408.437202 -290.36925)
			(xy 408.486057 -290.375182) (xy 408.533328 -290.388874) (xy 408.57779 -290.409972) (xy 408.618293 -290.437928)
			(xy 408.653786 -290.47202) (xy 408.683351 -290.511364) (xy 408.706222 -290.554941) (xy 408.721806 -290.601622)
			(xy 408.729701 -290.650199) (xy 408.730196 -290.674806) (xy 409.069044 -290.674806) (xy 409.073004 -290.625752)
			(xy 409.084781 -290.577968) (xy 409.104072 -290.532692) (xy 409.130375 -290.491096) (xy 409.16301 -290.454259)
			(xy 409.201131 -290.423134) (xy 409.243752 -290.398527) (xy 409.289768 -290.381075) (xy 409.337987 -290.371231)
			(xy 409.387162 -290.36925) (xy 409.436017 -290.375182) (xy 409.483288 -290.388874) (xy 409.52775 -290.409972)
			(xy 409.568253 -290.437928) (xy 409.603746 -290.47202) (xy 409.633311 -290.511364) (xy 409.656182 -290.554941)
			(xy 409.671766 -290.601622) (xy 409.679661 -290.650199) (xy 409.680156 -290.674806) (xy 410.019004 -290.674806)
			(xy 410.022964 -290.625752) (xy 410.034741 -290.577968) (xy 410.054032 -290.532692) (xy 410.080335 -290.491096)
			(xy 410.11297 -290.454259) (xy 410.151091 -290.423134) (xy 410.193712 -290.398527) (xy 410.239728 -290.381075)
			(xy 410.287947 -290.371231) (xy 410.337122 -290.36925) (xy 410.385977 -290.375182) (xy 410.433248 -290.388874)
			(xy 410.47771 -290.409972) (xy 410.518213 -290.437928) (xy 410.553706 -290.47202) (xy 410.583271 -290.511364)
			(xy 410.606142 -290.554941) (xy 410.621726 -290.601622) (xy 410.629621 -290.650199) (xy 410.630116 -290.674806)
			(xy 410.969218 -290.674806) (xy 410.973178 -290.625752) (xy 410.984955 -290.577968) (xy 411.004246 -290.532692)
			(xy 411.030549 -290.491096) (xy 411.063184 -290.454259) (xy 411.101305 -290.423134) (xy 411.143926 -290.398527)
			(xy 411.189942 -290.381075) (xy 411.238161 -290.371231) (xy 411.287336 -290.36925) (xy 411.336191 -290.375182)
			(xy 411.383462 -290.388874) (xy 411.427924 -290.409972) (xy 411.468427 -290.437928) (xy 411.50392 -290.47202)
			(xy 411.533485 -290.511364) (xy 411.556356 -290.554941) (xy 411.57194 -290.601622) (xy 411.579835 -290.650199)
			(xy 411.58033 -290.674806) (xy 411.919178 -290.674806) (xy 411.923138 -290.625752) (xy 411.934915 -290.577968)
			(xy 411.954206 -290.532692) (xy 411.980509 -290.491096) (xy 412.013144 -290.454259) (xy 412.051265 -290.423134)
			(xy 412.093886 -290.398527) (xy 412.139902 -290.381075) (xy 412.188121 -290.371231) (xy 412.237296 -290.36925)
			(xy 412.286151 -290.375182) (xy 412.333422 -290.388874) (xy 412.377884 -290.409972) (xy 412.418387 -290.437928)
			(xy 412.45388 -290.47202) (xy 412.483445 -290.511364) (xy 412.506316 -290.554941) (xy 412.5219 -290.601622)
			(xy 412.529795 -290.650199) (xy 412.53029 -290.674806) (xy 412.869138 -290.674806) (xy 412.873098 -290.625752)
			(xy 412.884875 -290.577968) (xy 412.904166 -290.532692) (xy 412.930469 -290.491096) (xy 412.963104 -290.454259)
			(xy 413.001225 -290.423134) (xy 413.043846 -290.398527) (xy 413.089862 -290.381075) (xy 413.138081 -290.371231)
			(xy 413.187256 -290.36925) (xy 413.236111 -290.375182) (xy 413.283382 -290.388874) (xy 413.327844 -290.409972)
			(xy 413.368347 -290.437928) (xy 413.40384 -290.47202) (xy 413.433405 -290.511364) (xy 413.456276 -290.554941)
			(xy 413.47186 -290.601622) (xy 413.479755 -290.650199) (xy 413.48025 -290.674806) (xy 413.819098 -290.674806)
			(xy 413.823058 -290.625752) (xy 413.834835 -290.577968) (xy 413.854126 -290.532692) (xy 413.880429 -290.491096)
			(xy 413.913064 -290.454259) (xy 413.951185 -290.423134) (xy 413.993806 -290.398527) (xy 414.039822 -290.381075)
			(xy 414.088041 -290.371231) (xy 414.137216 -290.36925) (xy 414.186071 -290.375182) (xy 414.233342 -290.388874)
			(xy 414.277804 -290.409972) (xy 414.318307 -290.437928) (xy 414.3538 -290.47202) (xy 414.383365 -290.511364)
			(xy 414.406236 -290.554941) (xy 414.42182 -290.601622) (xy 414.429715 -290.650199) (xy 414.43021 -290.674806)
			(xy 414.769058 -290.674806) (xy 414.773018 -290.625752) (xy 414.784795 -290.577968) (xy 414.804086 -290.532692)
			(xy 414.830389 -290.491096) (xy 414.863024 -290.454259) (xy 414.901145 -290.423134) (xy 414.943766 -290.398527)
			(xy 414.989782 -290.381075) (xy 415.038001 -290.371231) (xy 415.087176 -290.36925) (xy 415.136031 -290.375182)
			(xy 415.183302 -290.388874) (xy 415.227764 -290.409972) (xy 415.268267 -290.437928) (xy 415.30376 -290.47202)
			(xy 415.333325 -290.511364) (xy 415.356196 -290.554941) (xy 415.37178 -290.601622) (xy 415.379675 -290.650199)
			(xy 415.38017 -290.674806) (xy 415.719018 -290.674806) (xy 415.722978 -290.625752) (xy 415.734755 -290.577968)
			(xy 415.754046 -290.532692) (xy 415.780349 -290.491096) (xy 415.812984 -290.454259) (xy 415.851105 -290.423134)
			(xy 415.893726 -290.398527) (xy 415.939742 -290.381075) (xy 415.987961 -290.371231) (xy 416.037136 -290.36925)
			(xy 416.085991 -290.375182) (xy 416.133262 -290.388874) (xy 416.177724 -290.409972) (xy 416.218227 -290.437928)
			(xy 416.25372 -290.47202) (xy 416.283285 -290.511364) (xy 416.306156 -290.554941) (xy 416.32174 -290.601622)
			(xy 416.329635 -290.650199) (xy 416.33013 -290.674806) (xy 416.329635 -290.699413) (xy 416.32174 -290.74799)
			(xy 416.306156 -290.794671) (xy 416.283285 -290.838248) (xy 416.25372 -290.877592) (xy 416.218227 -290.911684)
			(xy 416.177724 -290.93964) (xy 416.133262 -290.960738) (xy 416.085991 -290.97443) (xy 416.037136 -290.980362)
			(xy 415.987961 -290.978381) (xy 415.939742 -290.968537) (xy 415.893726 -290.951085) (xy 415.851105 -290.926478)
			(xy 415.812984 -290.895353) (xy 415.780349 -290.858516) (xy 415.754046 -290.81692) (xy 415.734755 -290.771644)
			(xy 415.722978 -290.72386) (xy 415.719018 -290.674806) (xy 415.38017 -290.674806) (xy 415.379675 -290.699413)
			(xy 415.37178 -290.74799) (xy 415.356196 -290.794671) (xy 415.333325 -290.838248) (xy 415.30376 -290.877592)
			(xy 415.268267 -290.911684) (xy 415.227764 -290.93964) (xy 415.183302 -290.960738) (xy 415.136031 -290.97443)
			(xy 415.087176 -290.980362) (xy 415.038001 -290.978381) (xy 414.989782 -290.968537) (xy 414.943766 -290.951085)
			(xy 414.901145 -290.926478) (xy 414.863024 -290.895353) (xy 414.830389 -290.858516) (xy 414.804086 -290.81692)
			(xy 414.784795 -290.771644) (xy 414.773018 -290.72386) (xy 414.769058 -290.674806) (xy 414.43021 -290.674806)
			(xy 414.429715 -290.699413) (xy 414.42182 -290.74799) (xy 414.406236 -290.794671) (xy 414.383365 -290.838248)
			(xy 414.3538 -290.877592) (xy 414.318307 -290.911684) (xy 414.277804 -290.93964) (xy 414.233342 -290.960738)
			(xy 414.186071 -290.97443) (xy 414.137216 -290.980362) (xy 414.088041 -290.978381) (xy 414.039822 -290.968537)
			(xy 413.993806 -290.951085) (xy 413.951185 -290.926478) (xy 413.913064 -290.895353) (xy 413.880429 -290.858516)
			(xy 413.854126 -290.81692) (xy 413.834835 -290.771644) (xy 413.823058 -290.72386) (xy 413.819098 -290.674806)
			(xy 413.48025 -290.674806) (xy 413.479755 -290.699413) (xy 413.47186 -290.74799) (xy 413.456276 -290.794671)
			(xy 413.433405 -290.838248) (xy 413.40384 -290.877592) (xy 413.368347 -290.911684) (xy 413.327844 -290.93964)
			(xy 413.283382 -290.960738) (xy 413.236111 -290.97443) (xy 413.187256 -290.980362) (xy 413.138081 -290.978381)
			(xy 413.089862 -290.968537) (xy 413.043846 -290.951085) (xy 413.001225 -290.926478) (xy 412.963104 -290.895353)
			(xy 412.930469 -290.858516) (xy 412.904166 -290.81692) (xy 412.884875 -290.771644) (xy 412.873098 -290.72386)
			(xy 412.869138 -290.674806) (xy 412.53029 -290.674806) (xy 412.529795 -290.699413) (xy 412.5219 -290.74799)
			(xy 412.506316 -290.794671) (xy 412.483445 -290.838248) (xy 412.45388 -290.877592) (xy 412.418387 -290.911684)
			(xy 412.377884 -290.93964) (xy 412.333422 -290.960738) (xy 412.286151 -290.97443) (xy 412.237296 -290.980362)
			(xy 412.188121 -290.978381) (xy 412.139902 -290.968537) (xy 412.093886 -290.951085) (xy 412.051265 -290.926478)
			(xy 412.013144 -290.895353) (xy 411.980509 -290.858516) (xy 411.954206 -290.81692) (xy 411.934915 -290.771644)
			(xy 411.923138 -290.72386) (xy 411.919178 -290.674806) (xy 411.58033 -290.674806) (xy 411.579835 -290.699413)
			(xy 411.57194 -290.74799) (xy 411.556356 -290.794671) (xy 411.533485 -290.838248) (xy 411.50392 -290.877592)
			(xy 411.468427 -290.911684) (xy 411.427924 -290.93964) (xy 411.383462 -290.960738) (xy 411.336191 -290.97443)
			(xy 411.287336 -290.980362) (xy 411.238161 -290.978381) (xy 411.189942 -290.968537) (xy 411.143926 -290.951085)
			(xy 411.101305 -290.926478) (xy 411.063184 -290.895353) (xy 411.030549 -290.858516) (xy 411.004246 -290.81692)
			(xy 410.984955 -290.771644) (xy 410.973178 -290.72386) (xy 410.969218 -290.674806) (xy 410.630116 -290.674806)
			(xy 410.629621 -290.699413) (xy 410.621726 -290.74799) (xy 410.606142 -290.794671) (xy 410.583271 -290.838248)
			(xy 410.553706 -290.877592) (xy 410.518213 -290.911684) (xy 410.47771 -290.93964) (xy 410.433248 -290.960738)
			(xy 410.385977 -290.97443) (xy 410.337122 -290.980362) (xy 410.287947 -290.978381) (xy 410.239728 -290.968537)
			(xy 410.193712 -290.951085) (xy 410.151091 -290.926478) (xy 410.11297 -290.895353) (xy 410.080335 -290.858516)
			(xy 410.054032 -290.81692) (xy 410.034741 -290.771644) (xy 410.022964 -290.72386) (xy 410.019004 -290.674806)
			(xy 409.680156 -290.674806) (xy 409.679661 -290.699413) (xy 409.671766 -290.74799) (xy 409.656182 -290.794671)
			(xy 409.633311 -290.838248) (xy 409.603746 -290.877592) (xy 409.568253 -290.911684) (xy 409.52775 -290.93964)
			(xy 409.483288 -290.960738) (xy 409.436017 -290.97443) (xy 409.387162 -290.980362) (xy 409.337987 -290.978381)
			(xy 409.289768 -290.968537) (xy 409.243752 -290.951085) (xy 409.201131 -290.926478) (xy 409.16301 -290.895353)
			(xy 409.130375 -290.858516) (xy 409.104072 -290.81692) (xy 409.084781 -290.771644) (xy 409.073004 -290.72386)
			(xy 409.069044 -290.674806) (xy 408.730196 -290.674806) (xy 408.729701 -290.699413) (xy 408.721806 -290.74799)
			(xy 408.706222 -290.794671) (xy 408.683351 -290.838248) (xy 408.653786 -290.877592) (xy 408.618293 -290.911684)
			(xy 408.57779 -290.93964) (xy 408.533328 -290.960738) (xy 408.486057 -290.97443) (xy 408.437202 -290.980362)
			(xy 408.388027 -290.978381) (xy 408.339808 -290.968537) (xy 408.293792 -290.951085) (xy 408.251171 -290.926478)
			(xy 408.21305 -290.895353) (xy 408.180415 -290.858516) (xy 408.154112 -290.81692) (xy 408.134821 -290.771644)
			(xy 408.123044 -290.72386) (xy 408.119084 -290.674806) (xy 406.830276 -290.674806) (xy 406.829781 -290.699413)
			(xy 406.821886 -290.74799) (xy 406.806302 -290.794671) (xy 406.783431 -290.838248) (xy 406.753866 -290.877592)
			(xy 406.718373 -290.911684) (xy 406.67787 -290.93964) (xy 406.633408 -290.960738) (xy 406.586137 -290.97443)
			(xy 406.537282 -290.980362) (xy 406.488107 -290.978381) (xy 406.439888 -290.968537) (xy 406.393872 -290.951085)
			(xy 406.351251 -290.926478) (xy 406.31313 -290.895353) (xy 406.280495 -290.858516) (xy 406.254192 -290.81692)
			(xy 406.234901 -290.771644) (xy 406.223124 -290.72386) (xy 406.219164 -290.674806) (xy 405.880316 -290.674806)
			(xy 405.879821 -290.699413) (xy 405.871926 -290.74799) (xy 405.856342 -290.794671) (xy 405.833471 -290.838248)
			(xy 405.803906 -290.877592) (xy 405.768413 -290.911684) (xy 405.72791 -290.93964) (xy 405.683448 -290.960738)
			(xy 405.636177 -290.97443) (xy 405.587322 -290.980362) (xy 405.538147 -290.978381) (xy 405.489928 -290.968537)
			(xy 405.443912 -290.951085) (xy 405.401291 -290.926478) (xy 405.36317 -290.895353) (xy 405.330535 -290.858516)
			(xy 405.304232 -290.81692) (xy 405.284941 -290.771644) (xy 405.273164 -290.72386) (xy 405.269204 -290.674806)
			(xy 404.930102 -290.674806) (xy 404.929607 -290.699413) (xy 404.921712 -290.74799) (xy 404.906128 -290.794671)
			(xy 404.883257 -290.838248) (xy 404.853692 -290.877592) (xy 404.818199 -290.911684) (xy 404.777696 -290.93964)
			(xy 404.733234 -290.960738) (xy 404.685963 -290.97443) (xy 404.637108 -290.980362) (xy 404.587933 -290.978381)
			(xy 404.539714 -290.968537) (xy 404.493698 -290.951085) (xy 404.451077 -290.926478) (xy 404.412956 -290.895353)
			(xy 404.380321 -290.858516) (xy 404.354018 -290.81692) (xy 404.334727 -290.771644) (xy 404.32295 -290.72386)
			(xy 404.31899 -290.674806) (xy 403.980142 -290.674806) (xy 403.979647 -290.699413) (xy 403.971752 -290.74799)
			(xy 403.956168 -290.794671) (xy 403.933297 -290.838248) (xy 403.903732 -290.877592) (xy 403.868239 -290.911684)
			(xy 403.827736 -290.93964) (xy 403.783274 -290.960738) (xy 403.736003 -290.97443) (xy 403.687148 -290.980362)
			(xy 403.637973 -290.978381) (xy 403.589754 -290.968537) (xy 403.543738 -290.951085) (xy 403.501117 -290.926478)
			(xy 403.462996 -290.895353) (xy 403.430361 -290.858516) (xy 403.404058 -290.81692) (xy 403.384767 -290.771644)
			(xy 403.37299 -290.72386) (xy 403.36903 -290.674806) (xy 403.030182 -290.674806) (xy 403.029687 -290.699413)
			(xy 403.021792 -290.74799) (xy 403.006208 -290.794671) (xy 402.983337 -290.838248) (xy 402.953772 -290.877592)
			(xy 402.918279 -290.911684) (xy 402.877776 -290.93964) (xy 402.833314 -290.960738) (xy 402.786043 -290.97443)
			(xy 402.737188 -290.980362) (xy 402.688013 -290.978381) (xy 402.639794 -290.968537) (xy 402.593778 -290.951085)
			(xy 402.551157 -290.926478) (xy 402.513036 -290.895353) (xy 402.480401 -290.858516) (xy 402.454098 -290.81692)
			(xy 402.434807 -290.771644) (xy 402.42303 -290.72386) (xy 402.41907 -290.674806) (xy 402.080222 -290.674806)
			(xy 402.079727 -290.699413) (xy 402.071832 -290.74799) (xy 402.056248 -290.794671) (xy 402.033377 -290.838248)
			(xy 402.003812 -290.877592) (xy 401.968319 -290.911684) (xy 401.927816 -290.93964) (xy 401.883354 -290.960738)
			(xy 401.836083 -290.97443) (xy 401.787228 -290.980362) (xy 401.738053 -290.978381) (xy 401.689834 -290.968537)
			(xy 401.643818 -290.951085) (xy 401.601197 -290.926478) (xy 401.563076 -290.895353) (xy 401.530441 -290.858516)
			(xy 401.504138 -290.81692) (xy 401.484847 -290.771644) (xy 401.47307 -290.72386) (xy 401.46911 -290.674806)
			(xy 401.130262 -290.674806) (xy 401.129767 -290.699413) (xy 401.121872 -290.74799) (xy 401.106288 -290.794671)
			(xy 401.083417 -290.838248) (xy 401.053852 -290.877592) (xy 401.018359 -290.911684) (xy 400.977856 -290.93964)
			(xy 400.933394 -290.960738) (xy 400.886123 -290.97443) (xy 400.837268 -290.980362) (xy 400.788093 -290.978381)
			(xy 400.739874 -290.968537) (xy 400.693858 -290.951085) (xy 400.651237 -290.926478) (xy 400.613116 -290.895353)
			(xy 400.580481 -290.858516) (xy 400.554178 -290.81692) (xy 400.534887 -290.771644) (xy 400.52311 -290.72386)
			(xy 400.51915 -290.674806) (xy 400.180302 -290.674806) (xy 400.179807 -290.699413) (xy 400.171912 -290.74799)
			(xy 400.156328 -290.794671) (xy 400.133457 -290.838248) (xy 400.103892 -290.877592) (xy 400.068399 -290.911684)
			(xy 400.027896 -290.93964) (xy 399.983434 -290.960738) (xy 399.936163 -290.97443) (xy 399.887308 -290.980362)
			(xy 399.838133 -290.978381) (xy 399.789914 -290.968537) (xy 399.743898 -290.951085) (xy 399.701277 -290.926478)
			(xy 399.663156 -290.895353) (xy 399.630521 -290.858516) (xy 399.604218 -290.81692) (xy 399.584927 -290.771644)
			(xy 399.57315 -290.72386) (xy 399.56919 -290.674806) (xy 399.230342 -290.674806) (xy 399.229847 -290.699413)
			(xy 399.221952 -290.74799) (xy 399.206368 -290.794671) (xy 399.183497 -290.838248) (xy 399.153932 -290.877592)
			(xy 399.118439 -290.911684) (xy 399.077936 -290.93964) (xy 399.033474 -290.960738) (xy 398.986203 -290.97443)
			(xy 398.937348 -290.980362) (xy 398.888173 -290.978381) (xy 398.839954 -290.968537) (xy 398.793938 -290.951085)
			(xy 398.751317 -290.926478) (xy 398.713196 -290.895353) (xy 398.680561 -290.858516) (xy 398.654258 -290.81692)
			(xy 398.634967 -290.771644) (xy 398.62319 -290.72386) (xy 398.61923 -290.674806) (xy 398.280128 -290.674806)
			(xy 398.279633 -290.699413) (xy 398.271738 -290.74799) (xy 398.256154 -290.794671) (xy 398.233283 -290.838248)
			(xy 398.203718 -290.877592) (xy 398.168225 -290.911684) (xy 398.127722 -290.93964) (xy 398.08326 -290.960738)
			(xy 398.035989 -290.97443) (xy 397.987134 -290.980362) (xy 397.937959 -290.978381) (xy 397.88974 -290.968537)
			(xy 397.843724 -290.951085) (xy 397.801103 -290.926478) (xy 397.762982 -290.895353) (xy 397.730347 -290.858516)
			(xy 397.704044 -290.81692) (xy 397.684753 -290.771644) (xy 397.672976 -290.72386) (xy 397.669016 -290.674806)
			(xy 396.380208 -290.674806) (xy 396.379713 -290.699413) (xy 396.371818 -290.74799) (xy 396.356234 -290.794671)
			(xy 396.333363 -290.838248) (xy 396.303798 -290.877592) (xy 396.268305 -290.911684) (xy 396.227802 -290.93964)
			(xy 396.18334 -290.960738) (xy 396.136069 -290.97443) (xy 396.087214 -290.980362) (xy 396.038039 -290.978381)
			(xy 395.98982 -290.968537) (xy 395.943804 -290.951085) (xy 395.901183 -290.926478) (xy 395.863062 -290.895353)
			(xy 395.830427 -290.858516) (xy 395.804124 -290.81692) (xy 395.784833 -290.771644) (xy 395.773056 -290.72386)
			(xy 395.769096 -290.674806) (xy 395.430248 -290.674806) (xy 395.429753 -290.699413) (xy 395.421858 -290.74799)
			(xy 395.406274 -290.794671) (xy 395.383403 -290.838248) (xy 395.353838 -290.877592) (xy 395.318345 -290.911684)
			(xy 395.277842 -290.93964) (xy 395.23338 -290.960738) (xy 395.186109 -290.97443) (xy 395.137254 -290.980362)
			(xy 395.088079 -290.978381) (xy 395.03986 -290.968537) (xy 394.993844 -290.951085) (xy 394.951223 -290.926478)
			(xy 394.913102 -290.895353) (xy 394.880467 -290.858516) (xy 394.854164 -290.81692) (xy 394.834873 -290.771644)
			(xy 394.823096 -290.72386) (xy 394.819136 -290.674806) (xy 394.480288 -290.674806) (xy 394.479793 -290.699413)
			(xy 394.471898 -290.74799) (xy 394.456314 -290.794671) (xy 394.433443 -290.838248) (xy 394.403878 -290.877592)
			(xy 394.368385 -290.911684) (xy 394.327882 -290.93964) (xy 394.28342 -290.960738) (xy 394.236149 -290.97443)
			(xy 394.187294 -290.980362) (xy 394.138119 -290.978381) (xy 394.0899 -290.968537) (xy 394.043884 -290.951085)
			(xy 394.001263 -290.926478) (xy 393.963142 -290.895353) (xy 393.930507 -290.858516) (xy 393.904204 -290.81692)
			(xy 393.884913 -290.771644) (xy 393.873136 -290.72386) (xy 393.869176 -290.674806) (xy 393.530328 -290.674806)
			(xy 393.529833 -290.699413) (xy 393.521938 -290.74799) (xy 393.506354 -290.794671) (xy 393.483483 -290.838248)
			(xy 393.453918 -290.877592) (xy 393.418425 -290.911684) (xy 393.377922 -290.93964) (xy 393.33346 -290.960738)
			(xy 393.286189 -290.97443) (xy 393.237334 -290.980362) (xy 393.188159 -290.978381) (xy 393.13994 -290.968537)
			(xy 393.093924 -290.951085) (xy 393.051303 -290.926478) (xy 393.013182 -290.895353) (xy 392.980547 -290.858516)
			(xy 392.954244 -290.81692) (xy 392.934953 -290.771644) (xy 392.923176 -290.72386) (xy 392.919216 -290.674806)
			(xy 392.580114 -290.674806) (xy 392.579619 -290.699413) (xy 392.571724 -290.74799) (xy 392.55614 -290.794671)
			(xy 392.533269 -290.838248) (xy 392.503704 -290.877592) (xy 392.468211 -290.911684) (xy 392.427708 -290.93964)
			(xy 392.383246 -290.960738) (xy 392.335975 -290.97443) (xy 392.28712 -290.980362) (xy 392.237945 -290.978381)
			(xy 392.189726 -290.968537) (xy 392.14371 -290.951085) (xy 392.101089 -290.926478) (xy 392.062968 -290.895353)
			(xy 392.030333 -290.858516) (xy 392.00403 -290.81692) (xy 391.984739 -290.771644) (xy 391.972962 -290.72386)
			(xy 391.969002 -290.674806) (xy 391.630154 -290.674806) (xy 391.629659 -290.699413) (xy 391.621764 -290.74799)
			(xy 391.60618 -290.794671) (xy 391.583309 -290.838248) (xy 391.553744 -290.877592) (xy 391.518251 -290.911684)
			(xy 391.477748 -290.93964) (xy 391.433286 -290.960738) (xy 391.386015 -290.97443) (xy 391.33716 -290.980362)
			(xy 391.287985 -290.978381) (xy 391.239766 -290.968537) (xy 391.19375 -290.951085) (xy 391.151129 -290.926478)
			(xy 391.113008 -290.895353) (xy 391.080373 -290.858516) (xy 391.05407 -290.81692) (xy 391.034779 -290.771644)
			(xy 391.023002 -290.72386) (xy 391.019042 -290.674806) (xy 390.680194 -290.674806) (xy 390.679699 -290.699413)
			(xy 390.671804 -290.74799) (xy 390.65622 -290.794671) (xy 390.633349 -290.838248) (xy 390.603784 -290.877592)
			(xy 390.568291 -290.911684) (xy 390.527788 -290.93964) (xy 390.483326 -290.960738) (xy 390.436055 -290.97443)
			(xy 390.3872 -290.980362) (xy 390.338025 -290.978381) (xy 390.289806 -290.968537) (xy 390.24379 -290.951085)
			(xy 390.201169 -290.926478) (xy 390.163048 -290.895353) (xy 390.130413 -290.858516) (xy 390.10411 -290.81692)
			(xy 390.084819 -290.771644) (xy 390.073042 -290.72386) (xy 390.069082 -290.674806) (xy 389.730234 -290.674806)
			(xy 389.729739 -290.699413) (xy 389.721844 -290.74799) (xy 389.70626 -290.794671) (xy 389.683389 -290.838248)
			(xy 389.653824 -290.877592) (xy 389.618331 -290.911684) (xy 389.577828 -290.93964) (xy 389.533366 -290.960738)
			(xy 389.486095 -290.97443) (xy 389.43724 -290.980362) (xy 389.388065 -290.978381) (xy 389.339846 -290.968537)
			(xy 389.29383 -290.951085) (xy 389.251209 -290.926478) (xy 389.213088 -290.895353) (xy 389.180453 -290.858516)
			(xy 389.15415 -290.81692) (xy 389.134859 -290.771644) (xy 389.123082 -290.72386) (xy 389.119122 -290.674806)
			(xy 386.880354 -290.674806) (xy 386.879859 -290.699413) (xy 386.871964 -290.74799) (xy 386.85638 -290.794671)
			(xy 386.833509 -290.838248) (xy 386.803944 -290.877592) (xy 386.768451 -290.911684) (xy 386.727948 -290.93964)
			(xy 386.683486 -290.960738) (xy 386.636215 -290.97443) (xy 386.58736 -290.980362) (xy 386.538185 -290.978381)
			(xy 386.489966 -290.968537) (xy 386.44395 -290.951085) (xy 386.401329 -290.926478) (xy 386.363208 -290.895353)
			(xy 386.330573 -290.858516) (xy 386.30427 -290.81692) (xy 386.284979 -290.771644) (xy 386.273202 -290.72386)
			(xy 386.269242 -290.674806) (xy 385.93014 -290.674806) (xy 385.929645 -290.699413) (xy 385.92175 -290.74799)
			(xy 385.906166 -290.794671) (xy 385.883295 -290.838248) (xy 385.85373 -290.877592) (xy 385.818237 -290.911684)
			(xy 385.777734 -290.93964) (xy 385.733272 -290.960738) (xy 385.686001 -290.97443) (xy 385.637146 -290.980362)
			(xy 385.587971 -290.978381) (xy 385.539752 -290.968537) (xy 385.493736 -290.951085) (xy 385.451115 -290.926478)
			(xy 385.412994 -290.895353) (xy 385.380359 -290.858516) (xy 385.354056 -290.81692) (xy 385.334765 -290.771644)
			(xy 385.322988 -290.72386) (xy 385.319028 -290.674806) (xy 384.98018 -290.674806) (xy 384.979685 -290.699413)
			(xy 384.97179 -290.74799) (xy 384.956206 -290.794671) (xy 384.933335 -290.838248) (xy 384.90377 -290.877592)
			(xy 384.868277 -290.911684) (xy 384.827774 -290.93964) (xy 384.783312 -290.960738) (xy 384.736041 -290.97443)
			(xy 384.687186 -290.980362) (xy 384.638011 -290.978381) (xy 384.589792 -290.968537) (xy 384.543776 -290.951085)
			(xy 384.501155 -290.926478) (xy 384.463034 -290.895353) (xy 384.430399 -290.858516) (xy 384.404096 -290.81692)
			(xy 384.384805 -290.771644) (xy 384.373028 -290.72386) (xy 384.369068 -290.674806) (xy 382.328523 -290.674806)
			(xy 382.316972 -290.676077) (xy 382.261238 -290.67404) (xy 382.206395 -290.66391) (xy 382.153611 -290.645903)
			(xy 382.104011 -290.620402) (xy 382.058653 -290.587951) (xy 382.018504 -290.549242) (xy 381.984418 -290.505099)
			(xy 381.957122 -290.456464) (xy 381.937199 -290.404373) (xy 381.925073 -290.349936) (xy 381.921002 -290.294314)
			(xy 381.798068 -290.294314) (xy 381.797559 -290.3222) (xy 381.789439 -290.377376) (xy 381.773371 -290.430783)
			(xy 381.749699 -290.48128) (xy 381.718926 -290.527793) (xy 381.681709 -290.56933) (xy 381.638841 -290.605005)
			(xy 381.591235 -290.634059) (xy 381.539906 -290.655871) (xy 381.485949 -290.669977) (xy 381.430512 -290.676077)
			(xy 381.374778 -290.67404) (xy 381.319935 -290.66391) (xy 381.267151 -290.645903) (xy 381.217551 -290.620402)
			(xy 381.172193 -290.587951) (xy 381.132044 -290.549242) (xy 381.097958 -290.505099) (xy 381.070662 -290.456464)
			(xy 381.050739 -290.404373) (xy 381.038613 -290.349936) (xy 381.034542 -290.294314) (xy 380.401068 -290.294314)
			(xy 380.400582 -290.321565) (xy 380.392826 -290.375513) (xy 380.377471 -290.427808) (xy 380.354829 -290.477385)
			(xy 380.325363 -290.523235) (xy 380.289672 -290.564426) (xy 380.248481 -290.600117) (xy 380.202631 -290.629583)
			(xy 380.153054 -290.652225) (xy 380.100759 -290.66758) (xy 380.046811 -290.675336) (xy 379.992309 -290.675336)
			(xy 379.938361 -290.66758) (xy 379.886066 -290.652225) (xy 379.836489 -290.629583) (xy 379.790639 -290.600117)
			(xy 379.749448 -290.564426) (xy 379.713757 -290.523235) (xy 379.684291 -290.477385) (xy 379.661649 -290.427808)
			(xy 379.646294 -290.375513) (xy 379.638538 -290.321565) (xy 379.638052 -290.294314) (xy 368.55019 -290.294314)
			(xy 368.55019 -291.430456) (xy 374.111518 -291.430456) (xy 374.115589 -291.374834) (xy 374.127715 -291.320397)
			(xy 374.147638 -291.268306) (xy 374.174934 -291.219671) (xy 374.20902 -291.175528) (xy 374.249169 -291.136819)
			(xy 374.294527 -291.104368) (xy 374.344127 -291.078867) (xy 374.396911 -291.06086) (xy 374.451754 -291.05073)
			(xy 374.507488 -291.048693) (xy 374.562925 -291.054793) (xy 374.616882 -291.068899) (xy 374.668211 -291.090711)
			(xy 374.715817 -291.119765) (xy 374.758685 -291.15544) (xy 374.795902 -291.196977) (xy 374.826675 -291.24349)
			(xy 374.850347 -291.293987) (xy 374.866415 -291.347394) (xy 374.874535 -291.40257) (xy 374.875044 -291.430456)
			(xy 375.596656 -291.430456) (xy 375.600727 -291.374834) (xy 375.612853 -291.320397) (xy 375.632776 -291.268306)
			(xy 375.660072 -291.219671) (xy 375.694158 -291.175528) (xy 375.734307 -291.136819) (xy 375.779665 -291.104368)
			(xy 375.829265 -291.078867) (xy 375.882049 -291.06086) (xy 375.936892 -291.05073) (xy 375.992626 -291.048693)
			(xy 376.048063 -291.054793) (xy 376.10202 -291.068899) (xy 376.153349 -291.090711) (xy 376.200955 -291.119765)
			(xy 376.243823 -291.15544) (xy 376.28104 -291.196977) (xy 376.311813 -291.24349) (xy 376.335485 -291.293987)
			(xy 376.351553 -291.347394) (xy 376.359673 -291.40257) (xy 376.360182 -291.430456) (xy 376.359673 -291.458342)
			(xy 376.351553 -291.513518) (xy 376.335485 -291.566925) (xy 376.311813 -291.617422) (xy 376.306954 -291.624766)
			(xy 384.369068 -291.624766) (xy 384.373028 -291.575712) (xy 384.384805 -291.527928) (xy 384.404096 -291.482652)
			(xy 384.430399 -291.441056) (xy 384.463034 -291.404219) (xy 384.501155 -291.373094) (xy 384.543776 -291.348487)
			(xy 384.589792 -291.331035) (xy 384.638011 -291.321191) (xy 384.687186 -291.31921) (xy 384.736041 -291.325142)
			(xy 384.783312 -291.338834) (xy 384.827774 -291.359932) (xy 384.868277 -291.387888) (xy 384.90377 -291.42198)
			(xy 384.933335 -291.461324) (xy 384.956206 -291.504901) (xy 384.97179 -291.551582) (xy 384.979685 -291.600159)
			(xy 384.98018 -291.624766) (xy 385.319028 -291.624766) (xy 385.322988 -291.575712) (xy 385.334765 -291.527928)
			(xy 385.354056 -291.482652) (xy 385.380359 -291.441056) (xy 385.412994 -291.404219) (xy 385.451115 -291.373094)
			(xy 385.493736 -291.348487) (xy 385.539752 -291.331035) (xy 385.587971 -291.321191) (xy 385.637146 -291.31921)
			(xy 385.686001 -291.325142) (xy 385.733272 -291.338834) (xy 385.777734 -291.359932) (xy 385.818237 -291.387888)
			(xy 385.85373 -291.42198) (xy 385.883295 -291.461324) (xy 385.906166 -291.504901) (xy 385.92175 -291.551582)
			(xy 385.929645 -291.600159) (xy 385.93014 -291.624766) (xy 386.269242 -291.624766) (xy 386.273202 -291.575712)
			(xy 386.284979 -291.527928) (xy 386.30427 -291.482652) (xy 386.330573 -291.441056) (xy 386.363208 -291.404219)
			(xy 386.401329 -291.373094) (xy 386.44395 -291.348487) (xy 386.489966 -291.331035) (xy 386.538185 -291.321191)
			(xy 386.58736 -291.31921) (xy 386.636215 -291.325142) (xy 386.683486 -291.338834) (xy 386.727948 -291.359932)
			(xy 386.768451 -291.387888) (xy 386.803944 -291.42198) (xy 386.833509 -291.461324) (xy 386.85638 -291.504901)
			(xy 386.871964 -291.551582) (xy 386.879859 -291.600159) (xy 386.880354 -291.624766) (xy 389.119122 -291.624766)
			(xy 389.123082 -291.575712) (xy 389.134859 -291.527928) (xy 389.15415 -291.482652) (xy 389.180453 -291.441056)
			(xy 389.213088 -291.404219) (xy 389.251209 -291.373094) (xy 389.29383 -291.348487) (xy 389.339846 -291.331035)
			(xy 389.388065 -291.321191) (xy 389.43724 -291.31921) (xy 389.486095 -291.325142) (xy 389.533366 -291.338834)
			(xy 389.577828 -291.359932) (xy 389.618331 -291.387888) (xy 389.653824 -291.42198) (xy 389.683389 -291.461324)
			(xy 389.70626 -291.504901) (xy 389.721844 -291.551582) (xy 389.729739 -291.600159) (xy 389.730234 -291.624766)
			(xy 390.069082 -291.624766) (xy 390.073042 -291.575712) (xy 390.084819 -291.527928) (xy 390.10411 -291.482652)
			(xy 390.130413 -291.441056) (xy 390.163048 -291.404219) (xy 390.201169 -291.373094) (xy 390.24379 -291.348487)
			(xy 390.289806 -291.331035) (xy 390.338025 -291.321191) (xy 390.3872 -291.31921) (xy 390.436055 -291.325142)
			(xy 390.483326 -291.338834) (xy 390.527788 -291.359932) (xy 390.568291 -291.387888) (xy 390.603784 -291.42198)
			(xy 390.633349 -291.461324) (xy 390.65622 -291.504901) (xy 390.671804 -291.551582) (xy 390.679699 -291.600159)
			(xy 390.680194 -291.624766) (xy 391.019042 -291.624766) (xy 391.023002 -291.575712) (xy 391.034779 -291.527928)
			(xy 391.05407 -291.482652) (xy 391.080373 -291.441056) (xy 391.113008 -291.404219) (xy 391.151129 -291.373094)
			(xy 391.19375 -291.348487) (xy 391.239766 -291.331035) (xy 391.287985 -291.321191) (xy 391.33716 -291.31921)
			(xy 391.386015 -291.325142) (xy 391.433286 -291.338834) (xy 391.477748 -291.359932) (xy 391.518251 -291.387888)
			(xy 391.553744 -291.42198) (xy 391.583309 -291.461324) (xy 391.60618 -291.504901) (xy 391.621764 -291.551582)
			(xy 391.629659 -291.600159) (xy 391.630154 -291.624766) (xy 391.969002 -291.624766) (xy 391.972962 -291.575712)
			(xy 391.984739 -291.527928) (xy 392.00403 -291.482652) (xy 392.030333 -291.441056) (xy 392.062968 -291.404219)
			(xy 392.101089 -291.373094) (xy 392.14371 -291.348487) (xy 392.189726 -291.331035) (xy 392.237945 -291.321191)
			(xy 392.28712 -291.31921) (xy 392.335975 -291.325142) (xy 392.383246 -291.338834) (xy 392.427708 -291.359932)
			(xy 392.468211 -291.387888) (xy 392.503704 -291.42198) (xy 392.533269 -291.461324) (xy 392.55614 -291.504901)
			(xy 392.571724 -291.551582) (xy 392.579619 -291.600159) (xy 392.580114 -291.624766) (xy 392.919216 -291.624766)
			(xy 392.923176 -291.575712) (xy 392.934953 -291.527928) (xy 392.954244 -291.482652) (xy 392.980547 -291.441056)
			(xy 393.013182 -291.404219) (xy 393.051303 -291.373094) (xy 393.093924 -291.348487) (xy 393.13994 -291.331035)
			(xy 393.188159 -291.321191) (xy 393.237334 -291.31921) (xy 393.286189 -291.325142) (xy 393.33346 -291.338834)
			(xy 393.377922 -291.359932) (xy 393.418425 -291.387888) (xy 393.453918 -291.42198) (xy 393.483483 -291.461324)
			(xy 393.506354 -291.504901) (xy 393.521938 -291.551582) (xy 393.529833 -291.600159) (xy 393.530328 -291.624766)
			(xy 393.869176 -291.624766) (xy 393.873136 -291.575712) (xy 393.884913 -291.527928) (xy 393.904204 -291.482652)
			(xy 393.930507 -291.441056) (xy 393.963142 -291.404219) (xy 394.001263 -291.373094) (xy 394.043884 -291.348487)
			(xy 394.0899 -291.331035) (xy 394.138119 -291.321191) (xy 394.187294 -291.31921) (xy 394.236149 -291.325142)
			(xy 394.28342 -291.338834) (xy 394.327882 -291.359932) (xy 394.368385 -291.387888) (xy 394.403878 -291.42198)
			(xy 394.433443 -291.461324) (xy 394.456314 -291.504901) (xy 394.471898 -291.551582) (xy 394.479793 -291.600159)
			(xy 394.480288 -291.624766) (xy 395.769096 -291.624766) (xy 395.773056 -291.575712) (xy 395.784833 -291.527928)
			(xy 395.804124 -291.482652) (xy 395.830427 -291.441056) (xy 395.863062 -291.404219) (xy 395.901183 -291.373094)
			(xy 395.943804 -291.348487) (xy 395.98982 -291.331035) (xy 396.038039 -291.321191) (xy 396.087214 -291.31921)
			(xy 396.136069 -291.325142) (xy 396.18334 -291.338834) (xy 396.227802 -291.359932) (xy 396.268305 -291.387888)
			(xy 396.303798 -291.42198) (xy 396.333363 -291.461324) (xy 396.356234 -291.504901) (xy 396.371818 -291.551582)
			(xy 396.379713 -291.600159) (xy 396.380208 -291.624766) (xy 396.719056 -291.624766) (xy 396.723016 -291.575712)
			(xy 396.734793 -291.527928) (xy 396.754084 -291.482652) (xy 396.780387 -291.441056) (xy 396.813022 -291.404219)
			(xy 396.851143 -291.373094) (xy 396.893764 -291.348487) (xy 396.93978 -291.331035) (xy 396.987999 -291.321191)
			(xy 397.037174 -291.31921) (xy 397.086029 -291.325142) (xy 397.1333 -291.338834) (xy 397.177762 -291.359932)
			(xy 397.218265 -291.387888) (xy 397.253758 -291.42198) (xy 397.283323 -291.461324) (xy 397.306194 -291.504901)
			(xy 397.321778 -291.551582) (xy 397.329673 -291.600159) (xy 397.330168 -291.624766) (xy 398.61923 -291.624766)
			(xy 398.62319 -291.575712) (xy 398.634967 -291.527928) (xy 398.654258 -291.482652) (xy 398.680561 -291.441056)
			(xy 398.713196 -291.404219) (xy 398.751317 -291.373094) (xy 398.793938 -291.348487) (xy 398.839954 -291.331035)
			(xy 398.888173 -291.321191) (xy 398.937348 -291.31921) (xy 398.986203 -291.325142) (xy 399.033474 -291.338834)
			(xy 399.077936 -291.359932) (xy 399.118439 -291.387888) (xy 399.153932 -291.42198) (xy 399.183497 -291.461324)
			(xy 399.206368 -291.504901) (xy 399.221952 -291.551582) (xy 399.229847 -291.600159) (xy 399.230342 -291.624766)
			(xy 399.56919 -291.624766) (xy 399.57315 -291.575712) (xy 399.584927 -291.527928) (xy 399.604218 -291.482652)
			(xy 399.630521 -291.441056) (xy 399.663156 -291.404219) (xy 399.701277 -291.373094) (xy 399.743898 -291.348487)
			(xy 399.789914 -291.331035) (xy 399.838133 -291.321191) (xy 399.887308 -291.31921) (xy 399.936163 -291.325142)
			(xy 399.983434 -291.338834) (xy 400.027896 -291.359932) (xy 400.068399 -291.387888) (xy 400.103892 -291.42198)
			(xy 400.133457 -291.461324) (xy 400.156328 -291.504901) (xy 400.171912 -291.551582) (xy 400.179807 -291.600159)
			(xy 400.180302 -291.624766) (xy 400.51915 -291.624766) (xy 400.52311 -291.575712) (xy 400.534887 -291.527928)
			(xy 400.554178 -291.482652) (xy 400.580481 -291.441056) (xy 400.613116 -291.404219) (xy 400.651237 -291.373094)
			(xy 400.693858 -291.348487) (xy 400.739874 -291.331035) (xy 400.788093 -291.321191) (xy 400.837268 -291.31921)
			(xy 400.886123 -291.325142) (xy 400.933394 -291.338834) (xy 400.977856 -291.359932) (xy 401.018359 -291.387888)
			(xy 401.053852 -291.42198) (xy 401.083417 -291.461324) (xy 401.106288 -291.504901) (xy 401.121872 -291.551582)
			(xy 401.129767 -291.600159) (xy 401.130262 -291.624766) (xy 401.46911 -291.624766) (xy 401.47307 -291.575712)
			(xy 401.484847 -291.527928) (xy 401.504138 -291.482652) (xy 401.530441 -291.441056) (xy 401.563076 -291.404219)
			(xy 401.601197 -291.373094) (xy 401.643818 -291.348487) (xy 401.689834 -291.331035) (xy 401.738053 -291.321191)
			(xy 401.787228 -291.31921) (xy 401.836083 -291.325142) (xy 401.883354 -291.338834) (xy 401.927816 -291.359932)
			(xy 401.968319 -291.387888) (xy 402.003812 -291.42198) (xy 402.033377 -291.461324) (xy 402.056248 -291.504901)
			(xy 402.071832 -291.551582) (xy 402.079727 -291.600159) (xy 402.080222 -291.624766) (xy 402.41907 -291.624766)
			(xy 402.42303 -291.575712) (xy 402.434807 -291.527928) (xy 402.454098 -291.482652) (xy 402.480401 -291.441056)
			(xy 402.513036 -291.404219) (xy 402.551157 -291.373094) (xy 402.593778 -291.348487) (xy 402.639794 -291.331035)
			(xy 402.688013 -291.321191) (xy 402.737188 -291.31921) (xy 402.786043 -291.325142) (xy 402.833314 -291.338834)
			(xy 402.877776 -291.359932) (xy 402.918279 -291.387888) (xy 402.953772 -291.42198) (xy 402.983337 -291.461324)
			(xy 403.006208 -291.504901) (xy 403.021792 -291.551582) (xy 403.029687 -291.600159) (xy 403.030182 -291.624766)
			(xy 403.36903 -291.624766) (xy 403.37299 -291.575712) (xy 403.384767 -291.527928) (xy 403.404058 -291.482652)
			(xy 403.430361 -291.441056) (xy 403.462996 -291.404219) (xy 403.501117 -291.373094) (xy 403.543738 -291.348487)
			(xy 403.589754 -291.331035) (xy 403.637973 -291.321191) (xy 403.687148 -291.31921) (xy 403.736003 -291.325142)
			(xy 403.783274 -291.338834) (xy 403.827736 -291.359932) (xy 403.868239 -291.387888) (xy 403.903732 -291.42198)
			(xy 403.933297 -291.461324) (xy 403.956168 -291.504901) (xy 403.971752 -291.551582) (xy 403.979647 -291.600159)
			(xy 403.980142 -291.624766) (xy 404.31899 -291.624766) (xy 404.32295 -291.575712) (xy 404.334727 -291.527928)
			(xy 404.354018 -291.482652) (xy 404.380321 -291.441056) (xy 404.412956 -291.404219) (xy 404.451077 -291.373094)
			(xy 404.493698 -291.348487) (xy 404.539714 -291.331035) (xy 404.587933 -291.321191) (xy 404.637108 -291.31921)
			(xy 404.685963 -291.325142) (xy 404.733234 -291.338834) (xy 404.777696 -291.359932) (xy 404.818199 -291.387888)
			(xy 404.853692 -291.42198) (xy 404.883257 -291.461324) (xy 404.906128 -291.504901) (xy 404.921712 -291.551582)
			(xy 404.929607 -291.600159) (xy 404.930102 -291.624766) (xy 405.269204 -291.624766) (xy 405.273164 -291.575712)
			(xy 405.284941 -291.527928) (xy 405.304232 -291.482652) (xy 405.330535 -291.441056) (xy 405.36317 -291.404219)
			(xy 405.401291 -291.373094) (xy 405.443912 -291.348487) (xy 405.489928 -291.331035) (xy 405.538147 -291.321191)
			(xy 405.587322 -291.31921) (xy 405.636177 -291.325142) (xy 405.683448 -291.338834) (xy 405.72791 -291.359932)
			(xy 405.768413 -291.387888) (xy 405.803906 -291.42198) (xy 405.833471 -291.461324) (xy 405.856342 -291.504901)
			(xy 405.871926 -291.551582) (xy 405.879821 -291.600159) (xy 405.880316 -291.624766) (xy 406.219164 -291.624766)
			(xy 406.223124 -291.575712) (xy 406.234901 -291.527928) (xy 406.254192 -291.482652) (xy 406.280495 -291.441056)
			(xy 406.31313 -291.404219) (xy 406.351251 -291.373094) (xy 406.393872 -291.348487) (xy 406.439888 -291.331035)
			(xy 406.488107 -291.321191) (xy 406.537282 -291.31921) (xy 406.586137 -291.325142) (xy 406.633408 -291.338834)
			(xy 406.67787 -291.359932) (xy 406.718373 -291.387888) (xy 406.753866 -291.42198) (xy 406.783431 -291.461324)
			(xy 406.806302 -291.504901) (xy 406.821886 -291.551582) (xy 406.829781 -291.600159) (xy 406.830276 -291.624766)
			(xy 408.119084 -291.624766) (xy 408.123044 -291.575712) (xy 408.134821 -291.527928) (xy 408.154112 -291.482652)
			(xy 408.180415 -291.441056) (xy 408.21305 -291.404219) (xy 408.251171 -291.373094) (xy 408.293792 -291.348487)
			(xy 408.339808 -291.331035) (xy 408.388027 -291.321191) (xy 408.437202 -291.31921) (xy 408.486057 -291.325142)
			(xy 408.533328 -291.338834) (xy 408.57779 -291.359932) (xy 408.618293 -291.387888) (xy 408.653786 -291.42198)
			(xy 408.683351 -291.461324) (xy 408.706222 -291.504901) (xy 408.721806 -291.551582) (xy 408.729701 -291.600159)
			(xy 408.730196 -291.624766) (xy 409.069044 -291.624766) (xy 409.073004 -291.575712) (xy 409.084781 -291.527928)
			(xy 409.104072 -291.482652) (xy 409.130375 -291.441056) (xy 409.16301 -291.404219) (xy 409.201131 -291.373094)
			(xy 409.243752 -291.348487) (xy 409.289768 -291.331035) (xy 409.337987 -291.321191) (xy 409.387162 -291.31921)
			(xy 409.436017 -291.325142) (xy 409.483288 -291.338834) (xy 409.52775 -291.359932) (xy 409.568253 -291.387888)
			(xy 409.603746 -291.42198) (xy 409.633311 -291.461324) (xy 409.656182 -291.504901) (xy 409.671766 -291.551582)
			(xy 409.679661 -291.600159) (xy 409.680156 -291.624766) (xy 410.019004 -291.624766) (xy 410.022964 -291.575712)
			(xy 410.034741 -291.527928) (xy 410.054032 -291.482652) (xy 410.080335 -291.441056) (xy 410.11297 -291.404219)
			(xy 410.151091 -291.373094) (xy 410.193712 -291.348487) (xy 410.239728 -291.331035) (xy 410.287947 -291.321191)
			(xy 410.337122 -291.31921) (xy 410.385977 -291.325142) (xy 410.433248 -291.338834) (xy 410.47771 -291.359932)
			(xy 410.518213 -291.387888) (xy 410.553706 -291.42198) (xy 410.583271 -291.461324) (xy 410.606142 -291.504901)
			(xy 410.621726 -291.551582) (xy 410.629621 -291.600159) (xy 410.630116 -291.624766) (xy 410.969218 -291.624766)
			(xy 410.973178 -291.575712) (xy 410.984955 -291.527928) (xy 411.004246 -291.482652) (xy 411.030549 -291.441056)
			(xy 411.063184 -291.404219) (xy 411.101305 -291.373094) (xy 411.143926 -291.348487) (xy 411.189942 -291.331035)
			(xy 411.238161 -291.321191) (xy 411.287336 -291.31921) (xy 411.336191 -291.325142) (xy 411.383462 -291.338834)
			(xy 411.427924 -291.359932) (xy 411.468427 -291.387888) (xy 411.50392 -291.42198) (xy 411.533485 -291.461324)
			(xy 411.556356 -291.504901) (xy 411.57194 -291.551582) (xy 411.579835 -291.600159) (xy 411.58033 -291.624766)
			(xy 411.919178 -291.624766) (xy 411.923138 -291.575712) (xy 411.934915 -291.527928) (xy 411.954206 -291.482652)
			(xy 411.980509 -291.441056) (xy 412.013144 -291.404219) (xy 412.051265 -291.373094) (xy 412.093886 -291.348487)
			(xy 412.139902 -291.331035) (xy 412.188121 -291.321191) (xy 412.237296 -291.31921) (xy 412.286151 -291.325142)
			(xy 412.333422 -291.338834) (xy 412.377884 -291.359932) (xy 412.418387 -291.387888) (xy 412.45388 -291.42198)
			(xy 412.483445 -291.461324) (xy 412.506316 -291.504901) (xy 412.5219 -291.551582) (xy 412.529795 -291.600159)
			(xy 412.53029 -291.624766) (xy 412.869138 -291.624766) (xy 412.873098 -291.575712) (xy 412.884875 -291.527928)
			(xy 412.904166 -291.482652) (xy 412.930469 -291.441056) (xy 412.963104 -291.404219) (xy 413.001225 -291.373094)
			(xy 413.043846 -291.348487) (xy 413.089862 -291.331035) (xy 413.138081 -291.321191) (xy 413.187256 -291.31921)
			(xy 413.236111 -291.325142) (xy 413.283382 -291.338834) (xy 413.327844 -291.359932) (xy 413.368347 -291.387888)
			(xy 413.40384 -291.42198) (xy 413.433405 -291.461324) (xy 413.456276 -291.504901) (xy 413.47186 -291.551582)
			(xy 413.479755 -291.600159) (xy 413.48025 -291.624766) (xy 413.819098 -291.624766) (xy 413.823058 -291.575712)
			(xy 413.834835 -291.527928) (xy 413.854126 -291.482652) (xy 413.880429 -291.441056) (xy 413.913064 -291.404219)
			(xy 413.951185 -291.373094) (xy 413.993806 -291.348487) (xy 414.039822 -291.331035) (xy 414.088041 -291.321191)
			(xy 414.137216 -291.31921) (xy 414.186071 -291.325142) (xy 414.233342 -291.338834) (xy 414.277804 -291.359932)
			(xy 414.318307 -291.387888) (xy 414.3538 -291.42198) (xy 414.383365 -291.461324) (xy 414.406236 -291.504901)
			(xy 414.42182 -291.551582) (xy 414.429715 -291.600159) (xy 414.43021 -291.624766) (xy 414.769058 -291.624766)
			(xy 414.773018 -291.575712) (xy 414.784795 -291.527928) (xy 414.804086 -291.482652) (xy 414.830389 -291.441056)
			(xy 414.863024 -291.404219) (xy 414.901145 -291.373094) (xy 414.943766 -291.348487) (xy 414.989782 -291.331035)
			(xy 415.038001 -291.321191) (xy 415.087176 -291.31921) (xy 415.136031 -291.325142) (xy 415.183302 -291.338834)
			(xy 415.227764 -291.359932) (xy 415.268267 -291.387888) (xy 415.30376 -291.42198) (xy 415.333325 -291.461324)
			(xy 415.356196 -291.504901) (xy 415.37178 -291.551582) (xy 415.379675 -291.600159) (xy 415.38017 -291.624766)
			(xy 415.719018 -291.624766) (xy 415.722978 -291.575712) (xy 415.734755 -291.527928) (xy 415.754046 -291.482652)
			(xy 415.780349 -291.441056) (xy 415.812984 -291.404219) (xy 415.851105 -291.373094) (xy 415.893726 -291.348487)
			(xy 415.939742 -291.331035) (xy 415.987961 -291.321191) (xy 416.037136 -291.31921) (xy 416.085991 -291.325142)
			(xy 416.133262 -291.338834) (xy 416.177724 -291.359932) (xy 416.218227 -291.387888) (xy 416.25372 -291.42198)
			(xy 416.283285 -291.461324) (xy 416.306156 -291.504901) (xy 416.32174 -291.551582) (xy 416.329635 -291.600159)
			(xy 416.33013 -291.624766) (xy 416.329635 -291.649373) (xy 416.32174 -291.69795) (xy 416.306156 -291.744631)
			(xy 416.283285 -291.788208) (xy 416.25372 -291.827552) (xy 416.218227 -291.861644) (xy 416.177724 -291.8896)
			(xy 416.133262 -291.910698) (xy 416.085991 -291.92439) (xy 416.037136 -291.930322) (xy 415.987961 -291.928341)
			(xy 415.939742 -291.918497) (xy 415.893726 -291.901045) (xy 415.851105 -291.876438) (xy 415.812984 -291.845313)
			(xy 415.780349 -291.808476) (xy 415.754046 -291.76688) (xy 415.734755 -291.721604) (xy 415.722978 -291.67382)
			(xy 415.719018 -291.624766) (xy 415.38017 -291.624766) (xy 415.379675 -291.649373) (xy 415.37178 -291.69795)
			(xy 415.356196 -291.744631) (xy 415.333325 -291.788208) (xy 415.30376 -291.827552) (xy 415.268267 -291.861644)
			(xy 415.227764 -291.8896) (xy 415.183302 -291.910698) (xy 415.136031 -291.92439) (xy 415.087176 -291.930322)
			(xy 415.038001 -291.928341) (xy 414.989782 -291.918497) (xy 414.943766 -291.901045) (xy 414.901145 -291.876438)
			(xy 414.863024 -291.845313) (xy 414.830389 -291.808476) (xy 414.804086 -291.76688) (xy 414.784795 -291.721604)
			(xy 414.773018 -291.67382) (xy 414.769058 -291.624766) (xy 414.43021 -291.624766) (xy 414.429715 -291.649373)
			(xy 414.42182 -291.69795) (xy 414.406236 -291.744631) (xy 414.383365 -291.788208) (xy 414.3538 -291.827552)
			(xy 414.318307 -291.861644) (xy 414.277804 -291.8896) (xy 414.233342 -291.910698) (xy 414.186071 -291.92439)
			(xy 414.137216 -291.930322) (xy 414.088041 -291.928341) (xy 414.039822 -291.918497) (xy 413.993806 -291.901045)
			(xy 413.951185 -291.876438) (xy 413.913064 -291.845313) (xy 413.880429 -291.808476) (xy 413.854126 -291.76688)
			(xy 413.834835 -291.721604) (xy 413.823058 -291.67382) (xy 413.819098 -291.624766) (xy 413.48025 -291.624766)
			(xy 413.479755 -291.649373) (xy 413.47186 -291.69795) (xy 413.456276 -291.744631) (xy 413.433405 -291.788208)
			(xy 413.40384 -291.827552) (xy 413.368347 -291.861644) (xy 413.327844 -291.8896) (xy 413.283382 -291.910698)
			(xy 413.236111 -291.92439) (xy 413.187256 -291.930322) (xy 413.138081 -291.928341) (xy 413.089862 -291.918497)
			(xy 413.043846 -291.901045) (xy 413.001225 -291.876438) (xy 412.963104 -291.845313) (xy 412.930469 -291.808476)
			(xy 412.904166 -291.76688) (xy 412.884875 -291.721604) (xy 412.873098 -291.67382) (xy 412.869138 -291.624766)
			(xy 412.53029 -291.624766) (xy 412.529795 -291.649373) (xy 412.5219 -291.69795) (xy 412.506316 -291.744631)
			(xy 412.483445 -291.788208) (xy 412.45388 -291.827552) (xy 412.418387 -291.861644) (xy 412.377884 -291.8896)
			(xy 412.333422 -291.910698) (xy 412.286151 -291.92439) (xy 412.237296 -291.930322) (xy 412.188121 -291.928341)
			(xy 412.139902 -291.918497) (xy 412.093886 -291.901045) (xy 412.051265 -291.876438) (xy 412.013144 -291.845313)
			(xy 411.980509 -291.808476) (xy 411.954206 -291.76688) (xy 411.934915 -291.721604) (xy 411.923138 -291.67382)
			(xy 411.919178 -291.624766) (xy 411.58033 -291.624766) (xy 411.579835 -291.649373) (xy 411.57194 -291.69795)
			(xy 411.556356 -291.744631) (xy 411.533485 -291.788208) (xy 411.50392 -291.827552) (xy 411.468427 -291.861644)
			(xy 411.427924 -291.8896) (xy 411.383462 -291.910698) (xy 411.336191 -291.92439) (xy 411.287336 -291.930322)
			(xy 411.238161 -291.928341) (xy 411.189942 -291.918497) (xy 411.143926 -291.901045) (xy 411.101305 -291.876438)
			(xy 411.063184 -291.845313) (xy 411.030549 -291.808476) (xy 411.004246 -291.76688) (xy 410.984955 -291.721604)
			(xy 410.973178 -291.67382) (xy 410.969218 -291.624766) (xy 410.630116 -291.624766) (xy 410.629621 -291.649373)
			(xy 410.621726 -291.69795) (xy 410.606142 -291.744631) (xy 410.583271 -291.788208) (xy 410.553706 -291.827552)
			(xy 410.518213 -291.861644) (xy 410.47771 -291.8896) (xy 410.433248 -291.910698) (xy 410.385977 -291.92439)
			(xy 410.337122 -291.930322) (xy 410.287947 -291.928341) (xy 410.239728 -291.918497) (xy 410.193712 -291.901045)
			(xy 410.151091 -291.876438) (xy 410.11297 -291.845313) (xy 410.080335 -291.808476) (xy 410.054032 -291.76688)
			(xy 410.034741 -291.721604) (xy 410.022964 -291.67382) (xy 410.019004 -291.624766) (xy 409.680156 -291.624766)
			(xy 409.679661 -291.649373) (xy 409.671766 -291.69795) (xy 409.656182 -291.744631) (xy 409.633311 -291.788208)
			(xy 409.603746 -291.827552) (xy 409.568253 -291.861644) (xy 409.52775 -291.8896) (xy 409.483288 -291.910698)
			(xy 409.436017 -291.92439) (xy 409.387162 -291.930322) (xy 409.337987 -291.928341) (xy 409.289768 -291.918497)
			(xy 409.243752 -291.901045) (xy 409.201131 -291.876438) (xy 409.16301 -291.845313) (xy 409.130375 -291.808476)
			(xy 409.104072 -291.76688) (xy 409.084781 -291.721604) (xy 409.073004 -291.67382) (xy 409.069044 -291.624766)
			(xy 408.730196 -291.624766) (xy 408.729701 -291.649373) (xy 408.721806 -291.69795) (xy 408.706222 -291.744631)
			(xy 408.683351 -291.788208) (xy 408.653786 -291.827552) (xy 408.618293 -291.861644) (xy 408.57779 -291.8896)
			(xy 408.533328 -291.910698) (xy 408.486057 -291.92439) (xy 408.437202 -291.930322) (xy 408.388027 -291.928341)
			(xy 408.339808 -291.918497) (xy 408.293792 -291.901045) (xy 408.251171 -291.876438) (xy 408.21305 -291.845313)
			(xy 408.180415 -291.808476) (xy 408.154112 -291.76688) (xy 408.134821 -291.721604) (xy 408.123044 -291.67382)
			(xy 408.119084 -291.624766) (xy 406.830276 -291.624766) (xy 406.829781 -291.649373) (xy 406.821886 -291.69795)
			(xy 406.806302 -291.744631) (xy 406.783431 -291.788208) (xy 406.753866 -291.827552) (xy 406.718373 -291.861644)
			(xy 406.67787 -291.8896) (xy 406.633408 -291.910698) (xy 406.586137 -291.92439) (xy 406.537282 -291.930322)
			(xy 406.488107 -291.928341) (xy 406.439888 -291.918497) (xy 406.393872 -291.901045) (xy 406.351251 -291.876438)
			(xy 406.31313 -291.845313) (xy 406.280495 -291.808476) (xy 406.254192 -291.76688) (xy 406.234901 -291.721604)
			(xy 406.223124 -291.67382) (xy 406.219164 -291.624766) (xy 405.880316 -291.624766) (xy 405.879821 -291.649373)
			(xy 405.871926 -291.69795) (xy 405.856342 -291.744631) (xy 405.833471 -291.788208) (xy 405.803906 -291.827552)
			(xy 405.768413 -291.861644) (xy 405.72791 -291.8896) (xy 405.683448 -291.910698) (xy 405.636177 -291.92439)
			(xy 405.587322 -291.930322) (xy 405.538147 -291.928341) (xy 405.489928 -291.918497) (xy 405.443912 -291.901045)
			(xy 405.401291 -291.876438) (xy 405.36317 -291.845313) (xy 405.330535 -291.808476) (xy 405.304232 -291.76688)
			(xy 405.284941 -291.721604) (xy 405.273164 -291.67382) (xy 405.269204 -291.624766) (xy 404.930102 -291.624766)
			(xy 404.929607 -291.649373) (xy 404.921712 -291.69795) (xy 404.906128 -291.744631) (xy 404.883257 -291.788208)
			(xy 404.853692 -291.827552) (xy 404.818199 -291.861644) (xy 404.777696 -291.8896) (xy 404.733234 -291.910698)
			(xy 404.685963 -291.92439) (xy 404.637108 -291.930322) (xy 404.587933 -291.928341) (xy 404.539714 -291.918497)
			(xy 404.493698 -291.901045) (xy 404.451077 -291.876438) (xy 404.412956 -291.845313) (xy 404.380321 -291.808476)
			(xy 404.354018 -291.76688) (xy 404.334727 -291.721604) (xy 404.32295 -291.67382) (xy 404.31899 -291.624766)
			(xy 403.980142 -291.624766) (xy 403.979647 -291.649373) (xy 403.971752 -291.69795) (xy 403.956168 -291.744631)
			(xy 403.933297 -291.788208) (xy 403.903732 -291.827552) (xy 403.868239 -291.861644) (xy 403.827736 -291.8896)
			(xy 403.783274 -291.910698) (xy 403.736003 -291.92439) (xy 403.687148 -291.930322) (xy 403.637973 -291.928341)
			(xy 403.589754 -291.918497) (xy 403.543738 -291.901045) (xy 403.501117 -291.876438) (xy 403.462996 -291.845313)
			(xy 403.430361 -291.808476) (xy 403.404058 -291.76688) (xy 403.384767 -291.721604) (xy 403.37299 -291.67382)
			(xy 403.36903 -291.624766) (xy 403.030182 -291.624766) (xy 403.029687 -291.649373) (xy 403.021792 -291.69795)
			(xy 403.006208 -291.744631) (xy 402.983337 -291.788208) (xy 402.953772 -291.827552) (xy 402.918279 -291.861644)
			(xy 402.877776 -291.8896) (xy 402.833314 -291.910698) (xy 402.786043 -291.92439) (xy 402.737188 -291.930322)
			(xy 402.688013 -291.928341) (xy 402.639794 -291.918497) (xy 402.593778 -291.901045) (xy 402.551157 -291.876438)
			(xy 402.513036 -291.845313) (xy 402.480401 -291.808476) (xy 402.454098 -291.76688) (xy 402.434807 -291.721604)
			(xy 402.42303 -291.67382) (xy 402.41907 -291.624766) (xy 402.080222 -291.624766) (xy 402.079727 -291.649373)
			(xy 402.071832 -291.69795) (xy 402.056248 -291.744631) (xy 402.033377 -291.788208) (xy 402.003812 -291.827552)
			(xy 401.968319 -291.861644) (xy 401.927816 -291.8896) (xy 401.883354 -291.910698) (xy 401.836083 -291.92439)
			(xy 401.787228 -291.930322) (xy 401.738053 -291.928341) (xy 401.689834 -291.918497) (xy 401.643818 -291.901045)
			(xy 401.601197 -291.876438) (xy 401.563076 -291.845313) (xy 401.530441 -291.808476) (xy 401.504138 -291.76688)
			(xy 401.484847 -291.721604) (xy 401.47307 -291.67382) (xy 401.46911 -291.624766) (xy 401.130262 -291.624766)
			(xy 401.129767 -291.649373) (xy 401.121872 -291.69795) (xy 401.106288 -291.744631) (xy 401.083417 -291.788208)
			(xy 401.053852 -291.827552) (xy 401.018359 -291.861644) (xy 400.977856 -291.8896) (xy 400.933394 -291.910698)
			(xy 400.886123 -291.92439) (xy 400.837268 -291.930322) (xy 400.788093 -291.928341) (xy 400.739874 -291.918497)
			(xy 400.693858 -291.901045) (xy 400.651237 -291.876438) (xy 400.613116 -291.845313) (xy 400.580481 -291.808476)
			(xy 400.554178 -291.76688) (xy 400.534887 -291.721604) (xy 400.52311 -291.67382) (xy 400.51915 -291.624766)
			(xy 400.180302 -291.624766) (xy 400.179807 -291.649373) (xy 400.171912 -291.69795) (xy 400.156328 -291.744631)
			(xy 400.133457 -291.788208) (xy 400.103892 -291.827552) (xy 400.068399 -291.861644) (xy 400.027896 -291.8896)
			(xy 399.983434 -291.910698) (xy 399.936163 -291.92439) (xy 399.887308 -291.930322) (xy 399.838133 -291.928341)
			(xy 399.789914 -291.918497) (xy 399.743898 -291.901045) (xy 399.701277 -291.876438) (xy 399.663156 -291.845313)
			(xy 399.630521 -291.808476) (xy 399.604218 -291.76688) (xy 399.584927 -291.721604) (xy 399.57315 -291.67382)
			(xy 399.56919 -291.624766) (xy 399.230342 -291.624766) (xy 399.229847 -291.649373) (xy 399.221952 -291.69795)
			(xy 399.206368 -291.744631) (xy 399.183497 -291.788208) (xy 399.153932 -291.827552) (xy 399.118439 -291.861644)
			(xy 399.077936 -291.8896) (xy 399.033474 -291.910698) (xy 398.986203 -291.92439) (xy 398.937348 -291.930322)
			(xy 398.888173 -291.928341) (xy 398.839954 -291.918497) (xy 398.793938 -291.901045) (xy 398.751317 -291.876438)
			(xy 398.713196 -291.845313) (xy 398.680561 -291.808476) (xy 398.654258 -291.76688) (xy 398.634967 -291.721604)
			(xy 398.62319 -291.67382) (xy 398.61923 -291.624766) (xy 397.330168 -291.624766) (xy 397.329673 -291.649373)
			(xy 397.321778 -291.69795) (xy 397.306194 -291.744631) (xy 397.283323 -291.788208) (xy 397.253758 -291.827552)
			(xy 397.218265 -291.861644) (xy 397.177762 -291.8896) (xy 397.1333 -291.910698) (xy 397.086029 -291.92439)
			(xy 397.037174 -291.930322) (xy 396.987999 -291.928341) (xy 396.93978 -291.918497) (xy 396.893764 -291.901045)
			(xy 396.851143 -291.876438) (xy 396.813022 -291.845313) (xy 396.780387 -291.808476) (xy 396.754084 -291.76688)
			(xy 396.734793 -291.721604) (xy 396.723016 -291.67382) (xy 396.719056 -291.624766) (xy 396.380208 -291.624766)
			(xy 396.379713 -291.649373) (xy 396.371818 -291.69795) (xy 396.356234 -291.744631) (xy 396.333363 -291.788208)
			(xy 396.303798 -291.827552) (xy 396.268305 -291.861644) (xy 396.227802 -291.8896) (xy 396.18334 -291.910698)
			(xy 396.136069 -291.92439) (xy 396.087214 -291.930322) (xy 396.038039 -291.928341) (xy 395.98982 -291.918497)
			(xy 395.943804 -291.901045) (xy 395.901183 -291.876438) (xy 395.863062 -291.845313) (xy 395.830427 -291.808476)
			(xy 395.804124 -291.76688) (xy 395.784833 -291.721604) (xy 395.773056 -291.67382) (xy 395.769096 -291.624766)
			(xy 394.480288 -291.624766) (xy 394.479793 -291.649373) (xy 394.471898 -291.69795) (xy 394.456314 -291.744631)
			(xy 394.433443 -291.788208) (xy 394.403878 -291.827552) (xy 394.368385 -291.861644) (xy 394.327882 -291.8896)
			(xy 394.28342 -291.910698) (xy 394.236149 -291.92439) (xy 394.187294 -291.930322) (xy 394.138119 -291.928341)
			(xy 394.0899 -291.918497) (xy 394.043884 -291.901045) (xy 394.001263 -291.876438) (xy 393.963142 -291.845313)
			(xy 393.930507 -291.808476) (xy 393.904204 -291.76688) (xy 393.884913 -291.721604) (xy 393.873136 -291.67382)
			(xy 393.869176 -291.624766) (xy 393.530328 -291.624766) (xy 393.529833 -291.649373) (xy 393.521938 -291.69795)
			(xy 393.506354 -291.744631) (xy 393.483483 -291.788208) (xy 393.453918 -291.827552) (xy 393.418425 -291.861644)
			(xy 393.377922 -291.8896) (xy 393.33346 -291.910698) (xy 393.286189 -291.92439) (xy 393.237334 -291.930322)
			(xy 393.188159 -291.928341) (xy 393.13994 -291.918497) (xy 393.093924 -291.901045) (xy 393.051303 -291.876438)
			(xy 393.013182 -291.845313) (xy 392.980547 -291.808476) (xy 392.954244 -291.76688) (xy 392.934953 -291.721604)
			(xy 392.923176 -291.67382) (xy 392.919216 -291.624766) (xy 392.580114 -291.624766) (xy 392.579619 -291.649373)
			(xy 392.571724 -291.69795) (xy 392.55614 -291.744631) (xy 392.533269 -291.788208) (xy 392.503704 -291.827552)
			(xy 392.468211 -291.861644) (xy 392.427708 -291.8896) (xy 392.383246 -291.910698) (xy 392.335975 -291.92439)
			(xy 392.28712 -291.930322) (xy 392.237945 -291.928341) (xy 392.189726 -291.918497) (xy 392.14371 -291.901045)
			(xy 392.101089 -291.876438) (xy 392.062968 -291.845313) (xy 392.030333 -291.808476) (xy 392.00403 -291.76688)
			(xy 391.984739 -291.721604) (xy 391.972962 -291.67382) (xy 391.969002 -291.624766) (xy 391.630154 -291.624766)
			(xy 391.629659 -291.649373) (xy 391.621764 -291.69795) (xy 391.60618 -291.744631) (xy 391.583309 -291.788208)
			(xy 391.553744 -291.827552) (xy 391.518251 -291.861644) (xy 391.477748 -291.8896) (xy 391.433286 -291.910698)
			(xy 391.386015 -291.92439) (xy 391.33716 -291.930322) (xy 391.287985 -291.928341) (xy 391.239766 -291.918497)
			(xy 391.19375 -291.901045) (xy 391.151129 -291.876438) (xy 391.113008 -291.845313) (xy 391.080373 -291.808476)
			(xy 391.05407 -291.76688) (xy 391.034779 -291.721604) (xy 391.023002 -291.67382) (xy 391.019042 -291.624766)
			(xy 390.680194 -291.624766) (xy 390.679699 -291.649373) (xy 390.671804 -291.69795) (xy 390.65622 -291.744631)
			(xy 390.633349 -291.788208) (xy 390.603784 -291.827552) (xy 390.568291 -291.861644) (xy 390.527788 -291.8896)
			(xy 390.483326 -291.910698) (xy 390.436055 -291.92439) (xy 390.3872 -291.930322) (xy 390.338025 -291.928341)
			(xy 390.289806 -291.918497) (xy 390.24379 -291.901045) (xy 390.201169 -291.876438) (xy 390.163048 -291.845313)
			(xy 390.130413 -291.808476) (xy 390.10411 -291.76688) (xy 390.084819 -291.721604) (xy 390.073042 -291.67382)
			(xy 390.069082 -291.624766) (xy 389.730234 -291.624766) (xy 389.729739 -291.649373) (xy 389.721844 -291.69795)
			(xy 389.70626 -291.744631) (xy 389.683389 -291.788208) (xy 389.653824 -291.827552) (xy 389.618331 -291.861644)
			(xy 389.577828 -291.8896) (xy 389.533366 -291.910698) (xy 389.486095 -291.92439) (xy 389.43724 -291.930322)
			(xy 389.388065 -291.928341) (xy 389.339846 -291.918497) (xy 389.29383 -291.901045) (xy 389.251209 -291.876438)
			(xy 389.213088 -291.845313) (xy 389.180453 -291.808476) (xy 389.15415 -291.76688) (xy 389.134859 -291.721604)
			(xy 389.123082 -291.67382) (xy 389.119122 -291.624766) (xy 386.880354 -291.624766) (xy 386.879859 -291.649373)
			(xy 386.871964 -291.69795) (xy 386.85638 -291.744631) (xy 386.833509 -291.788208) (xy 386.803944 -291.827552)
			(xy 386.768451 -291.861644) (xy 386.727948 -291.8896) (xy 386.683486 -291.910698) (xy 386.636215 -291.92439)
			(xy 386.58736 -291.930322) (xy 386.538185 -291.928341) (xy 386.489966 -291.918497) (xy 386.44395 -291.901045)
			(xy 386.401329 -291.876438) (xy 386.363208 -291.845313) (xy 386.330573 -291.808476) (xy 386.30427 -291.76688)
			(xy 386.284979 -291.721604) (xy 386.273202 -291.67382) (xy 386.269242 -291.624766) (xy 385.93014 -291.624766)
			(xy 385.929645 -291.649373) (xy 385.92175 -291.69795) (xy 385.906166 -291.744631) (xy 385.883295 -291.788208)
			(xy 385.85373 -291.827552) (xy 385.818237 -291.861644) (xy 385.777734 -291.8896) (xy 385.733272 -291.910698)
			(xy 385.686001 -291.92439) (xy 385.637146 -291.930322) (xy 385.587971 -291.928341) (xy 385.539752 -291.918497)
			(xy 385.493736 -291.901045) (xy 385.451115 -291.876438) (xy 385.412994 -291.845313) (xy 385.380359 -291.808476)
			(xy 385.354056 -291.76688) (xy 385.334765 -291.721604) (xy 385.322988 -291.67382) (xy 385.319028 -291.624766)
			(xy 384.98018 -291.624766) (xy 384.979685 -291.649373) (xy 384.97179 -291.69795) (xy 384.956206 -291.744631)
			(xy 384.933335 -291.788208) (xy 384.90377 -291.827552) (xy 384.868277 -291.861644) (xy 384.827774 -291.8896)
			(xy 384.783312 -291.910698) (xy 384.736041 -291.92439) (xy 384.687186 -291.930322) (xy 384.638011 -291.928341)
			(xy 384.589792 -291.918497) (xy 384.543776 -291.901045) (xy 384.501155 -291.876438) (xy 384.463034 -291.845313)
			(xy 384.430399 -291.808476) (xy 384.404096 -291.76688) (xy 384.384805 -291.721604) (xy 384.373028 -291.67382)
			(xy 384.369068 -291.624766) (xy 376.306954 -291.624766) (xy 376.28104 -291.663935) (xy 376.243823 -291.705472)
			(xy 376.200955 -291.741147) (xy 376.153349 -291.770201) (xy 376.10202 -291.792013) (xy 376.048063 -291.806119)
			(xy 375.992626 -291.812219) (xy 375.936892 -291.810182) (xy 375.882049 -291.800052) (xy 375.829265 -291.782045)
			(xy 375.779665 -291.756544) (xy 375.734307 -291.724093) (xy 375.694158 -291.685384) (xy 375.660072 -291.641241)
			(xy 375.632776 -291.592606) (xy 375.612853 -291.540515) (xy 375.600727 -291.486078) (xy 375.596656 -291.430456)
			(xy 374.875044 -291.430456) (xy 374.874535 -291.458342) (xy 374.866415 -291.513518) (xy 374.850347 -291.566925)
			(xy 374.826675 -291.617422) (xy 374.795902 -291.663935) (xy 374.758685 -291.705472) (xy 374.715817 -291.741147)
			(xy 374.668211 -291.770201) (xy 374.616882 -291.792013) (xy 374.562925 -291.806119) (xy 374.507488 -291.812219)
			(xy 374.451754 -291.810182) (xy 374.396911 -291.800052) (xy 374.344127 -291.782045) (xy 374.294527 -291.756544)
			(xy 374.249169 -291.724093) (xy 374.20902 -291.685384) (xy 374.174934 -291.641241) (xy 374.147638 -291.592606)
			(xy 374.127715 -291.540515) (xy 374.115589 -291.486078) (xy 374.111518 -291.430456) (xy 368.55019 -291.430456)
			(xy 368.55019 -292.732714) (xy 374.111518 -292.732714) (xy 374.115589 -292.677092) (xy 374.127715 -292.622655)
			(xy 374.147638 -292.570564) (xy 374.174934 -292.521929) (xy 374.20902 -292.477786) (xy 374.249169 -292.439077)
			(xy 374.294527 -292.406626) (xy 374.344127 -292.381125) (xy 374.396911 -292.363118) (xy 374.451754 -292.352988)
			(xy 374.507488 -292.350951) (xy 374.562925 -292.357051) (xy 374.616882 -292.371157) (xy 374.668211 -292.392969)
			(xy 374.715817 -292.422023) (xy 374.758685 -292.457698) (xy 374.795902 -292.499235) (xy 374.826675 -292.545748)
			(xy 374.850347 -292.596245) (xy 374.866415 -292.649652) (xy 374.874535 -292.704828) (xy 374.875044 -292.732714)
			(xy 375.587004 -292.732714) (xy 375.591075 -292.677092) (xy 375.603201 -292.622655) (xy 375.623124 -292.570564)
			(xy 375.65042 -292.521929) (xy 375.684506 -292.477786) (xy 375.724655 -292.439077) (xy 375.770013 -292.406626)
			(xy 375.819613 -292.381125) (xy 375.872397 -292.363118) (xy 375.92724 -292.352988) (xy 375.982974 -292.350951)
			(xy 376.038411 -292.357051) (xy 376.092368 -292.371157) (xy 376.143697 -292.392969) (xy 376.191303 -292.422023)
			(xy 376.234171 -292.457698) (xy 376.271388 -292.499235) (xy 376.302161 -292.545748) (xy 376.325833 -292.596245)
			(xy 376.341901 -292.649652) (xy 376.350021 -292.704828) (xy 376.35053 -292.732714) (xy 376.476004 -292.732714)
			(xy 376.480075 -292.677092) (xy 376.492201 -292.622655) (xy 376.512124 -292.570564) (xy 376.53942 -292.521929)
			(xy 376.573506 -292.477786) (xy 376.613655 -292.439077) (xy 376.659013 -292.406626) (xy 376.708613 -292.381125)
			(xy 376.761397 -292.363118) (xy 376.81624 -292.352988) (xy 376.871974 -292.350951) (xy 376.927411 -292.357051)
			(xy 376.981368 -292.371157) (xy 377.032697 -292.392969) (xy 377.080303 -292.422023) (xy 377.123171 -292.457698)
			(xy 377.160388 -292.499235) (xy 377.191161 -292.545748) (xy 377.214833 -292.596245) (xy 377.230901 -292.649652)
			(xy 377.239021 -292.704828) (xy 377.23953 -292.732714) (xy 377.239021 -292.7606) (xy 377.230901 -292.815776)
			(xy 377.214833 -292.869183) (xy 377.191161 -292.91968) (xy 377.160388 -292.966193) (xy 377.123171 -293.00773)
			(xy 377.080303 -293.043405) (xy 377.032697 -293.072459) (xy 376.981368 -293.094271) (xy 376.927411 -293.108377)
			(xy 376.871974 -293.114477) (xy 376.81624 -293.11244) (xy 376.761397 -293.10231) (xy 376.708613 -293.084303)
			(xy 376.659013 -293.058802) (xy 376.613655 -293.026351) (xy 376.573506 -292.987642) (xy 376.53942 -292.943499)
			(xy 376.512124 -292.894864) (xy 376.492201 -292.842773) (xy 376.480075 -292.788336) (xy 376.476004 -292.732714)
			(xy 376.35053 -292.732714) (xy 376.350021 -292.7606) (xy 376.341901 -292.815776) (xy 376.325833 -292.869183)
			(xy 376.302161 -292.91968) (xy 376.271388 -292.966193) (xy 376.234171 -293.00773) (xy 376.191303 -293.043405)
			(xy 376.143697 -293.072459) (xy 376.092368 -293.094271) (xy 376.038411 -293.108377) (xy 375.982974 -293.114477)
			(xy 375.92724 -293.11244) (xy 375.872397 -293.10231) (xy 375.819613 -293.084303) (xy 375.770013 -293.058802)
			(xy 375.724655 -293.026351) (xy 375.684506 -292.987642) (xy 375.65042 -292.943499) (xy 375.623124 -292.894864)
			(xy 375.603201 -292.842773) (xy 375.591075 -292.788336) (xy 375.587004 -292.732714) (xy 374.875044 -292.732714)
			(xy 374.874535 -292.7606) (xy 374.866415 -292.815776) (xy 374.850347 -292.869183) (xy 374.826675 -292.91968)
			(xy 374.795902 -292.966193) (xy 374.758685 -293.00773) (xy 374.715817 -293.043405) (xy 374.668211 -293.072459)
			(xy 374.616882 -293.094271) (xy 374.562925 -293.108377) (xy 374.507488 -293.114477) (xy 374.451754 -293.11244)
			(xy 374.396911 -293.10231) (xy 374.344127 -293.084303) (xy 374.294527 -293.058802) (xy 374.249169 -293.026351)
			(xy 374.20902 -292.987642) (xy 374.174934 -292.943499) (xy 374.147638 -292.894864) (xy 374.127715 -292.842773)
			(xy 374.115589 -292.788336) (xy 374.111518 -292.732714) (xy 368.55019 -292.732714) (xy 368.55019 -292.943788)
			(xy 368.549769 -292.953859) (xy 368.542056 -292.972466) (xy 368.535204 -292.979856) (xy 368.020346 -293.494714)
			(xy 379.638052 -293.494714) (xy 379.638619 -293.465333) (xy 379.647646 -293.407268) (xy 379.665474 -293.351275)
			(xy 379.691681 -293.29868) (xy 379.725646 -293.250728) (xy 379.766565 -293.208554) (xy 379.78969 -293.190422)
			(xy 379.798622 -293.18295) (xy 379.809075 -293.162169) (xy 379.809756 -293.150544) (xy 379.811026 -293.058596)
			(xy 379.80112 -293.037514) (xy 379.791976 -293.030148) (xy 379.770116 -293.011956) (xy 379.731578 -292.970134)
			(xy 379.699673 -292.923055) (xy 379.675108 -292.871763) (xy 379.658427 -292.817393) (xy 379.65 -292.76115)
			(xy 379.649482 -292.732714) (xy 379.649968 -292.705463) (xy 379.657724 -292.651515) (xy 379.673079 -292.59922)
			(xy 379.695721 -292.549643) (xy 379.725187 -292.503793) (xy 379.760878 -292.462602) (xy 379.802069 -292.426911)
			(xy 379.847919 -292.397445) (xy 379.897496 -292.374803) (xy 379.949791 -292.359448) (xy 380.003739 -292.351692)
			(xy 380.058241 -292.351692) (xy 380.112189 -292.359448) (xy 380.164484 -292.374803) (xy 380.214061 -292.397445)
			(xy 380.259911 -292.426911) (xy 380.301102 -292.462602) (xy 380.336793 -292.503793) (xy 380.366259 -292.549643)
			(xy 380.377831 -292.57498) (xy 384.369068 -292.57498) (xy 384.373028 -292.525926) (xy 384.384805 -292.478142)
			(xy 384.404096 -292.432866) (xy 384.430399 -292.39127) (xy 384.463034 -292.354433) (xy 384.501155 -292.323308)
			(xy 384.543776 -292.298701) (xy 384.589792 -292.281249) (xy 384.638011 -292.271405) (xy 384.687186 -292.269424)
			(xy 384.736041 -292.275356) (xy 384.783312 -292.289048) (xy 384.827774 -292.310146) (xy 384.868277 -292.338102)
			(xy 384.90377 -292.372194) (xy 384.933335 -292.411538) (xy 384.956206 -292.455115) (xy 384.97179 -292.501796)
			(xy 384.979685 -292.550373) (xy 384.98018 -292.57498) (xy 385.319028 -292.57498) (xy 385.322988 -292.525926)
			(xy 385.334765 -292.478142) (xy 385.354056 -292.432866) (xy 385.380359 -292.39127) (xy 385.412994 -292.354433)
			(xy 385.451115 -292.323308) (xy 385.493736 -292.298701) (xy 385.539752 -292.281249) (xy 385.587971 -292.271405)
			(xy 385.637146 -292.269424) (xy 385.686001 -292.275356) (xy 385.733272 -292.289048) (xy 385.777734 -292.310146)
			(xy 385.818237 -292.338102) (xy 385.85373 -292.372194) (xy 385.883295 -292.411538) (xy 385.906166 -292.455115)
			(xy 385.92175 -292.501796) (xy 385.929645 -292.550373) (xy 385.93014 -292.57498) (xy 386.269242 -292.57498)
			(xy 386.273202 -292.525926) (xy 386.284979 -292.478142) (xy 386.30427 -292.432866) (xy 386.330573 -292.39127)
			(xy 386.363208 -292.354433) (xy 386.401329 -292.323308) (xy 386.44395 -292.298701) (xy 386.489966 -292.281249)
			(xy 386.538185 -292.271405) (xy 386.58736 -292.269424) (xy 386.636215 -292.275356) (xy 386.683486 -292.289048)
			(xy 386.727948 -292.310146) (xy 386.768451 -292.338102) (xy 386.803944 -292.372194) (xy 386.833509 -292.411538)
			(xy 386.85638 -292.455115) (xy 386.871964 -292.501796) (xy 386.879859 -292.550373) (xy 386.880349 -292.574726)
			(xy 387.219202 -292.574726) (xy 387.223162 -292.525672) (xy 387.234939 -292.477888) (xy 387.25423 -292.432612)
			(xy 387.280533 -292.391016) (xy 387.313168 -292.354179) (xy 387.351289 -292.323054) (xy 387.39391 -292.298447)
			(xy 387.439926 -292.280995) (xy 387.488145 -292.271151) (xy 387.53732 -292.26917) (xy 387.586175 -292.275102)
			(xy 387.633446 -292.288794) (xy 387.677908 -292.309892) (xy 387.718411 -292.337848) (xy 387.753904 -292.37194)
			(xy 387.783469 -292.411284) (xy 387.80634 -292.454861) (xy 387.821924 -292.501542) (xy 387.829819 -292.550119)
			(xy 387.830314 -292.574726) (xy 388.169162 -292.574726) (xy 388.173122 -292.525672) (xy 388.184899 -292.477888)
			(xy 388.20419 -292.432612) (xy 388.230493 -292.391016) (xy 388.263128 -292.354179) (xy 388.301249 -292.323054)
			(xy 388.34387 -292.298447) (xy 388.389886 -292.280995) (xy 388.438105 -292.271151) (xy 388.48728 -292.26917)
			(xy 388.536135 -292.275102) (xy 388.583406 -292.288794) (xy 388.627868 -292.309892) (xy 388.668371 -292.337848)
			(xy 388.703864 -292.37194) (xy 388.733429 -292.411284) (xy 388.7563 -292.454861) (xy 388.771884 -292.501542)
			(xy 388.779779 -292.550119) (xy 388.780274 -292.574726) (xy 388.780269 -292.57498) (xy 389.119122 -292.57498)
			(xy 389.123082 -292.525926) (xy 389.134859 -292.478142) (xy 389.15415 -292.432866) (xy 389.180453 -292.39127)
			(xy 389.213088 -292.354433) (xy 389.251209 -292.323308) (xy 389.29383 -292.298701) (xy 389.339846 -292.281249)
			(xy 389.388065 -292.271405) (xy 389.43724 -292.269424) (xy 389.486095 -292.275356) (xy 389.533366 -292.289048)
			(xy 389.577828 -292.310146) (xy 389.618331 -292.338102) (xy 389.653824 -292.372194) (xy 389.683389 -292.411538)
			(xy 389.70626 -292.455115) (xy 389.721844 -292.501796) (xy 389.729739 -292.550373) (xy 389.730234 -292.57498)
			(xy 389.729739 -292.599587) (xy 389.729407 -292.601629) (xy 390.019276 -292.601629) (xy 390.019276 -292.548331)
			(xy 390.027219 -292.495627) (xy 390.042929 -292.444697) (xy 390.066055 -292.396676) (xy 390.096079 -292.352639)
			(xy 390.132331 -292.313568) (xy 390.174002 -292.280337) (xy 390.22016 -292.253688) (xy 390.269774 -292.234216)
			(xy 390.321736 -292.222356) (xy 390.374886 -292.218373) (xy 390.428036 -292.222356) (xy 390.479998 -292.234216)
			(xy 390.529612 -292.253688) (xy 390.57577 -292.280337) (xy 390.617441 -292.313568) (xy 390.653693 -292.352639)
			(xy 390.683717 -292.396676) (xy 390.706843 -292.444697) (xy 390.722553 -292.495627) (xy 390.730496 -292.548331)
			(xy 390.730994 -292.57498) (xy 391.019042 -292.57498) (xy 391.023002 -292.525926) (xy 391.034779 -292.478142)
			(xy 391.05407 -292.432866) (xy 391.080373 -292.39127) (xy 391.113008 -292.354433) (xy 391.151129 -292.323308)
			(xy 391.19375 -292.298701) (xy 391.239766 -292.281249) (xy 391.287985 -292.271405) (xy 391.33716 -292.269424)
			(xy 391.386015 -292.275356) (xy 391.433286 -292.289048) (xy 391.477748 -292.310146) (xy 391.518251 -292.338102)
			(xy 391.553744 -292.372194) (xy 391.583309 -292.411538) (xy 391.60618 -292.455115) (xy 391.621764 -292.501796)
			(xy 391.629659 -292.550373) (xy 391.630154 -292.57498) (xy 391.969002 -292.57498) (xy 391.972962 -292.525926)
			(xy 391.984739 -292.478142) (xy 392.00403 -292.432866) (xy 392.030333 -292.39127) (xy 392.062968 -292.354433)
			(xy 392.101089 -292.323308) (xy 392.14371 -292.298701) (xy 392.189726 -292.281249) (xy 392.237945 -292.271405)
			(xy 392.28712 -292.269424) (xy 392.335975 -292.275356) (xy 392.383246 -292.289048) (xy 392.427708 -292.310146)
			(xy 392.468211 -292.338102) (xy 392.503704 -292.372194) (xy 392.533269 -292.411538) (xy 392.55614 -292.455115)
			(xy 392.571724 -292.501796) (xy 392.579619 -292.550373) (xy 392.580114 -292.57498) (xy 392.919216 -292.57498)
			(xy 392.923176 -292.525926) (xy 392.934953 -292.478142) (xy 392.954244 -292.432866) (xy 392.980547 -292.39127)
			(xy 393.013182 -292.354433) (xy 393.051303 -292.323308) (xy 393.093924 -292.298701) (xy 393.13994 -292.281249)
			(xy 393.188159 -292.271405) (xy 393.237334 -292.269424) (xy 393.286189 -292.275356) (xy 393.33346 -292.289048)
			(xy 393.377922 -292.310146) (xy 393.418425 -292.338102) (xy 393.453918 -292.372194) (xy 393.483483 -292.411538)
			(xy 393.506354 -292.455115) (xy 393.521938 -292.501796) (xy 393.529833 -292.550373) (xy 393.530328 -292.57498)
			(xy 393.869176 -292.57498) (xy 393.873136 -292.525926) (xy 393.884913 -292.478142) (xy 393.904204 -292.432866)
			(xy 393.930507 -292.39127) (xy 393.963142 -292.354433) (xy 394.001263 -292.323308) (xy 394.043884 -292.298701)
			(xy 394.0899 -292.281249) (xy 394.138119 -292.271405) (xy 394.187294 -292.269424) (xy 394.236149 -292.275356)
			(xy 394.28342 -292.289048) (xy 394.327882 -292.310146) (xy 394.368385 -292.338102) (xy 394.403878 -292.372194)
			(xy 394.433443 -292.411538) (xy 394.456314 -292.455115) (xy 394.471898 -292.501796) (xy 394.479793 -292.550373)
			(xy 394.480288 -292.57498) (xy 394.819136 -292.57498) (xy 394.823096 -292.525926) (xy 394.834873 -292.478142)
			(xy 394.854164 -292.432866) (xy 394.880467 -292.39127) (xy 394.913102 -292.354433) (xy 394.951223 -292.323308)
			(xy 394.993844 -292.298701) (xy 395.03986 -292.281249) (xy 395.088079 -292.271405) (xy 395.137254 -292.269424)
			(xy 395.186109 -292.275356) (xy 395.23338 -292.289048) (xy 395.277842 -292.310146) (xy 395.318345 -292.338102)
			(xy 395.353838 -292.372194) (xy 395.383403 -292.411538) (xy 395.406274 -292.455115) (xy 395.421858 -292.501796)
			(xy 395.429753 -292.550373) (xy 395.430248 -292.57498) (xy 395.769096 -292.57498) (xy 395.773056 -292.525926)
			(xy 395.784833 -292.478142) (xy 395.804124 -292.432866) (xy 395.830427 -292.39127) (xy 395.863062 -292.354433)
			(xy 395.901183 -292.323308) (xy 395.943804 -292.298701) (xy 395.98982 -292.281249) (xy 396.038039 -292.271405)
			(xy 396.087214 -292.269424) (xy 396.136069 -292.275356) (xy 396.18334 -292.289048) (xy 396.227802 -292.310146)
			(xy 396.268305 -292.338102) (xy 396.303798 -292.372194) (xy 396.333363 -292.411538) (xy 396.356234 -292.455115)
			(xy 396.371818 -292.501796) (xy 396.379713 -292.550373) (xy 396.380203 -292.574726) (xy 397.669016 -292.574726)
			(xy 397.672976 -292.525672) (xy 397.684753 -292.477888) (xy 397.704044 -292.432612) (xy 397.730347 -292.391016)
			(xy 397.762982 -292.354179) (xy 397.801103 -292.323054) (xy 397.843724 -292.298447) (xy 397.88974 -292.280995)
			(xy 397.937959 -292.271151) (xy 397.987134 -292.26917) (xy 398.035989 -292.275102) (xy 398.08326 -292.288794)
			(xy 398.127722 -292.309892) (xy 398.168225 -292.337848) (xy 398.203718 -292.37194) (xy 398.233283 -292.411284)
			(xy 398.256154 -292.454861) (xy 398.271738 -292.501542) (xy 398.279633 -292.550119) (xy 398.280128 -292.574726)
			(xy 398.280123 -292.57498) (xy 398.61923 -292.57498) (xy 398.62319 -292.525926) (xy 398.634967 -292.478142)
			(xy 398.654258 -292.432866) (xy 398.680561 -292.39127) (xy 398.713196 -292.354433) (xy 398.751317 -292.323308)
			(xy 398.793938 -292.298701) (xy 398.839954 -292.281249) (xy 398.888173 -292.271405) (xy 398.937348 -292.269424)
			(xy 398.986203 -292.275356) (xy 399.033474 -292.289048) (xy 399.077936 -292.310146) (xy 399.118439 -292.338102)
			(xy 399.153932 -292.372194) (xy 399.183497 -292.411538) (xy 399.206368 -292.455115) (xy 399.221952 -292.501796)
			(xy 399.229847 -292.550373) (xy 399.230342 -292.57498) (xy 399.56919 -292.57498) (xy 399.57315 -292.525926)
			(xy 399.584927 -292.478142) (xy 399.604218 -292.432866) (xy 399.630521 -292.39127) (xy 399.663156 -292.354433)
			(xy 399.701277 -292.323308) (xy 399.743898 -292.298701) (xy 399.789914 -292.281249) (xy 399.838133 -292.271405)
			(xy 399.887308 -292.269424) (xy 399.936163 -292.275356) (xy 399.983434 -292.289048) (xy 400.027896 -292.310146)
			(xy 400.068399 -292.338102) (xy 400.103892 -292.372194) (xy 400.133457 -292.411538) (xy 400.156328 -292.455115)
			(xy 400.171912 -292.501796) (xy 400.179807 -292.550373) (xy 400.180302 -292.57498) (xy 400.51915 -292.57498)
			(xy 400.52311 -292.525926) (xy 400.534887 -292.478142) (xy 400.554178 -292.432866) (xy 400.580481 -292.39127)
			(xy 400.613116 -292.354433) (xy 400.651237 -292.323308) (xy 400.693858 -292.298701) (xy 400.739874 -292.281249)
			(xy 400.788093 -292.271405) (xy 400.837268 -292.269424) (xy 400.886123 -292.275356) (xy 400.933394 -292.289048)
			(xy 400.977856 -292.310146) (xy 401.018359 -292.338102) (xy 401.053852 -292.372194) (xy 401.083417 -292.411538)
			(xy 401.106288 -292.455115) (xy 401.121872 -292.501796) (xy 401.129767 -292.550373) (xy 401.130262 -292.57498)
			(xy 401.46911 -292.57498) (xy 401.47307 -292.525926) (xy 401.484847 -292.478142) (xy 401.504138 -292.432866)
			(xy 401.530441 -292.39127) (xy 401.563076 -292.354433) (xy 401.601197 -292.323308) (xy 401.643818 -292.298701)
			(xy 401.689834 -292.281249) (xy 401.738053 -292.271405) (xy 401.787228 -292.269424) (xy 401.836083 -292.275356)
			(xy 401.883354 -292.289048) (xy 401.927816 -292.310146) (xy 401.968319 -292.338102) (xy 402.003812 -292.372194)
			(xy 402.033377 -292.411538) (xy 402.056248 -292.455115) (xy 402.071832 -292.501796) (xy 402.079727 -292.550373)
			(xy 402.080222 -292.57498) (xy 402.41907 -292.57498) (xy 402.42303 -292.525926) (xy 402.434807 -292.478142)
			(xy 402.454098 -292.432866) (xy 402.480401 -292.39127) (xy 402.513036 -292.354433) (xy 402.551157 -292.323308)
			(xy 402.593778 -292.298701) (xy 402.639794 -292.281249) (xy 402.688013 -292.271405) (xy 402.737188 -292.269424)
			(xy 402.786043 -292.275356) (xy 402.833314 -292.289048) (xy 402.877776 -292.310146) (xy 402.918279 -292.338102)
			(xy 402.953772 -292.372194) (xy 402.983337 -292.411538) (xy 403.006208 -292.455115) (xy 403.021792 -292.501796)
			(xy 403.029687 -292.550373) (xy 403.030182 -292.57498) (xy 403.36903 -292.57498) (xy 403.37299 -292.525926)
			(xy 403.384767 -292.478142) (xy 403.404058 -292.432866) (xy 403.430361 -292.39127) (xy 403.462996 -292.354433)
			(xy 403.501117 -292.323308) (xy 403.543738 -292.298701) (xy 403.589754 -292.281249) (xy 403.637973 -292.271405)
			(xy 403.687148 -292.269424) (xy 403.736003 -292.275356) (xy 403.783274 -292.289048) (xy 403.827736 -292.310146)
			(xy 403.868239 -292.338102) (xy 403.903732 -292.372194) (xy 403.933297 -292.411538) (xy 403.956168 -292.455115)
			(xy 403.971752 -292.501796) (xy 403.979647 -292.550373) (xy 403.980142 -292.57498) (xy 404.319244 -292.57498)
			(xy 404.323204 -292.525926) (xy 404.334981 -292.478142) (xy 404.354272 -292.432866) (xy 404.380575 -292.39127)
			(xy 404.41321 -292.354433) (xy 404.451331 -292.323308) (xy 404.493952 -292.298701) (xy 404.539968 -292.281249)
			(xy 404.588187 -292.271405) (xy 404.637362 -292.269424) (xy 404.686217 -292.275356) (xy 404.733488 -292.289048)
			(xy 404.77795 -292.310146) (xy 404.818453 -292.338102) (xy 404.853946 -292.372194) (xy 404.883511 -292.411538)
			(xy 404.906382 -292.455115) (xy 404.921966 -292.501796) (xy 404.929861 -292.550373) (xy 404.930356 -292.57498)
			(xy 405.269204 -292.57498) (xy 405.273164 -292.525926) (xy 405.284941 -292.478142) (xy 405.304232 -292.432866)
			(xy 405.330535 -292.39127) (xy 405.36317 -292.354433) (xy 405.401291 -292.323308) (xy 405.443912 -292.298701)
			(xy 405.489928 -292.281249) (xy 405.538147 -292.271405) (xy 405.587322 -292.269424) (xy 405.636177 -292.275356)
			(xy 405.683448 -292.289048) (xy 405.72791 -292.310146) (xy 405.768413 -292.338102) (xy 405.803906 -292.372194)
			(xy 405.833471 -292.411538) (xy 405.856342 -292.455115) (xy 405.871926 -292.501796) (xy 405.879821 -292.550373)
			(xy 405.880316 -292.57498) (xy 406.219164 -292.57498) (xy 406.223124 -292.525926) (xy 406.234901 -292.478142)
			(xy 406.254192 -292.432866) (xy 406.280495 -292.39127) (xy 406.31313 -292.354433) (xy 406.351251 -292.323308)
			(xy 406.393872 -292.298701) (xy 406.439888 -292.281249) (xy 406.488107 -292.271405) (xy 406.537282 -292.269424)
			(xy 406.586137 -292.275356) (xy 406.633408 -292.289048) (xy 406.67787 -292.310146) (xy 406.718373 -292.338102)
			(xy 406.753866 -292.372194) (xy 406.783431 -292.411538) (xy 406.806302 -292.455115) (xy 406.821886 -292.501796)
			(xy 406.829781 -292.550373) (xy 406.830271 -292.574726) (xy 408.119084 -292.574726) (xy 408.123044 -292.525672)
			(xy 408.134821 -292.477888) (xy 408.154112 -292.432612) (xy 408.180415 -292.391016) (xy 408.21305 -292.354179)
			(xy 408.251171 -292.323054) (xy 408.293792 -292.298447) (xy 408.339808 -292.280995) (xy 408.388027 -292.271151)
			(xy 408.437202 -292.26917) (xy 408.486057 -292.275102) (xy 408.533328 -292.288794) (xy 408.57779 -292.309892)
			(xy 408.618293 -292.337848) (xy 408.653786 -292.37194) (xy 408.683351 -292.411284) (xy 408.706222 -292.454861)
			(xy 408.721806 -292.501542) (xy 408.729701 -292.550119) (xy 408.730196 -292.574726) (xy 409.069044 -292.574726)
			(xy 409.073004 -292.525672) (xy 409.084781 -292.477888) (xy 409.104072 -292.432612) (xy 409.130375 -292.391016)
			(xy 409.16301 -292.354179) (xy 409.201131 -292.323054) (xy 409.243752 -292.298447) (xy 409.289768 -292.280995)
			(xy 409.337987 -292.271151) (xy 409.387162 -292.26917) (xy 409.436017 -292.275102) (xy 409.483288 -292.288794)
			(xy 409.52775 -292.309892) (xy 409.568253 -292.337848) (xy 409.603746 -292.37194) (xy 409.633311 -292.411284)
			(xy 409.656182 -292.454861) (xy 409.671766 -292.501542) (xy 409.679661 -292.550119) (xy 409.680156 -292.574726)
			(xy 410.019004 -292.574726) (xy 410.022964 -292.525672) (xy 410.034741 -292.477888) (xy 410.054032 -292.432612)
			(xy 410.080335 -292.391016) (xy 410.11297 -292.354179) (xy 410.151091 -292.323054) (xy 410.193712 -292.298447)
			(xy 410.239728 -292.280995) (xy 410.287947 -292.271151) (xy 410.337122 -292.26917) (xy 410.385977 -292.275102)
			(xy 410.433248 -292.288794) (xy 410.47771 -292.309892) (xy 410.518213 -292.337848) (xy 410.553706 -292.37194)
			(xy 410.583271 -292.411284) (xy 410.606142 -292.454861) (xy 410.621726 -292.501542) (xy 410.629621 -292.550119)
			(xy 410.630116 -292.574726) (xy 410.969218 -292.574726) (xy 410.973178 -292.525672) (xy 410.984955 -292.477888)
			(xy 411.004246 -292.432612) (xy 411.030549 -292.391016) (xy 411.063184 -292.354179) (xy 411.101305 -292.323054)
			(xy 411.143926 -292.298447) (xy 411.189942 -292.280995) (xy 411.238161 -292.271151) (xy 411.287336 -292.26917)
			(xy 411.336191 -292.275102) (xy 411.383462 -292.288794) (xy 411.427924 -292.309892) (xy 411.468427 -292.337848)
			(xy 411.50392 -292.37194) (xy 411.533485 -292.411284) (xy 411.556356 -292.454861) (xy 411.57194 -292.501542)
			(xy 411.579835 -292.550119) (xy 411.58033 -292.574726) (xy 411.919178 -292.574726) (xy 411.923138 -292.525672)
			(xy 411.934915 -292.477888) (xy 411.954206 -292.432612) (xy 411.980509 -292.391016) (xy 412.013144 -292.354179)
			(xy 412.051265 -292.323054) (xy 412.093886 -292.298447) (xy 412.139902 -292.280995) (xy 412.188121 -292.271151)
			(xy 412.237296 -292.26917) (xy 412.286151 -292.275102) (xy 412.333422 -292.288794) (xy 412.377884 -292.309892)
			(xy 412.418387 -292.337848) (xy 412.45388 -292.37194) (xy 412.483445 -292.411284) (xy 412.506316 -292.454861)
			(xy 412.5219 -292.501542) (xy 412.529795 -292.550119) (xy 412.53029 -292.574726) (xy 412.869138 -292.574726)
			(xy 412.873098 -292.525672) (xy 412.884875 -292.477888) (xy 412.904166 -292.432612) (xy 412.930469 -292.391016)
			(xy 412.963104 -292.354179) (xy 413.001225 -292.323054) (xy 413.043846 -292.298447) (xy 413.089862 -292.280995)
			(xy 413.138081 -292.271151) (xy 413.187256 -292.26917) (xy 413.236111 -292.275102) (xy 413.283382 -292.288794)
			(xy 413.327844 -292.309892) (xy 413.368347 -292.337848) (xy 413.40384 -292.37194) (xy 413.433405 -292.411284)
			(xy 413.456276 -292.454861) (xy 413.47186 -292.501542) (xy 413.479755 -292.550119) (xy 413.48025 -292.574726)
			(xy 413.819098 -292.574726) (xy 413.823058 -292.525672) (xy 413.834835 -292.477888) (xy 413.854126 -292.432612)
			(xy 413.880429 -292.391016) (xy 413.913064 -292.354179) (xy 413.951185 -292.323054) (xy 413.993806 -292.298447)
			(xy 414.039822 -292.280995) (xy 414.088041 -292.271151) (xy 414.137216 -292.26917) (xy 414.186071 -292.275102)
			(xy 414.233342 -292.288794) (xy 414.277804 -292.309892) (xy 414.318307 -292.337848) (xy 414.3538 -292.37194)
			(xy 414.383365 -292.411284) (xy 414.406236 -292.454861) (xy 414.42182 -292.501542) (xy 414.429715 -292.550119)
			(xy 414.43021 -292.574726) (xy 414.769058 -292.574726) (xy 414.773018 -292.525672) (xy 414.784795 -292.477888)
			(xy 414.804086 -292.432612) (xy 414.830389 -292.391016) (xy 414.863024 -292.354179) (xy 414.901145 -292.323054)
			(xy 414.943766 -292.298447) (xy 414.989782 -292.280995) (xy 415.038001 -292.271151) (xy 415.087176 -292.26917)
			(xy 415.136031 -292.275102) (xy 415.183302 -292.288794) (xy 415.227764 -292.309892) (xy 415.268267 -292.337848)
			(xy 415.30376 -292.37194) (xy 415.333325 -292.411284) (xy 415.356196 -292.454861) (xy 415.37178 -292.501542)
			(xy 415.379675 -292.550119) (xy 415.38017 -292.574726) (xy 415.719018 -292.574726) (xy 415.722978 -292.525672)
			(xy 415.734755 -292.477888) (xy 415.754046 -292.432612) (xy 415.780349 -292.391016) (xy 415.812984 -292.354179)
			(xy 415.851105 -292.323054) (xy 415.893726 -292.298447) (xy 415.939742 -292.280995) (xy 415.987961 -292.271151)
			(xy 416.037136 -292.26917) (xy 416.085991 -292.275102) (xy 416.133262 -292.288794) (xy 416.177724 -292.309892)
			(xy 416.218227 -292.337848) (xy 416.25372 -292.37194) (xy 416.283285 -292.411284) (xy 416.306156 -292.454861)
			(xy 416.32174 -292.501542) (xy 416.329635 -292.550119) (xy 416.33013 -292.574726) (xy 416.329635 -292.599333)
			(xy 416.32174 -292.64791) (xy 416.306156 -292.694591) (xy 416.283285 -292.738168) (xy 416.25372 -292.777512)
			(xy 416.218227 -292.811604) (xy 416.177724 -292.83956) (xy 416.133262 -292.860658) (xy 416.085991 -292.87435)
			(xy 416.037136 -292.880282) (xy 415.987961 -292.878301) (xy 415.939742 -292.868457) (xy 415.893726 -292.851005)
			(xy 415.851105 -292.826398) (xy 415.812984 -292.795273) (xy 415.780349 -292.758436) (xy 415.754046 -292.71684)
			(xy 415.734755 -292.671564) (xy 415.722978 -292.62378) (xy 415.719018 -292.574726) (xy 415.38017 -292.574726)
			(xy 415.379675 -292.599333) (xy 415.37178 -292.64791) (xy 415.356196 -292.694591) (xy 415.333325 -292.738168)
			(xy 415.30376 -292.777512) (xy 415.268267 -292.811604) (xy 415.227764 -292.83956) (xy 415.183302 -292.860658)
			(xy 415.136031 -292.87435) (xy 415.087176 -292.880282) (xy 415.038001 -292.878301) (xy 414.989782 -292.868457)
			(xy 414.943766 -292.851005) (xy 414.901145 -292.826398) (xy 414.863024 -292.795273) (xy 414.830389 -292.758436)
			(xy 414.804086 -292.71684) (xy 414.784795 -292.671564) (xy 414.773018 -292.62378) (xy 414.769058 -292.574726)
			(xy 414.43021 -292.574726) (xy 414.429715 -292.599333) (xy 414.42182 -292.64791) (xy 414.406236 -292.694591)
			(xy 414.383365 -292.738168) (xy 414.3538 -292.777512) (xy 414.318307 -292.811604) (xy 414.277804 -292.83956)
			(xy 414.233342 -292.860658) (xy 414.186071 -292.87435) (xy 414.137216 -292.880282) (xy 414.088041 -292.878301)
			(xy 414.039822 -292.868457) (xy 413.993806 -292.851005) (xy 413.951185 -292.826398) (xy 413.913064 -292.795273)
			(xy 413.880429 -292.758436) (xy 413.854126 -292.71684) (xy 413.834835 -292.671564) (xy 413.823058 -292.62378)
			(xy 413.819098 -292.574726) (xy 413.48025 -292.574726) (xy 413.479755 -292.599333) (xy 413.47186 -292.64791)
			(xy 413.456276 -292.694591) (xy 413.433405 -292.738168) (xy 413.40384 -292.777512) (xy 413.368347 -292.811604)
			(xy 413.327844 -292.83956) (xy 413.283382 -292.860658) (xy 413.236111 -292.87435) (xy 413.187256 -292.880282)
			(xy 413.138081 -292.878301) (xy 413.089862 -292.868457) (xy 413.043846 -292.851005) (xy 413.001225 -292.826398)
			(xy 412.963104 -292.795273) (xy 412.930469 -292.758436) (xy 412.904166 -292.71684) (xy 412.884875 -292.671564)
			(xy 412.873098 -292.62378) (xy 412.869138 -292.574726) (xy 412.53029 -292.574726) (xy 412.529795 -292.599333)
			(xy 412.5219 -292.64791) (xy 412.506316 -292.694591) (xy 412.483445 -292.738168) (xy 412.45388 -292.777512)
			(xy 412.418387 -292.811604) (xy 412.377884 -292.83956) (xy 412.333422 -292.860658) (xy 412.286151 -292.87435)
			(xy 412.237296 -292.880282) (xy 412.188121 -292.878301) (xy 412.139902 -292.868457) (xy 412.093886 -292.851005)
			(xy 412.051265 -292.826398) (xy 412.013144 -292.795273) (xy 411.980509 -292.758436) (xy 411.954206 -292.71684)
			(xy 411.934915 -292.671564) (xy 411.923138 -292.62378) (xy 411.919178 -292.574726) (xy 411.58033 -292.574726)
			(xy 411.579835 -292.599333) (xy 411.57194 -292.64791) (xy 411.556356 -292.694591) (xy 411.533485 -292.738168)
			(xy 411.50392 -292.777512) (xy 411.468427 -292.811604) (xy 411.427924 -292.83956) (xy 411.383462 -292.860658)
			(xy 411.336191 -292.87435) (xy 411.287336 -292.880282) (xy 411.238161 -292.878301) (xy 411.189942 -292.868457)
			(xy 411.143926 -292.851005) (xy 411.101305 -292.826398) (xy 411.063184 -292.795273) (xy 411.030549 -292.758436)
			(xy 411.004246 -292.71684) (xy 410.984955 -292.671564) (xy 410.973178 -292.62378) (xy 410.969218 -292.574726)
			(xy 410.630116 -292.574726) (xy 410.629621 -292.599333) (xy 410.621726 -292.64791) (xy 410.606142 -292.694591)
			(xy 410.583271 -292.738168) (xy 410.553706 -292.777512) (xy 410.518213 -292.811604) (xy 410.47771 -292.83956)
			(xy 410.433248 -292.860658) (xy 410.385977 -292.87435) (xy 410.337122 -292.880282) (xy 410.287947 -292.878301)
			(xy 410.239728 -292.868457) (xy 410.193712 -292.851005) (xy 410.151091 -292.826398) (xy 410.11297 -292.795273)
			(xy 410.080335 -292.758436) (xy 410.054032 -292.71684) (xy 410.034741 -292.671564) (xy 410.022964 -292.62378)
			(xy 410.019004 -292.574726) (xy 409.680156 -292.574726) (xy 409.679661 -292.599333) (xy 409.671766 -292.64791)
			(xy 409.656182 -292.694591) (xy 409.633311 -292.738168) (xy 409.603746 -292.777512) (xy 409.568253 -292.811604)
			(xy 409.52775 -292.83956) (xy 409.483288 -292.860658) (xy 409.436017 -292.87435) (xy 409.387162 -292.880282)
			(xy 409.337987 -292.878301) (xy 409.289768 -292.868457) (xy 409.243752 -292.851005) (xy 409.201131 -292.826398)
			(xy 409.16301 -292.795273) (xy 409.130375 -292.758436) (xy 409.104072 -292.71684) (xy 409.084781 -292.671564)
			(xy 409.073004 -292.62378) (xy 409.069044 -292.574726) (xy 408.730196 -292.574726) (xy 408.729701 -292.599333)
			(xy 408.721806 -292.64791) (xy 408.706222 -292.694591) (xy 408.683351 -292.738168) (xy 408.653786 -292.777512)
			(xy 408.618293 -292.811604) (xy 408.57779 -292.83956) (xy 408.533328 -292.860658) (xy 408.486057 -292.87435)
			(xy 408.437202 -292.880282) (xy 408.388027 -292.878301) (xy 408.339808 -292.868457) (xy 408.293792 -292.851005)
			(xy 408.251171 -292.826398) (xy 408.21305 -292.795273) (xy 408.180415 -292.758436) (xy 408.154112 -292.71684)
			(xy 408.134821 -292.671564) (xy 408.123044 -292.62378) (xy 408.119084 -292.574726) (xy 406.830271 -292.574726)
			(xy 406.830276 -292.57498) (xy 406.829781 -292.599587) (xy 406.821886 -292.648164) (xy 406.806302 -292.694845)
			(xy 406.783431 -292.738422) (xy 406.753866 -292.777766) (xy 406.718373 -292.811858) (xy 406.67787 -292.839814)
			(xy 406.633408 -292.860912) (xy 406.586137 -292.874604) (xy 406.537282 -292.880536) (xy 406.488107 -292.878555)
			(xy 406.439888 -292.868711) (xy 406.393872 -292.851259) (xy 406.351251 -292.826652) (xy 406.31313 -292.795527)
			(xy 406.280495 -292.75869) (xy 406.254192 -292.717094) (xy 406.234901 -292.671818) (xy 406.223124 -292.624034)
			(xy 406.219164 -292.57498) (xy 405.880316 -292.57498) (xy 405.879821 -292.599587) (xy 405.871926 -292.648164)
			(xy 405.856342 -292.694845) (xy 405.833471 -292.738422) (xy 405.803906 -292.777766) (xy 405.768413 -292.811858)
			(xy 405.72791 -292.839814) (xy 405.683448 -292.860912) (xy 405.636177 -292.874604) (xy 405.587322 -292.880536)
			(xy 405.538147 -292.878555) (xy 405.489928 -292.868711) (xy 405.443912 -292.851259) (xy 405.401291 -292.826652)
			(xy 405.36317 -292.795527) (xy 405.330535 -292.75869) (xy 405.304232 -292.717094) (xy 405.284941 -292.671818)
			(xy 405.273164 -292.624034) (xy 405.269204 -292.57498) (xy 404.930356 -292.57498) (xy 404.929861 -292.599587)
			(xy 404.921966 -292.648164) (xy 404.906382 -292.694845) (xy 404.883511 -292.738422) (xy 404.853946 -292.777766)
			(xy 404.818453 -292.811858) (xy 404.77795 -292.839814) (xy 404.733488 -292.860912) (xy 404.686217 -292.874604)
			(xy 404.637362 -292.880536) (xy 404.588187 -292.878555) (xy 404.539968 -292.868711) (xy 404.493952 -292.851259)
			(xy 404.451331 -292.826652) (xy 404.41321 -292.795527) (xy 404.380575 -292.75869) (xy 404.354272 -292.717094)
			(xy 404.334981 -292.671818) (xy 404.323204 -292.624034) (xy 404.319244 -292.57498) (xy 403.980142 -292.57498)
			(xy 403.979647 -292.599587) (xy 403.971752 -292.648164) (xy 403.956168 -292.694845) (xy 403.933297 -292.738422)
			(xy 403.903732 -292.777766) (xy 403.868239 -292.811858) (xy 403.827736 -292.839814) (xy 403.783274 -292.860912)
			(xy 403.736003 -292.874604) (xy 403.687148 -292.880536) (xy 403.637973 -292.878555) (xy 403.589754 -292.868711)
			(xy 403.543738 -292.851259) (xy 403.501117 -292.826652) (xy 403.462996 -292.795527) (xy 403.430361 -292.75869)
			(xy 403.404058 -292.717094) (xy 403.384767 -292.671818) (xy 403.37299 -292.624034) (xy 403.36903 -292.57498)
			(xy 403.030182 -292.57498) (xy 403.029687 -292.599587) (xy 403.021792 -292.648164) (xy 403.006208 -292.694845)
			(xy 402.983337 -292.738422) (xy 402.953772 -292.777766) (xy 402.918279 -292.811858) (xy 402.877776 -292.839814)
			(xy 402.833314 -292.860912) (xy 402.786043 -292.874604) (xy 402.737188 -292.880536) (xy 402.688013 -292.878555)
			(xy 402.639794 -292.868711) (xy 402.593778 -292.851259) (xy 402.551157 -292.826652) (xy 402.513036 -292.795527)
			(xy 402.480401 -292.75869) (xy 402.454098 -292.717094) (xy 402.434807 -292.671818) (xy 402.42303 -292.624034)
			(xy 402.41907 -292.57498) (xy 402.080222 -292.57498) (xy 402.079727 -292.599587) (xy 402.071832 -292.648164)
			(xy 402.056248 -292.694845) (xy 402.033377 -292.738422) (xy 402.003812 -292.777766) (xy 401.968319 -292.811858)
			(xy 401.927816 -292.839814) (xy 401.883354 -292.860912) (xy 401.836083 -292.874604) (xy 401.787228 -292.880536)
			(xy 401.738053 -292.878555) (xy 401.689834 -292.868711) (xy 401.643818 -292.851259) (xy 401.601197 -292.826652)
			(xy 401.563076 -292.795527) (xy 401.530441 -292.75869) (xy 401.504138 -292.717094) (xy 401.484847 -292.671818)
			(xy 401.47307 -292.624034) (xy 401.46911 -292.57498) (xy 401.130262 -292.57498) (xy 401.129767 -292.599587)
			(xy 401.121872 -292.648164) (xy 401.106288 -292.694845) (xy 401.083417 -292.738422) (xy 401.053852 -292.777766)
			(xy 401.018359 -292.811858) (xy 400.977856 -292.839814) (xy 400.933394 -292.860912) (xy 400.886123 -292.874604)
			(xy 400.837268 -292.880536) (xy 400.788093 -292.878555) (xy 400.739874 -292.868711) (xy 400.693858 -292.851259)
			(xy 400.651237 -292.826652) (xy 400.613116 -292.795527) (xy 400.580481 -292.75869) (xy 400.554178 -292.717094)
			(xy 400.534887 -292.671818) (xy 400.52311 -292.624034) (xy 400.51915 -292.57498) (xy 400.180302 -292.57498)
			(xy 400.179807 -292.599587) (xy 400.171912 -292.648164) (xy 400.156328 -292.694845) (xy 400.133457 -292.738422)
			(xy 400.103892 -292.777766) (xy 400.068399 -292.811858) (xy 400.027896 -292.839814) (xy 399.983434 -292.860912)
			(xy 399.936163 -292.874604) (xy 399.887308 -292.880536) (xy 399.838133 -292.878555) (xy 399.789914 -292.868711)
			(xy 399.743898 -292.851259) (xy 399.701277 -292.826652) (xy 399.663156 -292.795527) (xy 399.630521 -292.75869)
			(xy 399.604218 -292.717094) (xy 399.584927 -292.671818) (xy 399.57315 -292.624034) (xy 399.56919 -292.57498)
			(xy 399.230342 -292.57498) (xy 399.229847 -292.599587) (xy 399.221952 -292.648164) (xy 399.206368 -292.694845)
			(xy 399.183497 -292.738422) (xy 399.153932 -292.777766) (xy 399.118439 -292.811858) (xy 399.077936 -292.839814)
			(xy 399.033474 -292.860912) (xy 398.986203 -292.874604) (xy 398.937348 -292.880536) (xy 398.888173 -292.878555)
			(xy 398.839954 -292.868711) (xy 398.793938 -292.851259) (xy 398.751317 -292.826652) (xy 398.713196 -292.795527)
			(xy 398.680561 -292.75869) (xy 398.654258 -292.717094) (xy 398.634967 -292.671818) (xy 398.62319 -292.624034)
			(xy 398.61923 -292.57498) (xy 398.280123 -292.57498) (xy 398.279633 -292.599333) (xy 398.271738 -292.64791)
			(xy 398.256154 -292.694591) (xy 398.233283 -292.738168) (xy 398.203718 -292.777512) (xy 398.168225 -292.811604)
			(xy 398.127722 -292.83956) (xy 398.08326 -292.860658) (xy 398.035989 -292.87435) (xy 397.987134 -292.880282)
			(xy 397.937959 -292.878301) (xy 397.88974 -292.868457) (xy 397.843724 -292.851005) (xy 397.801103 -292.826398)
			(xy 397.762982 -292.795273) (xy 397.730347 -292.758436) (xy 397.704044 -292.71684) (xy 397.684753 -292.671564)
			(xy 397.672976 -292.62378) (xy 397.669016 -292.574726) (xy 396.380203 -292.574726) (xy 396.380208 -292.57498)
			(xy 396.379713 -292.599587) (xy 396.371818 -292.648164) (xy 396.356234 -292.694845) (xy 396.333363 -292.738422)
			(xy 396.303798 -292.777766) (xy 396.268305 -292.811858) (xy 396.227802 -292.839814) (xy 396.18334 -292.860912)
			(xy 396.136069 -292.874604) (xy 396.087214 -292.880536) (xy 396.038039 -292.878555) (xy 395.98982 -292.868711)
			(xy 395.943804 -292.851259) (xy 395.901183 -292.826652) (xy 395.863062 -292.795527) (xy 395.830427 -292.75869)
			(xy 395.804124 -292.717094) (xy 395.784833 -292.671818) (xy 395.773056 -292.624034) (xy 395.769096 -292.57498)
			(xy 395.430248 -292.57498) (xy 395.429753 -292.599587) (xy 395.421858 -292.648164) (xy 395.406274 -292.694845)
			(xy 395.383403 -292.738422) (xy 395.353838 -292.777766) (xy 395.318345 -292.811858) (xy 395.277842 -292.839814)
			(xy 395.23338 -292.860912) (xy 395.186109 -292.874604) (xy 395.137254 -292.880536) (xy 395.088079 -292.878555)
			(xy 395.03986 -292.868711) (xy 394.993844 -292.851259) (xy 394.951223 -292.826652) (xy 394.913102 -292.795527)
			(xy 394.880467 -292.75869) (xy 394.854164 -292.717094) (xy 394.834873 -292.671818) (xy 394.823096 -292.624034)
			(xy 394.819136 -292.57498) (xy 394.480288 -292.57498) (xy 394.479793 -292.599587) (xy 394.471898 -292.648164)
			(xy 394.456314 -292.694845) (xy 394.433443 -292.738422) (xy 394.403878 -292.777766) (xy 394.368385 -292.811858)
			(xy 394.327882 -292.839814) (xy 394.28342 -292.860912) (xy 394.236149 -292.874604) (xy 394.187294 -292.880536)
			(xy 394.138119 -292.878555) (xy 394.0899 -292.868711) (xy 394.043884 -292.851259) (xy 394.001263 -292.826652)
			(xy 393.963142 -292.795527) (xy 393.930507 -292.75869) (xy 393.904204 -292.717094) (xy 393.884913 -292.671818)
			(xy 393.873136 -292.624034) (xy 393.869176 -292.57498) (xy 393.530328 -292.57498) (xy 393.529833 -292.599587)
			(xy 393.521938 -292.648164) (xy 393.506354 -292.694845) (xy 393.483483 -292.738422) (xy 393.453918 -292.777766)
			(xy 393.418425 -292.811858) (xy 393.377922 -292.839814) (xy 393.33346 -292.860912) (xy 393.286189 -292.874604)
			(xy 393.237334 -292.880536) (xy 393.188159 -292.878555) (xy 393.13994 -292.868711) (xy 393.093924 -292.851259)
			(xy 393.051303 -292.826652) (xy 393.013182 -292.795527) (xy 392.980547 -292.75869) (xy 392.954244 -292.717094)
			(xy 392.934953 -292.671818) (xy 392.923176 -292.624034) (xy 392.919216 -292.57498) (xy 392.580114 -292.57498)
			(xy 392.579619 -292.599587) (xy 392.571724 -292.648164) (xy 392.55614 -292.694845) (xy 392.533269 -292.738422)
			(xy 392.503704 -292.777766) (xy 392.468211 -292.811858) (xy 392.427708 -292.839814) (xy 392.383246 -292.860912)
			(xy 392.335975 -292.874604) (xy 392.28712 -292.880536) (xy 392.237945 -292.878555) (xy 392.189726 -292.868711)
			(xy 392.14371 -292.851259) (xy 392.101089 -292.826652) (xy 392.062968 -292.795527) (xy 392.030333 -292.75869)
			(xy 392.00403 -292.717094) (xy 391.984739 -292.671818) (xy 391.972962 -292.624034) (xy 391.969002 -292.57498)
			(xy 391.630154 -292.57498) (xy 391.629659 -292.599587) (xy 391.621764 -292.648164) (xy 391.60618 -292.694845)
			(xy 391.583309 -292.738422) (xy 391.553744 -292.777766) (xy 391.518251 -292.811858) (xy 391.477748 -292.839814)
			(xy 391.433286 -292.860912) (xy 391.386015 -292.874604) (xy 391.33716 -292.880536) (xy 391.287985 -292.878555)
			(xy 391.239766 -292.868711) (xy 391.19375 -292.851259) (xy 391.151129 -292.826652) (xy 391.113008 -292.795527)
			(xy 391.080373 -292.75869) (xy 391.05407 -292.717094) (xy 391.034779 -292.671818) (xy 391.023002 -292.624034)
			(xy 391.019042 -292.57498) (xy 390.730994 -292.57498) (xy 390.730496 -292.601629) (xy 390.722553 -292.654333)
			(xy 390.706843 -292.705263) (xy 390.683717 -292.753284) (xy 390.653693 -292.797321) (xy 390.617441 -292.836392)
			(xy 390.57577 -292.869623) (xy 390.529612 -292.896272) (xy 390.479998 -292.915744) (xy 390.428036 -292.927604)
			(xy 390.374886 -292.931588) (xy 390.321736 -292.927604) (xy 390.269774 -292.915744) (xy 390.22016 -292.896272)
			(xy 390.174002 -292.869623) (xy 390.132331 -292.836392) (xy 390.096079 -292.797321) (xy 390.066055 -292.753284)
			(xy 390.042929 -292.705263) (xy 390.027219 -292.654333) (xy 390.019276 -292.601629) (xy 389.729407 -292.601629)
			(xy 389.721844 -292.648164) (xy 389.70626 -292.694845) (xy 389.683389 -292.738422) (xy 389.653824 -292.777766)
			(xy 389.618331 -292.811858) (xy 389.577828 -292.839814) (xy 389.533366 -292.860912) (xy 389.486095 -292.874604)
			(xy 389.43724 -292.880536) (xy 389.388065 -292.878555) (xy 389.339846 -292.868711) (xy 389.29383 -292.851259)
			(xy 389.251209 -292.826652) (xy 389.213088 -292.795527) (xy 389.180453 -292.75869) (xy 389.15415 -292.717094)
			(xy 389.134859 -292.671818) (xy 389.123082 -292.624034) (xy 389.119122 -292.57498) (xy 388.780269 -292.57498)
			(xy 388.779779 -292.599333) (xy 388.771884 -292.64791) (xy 388.7563 -292.694591) (xy 388.733429 -292.738168)
			(xy 388.703864 -292.777512) (xy 388.668371 -292.811604) (xy 388.627868 -292.83956) (xy 388.583406 -292.860658)
			(xy 388.536135 -292.87435) (xy 388.48728 -292.880282) (xy 388.438105 -292.878301) (xy 388.389886 -292.868457)
			(xy 388.34387 -292.851005) (xy 388.301249 -292.826398) (xy 388.263128 -292.795273) (xy 388.230493 -292.758436)
			(xy 388.20419 -292.71684) (xy 388.184899 -292.671564) (xy 388.173122 -292.62378) (xy 388.169162 -292.574726)
			(xy 387.830314 -292.574726) (xy 387.829819 -292.599333) (xy 387.821924 -292.64791) (xy 387.80634 -292.694591)
			(xy 387.783469 -292.738168) (xy 387.753904 -292.777512) (xy 387.718411 -292.811604) (xy 387.677908 -292.83956)
			(xy 387.633446 -292.860658) (xy 387.586175 -292.87435) (xy 387.53732 -292.880282) (xy 387.488145 -292.878301)
			(xy 387.439926 -292.868457) (xy 387.39391 -292.851005) (xy 387.351289 -292.826398) (xy 387.313168 -292.795273)
			(xy 387.280533 -292.758436) (xy 387.25423 -292.71684) (xy 387.234939 -292.671564) (xy 387.223162 -292.62378)
			(xy 387.219202 -292.574726) (xy 386.880349 -292.574726) (xy 386.880354 -292.57498) (xy 386.879859 -292.599587)
			(xy 386.871964 -292.648164) (xy 386.85638 -292.694845) (xy 386.833509 -292.738422) (xy 386.803944 -292.777766)
			(xy 386.768451 -292.811858) (xy 386.727948 -292.839814) (xy 386.683486 -292.860912) (xy 386.636215 -292.874604)
			(xy 386.58736 -292.880536) (xy 386.538185 -292.878555) (xy 386.489966 -292.868711) (xy 386.44395 -292.851259)
			(xy 386.401329 -292.826652) (xy 386.363208 -292.795527) (xy 386.330573 -292.75869) (xy 386.30427 -292.717094)
			(xy 386.284979 -292.671818) (xy 386.273202 -292.624034) (xy 386.269242 -292.57498) (xy 385.93014 -292.57498)
			(xy 385.929645 -292.599587) (xy 385.92175 -292.648164) (xy 385.906166 -292.694845) (xy 385.883295 -292.738422)
			(xy 385.85373 -292.777766) (xy 385.818237 -292.811858) (xy 385.777734 -292.839814) (xy 385.733272 -292.860912)
			(xy 385.686001 -292.874604) (xy 385.637146 -292.880536) (xy 385.587971 -292.878555) (xy 385.539752 -292.868711)
			(xy 385.493736 -292.851259) (xy 385.451115 -292.826652) (xy 385.412994 -292.795527) (xy 385.380359 -292.75869)
			(xy 385.354056 -292.717094) (xy 385.334765 -292.671818) (xy 385.322988 -292.624034) (xy 385.319028 -292.57498)
			(xy 384.98018 -292.57498) (xy 384.979685 -292.599587) (xy 384.97179 -292.648164) (xy 384.956206 -292.694845)
			(xy 384.933335 -292.738422) (xy 384.90377 -292.777766) (xy 384.868277 -292.811858) (xy 384.827774 -292.839814)
			(xy 384.783312 -292.860912) (xy 384.736041 -292.874604) (xy 384.687186 -292.880536) (xy 384.638011 -292.878555)
			(xy 384.589792 -292.868711) (xy 384.543776 -292.851259) (xy 384.501155 -292.826652) (xy 384.463034 -292.795527)
			(xy 384.430399 -292.75869) (xy 384.404096 -292.717094) (xy 384.384805 -292.671818) (xy 384.373028 -292.624034)
			(xy 384.369068 -292.57498) (xy 380.377831 -292.57498) (xy 380.388901 -292.59922) (xy 380.404256 -292.651515)
			(xy 380.412012 -292.705463) (xy 380.412498 -292.732714) (xy 380.411971 -292.762097) (xy 380.402938 -292.820164)
			(xy 380.385103 -292.876159) (xy 380.358889 -292.928754) (xy 380.324916 -292.976705) (xy 380.283989 -293.018876)
			(xy 380.26086 -293.037006) (xy 380.251924 -293.044475) (xy 380.241471 -293.065257) (xy 380.240794 -293.076884)
			(xy 380.239524 -293.168832) (xy 380.24943 -293.189914) (xy 380.258574 -293.19728) (xy 380.280389 -293.215524)
			(xy 380.318933 -293.257334) (xy 380.350844 -293.304401) (xy 380.375417 -293.355684) (xy 380.392107 -293.410045)
			(xy 380.400545 -293.466281) (xy 380.401068 -293.494714) (xy 381.034542 -293.494714) (xy 381.038613 -293.439092)
			(xy 381.050739 -293.384655) (xy 381.070662 -293.332564) (xy 381.097958 -293.283929) (xy 381.132044 -293.239786)
			(xy 381.172193 -293.201077) (xy 381.217551 -293.168626) (xy 381.267151 -293.143125) (xy 381.319935 -293.125118)
			(xy 381.374778 -293.114988) (xy 381.430512 -293.112951) (xy 381.485949 -293.119051) (xy 381.539906 -293.133157)
			(xy 381.591235 -293.154969) (xy 381.638841 -293.184023) (xy 381.681709 -293.219698) (xy 381.718926 -293.261235)
			(xy 381.749699 -293.307748) (xy 381.773371 -293.358245) (xy 381.789439 -293.411652) (xy 381.797559 -293.466828)
			(xy 381.798068 -293.494714) (xy 381.921002 -293.494714) (xy 381.925073 -293.439092) (xy 381.937199 -293.384655)
			(xy 381.957122 -293.332564) (xy 381.984418 -293.283929) (xy 382.018504 -293.239786) (xy 382.058653 -293.201077)
			(xy 382.104011 -293.168626) (xy 382.153611 -293.143125) (xy 382.206395 -293.125118) (xy 382.261238 -293.114988)
			(xy 382.316972 -293.112951) (xy 382.372409 -293.119051) (xy 382.426366 -293.133157) (xy 382.477695 -293.154969)
			(xy 382.525301 -293.184023) (xy 382.568169 -293.219698) (xy 382.605386 -293.261235) (xy 382.636159 -293.307748)
			(xy 382.659831 -293.358245) (xy 382.675899 -293.411652) (xy 382.684019 -293.466828) (xy 382.684528 -293.494714)
			(xy 382.684019 -293.5226) (xy 382.683675 -293.52494) (xy 384.369068 -293.52494) (xy 384.373028 -293.475886)
			(xy 384.384805 -293.428102) (xy 384.404096 -293.382826) (xy 384.430399 -293.34123) (xy 384.463034 -293.304393)
			(xy 384.501155 -293.273268) (xy 384.543776 -293.248661) (xy 384.589792 -293.231209) (xy 384.638011 -293.221365)
			(xy 384.687186 -293.219384) (xy 384.736041 -293.225316) (xy 384.783312 -293.239008) (xy 384.827774 -293.260106)
			(xy 384.868277 -293.288062) (xy 384.90377 -293.322154) (xy 384.933335 -293.361498) (xy 384.956206 -293.405075)
			(xy 384.97179 -293.451756) (xy 384.979685 -293.500333) (xy 384.98018 -293.52494) (xy 385.319028 -293.52494)
			(xy 385.322988 -293.475886) (xy 385.334765 -293.428102) (xy 385.354056 -293.382826) (xy 385.380359 -293.34123)
			(xy 385.412994 -293.304393) (xy 385.451115 -293.273268) (xy 385.493736 -293.248661) (xy 385.539752 -293.231209)
			(xy 385.587971 -293.221365) (xy 385.637146 -293.219384) (xy 385.686001 -293.225316) (xy 385.733272 -293.239008)
			(xy 385.777734 -293.260106) (xy 385.818237 -293.288062) (xy 385.85373 -293.322154) (xy 385.883295 -293.361498)
			(xy 385.906166 -293.405075) (xy 385.92175 -293.451756) (xy 385.929645 -293.500333) (xy 385.93014 -293.52494)
			(xy 386.269242 -293.52494) (xy 386.273202 -293.475886) (xy 386.284979 -293.428102) (xy 386.30427 -293.382826)
			(xy 386.330573 -293.34123) (xy 386.363208 -293.304393) (xy 386.401329 -293.273268) (xy 386.44395 -293.248661)
			(xy 386.489966 -293.231209) (xy 386.538185 -293.221365) (xy 386.58736 -293.219384) (xy 386.636215 -293.225316)
			(xy 386.683486 -293.239008) (xy 386.727948 -293.260106) (xy 386.768451 -293.288062) (xy 386.803944 -293.322154)
			(xy 386.833509 -293.361498) (xy 386.85638 -293.405075) (xy 386.871964 -293.451756) (xy 386.879859 -293.500333)
			(xy 386.880354 -293.52494) (xy 387.219202 -293.52494) (xy 387.223162 -293.475886) (xy 387.234939 -293.428102)
			(xy 387.25423 -293.382826) (xy 387.280533 -293.34123) (xy 387.313168 -293.304393) (xy 387.351289 -293.273268)
			(xy 387.39391 -293.248661) (xy 387.439926 -293.231209) (xy 387.488145 -293.221365) (xy 387.53732 -293.219384)
			(xy 387.586175 -293.225316) (xy 387.633446 -293.239008) (xy 387.677908 -293.260106) (xy 387.718411 -293.288062)
			(xy 387.753904 -293.322154) (xy 387.783469 -293.361498) (xy 387.80634 -293.405075) (xy 387.821924 -293.451756)
			(xy 387.829819 -293.500333) (xy 387.830314 -293.52494) (xy 388.169162 -293.52494) (xy 388.173122 -293.475886)
			(xy 388.184899 -293.428102) (xy 388.20419 -293.382826) (xy 388.230493 -293.34123) (xy 388.263128 -293.304393)
			(xy 388.301249 -293.273268) (xy 388.34387 -293.248661) (xy 388.389886 -293.231209) (xy 388.438105 -293.221365)
			(xy 388.48728 -293.219384) (xy 388.536135 -293.225316) (xy 388.583406 -293.239008) (xy 388.627868 -293.260106)
			(xy 388.668371 -293.288062) (xy 388.703864 -293.322154) (xy 388.733429 -293.361498) (xy 388.7563 -293.405075)
			(xy 388.771884 -293.451756) (xy 388.779779 -293.500333) (xy 388.780274 -293.52494) (xy 389.119122 -293.52494)
			(xy 389.123082 -293.475886) (xy 389.134859 -293.428102) (xy 389.15415 -293.382826) (xy 389.180453 -293.34123)
			(xy 389.213088 -293.304393) (xy 389.251209 -293.273268) (xy 389.29383 -293.248661) (xy 389.339846 -293.231209)
			(xy 389.388065 -293.221365) (xy 389.43724 -293.219384) (xy 389.486095 -293.225316) (xy 389.533366 -293.239008)
			(xy 389.577828 -293.260106) (xy 389.618331 -293.288062) (xy 389.653824 -293.322154) (xy 389.683389 -293.361498)
			(xy 389.70626 -293.405075) (xy 389.721844 -293.451756) (xy 389.729739 -293.500333) (xy 389.730234 -293.52494)
			(xy 390.069082 -293.52494) (xy 390.073042 -293.475886) (xy 390.084819 -293.428102) (xy 390.10411 -293.382826)
			(xy 390.130413 -293.34123) (xy 390.163048 -293.304393) (xy 390.201169 -293.273268) (xy 390.24379 -293.248661)
			(xy 390.289806 -293.231209) (xy 390.338025 -293.221365) (xy 390.3872 -293.219384) (xy 390.436055 -293.225316)
			(xy 390.483326 -293.239008) (xy 390.527788 -293.260106) (xy 390.568291 -293.288062) (xy 390.603784 -293.322154)
			(xy 390.633349 -293.361498) (xy 390.65622 -293.405075) (xy 390.671804 -293.451756) (xy 390.679699 -293.500333)
			(xy 390.680194 -293.52494) (xy 390.679699 -293.549547) (xy 390.679367 -293.551589) (xy 390.969236 -293.551589)
			(xy 390.969236 -293.498291) (xy 390.977179 -293.445587) (xy 390.992889 -293.394657) (xy 391.016015 -293.346636)
			(xy 391.046039 -293.302599) (xy 391.082291 -293.263528) (xy 391.123962 -293.230297) (xy 391.17012 -293.203648)
			(xy 391.219734 -293.184176) (xy 391.271696 -293.172316) (xy 391.324846 -293.168333) (xy 391.377996 -293.172316)
			(xy 391.429958 -293.184176) (xy 391.479572 -293.203648) (xy 391.52573 -293.230297) (xy 391.567401 -293.263528)
			(xy 391.603653 -293.302599) (xy 391.633677 -293.346636) (xy 391.656803 -293.394657) (xy 391.672513 -293.445587)
			(xy 391.680456 -293.498291) (xy 391.680954 -293.52494) (xy 391.969002 -293.52494) (xy 391.972962 -293.475886)
			(xy 391.984739 -293.428102) (xy 392.00403 -293.382826) (xy 392.030333 -293.34123) (xy 392.062968 -293.304393)
			(xy 392.101089 -293.273268) (xy 392.14371 -293.248661) (xy 392.189726 -293.231209) (xy 392.237945 -293.221365)
			(xy 392.28712 -293.219384) (xy 392.335975 -293.225316) (xy 392.383246 -293.239008) (xy 392.427708 -293.260106)
			(xy 392.468211 -293.288062) (xy 392.503704 -293.322154) (xy 392.533269 -293.361498) (xy 392.55614 -293.405075)
			(xy 392.571724 -293.451756) (xy 392.579619 -293.500333) (xy 392.580114 -293.52494) (xy 393.869176 -293.52494)
			(xy 393.873136 -293.475886) (xy 393.884913 -293.428102) (xy 393.904204 -293.382826) (xy 393.930507 -293.34123)
			(xy 393.963142 -293.304393) (xy 394.001263 -293.273268) (xy 394.043884 -293.248661) (xy 394.0899 -293.231209)
			(xy 394.138119 -293.221365) (xy 394.187294 -293.219384) (xy 394.236149 -293.225316) (xy 394.28342 -293.239008)
			(xy 394.327882 -293.260106) (xy 394.368385 -293.288062) (xy 394.403878 -293.322154) (xy 394.433443 -293.361498)
			(xy 394.456314 -293.405075) (xy 394.471898 -293.451756) (xy 394.479793 -293.500333) (xy 394.480288 -293.52494)
			(xy 395.769096 -293.52494) (xy 395.773056 -293.475886) (xy 395.784833 -293.428102) (xy 395.804124 -293.382826)
			(xy 395.830427 -293.34123) (xy 395.863062 -293.304393) (xy 395.901183 -293.273268) (xy 395.943804 -293.248661)
			(xy 395.98982 -293.231209) (xy 396.038039 -293.221365) (xy 396.087214 -293.219384) (xy 396.136069 -293.225316)
			(xy 396.18334 -293.239008) (xy 396.227802 -293.260106) (xy 396.268305 -293.288062) (xy 396.303798 -293.322154)
			(xy 396.333363 -293.361498) (xy 396.356234 -293.405075) (xy 396.371818 -293.451756) (xy 396.379713 -293.500333)
			(xy 396.380208 -293.52494) (xy 396.719056 -293.52494) (xy 396.723016 -293.475886) (xy 396.734793 -293.428102)
			(xy 396.754084 -293.382826) (xy 396.780387 -293.34123) (xy 396.813022 -293.304393) (xy 396.851143 -293.273268)
			(xy 396.893764 -293.248661) (xy 396.93978 -293.231209) (xy 396.987999 -293.221365) (xy 397.037174 -293.219384)
			(xy 397.086029 -293.225316) (xy 397.1333 -293.239008) (xy 397.177762 -293.260106) (xy 397.218265 -293.288062)
			(xy 397.253758 -293.322154) (xy 397.283323 -293.361498) (xy 397.306194 -293.405075) (xy 397.321778 -293.451756)
			(xy 397.329673 -293.500333) (xy 397.330168 -293.52494) (xy 398.61923 -293.52494) (xy 398.62319 -293.475886)
			(xy 398.634967 -293.428102) (xy 398.654258 -293.382826) (xy 398.680561 -293.34123) (xy 398.713196 -293.304393)
			(xy 398.751317 -293.273268) (xy 398.793938 -293.248661) (xy 398.839954 -293.231209) (xy 398.888173 -293.221365)
			(xy 398.937348 -293.219384) (xy 398.986203 -293.225316) (xy 399.033474 -293.239008) (xy 399.077936 -293.260106)
			(xy 399.118439 -293.288062) (xy 399.153932 -293.322154) (xy 399.183497 -293.361498) (xy 399.206368 -293.405075)
			(xy 399.221952 -293.451756) (xy 399.229847 -293.500333) (xy 399.230342 -293.52494) (xy 400.51915 -293.52494)
			(xy 400.52311 -293.475886) (xy 400.534887 -293.428102) (xy 400.554178 -293.382826) (xy 400.580481 -293.34123)
			(xy 400.613116 -293.304393) (xy 400.651237 -293.273268) (xy 400.693858 -293.248661) (xy 400.739874 -293.231209)
			(xy 400.788093 -293.221365) (xy 400.837268 -293.219384) (xy 400.886123 -293.225316) (xy 400.933394 -293.239008)
			(xy 400.977856 -293.260106) (xy 401.018359 -293.288062) (xy 401.053852 -293.322154) (xy 401.083417 -293.361498)
			(xy 401.106288 -293.405075) (xy 401.121872 -293.451756) (xy 401.129767 -293.500333) (xy 401.130262 -293.52494)
			(xy 402.41907 -293.52494) (xy 402.42303 -293.475886) (xy 402.434807 -293.428102) (xy 402.454098 -293.382826)
			(xy 402.480401 -293.34123) (xy 402.513036 -293.304393) (xy 402.551157 -293.273268) (xy 402.593778 -293.248661)
			(xy 402.639794 -293.231209) (xy 402.688013 -293.221365) (xy 402.737188 -293.219384) (xy 402.786043 -293.225316)
			(xy 402.833314 -293.239008) (xy 402.877776 -293.260106) (xy 402.918279 -293.288062) (xy 402.953772 -293.322154)
			(xy 402.983337 -293.361498) (xy 403.006208 -293.405075) (xy 403.021792 -293.451756) (xy 403.029687 -293.500333)
			(xy 403.030182 -293.52494) (xy 404.31899 -293.52494) (xy 404.32295 -293.475886) (xy 404.334727 -293.428102)
			(xy 404.354018 -293.382826) (xy 404.380321 -293.34123) (xy 404.412956 -293.304393) (xy 404.451077 -293.273268)
			(xy 404.493698 -293.248661) (xy 404.539714 -293.231209) (xy 404.587933 -293.221365) (xy 404.637108 -293.219384)
			(xy 404.685963 -293.225316) (xy 404.733234 -293.239008) (xy 404.777696 -293.260106) (xy 404.818199 -293.288062)
			(xy 404.853692 -293.322154) (xy 404.883257 -293.361498) (xy 404.906128 -293.405075) (xy 404.921712 -293.451756)
			(xy 404.929607 -293.500333) (xy 404.930102 -293.52494) (xy 406.219164 -293.52494) (xy 406.223124 -293.475886)
			(xy 406.234901 -293.428102) (xy 406.254192 -293.382826) (xy 406.280495 -293.34123) (xy 406.31313 -293.304393)
			(xy 406.351251 -293.273268) (xy 406.393872 -293.248661) (xy 406.439888 -293.231209) (xy 406.488107 -293.221365)
			(xy 406.537282 -293.219384) (xy 406.586137 -293.225316) (xy 406.633408 -293.239008) (xy 406.67787 -293.260106)
			(xy 406.718373 -293.288062) (xy 406.753866 -293.322154) (xy 406.783431 -293.361498) (xy 406.806302 -293.405075)
			(xy 406.821886 -293.451756) (xy 406.829781 -293.500333) (xy 406.830276 -293.52494) (xy 409.069044 -293.52494)
			(xy 409.073004 -293.475886) (xy 409.084781 -293.428102) (xy 409.104072 -293.382826) (xy 409.130375 -293.34123)
			(xy 409.16301 -293.304393) (xy 409.201131 -293.273268) (xy 409.243752 -293.248661) (xy 409.289768 -293.231209)
			(xy 409.337987 -293.221365) (xy 409.387162 -293.219384) (xy 409.436017 -293.225316) (xy 409.483288 -293.239008)
			(xy 409.52775 -293.260106) (xy 409.568253 -293.288062) (xy 409.603746 -293.322154) (xy 409.633311 -293.361498)
			(xy 409.656182 -293.405075) (xy 409.671766 -293.451756) (xy 409.679661 -293.500333) (xy 409.680156 -293.52494)
			(xy 410.969218 -293.52494) (xy 410.973178 -293.475886) (xy 410.984955 -293.428102) (xy 411.004246 -293.382826)
			(xy 411.030549 -293.34123) (xy 411.063184 -293.304393) (xy 411.101305 -293.273268) (xy 411.143926 -293.248661)
			(xy 411.189942 -293.231209) (xy 411.238161 -293.221365) (xy 411.287336 -293.219384) (xy 411.336191 -293.225316)
			(xy 411.383462 -293.239008) (xy 411.427924 -293.260106) (xy 411.468427 -293.288062) (xy 411.50392 -293.322154)
			(xy 411.533485 -293.361498) (xy 411.556356 -293.405075) (xy 411.57194 -293.451756) (xy 411.579835 -293.500333)
			(xy 411.58033 -293.52494) (xy 412.869138 -293.52494) (xy 412.873098 -293.475886) (xy 412.884875 -293.428102)
			(xy 412.904166 -293.382826) (xy 412.930469 -293.34123) (xy 412.963104 -293.304393) (xy 413.001225 -293.273268)
			(xy 413.043846 -293.248661) (xy 413.089862 -293.231209) (xy 413.138081 -293.221365) (xy 413.187256 -293.219384)
			(xy 413.236111 -293.225316) (xy 413.283382 -293.239008) (xy 413.327844 -293.260106) (xy 413.368347 -293.288062)
			(xy 413.40384 -293.322154) (xy 413.433405 -293.361498) (xy 413.456276 -293.405075) (xy 413.47186 -293.451756)
			(xy 413.479755 -293.500333) (xy 413.48025 -293.52494) (xy 414.769058 -293.52494) (xy 414.773018 -293.475886)
			(xy 414.784795 -293.428102) (xy 414.804086 -293.382826) (xy 414.830389 -293.34123) (xy 414.863024 -293.304393)
			(xy 414.901145 -293.273268) (xy 414.943766 -293.248661) (xy 414.989782 -293.231209) (xy 415.038001 -293.221365)
			(xy 415.087176 -293.219384) (xy 415.136031 -293.225316) (xy 415.183302 -293.239008) (xy 415.227764 -293.260106)
			(xy 415.268267 -293.288062) (xy 415.30376 -293.322154) (xy 415.333325 -293.361498) (xy 415.356196 -293.405075)
			(xy 415.37178 -293.451756) (xy 415.379675 -293.500333) (xy 415.38017 -293.52494) (xy 415.379675 -293.549547)
			(xy 415.37178 -293.598124) (xy 415.356196 -293.644805) (xy 415.333325 -293.688382) (xy 415.30376 -293.727726)
			(xy 415.268267 -293.761818) (xy 415.227764 -293.789774) (xy 415.183302 -293.810872) (xy 415.136031 -293.824564)
			(xy 415.087176 -293.830496) (xy 415.038001 -293.828515) (xy 414.989782 -293.818671) (xy 414.943766 -293.801219)
			(xy 414.901145 -293.776612) (xy 414.863024 -293.745487) (xy 414.830389 -293.70865) (xy 414.804086 -293.667054)
			(xy 414.784795 -293.621778) (xy 414.773018 -293.573994) (xy 414.769058 -293.52494) (xy 413.48025 -293.52494)
			(xy 413.479755 -293.549547) (xy 413.47186 -293.598124) (xy 413.456276 -293.644805) (xy 413.433405 -293.688382)
			(xy 413.40384 -293.727726) (xy 413.368347 -293.761818) (xy 413.327844 -293.789774) (xy 413.283382 -293.810872)
			(xy 413.236111 -293.824564) (xy 413.187256 -293.830496) (xy 413.138081 -293.828515) (xy 413.089862 -293.818671)
			(xy 413.043846 -293.801219) (xy 413.001225 -293.776612) (xy 412.963104 -293.745487) (xy 412.930469 -293.70865)
			(xy 412.904166 -293.667054) (xy 412.884875 -293.621778) (xy 412.873098 -293.573994) (xy 412.869138 -293.52494)
			(xy 411.58033 -293.52494) (xy 411.579835 -293.549547) (xy 411.57194 -293.598124) (xy 411.556356 -293.644805)
			(xy 411.533485 -293.688382) (xy 411.50392 -293.727726) (xy 411.468427 -293.761818) (xy 411.427924 -293.789774)
			(xy 411.383462 -293.810872) (xy 411.336191 -293.824564) (xy 411.287336 -293.830496) (xy 411.238161 -293.828515)
			(xy 411.189942 -293.818671) (xy 411.143926 -293.801219) (xy 411.101305 -293.776612) (xy 411.063184 -293.745487)
			(xy 411.030549 -293.70865) (xy 411.004246 -293.667054) (xy 410.984955 -293.621778) (xy 410.973178 -293.573994)
			(xy 410.969218 -293.52494) (xy 409.680156 -293.52494) (xy 409.679661 -293.549547) (xy 409.671766 -293.598124)
			(xy 409.656182 -293.644805) (xy 409.633311 -293.688382) (xy 409.603746 -293.727726) (xy 409.568253 -293.761818)
			(xy 409.52775 -293.789774) (xy 409.483288 -293.810872) (xy 409.436017 -293.824564) (xy 409.387162 -293.830496)
			(xy 409.337987 -293.828515) (xy 409.289768 -293.818671) (xy 409.243752 -293.801219) (xy 409.201131 -293.776612)
			(xy 409.16301 -293.745487) (xy 409.130375 -293.70865) (xy 409.104072 -293.667054) (xy 409.084781 -293.621778)
			(xy 409.073004 -293.573994) (xy 409.069044 -293.52494) (xy 406.830276 -293.52494) (xy 406.829781 -293.549547)
			(xy 406.821886 -293.598124) (xy 406.806302 -293.644805) (xy 406.783431 -293.688382) (xy 406.753866 -293.727726)
			(xy 406.718373 -293.761818) (xy 406.67787 -293.789774) (xy 406.633408 -293.810872) (xy 406.586137 -293.824564)
			(xy 406.537282 -293.830496) (xy 406.488107 -293.828515) (xy 406.439888 -293.818671) (xy 406.393872 -293.801219)
			(xy 406.351251 -293.776612) (xy 406.31313 -293.745487) (xy 406.280495 -293.70865) (xy 406.254192 -293.667054)
			(xy 406.234901 -293.621778) (xy 406.223124 -293.573994) (xy 406.219164 -293.52494) (xy 404.930102 -293.52494)
			(xy 404.929607 -293.549547) (xy 404.921712 -293.598124) (xy 404.906128 -293.644805) (xy 404.883257 -293.688382)
			(xy 404.853692 -293.727726) (xy 404.818199 -293.761818) (xy 404.777696 -293.789774) (xy 404.733234 -293.810872)
			(xy 404.685963 -293.824564) (xy 404.637108 -293.830496) (xy 404.587933 -293.828515) (xy 404.539714 -293.818671)
			(xy 404.493698 -293.801219) (xy 404.451077 -293.776612) (xy 404.412956 -293.745487) (xy 404.380321 -293.70865)
			(xy 404.354018 -293.667054) (xy 404.334727 -293.621778) (xy 404.32295 -293.573994) (xy 404.31899 -293.52494)
			(xy 403.030182 -293.52494) (xy 403.029687 -293.549547) (xy 403.021792 -293.598124) (xy 403.006208 -293.644805)
			(xy 402.983337 -293.688382) (xy 402.953772 -293.727726) (xy 402.918279 -293.761818) (xy 402.877776 -293.789774)
			(xy 402.833314 -293.810872) (xy 402.786043 -293.824564) (xy 402.737188 -293.830496) (xy 402.688013 -293.828515)
			(xy 402.639794 -293.818671) (xy 402.593778 -293.801219) (xy 402.551157 -293.776612) (xy 402.513036 -293.745487)
			(xy 402.480401 -293.70865) (xy 402.454098 -293.667054) (xy 402.434807 -293.621778) (xy 402.42303 -293.573994)
			(xy 402.41907 -293.52494) (xy 401.130262 -293.52494) (xy 401.129767 -293.549547) (xy 401.121872 -293.598124)
			(xy 401.106288 -293.644805) (xy 401.083417 -293.688382) (xy 401.053852 -293.727726) (xy 401.018359 -293.761818)
			(xy 400.977856 -293.789774) (xy 400.933394 -293.810872) (xy 400.886123 -293.824564) (xy 400.837268 -293.830496)
			(xy 400.788093 -293.828515) (xy 400.739874 -293.818671) (xy 400.693858 -293.801219) (xy 400.651237 -293.776612)
			(xy 400.613116 -293.745487) (xy 400.580481 -293.70865) (xy 400.554178 -293.667054) (xy 400.534887 -293.621778)
			(xy 400.52311 -293.573994) (xy 400.51915 -293.52494) (xy 399.230342 -293.52494) (xy 399.229847 -293.549547)
			(xy 399.221952 -293.598124) (xy 399.206368 -293.644805) (xy 399.183497 -293.688382) (xy 399.153932 -293.727726)
			(xy 399.118439 -293.761818) (xy 399.077936 -293.789774) (xy 399.033474 -293.810872) (xy 398.986203 -293.824564)
			(xy 398.937348 -293.830496) (xy 398.888173 -293.828515) (xy 398.839954 -293.818671) (xy 398.793938 -293.801219)
			(xy 398.751317 -293.776612) (xy 398.713196 -293.745487) (xy 398.680561 -293.70865) (xy 398.654258 -293.667054)
			(xy 398.634967 -293.621778) (xy 398.62319 -293.573994) (xy 398.61923 -293.52494) (xy 397.330168 -293.52494)
			(xy 397.329673 -293.549547) (xy 397.321778 -293.598124) (xy 397.306194 -293.644805) (xy 397.283323 -293.688382)
			(xy 397.253758 -293.727726) (xy 397.218265 -293.761818) (xy 397.177762 -293.789774) (xy 397.1333 -293.810872)
			(xy 397.086029 -293.824564) (xy 397.037174 -293.830496) (xy 396.987999 -293.828515) (xy 396.93978 -293.818671)
			(xy 396.893764 -293.801219) (xy 396.851143 -293.776612) (xy 396.813022 -293.745487) (xy 396.780387 -293.70865)
			(xy 396.754084 -293.667054) (xy 396.734793 -293.621778) (xy 396.723016 -293.573994) (xy 396.719056 -293.52494)
			(xy 396.380208 -293.52494) (xy 396.379713 -293.549547) (xy 396.371818 -293.598124) (xy 396.356234 -293.644805)
			(xy 396.333363 -293.688382) (xy 396.303798 -293.727726) (xy 396.268305 -293.761818) (xy 396.227802 -293.789774)
			(xy 396.18334 -293.810872) (xy 396.136069 -293.824564) (xy 396.087214 -293.830496) (xy 396.038039 -293.828515)
			(xy 395.98982 -293.818671) (xy 395.943804 -293.801219) (xy 395.901183 -293.776612) (xy 395.863062 -293.745487)
			(xy 395.830427 -293.70865) (xy 395.804124 -293.667054) (xy 395.784833 -293.621778) (xy 395.773056 -293.573994)
			(xy 395.769096 -293.52494) (xy 394.480288 -293.52494) (xy 394.479793 -293.549547) (xy 394.471898 -293.598124)
			(xy 394.456314 -293.644805) (xy 394.433443 -293.688382) (xy 394.403878 -293.727726) (xy 394.368385 -293.761818)
			(xy 394.327882 -293.789774) (xy 394.28342 -293.810872) (xy 394.236149 -293.824564) (xy 394.187294 -293.830496)
			(xy 394.138119 -293.828515) (xy 394.0899 -293.818671) (xy 394.043884 -293.801219) (xy 394.001263 -293.776612)
			(xy 393.963142 -293.745487) (xy 393.930507 -293.70865) (xy 393.904204 -293.667054) (xy 393.884913 -293.621778)
			(xy 393.873136 -293.573994) (xy 393.869176 -293.52494) (xy 392.580114 -293.52494) (xy 392.579619 -293.549547)
			(xy 392.571724 -293.598124) (xy 392.55614 -293.644805) (xy 392.533269 -293.688382) (xy 392.503704 -293.727726)
			(xy 392.468211 -293.761818) (xy 392.427708 -293.789774) (xy 392.383246 -293.810872) (xy 392.335975 -293.824564)
			(xy 392.28712 -293.830496) (xy 392.237945 -293.828515) (xy 392.189726 -293.818671) (xy 392.14371 -293.801219)
			(xy 392.101089 -293.776612) (xy 392.062968 -293.745487) (xy 392.030333 -293.70865) (xy 392.00403 -293.667054)
			(xy 391.984739 -293.621778) (xy 391.972962 -293.573994) (xy 391.969002 -293.52494) (xy 391.680954 -293.52494)
			(xy 391.680456 -293.551589) (xy 391.672513 -293.604293) (xy 391.656803 -293.655223) (xy 391.633677 -293.703244)
			(xy 391.603653 -293.747281) (xy 391.567401 -293.786352) (xy 391.52573 -293.819583) (xy 391.479572 -293.846232)
			(xy 391.429958 -293.865704) (xy 391.377996 -293.877564) (xy 391.324846 -293.881548) (xy 391.271696 -293.877564)
			(xy 391.219734 -293.865704) (xy 391.17012 -293.846232) (xy 391.123962 -293.819583) (xy 391.082291 -293.786352)
			(xy 391.046039 -293.747281) (xy 391.016015 -293.703244) (xy 390.992889 -293.655223) (xy 390.977179 -293.604293)
			(xy 390.969236 -293.551589) (xy 390.679367 -293.551589) (xy 390.671804 -293.598124) (xy 390.65622 -293.644805)
			(xy 390.633349 -293.688382) (xy 390.603784 -293.727726) (xy 390.568291 -293.761818) (xy 390.527788 -293.789774)
			(xy 390.483326 -293.810872) (xy 390.436055 -293.824564) (xy 390.3872 -293.830496) (xy 390.338025 -293.828515)
			(xy 390.289806 -293.818671) (xy 390.24379 -293.801219) (xy 390.201169 -293.776612) (xy 390.163048 -293.745487)
			(xy 390.130413 -293.70865) (xy 390.10411 -293.667054) (xy 390.084819 -293.621778) (xy 390.073042 -293.573994)
			(xy 390.069082 -293.52494) (xy 389.730234 -293.52494) (xy 389.729739 -293.549547) (xy 389.721844 -293.598124)
			(xy 389.70626 -293.644805) (xy 389.683389 -293.688382) (xy 389.653824 -293.727726) (xy 389.618331 -293.761818)
			(xy 389.577828 -293.789774) (xy 389.533366 -293.810872) (xy 389.486095 -293.824564) (xy 389.43724 -293.830496)
			(xy 389.388065 -293.828515) (xy 389.339846 -293.818671) (xy 389.29383 -293.801219) (xy 389.251209 -293.776612)
			(xy 389.213088 -293.745487) (xy 389.180453 -293.70865) (xy 389.15415 -293.667054) (xy 389.134859 -293.621778)
			(xy 389.123082 -293.573994) (xy 389.119122 -293.52494) (xy 388.780274 -293.52494) (xy 388.779779 -293.549547)
			(xy 388.771884 -293.598124) (xy 388.7563 -293.644805) (xy 388.733429 -293.688382) (xy 388.703864 -293.727726)
			(xy 388.668371 -293.761818) (xy 388.627868 -293.789774) (xy 388.583406 -293.810872) (xy 388.536135 -293.824564)
			(xy 388.48728 -293.830496) (xy 388.438105 -293.828515) (xy 388.389886 -293.818671) (xy 388.34387 -293.801219)
			(xy 388.301249 -293.776612) (xy 388.263128 -293.745487) (xy 388.230493 -293.70865) (xy 388.20419 -293.667054)
			(xy 388.184899 -293.621778) (xy 388.173122 -293.573994) (xy 388.169162 -293.52494) (xy 387.830314 -293.52494)
			(xy 387.829819 -293.549547) (xy 387.821924 -293.598124) (xy 387.80634 -293.644805) (xy 387.783469 -293.688382)
			(xy 387.753904 -293.727726) (xy 387.718411 -293.761818) (xy 387.677908 -293.789774) (xy 387.633446 -293.810872)
			(xy 387.586175 -293.824564) (xy 387.53732 -293.830496) (xy 387.488145 -293.828515) (xy 387.439926 -293.818671)
			(xy 387.39391 -293.801219) (xy 387.351289 -293.776612) (xy 387.313168 -293.745487) (xy 387.280533 -293.70865)
			(xy 387.25423 -293.667054) (xy 387.234939 -293.621778) (xy 387.223162 -293.573994) (xy 387.219202 -293.52494)
			(xy 386.880354 -293.52494) (xy 386.879859 -293.549547) (xy 386.871964 -293.598124) (xy 386.85638 -293.644805)
			(xy 386.833509 -293.688382) (xy 386.803944 -293.727726) (xy 386.768451 -293.761818) (xy 386.727948 -293.789774)
			(xy 386.683486 -293.810872) (xy 386.636215 -293.824564) (xy 386.58736 -293.830496) (xy 386.538185 -293.828515)
			(xy 386.489966 -293.818671) (xy 386.44395 -293.801219) (xy 386.401329 -293.776612) (xy 386.363208 -293.745487)
			(xy 386.330573 -293.70865) (xy 386.30427 -293.667054) (xy 386.284979 -293.621778) (xy 386.273202 -293.573994)
			(xy 386.269242 -293.52494) (xy 385.93014 -293.52494) (xy 385.929645 -293.549547) (xy 385.92175 -293.598124)
			(xy 385.906166 -293.644805) (xy 385.883295 -293.688382) (xy 385.85373 -293.727726) (xy 385.818237 -293.761818)
			(xy 385.777734 -293.789774) (xy 385.733272 -293.810872) (xy 385.686001 -293.824564) (xy 385.637146 -293.830496)
			(xy 385.587971 -293.828515) (xy 385.539752 -293.818671) (xy 385.493736 -293.801219) (xy 385.451115 -293.776612)
			(xy 385.412994 -293.745487) (xy 385.380359 -293.70865) (xy 385.354056 -293.667054) (xy 385.334765 -293.621778)
			(xy 385.322988 -293.573994) (xy 385.319028 -293.52494) (xy 384.98018 -293.52494) (xy 384.979685 -293.549547)
			(xy 384.97179 -293.598124) (xy 384.956206 -293.644805) (xy 384.933335 -293.688382) (xy 384.90377 -293.727726)
			(xy 384.868277 -293.761818) (xy 384.827774 -293.789774) (xy 384.783312 -293.810872) (xy 384.736041 -293.824564)
			(xy 384.687186 -293.830496) (xy 384.638011 -293.828515) (xy 384.589792 -293.818671) (xy 384.543776 -293.801219)
			(xy 384.501155 -293.776612) (xy 384.463034 -293.745487) (xy 384.430399 -293.70865) (xy 384.404096 -293.667054)
			(xy 384.384805 -293.621778) (xy 384.373028 -293.573994) (xy 384.369068 -293.52494) (xy 382.683675 -293.52494)
			(xy 382.675899 -293.577776) (xy 382.659831 -293.631183) (xy 382.636159 -293.68168) (xy 382.605386 -293.728193)
			(xy 382.568169 -293.76973) (xy 382.525301 -293.805405) (xy 382.477695 -293.834459) (xy 382.426366 -293.856271)
			(xy 382.372409 -293.870377) (xy 382.316972 -293.876477) (xy 382.261238 -293.87444) (xy 382.206395 -293.86431)
			(xy 382.153611 -293.846303) (xy 382.104011 -293.820802) (xy 382.058653 -293.788351) (xy 382.018504 -293.749642)
			(xy 381.984418 -293.705499) (xy 381.957122 -293.656864) (xy 381.937199 -293.604773) (xy 381.925073 -293.550336)
			(xy 381.921002 -293.494714) (xy 381.798068 -293.494714) (xy 381.797559 -293.5226) (xy 381.789439 -293.577776)
			(xy 381.773371 -293.631183) (xy 381.749699 -293.68168) (xy 381.718926 -293.728193) (xy 381.681709 -293.76973)
			(xy 381.638841 -293.805405) (xy 381.591235 -293.834459) (xy 381.539906 -293.856271) (xy 381.485949 -293.870377)
			(xy 381.430512 -293.876477) (xy 381.374778 -293.87444) (xy 381.319935 -293.86431) (xy 381.267151 -293.846303)
			(xy 381.217551 -293.820802) (xy 381.172193 -293.788351) (xy 381.132044 -293.749642) (xy 381.097958 -293.705499)
			(xy 381.070662 -293.656864) (xy 381.050739 -293.604773) (xy 381.038613 -293.550336) (xy 381.034542 -293.494714)
			(xy 380.401068 -293.494714) (xy 380.400582 -293.521965) (xy 380.392826 -293.575913) (xy 380.377471 -293.628208)
			(xy 380.354829 -293.677785) (xy 380.325363 -293.723635) (xy 380.289672 -293.764826) (xy 380.248481 -293.800517)
			(xy 380.202631 -293.829983) (xy 380.153054 -293.852625) (xy 380.100759 -293.86798) (xy 380.046811 -293.875736)
			(xy 379.992309 -293.875736) (xy 379.938361 -293.86798) (xy 379.886066 -293.852625) (xy 379.836489 -293.829983)
			(xy 379.790639 -293.800517) (xy 379.749448 -293.764826) (xy 379.713757 -293.723635) (xy 379.684291 -293.677785)
			(xy 379.661649 -293.628208) (xy 379.646294 -293.575913) (xy 379.638538 -293.521965) (xy 379.638052 -293.494714)
			(xy 368.020346 -293.494714) (xy 367.391442 -294.123618) (xy 367.384044 -294.130464) (xy 367.365445 -294.13819)
			(xy 367.355374 -294.138604) (xy 351.689416 -294.138604) (xy 351.684539 -294.138703) (xy 351.674953 -294.140499)
			(xy 351.670366 -294.14216) (xy 351.661222 -294.14597) (xy 351.176336 -294.630856) (xy 374.111518 -294.630856)
			(xy 374.115589 -294.575234) (xy 374.127715 -294.520797) (xy 374.147638 -294.468706) (xy 374.174934 -294.420071)
			(xy 374.20902 -294.375928) (xy 374.249169 -294.337219) (xy 374.294527 -294.304768) (xy 374.344127 -294.279267)
			(xy 374.396911 -294.26126) (xy 374.451754 -294.25113) (xy 374.507488 -294.249093) (xy 374.562925 -294.255193)
			(xy 374.616882 -294.269299) (xy 374.668211 -294.291111) (xy 374.715817 -294.320165) (xy 374.758685 -294.35584)
			(xy 374.795902 -294.397377) (xy 374.826675 -294.44389) (xy 374.850347 -294.494387) (xy 374.866415 -294.547794)
			(xy 374.874535 -294.60297) (xy 374.875044 -294.630856) (xy 375.596656 -294.630856) (xy 375.600727 -294.575234)
			(xy 375.612853 -294.520797) (xy 375.632776 -294.468706) (xy 375.660072 -294.420071) (xy 375.694158 -294.375928)
			(xy 375.734307 -294.337219) (xy 375.779665 -294.304768) (xy 375.829265 -294.279267) (xy 375.882049 -294.26126)
			(xy 375.936892 -294.25113) (xy 375.992626 -294.249093) (xy 376.048063 -294.255193) (xy 376.10202 -294.269299)
			(xy 376.153349 -294.291111) (xy 376.200955 -294.320165) (xy 376.243823 -294.35584) (xy 376.28104 -294.397377)
			(xy 376.311813 -294.44389) (xy 376.32635 -294.4749) (xy 384.369068 -294.4749) (xy 384.373028 -294.425846)
			(xy 384.384805 -294.378062) (xy 384.404096 -294.332786) (xy 384.430399 -294.29119) (xy 384.463034 -294.254353)
			(xy 384.501155 -294.223228) (xy 384.543776 -294.198621) (xy 384.589792 -294.181169) (xy 384.638011 -294.171325)
			(xy 384.687186 -294.169344) (xy 384.736041 -294.175276) (xy 384.783312 -294.188968) (xy 384.827774 -294.210066)
			(xy 384.868277 -294.238022) (xy 384.90377 -294.272114) (xy 384.933335 -294.311458) (xy 384.956206 -294.355035)
			(xy 384.97179 -294.401716) (xy 384.979685 -294.450293) (xy 384.98018 -294.4749) (xy 385.319028 -294.4749)
			(xy 385.322988 -294.425846) (xy 385.334765 -294.378062) (xy 385.354056 -294.332786) (xy 385.380359 -294.29119)
			(xy 385.412994 -294.254353) (xy 385.451115 -294.223228) (xy 385.493736 -294.198621) (xy 385.539752 -294.181169)
			(xy 385.587971 -294.171325) (xy 385.637146 -294.169344) (xy 385.686001 -294.175276) (xy 385.733272 -294.188968)
			(xy 385.777734 -294.210066) (xy 385.818237 -294.238022) (xy 385.85373 -294.272114) (xy 385.883295 -294.311458)
			(xy 385.906166 -294.355035) (xy 385.92175 -294.401716) (xy 385.929645 -294.450293) (xy 385.93014 -294.4749)
			(xy 386.269242 -294.4749) (xy 386.273202 -294.425846) (xy 386.284979 -294.378062) (xy 386.30427 -294.332786)
			(xy 386.330573 -294.29119) (xy 386.363208 -294.254353) (xy 386.401329 -294.223228) (xy 386.44395 -294.198621)
			(xy 386.489966 -294.181169) (xy 386.538185 -294.171325) (xy 386.58736 -294.169344) (xy 386.636215 -294.175276)
			(xy 386.683486 -294.188968) (xy 386.727948 -294.210066) (xy 386.768451 -294.238022) (xy 386.803944 -294.272114)
			(xy 386.833509 -294.311458) (xy 386.85638 -294.355035) (xy 386.871964 -294.401716) (xy 386.879859 -294.450293)
			(xy 386.880354 -294.4749) (xy 389.119122 -294.4749) (xy 389.123082 -294.425846) (xy 389.134859 -294.378062)
			(xy 389.15415 -294.332786) (xy 389.180453 -294.29119) (xy 389.213088 -294.254353) (xy 389.251209 -294.223228)
			(xy 389.29383 -294.198621) (xy 389.339846 -294.181169) (xy 389.388065 -294.171325) (xy 389.43724 -294.169344)
			(xy 389.486095 -294.175276) (xy 389.533366 -294.188968) (xy 389.577828 -294.210066) (xy 389.618331 -294.238022)
			(xy 389.653824 -294.272114) (xy 389.683389 -294.311458) (xy 389.70626 -294.355035) (xy 389.721844 -294.401716)
			(xy 389.729739 -294.450293) (xy 389.730234 -294.4749) (xy 389.729739 -294.499507) (xy 389.729407 -294.501549)
			(xy 390.019276 -294.501549) (xy 390.019276 -294.448251) (xy 390.027219 -294.395547) (xy 390.042929 -294.344617)
			(xy 390.066055 -294.296596) (xy 390.096079 -294.252559) (xy 390.132331 -294.213488) (xy 390.174002 -294.180257)
			(xy 390.22016 -294.153608) (xy 390.269774 -294.134136) (xy 390.321736 -294.122276) (xy 390.374886 -294.118293)
			(xy 390.428036 -294.122276) (xy 390.479998 -294.134136) (xy 390.529612 -294.153608) (xy 390.57577 -294.180257)
			(xy 390.617441 -294.213488) (xy 390.653693 -294.252559) (xy 390.683717 -294.296596) (xy 390.706843 -294.344617)
			(xy 390.722553 -294.395547) (xy 390.730496 -294.448251) (xy 390.730994 -294.4749) (xy 391.019042 -294.4749)
			(xy 391.023002 -294.425846) (xy 391.034779 -294.378062) (xy 391.05407 -294.332786) (xy 391.080373 -294.29119)
			(xy 391.113008 -294.254353) (xy 391.151129 -294.223228) (xy 391.19375 -294.198621) (xy 391.239766 -294.181169)
			(xy 391.287985 -294.171325) (xy 391.33716 -294.169344) (xy 391.386015 -294.175276) (xy 391.433286 -294.188968)
			(xy 391.477748 -294.210066) (xy 391.518251 -294.238022) (xy 391.553744 -294.272114) (xy 391.583309 -294.311458)
			(xy 391.60618 -294.355035) (xy 391.621764 -294.401716) (xy 391.629659 -294.450293) (xy 391.630154 -294.4749)
			(xy 391.969002 -294.4749) (xy 391.972962 -294.425846) (xy 391.984739 -294.378062) (xy 392.00403 -294.332786)
			(xy 392.030333 -294.29119) (xy 392.062968 -294.254353) (xy 392.101089 -294.223228) (xy 392.14371 -294.198621)
			(xy 392.189726 -294.181169) (xy 392.237945 -294.171325) (xy 392.28712 -294.169344) (xy 392.335975 -294.175276)
			(xy 392.383246 -294.188968) (xy 392.427708 -294.210066) (xy 392.468211 -294.238022) (xy 392.503704 -294.272114)
			(xy 392.533269 -294.311458) (xy 392.55614 -294.355035) (xy 392.571724 -294.401716) (xy 392.579619 -294.450293)
			(xy 392.580114 -294.4749) (xy 392.919216 -294.4749) (xy 392.923176 -294.425846) (xy 392.934953 -294.378062)
			(xy 392.954244 -294.332786) (xy 392.980547 -294.29119) (xy 393.013182 -294.254353) (xy 393.051303 -294.223228)
			(xy 393.093924 -294.198621) (xy 393.13994 -294.181169) (xy 393.188159 -294.171325) (xy 393.237334 -294.169344)
			(xy 393.286189 -294.175276) (xy 393.33346 -294.188968) (xy 393.377922 -294.210066) (xy 393.418425 -294.238022)
			(xy 393.453918 -294.272114) (xy 393.483483 -294.311458) (xy 393.506354 -294.355035) (xy 393.521938 -294.401716)
			(xy 393.529833 -294.450293) (xy 393.530328 -294.4749) (xy 393.869176 -294.4749) (xy 393.873136 -294.425846)
			(xy 393.884913 -294.378062) (xy 393.904204 -294.332786) (xy 393.930507 -294.29119) (xy 393.963142 -294.254353)
			(xy 394.001263 -294.223228) (xy 394.043884 -294.198621) (xy 394.0899 -294.181169) (xy 394.138119 -294.171325)
			(xy 394.187294 -294.169344) (xy 394.236149 -294.175276) (xy 394.28342 -294.188968) (xy 394.327882 -294.210066)
			(xy 394.368385 -294.238022) (xy 394.403878 -294.272114) (xy 394.433443 -294.311458) (xy 394.456314 -294.355035)
			(xy 394.471898 -294.401716) (xy 394.479793 -294.450293) (xy 394.480288 -294.4749) (xy 394.819136 -294.4749)
			(xy 394.823096 -294.425846) (xy 394.834873 -294.378062) (xy 394.854164 -294.332786) (xy 394.880467 -294.29119)
			(xy 394.913102 -294.254353) (xy 394.951223 -294.223228) (xy 394.993844 -294.198621) (xy 395.03986 -294.181169)
			(xy 395.088079 -294.171325) (xy 395.137254 -294.169344) (xy 395.186109 -294.175276) (xy 395.23338 -294.188968)
			(xy 395.277842 -294.210066) (xy 395.318345 -294.238022) (xy 395.353838 -294.272114) (xy 395.383403 -294.311458)
			(xy 395.406274 -294.355035) (xy 395.421858 -294.401716) (xy 395.429753 -294.450293) (xy 395.430248 -294.4749)
			(xy 395.769096 -294.4749) (xy 395.773056 -294.425846) (xy 395.784833 -294.378062) (xy 395.804124 -294.332786)
			(xy 395.830427 -294.29119) (xy 395.863062 -294.254353) (xy 395.901183 -294.223228) (xy 395.943804 -294.198621)
			(xy 395.98982 -294.181169) (xy 396.038039 -294.171325) (xy 396.087214 -294.169344) (xy 396.136069 -294.175276)
			(xy 396.18334 -294.188968) (xy 396.227802 -294.210066) (xy 396.268305 -294.238022) (xy 396.303798 -294.272114)
			(xy 396.333363 -294.311458) (xy 396.356234 -294.355035) (xy 396.371818 -294.401716) (xy 396.379713 -294.450293)
			(xy 396.380208 -294.4749) (xy 397.669016 -294.4749) (xy 397.672976 -294.425846) (xy 397.684753 -294.378062)
			(xy 397.704044 -294.332786) (xy 397.730347 -294.29119) (xy 397.762982 -294.254353) (xy 397.801103 -294.223228)
			(xy 397.843724 -294.198621) (xy 397.88974 -294.181169) (xy 397.937959 -294.171325) (xy 397.987134 -294.169344)
			(xy 398.035989 -294.175276) (xy 398.08326 -294.188968) (xy 398.127722 -294.210066) (xy 398.168225 -294.238022)
			(xy 398.203718 -294.272114) (xy 398.233283 -294.311458) (xy 398.256154 -294.355035) (xy 398.271738 -294.401716)
			(xy 398.279633 -294.450293) (xy 398.280128 -294.4749) (xy 399.56919 -294.4749) (xy 399.57315 -294.425846)
			(xy 399.584927 -294.378062) (xy 399.604218 -294.332786) (xy 399.630521 -294.29119) (xy 399.663156 -294.254353)
			(xy 399.701277 -294.223228) (xy 399.743898 -294.198621) (xy 399.789914 -294.181169) (xy 399.838133 -294.171325)
			(xy 399.887308 -294.169344) (xy 399.936163 -294.175276) (xy 399.983434 -294.188968) (xy 400.027896 -294.210066)
			(xy 400.068399 -294.238022) (xy 400.103892 -294.272114) (xy 400.133457 -294.311458) (xy 400.156328 -294.355035)
			(xy 400.171912 -294.401716) (xy 400.179807 -294.450293) (xy 400.180302 -294.4749) (xy 401.46911 -294.4749)
			(xy 401.47307 -294.425846) (xy 401.484847 -294.378062) (xy 401.504138 -294.332786) (xy 401.530441 -294.29119)
			(xy 401.563076 -294.254353) (xy 401.601197 -294.223228) (xy 401.643818 -294.198621) (xy 401.689834 -294.181169)
			(xy 401.738053 -294.171325) (xy 401.787228 -294.169344) (xy 401.836083 -294.175276) (xy 401.883354 -294.188968)
			(xy 401.927816 -294.210066) (xy 401.968319 -294.238022) (xy 402.003812 -294.272114) (xy 402.033377 -294.311458)
			(xy 402.056248 -294.355035) (xy 402.071832 -294.401716) (xy 402.079727 -294.450293) (xy 402.080222 -294.4749)
			(xy 403.36903 -294.4749) (xy 403.37299 -294.425846) (xy 403.384767 -294.378062) (xy 403.404058 -294.332786)
			(xy 403.430361 -294.29119) (xy 403.462996 -294.254353) (xy 403.501117 -294.223228) (xy 403.543738 -294.198621)
			(xy 403.589754 -294.181169) (xy 403.637973 -294.171325) (xy 403.687148 -294.169344) (xy 403.736003 -294.175276)
			(xy 403.783274 -294.188968) (xy 403.827736 -294.210066) (xy 403.868239 -294.238022) (xy 403.903732 -294.272114)
			(xy 403.933297 -294.311458) (xy 403.956168 -294.355035) (xy 403.971752 -294.401716) (xy 403.979647 -294.450293)
			(xy 403.980142 -294.4749) (xy 405.269204 -294.4749) (xy 405.273164 -294.425846) (xy 405.284941 -294.378062)
			(xy 405.304232 -294.332786) (xy 405.330535 -294.29119) (xy 405.36317 -294.254353) (xy 405.401291 -294.223228)
			(xy 405.443912 -294.198621) (xy 405.489928 -294.181169) (xy 405.538147 -294.171325) (xy 405.587322 -294.169344)
			(xy 405.636177 -294.175276) (xy 405.683448 -294.188968) (xy 405.72791 -294.210066) (xy 405.768413 -294.238022)
			(xy 405.803906 -294.272114) (xy 405.833471 -294.311458) (xy 405.856342 -294.355035) (xy 405.871926 -294.401716)
			(xy 405.879821 -294.450293) (xy 405.880316 -294.4749) (xy 408.119084 -294.4749) (xy 408.123044 -294.425846)
			(xy 408.134821 -294.378062) (xy 408.154112 -294.332786) (xy 408.180415 -294.29119) (xy 408.21305 -294.254353)
			(xy 408.251171 -294.223228) (xy 408.293792 -294.198621) (xy 408.339808 -294.181169) (xy 408.388027 -294.171325)
			(xy 408.437202 -294.169344) (xy 408.486057 -294.175276) (xy 408.533328 -294.188968) (xy 408.57779 -294.210066)
			(xy 408.618293 -294.238022) (xy 408.653786 -294.272114) (xy 408.683351 -294.311458) (xy 408.706222 -294.355035)
			(xy 408.721806 -294.401716) (xy 408.729701 -294.450293) (xy 408.730196 -294.4749) (xy 410.019004 -294.4749)
			(xy 410.022964 -294.425846) (xy 410.034741 -294.378062) (xy 410.054032 -294.332786) (xy 410.080335 -294.29119)
			(xy 410.11297 -294.254353) (xy 410.151091 -294.223228) (xy 410.193712 -294.198621) (xy 410.239728 -294.181169)
			(xy 410.287947 -294.171325) (xy 410.337122 -294.169344) (xy 410.385977 -294.175276) (xy 410.433248 -294.188968)
			(xy 410.47771 -294.210066) (xy 410.518213 -294.238022) (xy 410.553706 -294.272114) (xy 410.583271 -294.311458)
			(xy 410.606142 -294.355035) (xy 410.621726 -294.401716) (xy 410.629621 -294.450293) (xy 410.630116 -294.4749)
			(xy 411.919178 -294.4749) (xy 411.923138 -294.425846) (xy 411.934915 -294.378062) (xy 411.954206 -294.332786)
			(xy 411.980509 -294.29119) (xy 412.013144 -294.254353) (xy 412.051265 -294.223228) (xy 412.093886 -294.198621)
			(xy 412.139902 -294.181169) (xy 412.188121 -294.171325) (xy 412.237296 -294.169344) (xy 412.286151 -294.175276)
			(xy 412.333422 -294.188968) (xy 412.377884 -294.210066) (xy 412.418387 -294.238022) (xy 412.45388 -294.272114)
			(xy 412.483445 -294.311458) (xy 412.506316 -294.355035) (xy 412.5219 -294.401716) (xy 412.529795 -294.450293)
			(xy 412.53029 -294.4749) (xy 413.819098 -294.4749) (xy 413.823058 -294.425846) (xy 413.834835 -294.378062)
			(xy 413.854126 -294.332786) (xy 413.880429 -294.29119) (xy 413.913064 -294.254353) (xy 413.951185 -294.223228)
			(xy 413.993806 -294.198621) (xy 414.039822 -294.181169) (xy 414.088041 -294.171325) (xy 414.137216 -294.169344)
			(xy 414.186071 -294.175276) (xy 414.233342 -294.188968) (xy 414.277804 -294.210066) (xy 414.318307 -294.238022)
			(xy 414.3538 -294.272114) (xy 414.383365 -294.311458) (xy 414.406236 -294.355035) (xy 414.42182 -294.401716)
			(xy 414.429715 -294.450293) (xy 414.43021 -294.4749) (xy 414.769058 -294.4749) (xy 414.773018 -294.425846)
			(xy 414.784795 -294.378062) (xy 414.804086 -294.332786) (xy 414.830389 -294.29119) (xy 414.863024 -294.254353)
			(xy 414.901145 -294.223228) (xy 414.943766 -294.198621) (xy 414.989782 -294.181169) (xy 415.038001 -294.171325)
			(xy 415.087176 -294.169344) (xy 415.136031 -294.175276) (xy 415.183302 -294.188968) (xy 415.227764 -294.210066)
			(xy 415.268267 -294.238022) (xy 415.30376 -294.272114) (xy 415.333325 -294.311458) (xy 415.356196 -294.355035)
			(xy 415.37178 -294.401716) (xy 415.379675 -294.450293) (xy 415.38017 -294.4749) (xy 415.719018 -294.4749)
			(xy 415.722978 -294.425846) (xy 415.734755 -294.378062) (xy 415.754046 -294.332786) (xy 415.780349 -294.29119)
			(xy 415.812984 -294.254353) (xy 415.851105 -294.223228) (xy 415.893726 -294.198621) (xy 415.939742 -294.181169)
			(xy 415.987961 -294.171325) (xy 416.037136 -294.169344) (xy 416.085991 -294.175276) (xy 416.133262 -294.188968)
			(xy 416.177724 -294.210066) (xy 416.218227 -294.238022) (xy 416.25372 -294.272114) (xy 416.283285 -294.311458)
			(xy 416.306156 -294.355035) (xy 416.32174 -294.401716) (xy 416.329635 -294.450293) (xy 416.33013 -294.4749)
			(xy 416.329635 -294.499507) (xy 416.32174 -294.548084) (xy 416.306156 -294.594765) (xy 416.283285 -294.638342)
			(xy 416.25372 -294.677686) (xy 416.218227 -294.711778) (xy 416.177724 -294.739734) (xy 416.133262 -294.760832)
			(xy 416.085991 -294.774524) (xy 416.037136 -294.780456) (xy 415.987961 -294.778475) (xy 415.939742 -294.768631)
			(xy 415.893726 -294.751179) (xy 415.851105 -294.726572) (xy 415.812984 -294.695447) (xy 415.780349 -294.65861)
			(xy 415.754046 -294.617014) (xy 415.734755 -294.571738) (xy 415.722978 -294.523954) (xy 415.719018 -294.4749)
			(xy 415.38017 -294.4749) (xy 415.379675 -294.499507) (xy 415.37178 -294.548084) (xy 415.356196 -294.594765)
			(xy 415.333325 -294.638342) (xy 415.30376 -294.677686) (xy 415.268267 -294.711778) (xy 415.227764 -294.739734)
			(xy 415.183302 -294.760832) (xy 415.136031 -294.774524) (xy 415.087176 -294.780456) (xy 415.038001 -294.778475)
			(xy 414.989782 -294.768631) (xy 414.943766 -294.751179) (xy 414.901145 -294.726572) (xy 414.863024 -294.695447)
			(xy 414.830389 -294.65861) (xy 414.804086 -294.617014) (xy 414.784795 -294.571738) (xy 414.773018 -294.523954)
			(xy 414.769058 -294.4749) (xy 414.43021 -294.4749) (xy 414.429715 -294.499507) (xy 414.42182 -294.548084)
			(xy 414.406236 -294.594765) (xy 414.383365 -294.638342) (xy 414.3538 -294.677686) (xy 414.318307 -294.711778)
			(xy 414.277804 -294.739734) (xy 414.233342 -294.760832) (xy 414.186071 -294.774524) (xy 414.137216 -294.780456)
			(xy 414.088041 -294.778475) (xy 414.039822 -294.768631) (xy 413.993806 -294.751179) (xy 413.951185 -294.726572)
			(xy 413.913064 -294.695447) (xy 413.880429 -294.65861) (xy 413.854126 -294.617014) (xy 413.834835 -294.571738)
			(xy 413.823058 -294.523954) (xy 413.819098 -294.4749) (xy 412.53029 -294.4749) (xy 412.529795 -294.499507)
			(xy 412.5219 -294.548084) (xy 412.506316 -294.594765) (xy 412.483445 -294.638342) (xy 412.45388 -294.677686)
			(xy 412.418387 -294.711778) (xy 412.377884 -294.739734) (xy 412.333422 -294.760832) (xy 412.286151 -294.774524)
			(xy 412.237296 -294.780456) (xy 412.188121 -294.778475) (xy 412.139902 -294.768631) (xy 412.093886 -294.751179)
			(xy 412.051265 -294.726572) (xy 412.013144 -294.695447) (xy 411.980509 -294.65861) (xy 411.954206 -294.617014)
			(xy 411.934915 -294.571738) (xy 411.923138 -294.523954) (xy 411.919178 -294.4749) (xy 410.630116 -294.4749)
			(xy 410.629621 -294.499507) (xy 410.621726 -294.548084) (xy 410.606142 -294.594765) (xy 410.583271 -294.638342)
			(xy 410.553706 -294.677686) (xy 410.518213 -294.711778) (xy 410.47771 -294.739734) (xy 410.433248 -294.760832)
			(xy 410.385977 -294.774524) (xy 410.337122 -294.780456) (xy 410.287947 -294.778475) (xy 410.239728 -294.768631)
			(xy 410.193712 -294.751179) (xy 410.151091 -294.726572) (xy 410.11297 -294.695447) (xy 410.080335 -294.65861)
			(xy 410.054032 -294.617014) (xy 410.034741 -294.571738) (xy 410.022964 -294.523954) (xy 410.019004 -294.4749)
			(xy 408.730196 -294.4749) (xy 408.729701 -294.499507) (xy 408.721806 -294.548084) (xy 408.706222 -294.594765)
			(xy 408.683351 -294.638342) (xy 408.653786 -294.677686) (xy 408.618293 -294.711778) (xy 408.57779 -294.739734)
			(xy 408.533328 -294.760832) (xy 408.486057 -294.774524) (xy 408.437202 -294.780456) (xy 408.388027 -294.778475)
			(xy 408.339808 -294.768631) (xy 408.293792 -294.751179) (xy 408.251171 -294.726572) (xy 408.21305 -294.695447)
			(xy 408.180415 -294.65861) (xy 408.154112 -294.617014) (xy 408.134821 -294.571738) (xy 408.123044 -294.523954)
			(xy 408.119084 -294.4749) (xy 405.880316 -294.4749) (xy 405.879821 -294.499507) (xy 405.871926 -294.548084)
			(xy 405.856342 -294.594765) (xy 405.833471 -294.638342) (xy 405.803906 -294.677686) (xy 405.768413 -294.711778)
			(xy 405.72791 -294.739734) (xy 405.683448 -294.760832) (xy 405.636177 -294.774524) (xy 405.587322 -294.780456)
			(xy 405.538147 -294.778475) (xy 405.489928 -294.768631) (xy 405.443912 -294.751179) (xy 405.401291 -294.726572)
			(xy 405.36317 -294.695447) (xy 405.330535 -294.65861) (xy 405.304232 -294.617014) (xy 405.284941 -294.571738)
			(xy 405.273164 -294.523954) (xy 405.269204 -294.4749) (xy 403.980142 -294.4749) (xy 403.979647 -294.499507)
			(xy 403.971752 -294.548084) (xy 403.956168 -294.594765) (xy 403.933297 -294.638342) (xy 403.903732 -294.677686)
			(xy 403.868239 -294.711778) (xy 403.827736 -294.739734) (xy 403.783274 -294.760832) (xy 403.736003 -294.774524)
			(xy 403.687148 -294.780456) (xy 403.637973 -294.778475) (xy 403.589754 -294.768631) (xy 403.543738 -294.751179)
			(xy 403.501117 -294.726572) (xy 403.462996 -294.695447) (xy 403.430361 -294.65861) (xy 403.404058 -294.617014)
			(xy 403.384767 -294.571738) (xy 403.37299 -294.523954) (xy 403.36903 -294.4749) (xy 402.080222 -294.4749)
			(xy 402.079727 -294.499507) (xy 402.071832 -294.548084) (xy 402.056248 -294.594765) (xy 402.033377 -294.638342)
			(xy 402.003812 -294.677686) (xy 401.968319 -294.711778) (xy 401.927816 -294.739734) (xy 401.883354 -294.760832)
			(xy 401.836083 -294.774524) (xy 401.787228 -294.780456) (xy 401.738053 -294.778475) (xy 401.689834 -294.768631)
			(xy 401.643818 -294.751179) (xy 401.601197 -294.726572) (xy 401.563076 -294.695447) (xy 401.530441 -294.65861)
			(xy 401.504138 -294.617014) (xy 401.484847 -294.571738) (xy 401.47307 -294.523954) (xy 401.46911 -294.4749)
			(xy 400.180302 -294.4749) (xy 400.179807 -294.499507) (xy 400.171912 -294.548084) (xy 400.156328 -294.594765)
			(xy 400.133457 -294.638342) (xy 400.103892 -294.677686) (xy 400.068399 -294.711778) (xy 400.027896 -294.739734)
			(xy 399.983434 -294.760832) (xy 399.936163 -294.774524) (xy 399.887308 -294.780456) (xy 399.838133 -294.778475)
			(xy 399.789914 -294.768631) (xy 399.743898 -294.751179) (xy 399.701277 -294.726572) (xy 399.663156 -294.695447)
			(xy 399.630521 -294.65861) (xy 399.604218 -294.617014) (xy 399.584927 -294.571738) (xy 399.57315 -294.523954)
			(xy 399.56919 -294.4749) (xy 398.280128 -294.4749) (xy 398.279633 -294.499507) (xy 398.271738 -294.548084)
			(xy 398.256154 -294.594765) (xy 398.233283 -294.638342) (xy 398.203718 -294.677686) (xy 398.168225 -294.711778)
			(xy 398.127722 -294.739734) (xy 398.08326 -294.760832) (xy 398.035989 -294.774524) (xy 397.987134 -294.780456)
			(xy 397.937959 -294.778475) (xy 397.88974 -294.768631) (xy 397.843724 -294.751179) (xy 397.801103 -294.726572)
			(xy 397.762982 -294.695447) (xy 397.730347 -294.65861) (xy 397.704044 -294.617014) (xy 397.684753 -294.571738)
			(xy 397.672976 -294.523954) (xy 397.669016 -294.4749) (xy 396.380208 -294.4749) (xy 396.379713 -294.499507)
			(xy 396.371818 -294.548084) (xy 396.356234 -294.594765) (xy 396.333363 -294.638342) (xy 396.303798 -294.677686)
			(xy 396.268305 -294.711778) (xy 396.227802 -294.739734) (xy 396.18334 -294.760832) (xy 396.136069 -294.774524)
			(xy 396.087214 -294.780456) (xy 396.038039 -294.778475) (xy 395.98982 -294.768631) (xy 395.943804 -294.751179)
			(xy 395.901183 -294.726572) (xy 395.863062 -294.695447) (xy 395.830427 -294.65861) (xy 395.804124 -294.617014)
			(xy 395.784833 -294.571738) (xy 395.773056 -294.523954) (xy 395.769096 -294.4749) (xy 395.430248 -294.4749)
			(xy 395.429753 -294.499507) (xy 395.421858 -294.548084) (xy 395.406274 -294.594765) (xy 395.383403 -294.638342)
			(xy 395.353838 -294.677686) (xy 395.318345 -294.711778) (xy 395.277842 -294.739734) (xy 395.23338 -294.760832)
			(xy 395.186109 -294.774524) (xy 395.137254 -294.780456) (xy 395.088079 -294.778475) (xy 395.03986 -294.768631)
			(xy 394.993844 -294.751179) (xy 394.951223 -294.726572) (xy 394.913102 -294.695447) (xy 394.880467 -294.65861)
			(xy 394.854164 -294.617014) (xy 394.834873 -294.571738) (xy 394.823096 -294.523954) (xy 394.819136 -294.4749)
			(xy 394.480288 -294.4749) (xy 394.479793 -294.499507) (xy 394.471898 -294.548084) (xy 394.456314 -294.594765)
			(xy 394.433443 -294.638342) (xy 394.403878 -294.677686) (xy 394.368385 -294.711778) (xy 394.327882 -294.739734)
			(xy 394.28342 -294.760832) (xy 394.236149 -294.774524) (xy 394.187294 -294.780456) (xy 394.138119 -294.778475)
			(xy 394.0899 -294.768631) (xy 394.043884 -294.751179) (xy 394.001263 -294.726572) (xy 393.963142 -294.695447)
			(xy 393.930507 -294.65861) (xy 393.904204 -294.617014) (xy 393.884913 -294.571738) (xy 393.873136 -294.523954)
			(xy 393.869176 -294.4749) (xy 393.530328 -294.4749) (xy 393.529833 -294.499507) (xy 393.521938 -294.548084)
			(xy 393.506354 -294.594765) (xy 393.483483 -294.638342) (xy 393.453918 -294.677686) (xy 393.418425 -294.711778)
			(xy 393.377922 -294.739734) (xy 393.33346 -294.760832) (xy 393.286189 -294.774524) (xy 393.237334 -294.780456)
			(xy 393.188159 -294.778475) (xy 393.13994 -294.768631) (xy 393.093924 -294.751179) (xy 393.051303 -294.726572)
			(xy 393.013182 -294.695447) (xy 392.980547 -294.65861) (xy 392.954244 -294.617014) (xy 392.934953 -294.571738)
			(xy 392.923176 -294.523954) (xy 392.919216 -294.4749) (xy 392.580114 -294.4749) (xy 392.579619 -294.499507)
			(xy 392.571724 -294.548084) (xy 392.55614 -294.594765) (xy 392.533269 -294.638342) (xy 392.503704 -294.677686)
			(xy 392.468211 -294.711778) (xy 392.427708 -294.739734) (xy 392.383246 -294.760832) (xy 392.335975 -294.774524)
			(xy 392.28712 -294.780456) (xy 392.237945 -294.778475) (xy 392.189726 -294.768631) (xy 392.14371 -294.751179)
			(xy 392.101089 -294.726572) (xy 392.062968 -294.695447) (xy 392.030333 -294.65861) (xy 392.00403 -294.617014)
			(xy 391.984739 -294.571738) (xy 391.972962 -294.523954) (xy 391.969002 -294.4749) (xy 391.630154 -294.4749)
			(xy 391.629659 -294.499507) (xy 391.621764 -294.548084) (xy 391.60618 -294.594765) (xy 391.583309 -294.638342)
			(xy 391.553744 -294.677686) (xy 391.518251 -294.711778) (xy 391.477748 -294.739734) (xy 391.433286 -294.760832)
			(xy 391.386015 -294.774524) (xy 391.33716 -294.780456) (xy 391.287985 -294.778475) (xy 391.239766 -294.768631)
			(xy 391.19375 -294.751179) (xy 391.151129 -294.726572) (xy 391.113008 -294.695447) (xy 391.080373 -294.65861)
			(xy 391.05407 -294.617014) (xy 391.034779 -294.571738) (xy 391.023002 -294.523954) (xy 391.019042 -294.4749)
			(xy 390.730994 -294.4749) (xy 390.730496 -294.501549) (xy 390.722553 -294.554253) (xy 390.706843 -294.605183)
			(xy 390.683717 -294.653204) (xy 390.653693 -294.697241) (xy 390.617441 -294.736312) (xy 390.57577 -294.769543)
			(xy 390.529612 -294.796192) (xy 390.479998 -294.815664) (xy 390.428036 -294.827524) (xy 390.374886 -294.831508)
			(xy 390.321736 -294.827524) (xy 390.269774 -294.815664) (xy 390.22016 -294.796192) (xy 390.174002 -294.769543)
			(xy 390.132331 -294.736312) (xy 390.096079 -294.697241) (xy 390.066055 -294.653204) (xy 390.042929 -294.605183)
			(xy 390.027219 -294.554253) (xy 390.019276 -294.501549) (xy 389.729407 -294.501549) (xy 389.721844 -294.548084)
			(xy 389.70626 -294.594765) (xy 389.683389 -294.638342) (xy 389.653824 -294.677686) (xy 389.618331 -294.711778)
			(xy 389.577828 -294.739734) (xy 389.533366 -294.760832) (xy 389.486095 -294.774524) (xy 389.43724 -294.780456)
			(xy 389.388065 -294.778475) (xy 389.339846 -294.768631) (xy 389.29383 -294.751179) (xy 389.251209 -294.726572)
			(xy 389.213088 -294.695447) (xy 389.180453 -294.65861) (xy 389.15415 -294.617014) (xy 389.134859 -294.571738)
			(xy 389.123082 -294.523954) (xy 389.119122 -294.4749) (xy 386.880354 -294.4749) (xy 386.879859 -294.499507)
			(xy 386.871964 -294.548084) (xy 386.85638 -294.594765) (xy 386.833509 -294.638342) (xy 386.803944 -294.677686)
			(xy 386.768451 -294.711778) (xy 386.727948 -294.739734) (xy 386.683486 -294.760832) (xy 386.636215 -294.774524)
			(xy 386.58736 -294.780456) (xy 386.538185 -294.778475) (xy 386.489966 -294.768631) (xy 386.44395 -294.751179)
			(xy 386.401329 -294.726572) (xy 386.363208 -294.695447) (xy 386.330573 -294.65861) (xy 386.30427 -294.617014)
			(xy 386.284979 -294.571738) (xy 386.273202 -294.523954) (xy 386.269242 -294.4749) (xy 385.93014 -294.4749)
			(xy 385.929645 -294.499507) (xy 385.92175 -294.548084) (xy 385.906166 -294.594765) (xy 385.883295 -294.638342)
			(xy 385.85373 -294.677686) (xy 385.818237 -294.711778) (xy 385.777734 -294.739734) (xy 385.733272 -294.760832)
			(xy 385.686001 -294.774524) (xy 385.637146 -294.780456) (xy 385.587971 -294.778475) (xy 385.539752 -294.768631)
			(xy 385.493736 -294.751179) (xy 385.451115 -294.726572) (xy 385.412994 -294.695447) (xy 385.380359 -294.65861)
			(xy 385.354056 -294.617014) (xy 385.334765 -294.571738) (xy 385.322988 -294.523954) (xy 385.319028 -294.4749)
			(xy 384.98018 -294.4749) (xy 384.979685 -294.499507) (xy 384.97179 -294.548084) (xy 384.956206 -294.594765)
			(xy 384.933335 -294.638342) (xy 384.90377 -294.677686) (xy 384.868277 -294.711778) (xy 384.827774 -294.739734)
			(xy 384.783312 -294.760832) (xy 384.736041 -294.774524) (xy 384.687186 -294.780456) (xy 384.638011 -294.778475)
			(xy 384.589792 -294.768631) (xy 384.543776 -294.751179) (xy 384.501155 -294.726572) (xy 384.463034 -294.695447)
			(xy 384.430399 -294.65861) (xy 384.404096 -294.617014) (xy 384.384805 -294.571738) (xy 384.373028 -294.523954)
			(xy 384.369068 -294.4749) (xy 376.32635 -294.4749) (xy 376.335485 -294.494387) (xy 376.351553 -294.547794)
			(xy 376.359673 -294.60297) (xy 376.360182 -294.630856) (xy 376.359673 -294.658742) (xy 376.351553 -294.713918)
			(xy 376.335485 -294.767325) (xy 376.311813 -294.817822) (xy 376.28104 -294.864335) (xy 376.243823 -294.905872)
			(xy 376.200955 -294.941547) (xy 376.153349 -294.970601) (xy 376.10202 -294.992413) (xy 376.048063 -295.006519)
			(xy 375.992626 -295.012619) (xy 375.936892 -295.010582) (xy 375.882049 -295.000452) (xy 375.829265 -294.982445)
			(xy 375.779665 -294.956944) (xy 375.734307 -294.924493) (xy 375.694158 -294.885784) (xy 375.660072 -294.841641)
			(xy 375.632776 -294.793006) (xy 375.612853 -294.740915) (xy 375.600727 -294.686478) (xy 375.596656 -294.630856)
			(xy 374.875044 -294.630856) (xy 374.874535 -294.658742) (xy 374.866415 -294.713918) (xy 374.850347 -294.767325)
			(xy 374.826675 -294.817822) (xy 374.795902 -294.864335) (xy 374.758685 -294.905872) (xy 374.715817 -294.941547)
			(xy 374.668211 -294.970601) (xy 374.616882 -294.992413) (xy 374.562925 -295.006519) (xy 374.507488 -295.012619)
			(xy 374.451754 -295.010582) (xy 374.396911 -295.000452) (xy 374.344127 -294.982445) (xy 374.294527 -294.956944)
			(xy 374.249169 -294.924493) (xy 374.20902 -294.885784) (xy 374.174934 -294.841641) (xy 374.147638 -294.793006)
			(xy 374.127715 -294.740915) (xy 374.115589 -294.686478) (xy 374.111518 -294.630856) (xy 351.176336 -294.630856)
			(xy 351.113598 -294.693594) (xy 351.11003 -294.697) (xy 351.101847 -294.702508) (xy 351.097342 -294.704516)
			(xy 351.09531 -294.705278) (xy 351.094294 -294.705786) (xy 351.078546 -294.71239) (xy 351.074342 -294.714365)
			(xy 351.066676 -294.719607) (xy 351.063306 -294.722804) (xy 351.047812 -294.738298) (xy 351.045107 -294.74115)
			(xy 351.040516 -294.747529) (xy 351.038668 -294.750998) (xy 351.036082 -294.756424) (xy 351.033249 -294.768104)
			(xy 351.03308 -294.774112) (xy 351.03308 -295.933114) (xy 374.111518 -295.933114) (xy 374.115589 -295.877492)
			(xy 374.127715 -295.823055) (xy 374.147638 -295.770964) (xy 374.174934 -295.722329) (xy 374.20902 -295.678186)
			(xy 374.249169 -295.639477) (xy 374.294527 -295.607026) (xy 374.344127 -295.581525) (xy 374.396911 -295.563518)
			(xy 374.451754 -295.553388) (xy 374.507488 -295.551351) (xy 374.562925 -295.557451) (xy 374.616882 -295.571557)
			(xy 374.668211 -295.593369) (xy 374.715817 -295.622423) (xy 374.758685 -295.658098) (xy 374.795902 -295.699635)
			(xy 374.826675 -295.746148) (xy 374.850347 -295.796645) (xy 374.866415 -295.850052) (xy 374.874535 -295.905228)
			(xy 374.875044 -295.933114) (xy 375.587004 -295.933114) (xy 375.591075 -295.877492) (xy 375.603201 -295.823055)
			(xy 375.623124 -295.770964) (xy 375.65042 -295.722329) (xy 375.684506 -295.678186) (xy 375.724655 -295.639477)
			(xy 375.770013 -295.607026) (xy 375.819613 -295.581525) (xy 375.872397 -295.563518) (xy 375.92724 -295.553388)
			(xy 375.982974 -295.551351) (xy 376.038411 -295.557451) (xy 376.092368 -295.571557) (xy 376.143697 -295.593369)
			(xy 376.191303 -295.622423) (xy 376.234171 -295.658098) (xy 376.271388 -295.699635) (xy 376.302161 -295.746148)
			(xy 376.325833 -295.796645) (xy 376.341901 -295.850052) (xy 376.350021 -295.905228) (xy 376.35053 -295.933114)
			(xy 376.476004 -295.933114) (xy 376.480075 -295.877492) (xy 376.492201 -295.823055) (xy 376.512124 -295.770964)
			(xy 376.53942 -295.722329) (xy 376.573506 -295.678186) (xy 376.613655 -295.639477) (xy 376.659013 -295.607026)
			(xy 376.708613 -295.581525) (xy 376.761397 -295.563518) (xy 376.81624 -295.553388) (xy 376.871974 -295.551351)
			(xy 376.927411 -295.557451) (xy 376.981368 -295.571557) (xy 377.032697 -295.593369) (xy 377.080303 -295.622423)
			(xy 377.123171 -295.658098) (xy 377.160388 -295.699635) (xy 377.191161 -295.746148) (xy 377.214833 -295.796645)
			(xy 377.230901 -295.850052) (xy 377.239021 -295.905228) (xy 377.23953 -295.933114) (xy 377.239021 -295.961)
			(xy 377.230901 -296.016176) (xy 377.214833 -296.069583) (xy 377.191161 -296.12008) (xy 377.160388 -296.166593)
			(xy 377.123171 -296.20813) (xy 377.080303 -296.243805) (xy 377.032697 -296.272859) (xy 376.981368 -296.294671)
			(xy 376.927411 -296.308777) (xy 376.871974 -296.314877) (xy 376.81624 -296.31284) (xy 376.761397 -296.30271)
			(xy 376.708613 -296.284703) (xy 376.659013 -296.259202) (xy 376.613655 -296.226751) (xy 376.573506 -296.188042)
			(xy 376.53942 -296.143899) (xy 376.512124 -296.095264) (xy 376.492201 -296.043173) (xy 376.480075 -295.988736)
			(xy 376.476004 -295.933114) (xy 376.35053 -295.933114) (xy 376.350021 -295.961) (xy 376.341901 -296.016176)
			(xy 376.325833 -296.069583) (xy 376.302161 -296.12008) (xy 376.271388 -296.166593) (xy 376.234171 -296.20813)
			(xy 376.191303 -296.243805) (xy 376.143697 -296.272859) (xy 376.092368 -296.294671) (xy 376.038411 -296.308777)
			(xy 375.982974 -296.314877) (xy 375.92724 -296.31284) (xy 375.872397 -296.30271) (xy 375.819613 -296.284703)
			(xy 375.770013 -296.259202) (xy 375.724655 -296.226751) (xy 375.684506 -296.188042) (xy 375.65042 -296.143899)
			(xy 375.623124 -296.095264) (xy 375.603201 -296.043173) (xy 375.591075 -295.988736) (xy 375.587004 -295.933114)
			(xy 374.875044 -295.933114) (xy 374.874535 -295.961) (xy 374.866415 -296.016176) (xy 374.850347 -296.069583)
			(xy 374.826675 -296.12008) (xy 374.795902 -296.166593) (xy 374.758685 -296.20813) (xy 374.715817 -296.243805)
			(xy 374.668211 -296.272859) (xy 374.616882 -296.294671) (xy 374.562925 -296.308777) (xy 374.507488 -296.314877)
			(xy 374.451754 -296.31284) (xy 374.396911 -296.30271) (xy 374.344127 -296.284703) (xy 374.294527 -296.259202)
			(xy 374.249169 -296.226751) (xy 374.20902 -296.188042) (xy 374.174934 -296.143899) (xy 374.147638 -296.095264)
			(xy 374.127715 -296.043173) (xy 374.115589 -295.988736) (xy 374.111518 -295.933114) (xy 351.03308 -295.933114)
			(xy 351.03308 -296.695114) (xy 379.638052 -296.695114) (xy 379.638619 -296.665733) (xy 379.647646 -296.607668)
			(xy 379.665474 -296.551675) (xy 379.691681 -296.49908) (xy 379.725646 -296.451128) (xy 379.766565 -296.408954)
			(xy 379.78969 -296.390822) (xy 379.798622 -296.38335) (xy 379.809075 -296.362569) (xy 379.809756 -296.350944)
			(xy 379.811026 -296.258996) (xy 379.80112 -296.237914) (xy 379.791976 -296.230548) (xy 379.770116 -296.212356)
			(xy 379.731578 -296.170534) (xy 379.699673 -296.123455) (xy 379.675108 -296.072163) (xy 379.658427 -296.017793)
			(xy 379.65 -295.96155) (xy 379.649482 -295.933114) (xy 379.649968 -295.905863) (xy 379.657724 -295.851915)
			(xy 379.673079 -295.79962) (xy 379.695721 -295.750043) (xy 379.725187 -295.704193) (xy 379.760878 -295.663002)
			(xy 379.802069 -295.627311) (xy 379.847919 -295.597845) (xy 379.897496 -295.575203) (xy 379.949791 -295.559848)
			(xy 380.003739 -295.552092) (xy 380.058241 -295.552092) (xy 380.112189 -295.559848) (xy 380.164484 -295.575203)
			(xy 380.214061 -295.597845) (xy 380.259911 -295.627311) (xy 380.301102 -295.663002) (xy 380.336793 -295.704193)
			(xy 380.366259 -295.750043) (xy 380.388901 -295.79962) (xy 380.404256 -295.851915) (xy 380.412012 -295.905863)
			(xy 380.412498 -295.933114) (xy 380.411971 -295.962497) (xy 380.402938 -296.020564) (xy 380.385103 -296.076559)
			(xy 380.358889 -296.129154) (xy 380.324916 -296.177105) (xy 380.283989 -296.219276) (xy 380.26086 -296.237406)
			(xy 380.251924 -296.244875) (xy 380.241471 -296.265657) (xy 380.240794 -296.277284) (xy 380.239524 -296.369232)
			(xy 380.24943 -296.390314) (xy 380.258574 -296.39768) (xy 380.280389 -296.415924) (xy 380.318933 -296.457734)
			(xy 380.350844 -296.504801) (xy 380.375417 -296.556084) (xy 380.392107 -296.610445) (xy 380.400545 -296.666681)
			(xy 380.401068 -296.695114) (xy 381.034542 -296.695114) (xy 381.038613 -296.639492) (xy 381.050739 -296.585055)
			(xy 381.070662 -296.532964) (xy 381.097958 -296.484329) (xy 381.132044 -296.440186) (xy 381.172193 -296.401477)
			(xy 381.217551 -296.369026) (xy 381.267151 -296.343525) (xy 381.319935 -296.325518) (xy 381.374778 -296.315388)
			(xy 381.430512 -296.313351) (xy 381.485949 -296.319451) (xy 381.539906 -296.333557) (xy 381.591235 -296.355369)
			(xy 381.638841 -296.384423) (xy 381.681709 -296.420098) (xy 381.718926 -296.461635) (xy 381.749699 -296.508148)
			(xy 381.773371 -296.558645) (xy 381.789439 -296.612052) (xy 381.797559 -296.667228) (xy 381.798068 -296.695114)
			(xy 381.921002 -296.695114) (xy 381.925073 -296.639492) (xy 381.937199 -296.585055) (xy 381.957122 -296.532964)
			(xy 381.984418 -296.484329) (xy 382.018504 -296.440186) (xy 382.058653 -296.401477) (xy 382.104011 -296.369026)
			(xy 382.153611 -296.343525) (xy 382.206395 -296.325518) (xy 382.261238 -296.315388) (xy 382.316972 -296.313351)
			(xy 382.372409 -296.319451) (xy 382.426366 -296.333557) (xy 382.477695 -296.355369) (xy 382.50915 -296.374566)
			(xy 384.369068 -296.374566) (xy 384.373028 -296.325512) (xy 384.384805 -296.277728) (xy 384.404096 -296.232452)
			(xy 384.430399 -296.190856) (xy 384.463034 -296.154019) (xy 384.501155 -296.122894) (xy 384.543776 -296.098287)
			(xy 384.589792 -296.080835) (xy 384.638011 -296.070991) (xy 384.687186 -296.06901) (xy 384.736041 -296.074942)
			(xy 384.783312 -296.088634) (xy 384.827774 -296.109732) (xy 384.868277 -296.137688) (xy 384.90377 -296.17178)
			(xy 384.933335 -296.211124) (xy 384.956206 -296.254701) (xy 384.97179 -296.301382) (xy 384.979685 -296.349959)
			(xy 384.98018 -296.374566) (xy 384.980175 -296.37482) (xy 385.319282 -296.37482) (xy 385.323242 -296.325766)
			(xy 385.335019 -296.277982) (xy 385.35431 -296.232706) (xy 385.380613 -296.19111) (xy 385.413248 -296.154273)
			(xy 385.451369 -296.123148) (xy 385.49399 -296.098541) (xy 385.540006 -296.081089) (xy 385.588225 -296.071245)
			(xy 385.6374 -296.069264) (xy 385.686255 -296.075196) (xy 385.733526 -296.088888) (xy 385.777988 -296.109986)
			(xy 385.818491 -296.137942) (xy 385.853984 -296.172034) (xy 385.883549 -296.211378) (xy 385.90642 -296.254955)
			(xy 385.922004 -296.301636) (xy 385.929899 -296.350213) (xy 385.930394 -296.37482) (xy 386.268988 -296.37482)
			(xy 386.272948 -296.325766) (xy 386.284725 -296.277982) (xy 386.304016 -296.232706) (xy 386.330319 -296.19111)
			(xy 386.362954 -296.154273) (xy 386.401075 -296.123148) (xy 386.443696 -296.098541) (xy 386.489712 -296.081089)
			(xy 386.537931 -296.071245) (xy 386.587106 -296.069264) (xy 386.635961 -296.075196) (xy 386.683232 -296.088888)
			(xy 386.727694 -296.109986) (xy 386.768197 -296.137942) (xy 386.80369 -296.172034) (xy 386.833255 -296.211378)
			(xy 386.856126 -296.254955) (xy 386.87171 -296.301636) (xy 386.879605 -296.350213) (xy 386.8801 -296.37482)
			(xy 387.219202 -296.37482) (xy 387.223162 -296.325766) (xy 387.234939 -296.277982) (xy 387.25423 -296.232706)
			(xy 387.280533 -296.19111) (xy 387.313168 -296.154273) (xy 387.351289 -296.123148) (xy 387.39391 -296.098541)
			(xy 387.439926 -296.081089) (xy 387.488145 -296.071245) (xy 387.53732 -296.069264) (xy 387.586175 -296.075196)
			(xy 387.633446 -296.088888) (xy 387.677908 -296.109986) (xy 387.718411 -296.137942) (xy 387.753904 -296.172034)
			(xy 387.783469 -296.211378) (xy 387.80634 -296.254955) (xy 387.821924 -296.301636) (xy 387.829819 -296.350213)
			(xy 387.830314 -296.37482) (xy 388.169162 -296.37482) (xy 388.173122 -296.325766) (xy 388.184899 -296.277982)
			(xy 388.20419 -296.232706) (xy 388.230493 -296.19111) (xy 388.263128 -296.154273) (xy 388.301249 -296.123148)
			(xy 388.34387 -296.098541) (xy 388.389886 -296.081089) (xy 388.438105 -296.071245) (xy 388.48728 -296.069264)
			(xy 388.536135 -296.075196) (xy 388.583406 -296.088888) (xy 388.627868 -296.109986) (xy 388.668371 -296.137942)
			(xy 388.703864 -296.172034) (xy 388.733429 -296.211378) (xy 388.7563 -296.254955) (xy 388.771884 -296.301636)
			(xy 388.779779 -296.350213) (xy 388.780274 -296.37482) (xy 390.069082 -296.37482) (xy 390.073042 -296.325766)
			(xy 390.084819 -296.277982) (xy 390.10411 -296.232706) (xy 390.130413 -296.19111) (xy 390.163048 -296.154273)
			(xy 390.201169 -296.123148) (xy 390.24379 -296.098541) (xy 390.289806 -296.081089) (xy 390.338025 -296.071245)
			(xy 390.3872 -296.069264) (xy 390.436055 -296.075196) (xy 390.483326 -296.088888) (xy 390.527788 -296.109986)
			(xy 390.568291 -296.137942) (xy 390.603784 -296.172034) (xy 390.633349 -296.211378) (xy 390.65622 -296.254955)
			(xy 390.671804 -296.301636) (xy 390.679699 -296.350213) (xy 390.680194 -296.37482) (xy 391.969002 -296.37482)
			(xy 391.972962 -296.325766) (xy 391.984739 -296.277982) (xy 392.00403 -296.232706) (xy 392.030333 -296.19111)
			(xy 392.062968 -296.154273) (xy 392.101089 -296.123148) (xy 392.14371 -296.098541) (xy 392.189726 -296.081089)
			(xy 392.237945 -296.071245) (xy 392.28712 -296.069264) (xy 392.335975 -296.075196) (xy 392.383246 -296.088888)
			(xy 392.427708 -296.109986) (xy 392.468211 -296.137942) (xy 392.503704 -296.172034) (xy 392.533269 -296.211378)
			(xy 392.55614 -296.254955) (xy 392.571724 -296.301636) (xy 392.579619 -296.350213) (xy 392.580114 -296.37482)
			(xy 392.919216 -296.37482) (xy 392.923176 -296.325766) (xy 392.934953 -296.277982) (xy 392.954244 -296.232706)
			(xy 392.980547 -296.19111) (xy 393.013182 -296.154273) (xy 393.051303 -296.123148) (xy 393.093924 -296.098541)
			(xy 393.13994 -296.081089) (xy 393.188159 -296.071245) (xy 393.237334 -296.069264) (xy 393.286189 -296.075196)
			(xy 393.33346 -296.088888) (xy 393.377922 -296.109986) (xy 393.418425 -296.137942) (xy 393.453918 -296.172034)
			(xy 393.483483 -296.211378) (xy 393.506354 -296.254955) (xy 393.521938 -296.301636) (xy 393.529833 -296.350213)
			(xy 393.530328 -296.37482) (xy 393.869176 -296.37482) (xy 393.873136 -296.325766) (xy 393.884913 -296.277982)
			(xy 393.904204 -296.232706) (xy 393.930507 -296.19111) (xy 393.963142 -296.154273) (xy 394.001263 -296.123148)
			(xy 394.043884 -296.098541) (xy 394.0899 -296.081089) (xy 394.138119 -296.071245) (xy 394.187294 -296.069264)
			(xy 394.236149 -296.075196) (xy 394.28342 -296.088888) (xy 394.327882 -296.109986) (xy 394.368385 -296.137942)
			(xy 394.403878 -296.172034) (xy 394.433443 -296.211378) (xy 394.456314 -296.254955) (xy 394.471898 -296.301636)
			(xy 394.479793 -296.350213) (xy 394.480288 -296.37482) (xy 395.769096 -296.37482) (xy 395.773056 -296.325766)
			(xy 395.784833 -296.277982) (xy 395.804124 -296.232706) (xy 395.830427 -296.19111) (xy 395.863062 -296.154273)
			(xy 395.901183 -296.123148) (xy 395.943804 -296.098541) (xy 395.98982 -296.081089) (xy 396.038039 -296.071245)
			(xy 396.087214 -296.069264) (xy 396.136069 -296.075196) (xy 396.18334 -296.088888) (xy 396.227802 -296.109986)
			(xy 396.268305 -296.137942) (xy 396.303798 -296.172034) (xy 396.333363 -296.211378) (xy 396.356234 -296.254955)
			(xy 396.371818 -296.301636) (xy 396.379713 -296.350213) (xy 396.380208 -296.37482) (xy 396.719056 -296.37482)
			(xy 396.723016 -296.325766) (xy 396.734793 -296.277982) (xy 396.754084 -296.232706) (xy 396.780387 -296.19111)
			(xy 396.813022 -296.154273) (xy 396.851143 -296.123148) (xy 396.893764 -296.098541) (xy 396.93978 -296.081089)
			(xy 396.987999 -296.071245) (xy 397.037174 -296.069264) (xy 397.086029 -296.075196) (xy 397.1333 -296.088888)
			(xy 397.177762 -296.109986) (xy 397.218265 -296.137942) (xy 397.253758 -296.172034) (xy 397.283323 -296.211378)
			(xy 397.306194 -296.254955) (xy 397.321778 -296.301636) (xy 397.329673 -296.350213) (xy 397.330168 -296.37482)
			(xy 398.61923 -296.37482) (xy 398.62319 -296.325766) (xy 398.634967 -296.277982) (xy 398.654258 -296.232706)
			(xy 398.680561 -296.19111) (xy 398.713196 -296.154273) (xy 398.751317 -296.123148) (xy 398.793938 -296.098541)
			(xy 398.839954 -296.081089) (xy 398.888173 -296.071245) (xy 398.937348 -296.069264) (xy 398.986203 -296.075196)
			(xy 399.033474 -296.088888) (xy 399.077936 -296.109986) (xy 399.118439 -296.137942) (xy 399.153932 -296.172034)
			(xy 399.183497 -296.211378) (xy 399.206368 -296.254955) (xy 399.221952 -296.301636) (xy 399.229847 -296.350213)
			(xy 399.230342 -296.37482) (xy 400.51915 -296.37482) (xy 400.52311 -296.325766) (xy 400.534887 -296.277982)
			(xy 400.554178 -296.232706) (xy 400.580481 -296.19111) (xy 400.613116 -296.154273) (xy 400.651237 -296.123148)
			(xy 400.693858 -296.098541) (xy 400.739874 -296.081089) (xy 400.788093 -296.071245) (xy 400.837268 -296.069264)
			(xy 400.886123 -296.075196) (xy 400.933394 -296.088888) (xy 400.977856 -296.109986) (xy 401.018359 -296.137942)
			(xy 401.053852 -296.172034) (xy 401.083417 -296.211378) (xy 401.106288 -296.254955) (xy 401.121872 -296.301636)
			(xy 401.129767 -296.350213) (xy 401.130262 -296.37482) (xy 402.41907 -296.37482) (xy 402.42303 -296.325766)
			(xy 402.434807 -296.277982) (xy 402.454098 -296.232706) (xy 402.480401 -296.19111) (xy 402.513036 -296.154273)
			(xy 402.551157 -296.123148) (xy 402.593778 -296.098541) (xy 402.639794 -296.081089) (xy 402.688013 -296.071245)
			(xy 402.737188 -296.069264) (xy 402.786043 -296.075196) (xy 402.833314 -296.088888) (xy 402.877776 -296.109986)
			(xy 402.918279 -296.137942) (xy 402.953772 -296.172034) (xy 402.983337 -296.211378) (xy 403.006208 -296.254955)
			(xy 403.021792 -296.301636) (xy 403.029687 -296.350213) (xy 403.030182 -296.37482) (xy 404.319244 -296.37482)
			(xy 404.323204 -296.325766) (xy 404.334981 -296.277982) (xy 404.354272 -296.232706) (xy 404.380575 -296.19111)
			(xy 404.41321 -296.154273) (xy 404.451331 -296.123148) (xy 404.493952 -296.098541) (xy 404.539968 -296.081089)
			(xy 404.588187 -296.071245) (xy 404.637362 -296.069264) (xy 404.686217 -296.075196) (xy 404.733488 -296.088888)
			(xy 404.77795 -296.109986) (xy 404.818453 -296.137942) (xy 404.853946 -296.172034) (xy 404.883511 -296.211378)
			(xy 404.906382 -296.254955) (xy 404.921966 -296.301636) (xy 404.929861 -296.350213) (xy 404.930356 -296.37482)
			(xy 406.219164 -296.37482) (xy 406.223124 -296.325766) (xy 406.234901 -296.277982) (xy 406.254192 -296.232706)
			(xy 406.280495 -296.19111) (xy 406.31313 -296.154273) (xy 406.351251 -296.123148) (xy 406.393872 -296.098541)
			(xy 406.439888 -296.081089) (xy 406.488107 -296.071245) (xy 406.537282 -296.069264) (xy 406.586137 -296.075196)
			(xy 406.633408 -296.088888) (xy 406.67787 -296.109986) (xy 406.718373 -296.137942) (xy 406.753866 -296.172034)
			(xy 406.783431 -296.211378) (xy 406.806302 -296.254955) (xy 406.821886 -296.301636) (xy 406.829781 -296.350213)
			(xy 406.830276 -296.37482) (xy 409.069044 -296.37482) (xy 409.073004 -296.325766) (xy 409.084781 -296.277982)
			(xy 409.104072 -296.232706) (xy 409.130375 -296.19111) (xy 409.16301 -296.154273) (xy 409.201131 -296.123148)
			(xy 409.243752 -296.098541) (xy 409.289768 -296.081089) (xy 409.337987 -296.071245) (xy 409.387162 -296.069264)
			(xy 409.436017 -296.075196) (xy 409.483288 -296.088888) (xy 409.52775 -296.109986) (xy 409.568253 -296.137942)
			(xy 409.603746 -296.172034) (xy 409.633311 -296.211378) (xy 409.656182 -296.254955) (xy 409.671766 -296.301636)
			(xy 409.679661 -296.350213) (xy 409.680156 -296.37482) (xy 410.969218 -296.37482) (xy 410.973178 -296.325766)
			(xy 410.984955 -296.277982) (xy 411.004246 -296.232706) (xy 411.030549 -296.19111) (xy 411.063184 -296.154273)
			(xy 411.101305 -296.123148) (xy 411.143926 -296.098541) (xy 411.189942 -296.081089) (xy 411.238161 -296.071245)
			(xy 411.287336 -296.069264) (xy 411.336191 -296.075196) (xy 411.383462 -296.088888) (xy 411.427924 -296.109986)
			(xy 411.468427 -296.137942) (xy 411.50392 -296.172034) (xy 411.533485 -296.211378) (xy 411.556356 -296.254955)
			(xy 411.57194 -296.301636) (xy 411.579835 -296.350213) (xy 411.58033 -296.37482) (xy 412.869138 -296.37482)
			(xy 412.873098 -296.325766) (xy 412.884875 -296.277982) (xy 412.904166 -296.232706) (xy 412.930469 -296.19111)
			(xy 412.963104 -296.154273) (xy 413.001225 -296.123148) (xy 413.043846 -296.098541) (xy 413.089862 -296.081089)
			(xy 413.138081 -296.071245) (xy 413.187256 -296.069264) (xy 413.236111 -296.075196) (xy 413.283382 -296.088888)
			(xy 413.327844 -296.109986) (xy 413.368347 -296.137942) (xy 413.40384 -296.172034) (xy 413.433405 -296.211378)
			(xy 413.456276 -296.254955) (xy 413.47186 -296.301636) (xy 413.479755 -296.350213) (xy 413.48025 -296.37482)
			(xy 414.769058 -296.37482) (xy 414.773018 -296.325766) (xy 414.784795 -296.277982) (xy 414.804086 -296.232706)
			(xy 414.830389 -296.19111) (xy 414.863024 -296.154273) (xy 414.901145 -296.123148) (xy 414.943766 -296.098541)
			(xy 414.989782 -296.081089) (xy 415.038001 -296.071245) (xy 415.087176 -296.069264) (xy 415.136031 -296.075196)
			(xy 415.183302 -296.088888) (xy 415.227764 -296.109986) (xy 415.268267 -296.137942) (xy 415.30376 -296.172034)
			(xy 415.333325 -296.211378) (xy 415.356196 -296.254955) (xy 415.37178 -296.301636) (xy 415.379675 -296.350213)
			(xy 415.38017 -296.37482) (xy 415.719018 -296.37482) (xy 415.722978 -296.325766) (xy 415.734755 -296.277982)
			(xy 415.754046 -296.232706) (xy 415.780349 -296.19111) (xy 415.812984 -296.154273) (xy 415.851105 -296.123148)
			(xy 415.893726 -296.098541) (xy 415.939742 -296.081089) (xy 415.987961 -296.071245) (xy 416.037136 -296.069264)
			(xy 416.085991 -296.075196) (xy 416.133262 -296.088888) (xy 416.177724 -296.109986) (xy 416.218227 -296.137942)
			(xy 416.25372 -296.172034) (xy 416.283285 -296.211378) (xy 416.306156 -296.254955) (xy 416.32174 -296.301636)
			(xy 416.329635 -296.350213) (xy 416.33013 -296.37482) (xy 416.329635 -296.399427) (xy 416.32174 -296.448004)
			(xy 416.306156 -296.494685) (xy 416.283285 -296.538262) (xy 416.25372 -296.577606) (xy 416.218227 -296.611698)
			(xy 416.177724 -296.639654) (xy 416.133262 -296.660752) (xy 416.085991 -296.674444) (xy 416.037136 -296.680376)
			(xy 415.987961 -296.678395) (xy 415.939742 -296.668551) (xy 415.893726 -296.651099) (xy 415.851105 -296.626492)
			(xy 415.812984 -296.595367) (xy 415.780349 -296.55853) (xy 415.754046 -296.516934) (xy 415.734755 -296.471658)
			(xy 415.722978 -296.423874) (xy 415.719018 -296.37482) (xy 415.38017 -296.37482) (xy 415.379675 -296.399427)
			(xy 415.37178 -296.448004) (xy 415.356196 -296.494685) (xy 415.333325 -296.538262) (xy 415.30376 -296.577606)
			(xy 415.268267 -296.611698) (xy 415.227764 -296.639654) (xy 415.183302 -296.660752) (xy 415.136031 -296.674444)
			(xy 415.087176 -296.680376) (xy 415.038001 -296.678395) (xy 414.989782 -296.668551) (xy 414.943766 -296.651099)
			(xy 414.901145 -296.626492) (xy 414.863024 -296.595367) (xy 414.830389 -296.55853) (xy 414.804086 -296.516934)
			(xy 414.784795 -296.471658) (xy 414.773018 -296.423874) (xy 414.769058 -296.37482) (xy 413.48025 -296.37482)
			(xy 413.479755 -296.399427) (xy 413.47186 -296.448004) (xy 413.456276 -296.494685) (xy 413.433405 -296.538262)
			(xy 413.40384 -296.577606) (xy 413.368347 -296.611698) (xy 413.327844 -296.639654) (xy 413.283382 -296.660752)
			(xy 413.236111 -296.674444) (xy 413.187256 -296.680376) (xy 413.138081 -296.678395) (xy 413.089862 -296.668551)
			(xy 413.043846 -296.651099) (xy 413.001225 -296.626492) (xy 412.963104 -296.595367) (xy 412.930469 -296.55853)
			(xy 412.904166 -296.516934) (xy 412.884875 -296.471658) (xy 412.873098 -296.423874) (xy 412.869138 -296.37482)
			(xy 411.58033 -296.37482) (xy 411.579835 -296.399427) (xy 411.57194 -296.448004) (xy 411.556356 -296.494685)
			(xy 411.533485 -296.538262) (xy 411.50392 -296.577606) (xy 411.468427 -296.611698) (xy 411.427924 -296.639654)
			(xy 411.383462 -296.660752) (xy 411.336191 -296.674444) (xy 411.287336 -296.680376) (xy 411.238161 -296.678395)
			(xy 411.189942 -296.668551) (xy 411.143926 -296.651099) (xy 411.101305 -296.626492) (xy 411.063184 -296.595367)
			(xy 411.030549 -296.55853) (xy 411.004246 -296.516934) (xy 410.984955 -296.471658) (xy 410.973178 -296.423874)
			(xy 410.969218 -296.37482) (xy 409.680156 -296.37482) (xy 409.679661 -296.399427) (xy 409.671766 -296.448004)
			(xy 409.656182 -296.494685) (xy 409.633311 -296.538262) (xy 409.603746 -296.577606) (xy 409.568253 -296.611698)
			(xy 409.52775 -296.639654) (xy 409.483288 -296.660752) (xy 409.436017 -296.674444) (xy 409.387162 -296.680376)
			(xy 409.337987 -296.678395) (xy 409.289768 -296.668551) (xy 409.243752 -296.651099) (xy 409.201131 -296.626492)
			(xy 409.16301 -296.595367) (xy 409.130375 -296.55853) (xy 409.104072 -296.516934) (xy 409.084781 -296.471658)
			(xy 409.073004 -296.423874) (xy 409.069044 -296.37482) (xy 406.830276 -296.37482) (xy 406.829781 -296.399427)
			(xy 406.821886 -296.448004) (xy 406.806302 -296.494685) (xy 406.783431 -296.538262) (xy 406.753866 -296.577606)
			(xy 406.718373 -296.611698) (xy 406.67787 -296.639654) (xy 406.633408 -296.660752) (xy 406.586137 -296.674444)
			(xy 406.537282 -296.680376) (xy 406.488107 -296.678395) (xy 406.439888 -296.668551) (xy 406.393872 -296.651099)
			(xy 406.351251 -296.626492) (xy 406.31313 -296.595367) (xy 406.280495 -296.55853) (xy 406.254192 -296.516934)
			(xy 406.234901 -296.471658) (xy 406.223124 -296.423874) (xy 406.219164 -296.37482) (xy 404.930356 -296.37482)
			(xy 404.929861 -296.399427) (xy 404.921966 -296.448004) (xy 404.906382 -296.494685) (xy 404.883511 -296.538262)
			(xy 404.853946 -296.577606) (xy 404.818453 -296.611698) (xy 404.77795 -296.639654) (xy 404.733488 -296.660752)
			(xy 404.686217 -296.674444) (xy 404.637362 -296.680376) (xy 404.588187 -296.678395) (xy 404.539968 -296.668551)
			(xy 404.493952 -296.651099) (xy 404.451331 -296.626492) (xy 404.41321 -296.595367) (xy 404.380575 -296.55853)
			(xy 404.354272 -296.516934) (xy 404.334981 -296.471658) (xy 404.323204 -296.423874) (xy 404.319244 -296.37482)
			(xy 403.030182 -296.37482) (xy 403.029687 -296.399427) (xy 403.021792 -296.448004) (xy 403.006208 -296.494685)
			(xy 402.983337 -296.538262) (xy 402.953772 -296.577606) (xy 402.918279 -296.611698) (xy 402.877776 -296.639654)
			(xy 402.833314 -296.660752) (xy 402.786043 -296.674444) (xy 402.737188 -296.680376) (xy 402.688013 -296.678395)
			(xy 402.639794 -296.668551) (xy 402.593778 -296.651099) (xy 402.551157 -296.626492) (xy 402.513036 -296.595367)
			(xy 402.480401 -296.55853) (xy 402.454098 -296.516934) (xy 402.434807 -296.471658) (xy 402.42303 -296.423874)
			(xy 402.41907 -296.37482) (xy 401.130262 -296.37482) (xy 401.129767 -296.399427) (xy 401.121872 -296.448004)
			(xy 401.106288 -296.494685) (xy 401.083417 -296.538262) (xy 401.053852 -296.577606) (xy 401.018359 -296.611698)
			(xy 400.977856 -296.639654) (xy 400.933394 -296.660752) (xy 400.886123 -296.674444) (xy 400.837268 -296.680376)
			(xy 400.788093 -296.678395) (xy 400.739874 -296.668551) (xy 400.693858 -296.651099) (xy 400.651237 -296.626492)
			(xy 400.613116 -296.595367) (xy 400.580481 -296.55853) (xy 400.554178 -296.516934) (xy 400.534887 -296.471658)
			(xy 400.52311 -296.423874) (xy 400.51915 -296.37482) (xy 399.230342 -296.37482) (xy 399.229847 -296.399427)
			(xy 399.221952 -296.448004) (xy 399.206368 -296.494685) (xy 399.183497 -296.538262) (xy 399.153932 -296.577606)
			(xy 399.118439 -296.611698) (xy 399.077936 -296.639654) (xy 399.033474 -296.660752) (xy 398.986203 -296.674444)
			(xy 398.937348 -296.680376) (xy 398.888173 -296.678395) (xy 398.839954 -296.668551) (xy 398.793938 -296.651099)
			(xy 398.751317 -296.626492) (xy 398.713196 -296.595367) (xy 398.680561 -296.55853) (xy 398.654258 -296.516934)
			(xy 398.634967 -296.471658) (xy 398.62319 -296.423874) (xy 398.61923 -296.37482) (xy 397.330168 -296.37482)
			(xy 397.329673 -296.399427) (xy 397.321778 -296.448004) (xy 397.306194 -296.494685) (xy 397.283323 -296.538262)
			(xy 397.253758 -296.577606) (xy 397.218265 -296.611698) (xy 397.177762 -296.639654) (xy 397.1333 -296.660752)
			(xy 397.086029 -296.674444) (xy 397.037174 -296.680376) (xy 396.987999 -296.678395) (xy 396.93978 -296.668551)
			(xy 396.893764 -296.651099) (xy 396.851143 -296.626492) (xy 396.813022 -296.595367) (xy 396.780387 -296.55853)
			(xy 396.754084 -296.516934) (xy 396.734793 -296.471658) (xy 396.723016 -296.423874) (xy 396.719056 -296.37482)
			(xy 396.380208 -296.37482) (xy 396.379713 -296.399427) (xy 396.371818 -296.448004) (xy 396.356234 -296.494685)
			(xy 396.333363 -296.538262) (xy 396.303798 -296.577606) (xy 396.268305 -296.611698) (xy 396.227802 -296.639654)
			(xy 396.18334 -296.660752) (xy 396.136069 -296.674444) (xy 396.087214 -296.680376) (xy 396.038039 -296.678395)
			(xy 395.98982 -296.668551) (xy 395.943804 -296.651099) (xy 395.901183 -296.626492) (xy 395.863062 -296.595367)
			(xy 395.830427 -296.55853) (xy 395.804124 -296.516934) (xy 395.784833 -296.471658) (xy 395.773056 -296.423874)
			(xy 395.769096 -296.37482) (xy 394.480288 -296.37482) (xy 394.479793 -296.399427) (xy 394.471898 -296.448004)
			(xy 394.456314 -296.494685) (xy 394.433443 -296.538262) (xy 394.403878 -296.577606) (xy 394.368385 -296.611698)
			(xy 394.327882 -296.639654) (xy 394.28342 -296.660752) (xy 394.236149 -296.674444) (xy 394.187294 -296.680376)
			(xy 394.138119 -296.678395) (xy 394.0899 -296.668551) (xy 394.043884 -296.651099) (xy 394.001263 -296.626492)
			(xy 393.963142 -296.595367) (xy 393.930507 -296.55853) (xy 393.904204 -296.516934) (xy 393.884913 -296.471658)
			(xy 393.873136 -296.423874) (xy 393.869176 -296.37482) (xy 393.530328 -296.37482) (xy 393.529833 -296.399427)
			(xy 393.521938 -296.448004) (xy 393.506354 -296.494685) (xy 393.483483 -296.538262) (xy 393.453918 -296.577606)
			(xy 393.418425 -296.611698) (xy 393.377922 -296.639654) (xy 393.33346 -296.660752) (xy 393.286189 -296.674444)
			(xy 393.237334 -296.680376) (xy 393.188159 -296.678395) (xy 393.13994 -296.668551) (xy 393.093924 -296.651099)
			(xy 393.051303 -296.626492) (xy 393.013182 -296.595367) (xy 392.980547 -296.55853) (xy 392.954244 -296.516934)
			(xy 392.934953 -296.471658) (xy 392.923176 -296.423874) (xy 392.919216 -296.37482) (xy 392.580114 -296.37482)
			(xy 392.579619 -296.399427) (xy 392.571724 -296.448004) (xy 392.55614 -296.494685) (xy 392.533269 -296.538262)
			(xy 392.503704 -296.577606) (xy 392.468211 -296.611698) (xy 392.427708 -296.639654) (xy 392.383246 -296.660752)
			(xy 392.335975 -296.674444) (xy 392.28712 -296.680376) (xy 392.237945 -296.678395) (xy 392.189726 -296.668551)
			(xy 392.14371 -296.651099) (xy 392.101089 -296.626492) (xy 392.062968 -296.595367) (xy 392.030333 -296.55853)
			(xy 392.00403 -296.516934) (xy 391.984739 -296.471658) (xy 391.972962 -296.423874) (xy 391.969002 -296.37482)
			(xy 390.680194 -296.37482) (xy 390.679699 -296.399427) (xy 390.671804 -296.448004) (xy 390.65622 -296.494685)
			(xy 390.633349 -296.538262) (xy 390.603784 -296.577606) (xy 390.568291 -296.611698) (xy 390.527788 -296.639654)
			(xy 390.483326 -296.660752) (xy 390.436055 -296.674444) (xy 390.3872 -296.680376) (xy 390.338025 -296.678395)
			(xy 390.289806 -296.668551) (xy 390.24379 -296.651099) (xy 390.201169 -296.626492) (xy 390.163048 -296.595367)
			(xy 390.130413 -296.55853) (xy 390.10411 -296.516934) (xy 390.084819 -296.471658) (xy 390.073042 -296.423874)
			(xy 390.069082 -296.37482) (xy 388.780274 -296.37482) (xy 388.779779 -296.399427) (xy 388.771884 -296.448004)
			(xy 388.7563 -296.494685) (xy 388.733429 -296.538262) (xy 388.703864 -296.577606) (xy 388.668371 -296.611698)
			(xy 388.627868 -296.639654) (xy 388.583406 -296.660752) (xy 388.536135 -296.674444) (xy 388.48728 -296.680376)
			(xy 388.438105 -296.678395) (xy 388.389886 -296.668551) (xy 388.34387 -296.651099) (xy 388.301249 -296.626492)
			(xy 388.263128 -296.595367) (xy 388.230493 -296.55853) (xy 388.20419 -296.516934) (xy 388.184899 -296.471658)
			(xy 388.173122 -296.423874) (xy 388.169162 -296.37482) (xy 387.830314 -296.37482) (xy 387.829819 -296.399427)
			(xy 387.821924 -296.448004) (xy 387.80634 -296.494685) (xy 387.783469 -296.538262) (xy 387.753904 -296.577606)
			(xy 387.718411 -296.611698) (xy 387.677908 -296.639654) (xy 387.633446 -296.660752) (xy 387.586175 -296.674444)
			(xy 387.53732 -296.680376) (xy 387.488145 -296.678395) (xy 387.439926 -296.668551) (xy 387.39391 -296.651099)
			(xy 387.351289 -296.626492) (xy 387.313168 -296.595367) (xy 387.280533 -296.55853) (xy 387.25423 -296.516934)
			(xy 387.234939 -296.471658) (xy 387.223162 -296.423874) (xy 387.219202 -296.37482) (xy 386.8801 -296.37482)
			(xy 386.879605 -296.399427) (xy 386.87171 -296.448004) (xy 386.856126 -296.494685) (xy 386.833255 -296.538262)
			(xy 386.80369 -296.577606) (xy 386.768197 -296.611698) (xy 386.727694 -296.639654) (xy 386.683232 -296.660752)
			(xy 386.635961 -296.674444) (xy 386.587106 -296.680376) (xy 386.537931 -296.678395) (xy 386.489712 -296.668551)
			(xy 386.443696 -296.651099) (xy 386.401075 -296.626492) (xy 386.362954 -296.595367) (xy 386.330319 -296.55853)
			(xy 386.304016 -296.516934) (xy 386.284725 -296.471658) (xy 386.272948 -296.423874) (xy 386.268988 -296.37482)
			(xy 385.930394 -296.37482) (xy 385.929899 -296.399427) (xy 385.922004 -296.448004) (xy 385.90642 -296.494685)
			(xy 385.883549 -296.538262) (xy 385.853984 -296.577606) (xy 385.818491 -296.611698) (xy 385.777988 -296.639654)
			(xy 385.733526 -296.660752) (xy 385.686255 -296.674444) (xy 385.6374 -296.680376) (xy 385.588225 -296.678395)
			(xy 385.540006 -296.668551) (xy 385.49399 -296.651099) (xy 385.451369 -296.626492) (xy 385.413248 -296.595367)
			(xy 385.380613 -296.55853) (xy 385.35431 -296.516934) (xy 385.335019 -296.471658) (xy 385.323242 -296.423874)
			(xy 385.319282 -296.37482) (xy 384.980175 -296.37482) (xy 384.979685 -296.399173) (xy 384.97179 -296.44775)
			(xy 384.956206 -296.494431) (xy 384.933335 -296.538008) (xy 384.90377 -296.577352) (xy 384.868277 -296.611444)
			(xy 384.827774 -296.6394) (xy 384.783312 -296.660498) (xy 384.736041 -296.67419) (xy 384.687186 -296.680122)
			(xy 384.638011 -296.678141) (xy 384.589792 -296.668297) (xy 384.543776 -296.650845) (xy 384.501155 -296.626238)
			(xy 384.463034 -296.595113) (xy 384.430399 -296.558276) (xy 384.404096 -296.51668) (xy 384.384805 -296.471404)
			(xy 384.373028 -296.42362) (xy 384.369068 -296.374566) (xy 382.50915 -296.374566) (xy 382.525301 -296.384423)
			(xy 382.568169 -296.420098) (xy 382.605386 -296.461635) (xy 382.636159 -296.508148) (xy 382.659831 -296.558645)
			(xy 382.675899 -296.612052) (xy 382.684019 -296.667228) (xy 382.684528 -296.695114) (xy 382.684019 -296.723)
			(xy 382.675899 -296.778176) (xy 382.659831 -296.831583) (xy 382.636159 -296.88208) (xy 382.605386 -296.928593)
			(xy 382.568169 -296.97013) (xy 382.525301 -297.005805) (xy 382.477695 -297.034859) (xy 382.426366 -297.056671)
			(xy 382.372409 -297.070777) (xy 382.316972 -297.076877) (xy 382.261238 -297.07484) (xy 382.206395 -297.06471)
			(xy 382.153611 -297.046703) (xy 382.104011 -297.021202) (xy 382.058653 -296.988751) (xy 382.018504 -296.950042)
			(xy 381.984418 -296.905899) (xy 381.957122 -296.857264) (xy 381.937199 -296.805173) (xy 381.925073 -296.750736)
			(xy 381.921002 -296.695114) (xy 381.798068 -296.695114) (xy 381.797559 -296.723) (xy 381.789439 -296.778176)
			(xy 381.773371 -296.831583) (xy 381.749699 -296.88208) (xy 381.718926 -296.928593) (xy 381.681709 -296.97013)
			(xy 381.638841 -297.005805) (xy 381.591235 -297.034859) (xy 381.539906 -297.056671) (xy 381.485949 -297.070777)
			(xy 381.430512 -297.076877) (xy 381.374778 -297.07484) (xy 381.319935 -297.06471) (xy 381.267151 -297.046703)
			(xy 381.217551 -297.021202) (xy 381.172193 -296.988751) (xy 381.132044 -296.950042) (xy 381.097958 -296.905899)
			(xy 381.070662 -296.857264) (xy 381.050739 -296.805173) (xy 381.038613 -296.750736) (xy 381.034542 -296.695114)
			(xy 380.401068 -296.695114) (xy 380.400582 -296.722365) (xy 380.392826 -296.776313) (xy 380.377471 -296.828608)
			(xy 380.354829 -296.878185) (xy 380.325363 -296.924035) (xy 380.289672 -296.965226) (xy 380.248481 -297.000917)
			(xy 380.202631 -297.030383) (xy 380.153054 -297.053025) (xy 380.100759 -297.06838) (xy 380.046811 -297.076136)
			(xy 379.992309 -297.076136) (xy 379.938361 -297.06838) (xy 379.886066 -297.053025) (xy 379.836489 -297.030383)
			(xy 379.790639 -297.000917) (xy 379.749448 -296.965226) (xy 379.713757 -296.924035) (xy 379.684291 -296.878185)
			(xy 379.661649 -296.828608) (xy 379.646294 -296.776313) (xy 379.638538 -296.722365) (xy 379.638052 -296.695114)
			(xy 351.03308 -296.695114) (xy 351.03308 -297.3248) (xy 383.734049 -297.3248) (xy 383.73822 -297.274461)
			(xy 383.750619 -297.225496) (xy 383.770908 -297.179239) (xy 383.798533 -297.136952) (xy 383.832742 -297.099788)
			(xy 383.872601 -297.068761) (xy 383.917022 -297.044718) (xy 383.964795 -297.028314) (xy 384.014617 -297.019996)
			(xy 384.039872 -297.019472) (xy 384.065267 -297.019985) (xy 384.115357 -297.028398) (xy 384.163364 -297.044982)
			(xy 384.207966 -297.069279) (xy 384.247935 -297.100619) (xy 384.265424 -297.11904) (xy 384.27279 -297.127168)
			(xy 384.292856 -297.135804) (xy 384.39217 -297.13301) (xy 384.411728 -297.123612) (xy 384.41884 -297.114976)
			(xy 384.43463 -297.096405) (xy 384.470763 -297.063686) (xy 384.511304 -297.036619) (xy 384.555376 -297.01579)
			(xy 384.602026 -297.00165) (xy 384.650245 -296.994504) (xy 384.674618 -296.994072) (xy 385.624578 -296.994072)
			(xy 385.650567 -296.994593) (xy 385.701905 -297.002721) (xy 385.751339 -297.018781) (xy 385.797653 -297.042376)
			(xy 385.839705 -297.072926) (xy 385.87646 -297.109678) (xy 385.907013 -297.151728) (xy 385.930611 -297.19804)
			(xy 385.946673 -297.247474) (xy 385.954805 -297.298811) (xy 385.954805 -297.32478) (xy 386.268988 -297.32478)
			(xy 386.272948 -297.275726) (xy 386.284725 -297.227942) (xy 386.304016 -297.182666) (xy 386.330319 -297.14107)
			(xy 386.362954 -297.104233) (xy 386.401075 -297.073108) (xy 386.443696 -297.048501) (xy 386.489712 -297.031049)
			(xy 386.537931 -297.021205) (xy 386.587106 -297.019224) (xy 386.635961 -297.025156) (xy 386.683232 -297.038848)
			(xy 386.727694 -297.059946) (xy 386.768197 -297.087902) (xy 386.80369 -297.121994) (xy 386.833255 -297.161338)
			(xy 386.856126 -297.204915) (xy 386.87171 -297.251596) (xy 386.879605 -297.300173) (xy 386.8801 -297.32478)
			(xy 387.219202 -297.32478) (xy 387.223162 -297.275726) (xy 387.234939 -297.227942) (xy 387.25423 -297.182666)
			(xy 387.280533 -297.14107) (xy 387.313168 -297.104233) (xy 387.351289 -297.073108) (xy 387.39391 -297.048501)
			(xy 387.439926 -297.031049) (xy 387.488145 -297.021205) (xy 387.53732 -297.019224) (xy 387.586175 -297.025156)
			(xy 387.633446 -297.038848) (xy 387.677908 -297.059946) (xy 387.718411 -297.087902) (xy 387.753904 -297.121994)
			(xy 387.783469 -297.161338) (xy 387.80634 -297.204915) (xy 387.821924 -297.251596) (xy 387.829819 -297.300173)
			(xy 387.830314 -297.32478) (xy 390.069082 -297.32478) (xy 390.073042 -297.275726) (xy 390.084819 -297.227942)
			(xy 390.10411 -297.182666) (xy 390.130413 -297.14107) (xy 390.163048 -297.104233) (xy 390.201169 -297.073108)
			(xy 390.24379 -297.048501) (xy 390.289806 -297.031049) (xy 390.338025 -297.021205) (xy 390.3872 -297.019224)
			(xy 390.436055 -297.025156) (xy 390.483326 -297.038848) (xy 390.527788 -297.059946) (xy 390.568291 -297.087902)
			(xy 390.603784 -297.121994) (xy 390.633349 -297.161338) (xy 390.65622 -297.204915) (xy 390.671804 -297.251596)
			(xy 390.679699 -297.300173) (xy 390.680194 -297.32478) (xy 391.019042 -297.32478) (xy 391.023002 -297.275726)
			(xy 391.034779 -297.227942) (xy 391.05407 -297.182666) (xy 391.080373 -297.14107) (xy 391.113008 -297.104233)
			(xy 391.151129 -297.073108) (xy 391.19375 -297.048501) (xy 391.239766 -297.031049) (xy 391.287985 -297.021205)
			(xy 391.33716 -297.019224) (xy 391.386015 -297.025156) (xy 391.433286 -297.038848) (xy 391.477748 -297.059946)
			(xy 391.518251 -297.087902) (xy 391.553744 -297.121994) (xy 391.583309 -297.161338) (xy 391.60618 -297.204915)
			(xy 391.621764 -297.251596) (xy 391.629659 -297.300173) (xy 391.630154 -297.32478) (xy 391.969002 -297.32478)
			(xy 391.972962 -297.275726) (xy 391.984739 -297.227942) (xy 392.00403 -297.182666) (xy 392.030333 -297.14107)
			(xy 392.062968 -297.104233) (xy 392.101089 -297.073108) (xy 392.14371 -297.048501) (xy 392.189726 -297.031049)
			(xy 392.237945 -297.021205) (xy 392.28712 -297.019224) (xy 392.335975 -297.025156) (xy 392.383246 -297.038848)
			(xy 392.427708 -297.059946) (xy 392.468211 -297.087902) (xy 392.503704 -297.121994) (xy 392.533269 -297.161338)
			(xy 392.55614 -297.204915) (xy 392.571724 -297.251596) (xy 392.579619 -297.300173) (xy 392.580114 -297.32478)
			(xy 392.919216 -297.32478) (xy 392.923176 -297.275726) (xy 392.934953 -297.227942) (xy 392.954244 -297.182666)
			(xy 392.980547 -297.14107) (xy 393.013182 -297.104233) (xy 393.051303 -297.073108) (xy 393.093924 -297.048501)
			(xy 393.13994 -297.031049) (xy 393.188159 -297.021205) (xy 393.237334 -297.019224) (xy 393.286189 -297.025156)
			(xy 393.33346 -297.038848) (xy 393.377922 -297.059946) (xy 393.418425 -297.087902) (xy 393.453918 -297.121994)
			(xy 393.483483 -297.161338) (xy 393.506354 -297.204915) (xy 393.521938 -297.251596) (xy 393.529833 -297.300173)
			(xy 393.530328 -297.32478) (xy 393.869176 -297.32478) (xy 393.873136 -297.275726) (xy 393.884913 -297.227942)
			(xy 393.904204 -297.182666) (xy 393.930507 -297.14107) (xy 393.963142 -297.104233) (xy 394.001263 -297.073108)
			(xy 394.043884 -297.048501) (xy 394.0899 -297.031049) (xy 394.138119 -297.021205) (xy 394.187294 -297.019224)
			(xy 394.236149 -297.025156) (xy 394.28342 -297.038848) (xy 394.327882 -297.059946) (xy 394.368385 -297.087902)
			(xy 394.403878 -297.121994) (xy 394.433443 -297.161338) (xy 394.456314 -297.204915) (xy 394.471898 -297.251596)
			(xy 394.479793 -297.300173) (xy 394.480288 -297.32478) (xy 394.819136 -297.32478) (xy 394.823096 -297.275726)
			(xy 394.834873 -297.227942) (xy 394.854164 -297.182666) (xy 394.880467 -297.14107) (xy 394.913102 -297.104233)
			(xy 394.951223 -297.073108) (xy 394.993844 -297.048501) (xy 395.03986 -297.031049) (xy 395.088079 -297.021205)
			(xy 395.137254 -297.019224) (xy 395.186109 -297.025156) (xy 395.23338 -297.038848) (xy 395.277842 -297.059946)
			(xy 395.318345 -297.087902) (xy 395.353838 -297.121994) (xy 395.383403 -297.161338) (xy 395.406274 -297.204915)
			(xy 395.421858 -297.251596) (xy 395.429753 -297.300173) (xy 395.430248 -297.32478) (xy 395.769096 -297.32478)
			(xy 395.773056 -297.275726) (xy 395.784833 -297.227942) (xy 395.804124 -297.182666) (xy 395.830427 -297.14107)
			(xy 395.863062 -297.104233) (xy 395.901183 -297.073108) (xy 395.943804 -297.048501) (xy 395.98982 -297.031049)
			(xy 396.038039 -297.021205) (xy 396.087214 -297.019224) (xy 396.136069 -297.025156) (xy 396.18334 -297.038848)
			(xy 396.227802 -297.059946) (xy 396.268305 -297.087902) (xy 396.303798 -297.121994) (xy 396.333363 -297.161338)
			(xy 396.356234 -297.204915) (xy 396.371818 -297.251596) (xy 396.379713 -297.300173) (xy 396.380208 -297.32478)
			(xy 397.669016 -297.32478) (xy 397.672976 -297.275726) (xy 397.684753 -297.227942) (xy 397.704044 -297.182666)
			(xy 397.730347 -297.14107) (xy 397.762982 -297.104233) (xy 397.801103 -297.073108) (xy 397.843724 -297.048501)
			(xy 397.88974 -297.031049) (xy 397.937959 -297.021205) (xy 397.987134 -297.019224) (xy 398.035989 -297.025156)
			(xy 398.08326 -297.038848) (xy 398.127722 -297.059946) (xy 398.168225 -297.087902) (xy 398.203718 -297.121994)
			(xy 398.233283 -297.161338) (xy 398.256154 -297.204915) (xy 398.271738 -297.251596) (xy 398.279633 -297.300173)
			(xy 398.280128 -297.32478) (xy 399.56919 -297.32478) (xy 399.57315 -297.275726) (xy 399.584927 -297.227942)
			(xy 399.604218 -297.182666) (xy 399.630521 -297.14107) (xy 399.663156 -297.104233) (xy 399.701277 -297.073108)
			(xy 399.743898 -297.048501) (xy 399.789914 -297.031049) (xy 399.838133 -297.021205) (xy 399.887308 -297.019224)
			(xy 399.936163 -297.025156) (xy 399.983434 -297.038848) (xy 400.027896 -297.059946) (xy 400.068399 -297.087902)
			(xy 400.103892 -297.121994) (xy 400.133457 -297.161338) (xy 400.156328 -297.204915) (xy 400.171912 -297.251596)
			(xy 400.179807 -297.300173) (xy 400.180302 -297.32478) (xy 401.46911 -297.32478) (xy 401.47307 -297.275726)
			(xy 401.484847 -297.227942) (xy 401.504138 -297.182666) (xy 401.530441 -297.14107) (xy 401.563076 -297.104233)
			(xy 401.601197 -297.073108) (xy 401.643818 -297.048501) (xy 401.689834 -297.031049) (xy 401.738053 -297.021205)
			(xy 401.787228 -297.019224) (xy 401.836083 -297.025156) (xy 401.883354 -297.038848) (xy 401.927816 -297.059946)
			(xy 401.968319 -297.087902) (xy 402.003812 -297.121994) (xy 402.033377 -297.161338) (xy 402.056248 -297.204915)
			(xy 402.071832 -297.251596) (xy 402.079727 -297.300173) (xy 402.080222 -297.32478) (xy 403.36903 -297.32478)
			(xy 403.37299 -297.275726) (xy 403.384767 -297.227942) (xy 403.404058 -297.182666) (xy 403.430361 -297.14107)
			(xy 403.462996 -297.104233) (xy 403.501117 -297.073108) (xy 403.543738 -297.048501) (xy 403.589754 -297.031049)
			(xy 403.637973 -297.021205) (xy 403.687148 -297.019224) (xy 403.736003 -297.025156) (xy 403.783274 -297.038848)
			(xy 403.827736 -297.059946) (xy 403.868239 -297.087902) (xy 403.903732 -297.121994) (xy 403.933297 -297.161338)
			(xy 403.956168 -297.204915) (xy 403.971752 -297.251596) (xy 403.979647 -297.300173) (xy 403.980142 -297.32478)
			(xy 405.269204 -297.32478) (xy 405.273164 -297.275726) (xy 405.284941 -297.227942) (xy 405.304232 -297.182666)
			(xy 405.330535 -297.14107) (xy 405.36317 -297.104233) (xy 405.401291 -297.073108) (xy 405.443912 -297.048501)
			(xy 405.489928 -297.031049) (xy 405.538147 -297.021205) (xy 405.587322 -297.019224) (xy 405.636177 -297.025156)
			(xy 405.683448 -297.038848) (xy 405.72791 -297.059946) (xy 405.768413 -297.087902) (xy 405.803906 -297.121994)
			(xy 405.833471 -297.161338) (xy 405.856342 -297.204915) (xy 405.871926 -297.251596) (xy 405.879821 -297.300173)
			(xy 405.880316 -297.32478) (xy 408.119084 -297.32478) (xy 408.123044 -297.275726) (xy 408.134821 -297.227942)
			(xy 408.154112 -297.182666) (xy 408.180415 -297.14107) (xy 408.21305 -297.104233) (xy 408.251171 -297.073108)
			(xy 408.293792 -297.048501) (xy 408.339808 -297.031049) (xy 408.388027 -297.021205) (xy 408.437202 -297.019224)
			(xy 408.486057 -297.025156) (xy 408.533328 -297.038848) (xy 408.57779 -297.059946) (xy 408.618293 -297.087902)
			(xy 408.653786 -297.121994) (xy 408.683351 -297.161338) (xy 408.706222 -297.204915) (xy 408.721806 -297.251596)
			(xy 408.729701 -297.300173) (xy 408.730196 -297.32478) (xy 410.019004 -297.32478) (xy 410.022964 -297.275726)
			(xy 410.034741 -297.227942) (xy 410.054032 -297.182666) (xy 410.080335 -297.14107) (xy 410.11297 -297.104233)
			(xy 410.151091 -297.073108) (xy 410.193712 -297.048501) (xy 410.239728 -297.031049) (xy 410.287947 -297.021205)
			(xy 410.337122 -297.019224) (xy 410.385977 -297.025156) (xy 410.433248 -297.038848) (xy 410.47771 -297.059946)
			(xy 410.518213 -297.087902) (xy 410.553706 -297.121994) (xy 410.583271 -297.161338) (xy 410.606142 -297.204915)
			(xy 410.621726 -297.251596) (xy 410.629621 -297.300173) (xy 410.630116 -297.32478) (xy 411.919178 -297.32478)
			(xy 411.923138 -297.275726) (xy 411.934915 -297.227942) (xy 411.954206 -297.182666) (xy 411.980509 -297.14107)
			(xy 412.013144 -297.104233) (xy 412.051265 -297.073108) (xy 412.093886 -297.048501) (xy 412.139902 -297.031049)
			(xy 412.188121 -297.021205) (xy 412.237296 -297.019224) (xy 412.286151 -297.025156) (xy 412.333422 -297.038848)
			(xy 412.377884 -297.059946) (xy 412.418387 -297.087902) (xy 412.45388 -297.121994) (xy 412.483445 -297.161338)
			(xy 412.506316 -297.204915) (xy 412.5219 -297.251596) (xy 412.529795 -297.300173) (xy 412.53029 -297.32478)
			(xy 413.819098 -297.32478) (xy 413.823058 -297.275726) (xy 413.834835 -297.227942) (xy 413.854126 -297.182666)
			(xy 413.880429 -297.14107) (xy 413.913064 -297.104233) (xy 413.951185 -297.073108) (xy 413.993806 -297.048501)
			(xy 414.039822 -297.031049) (xy 414.088041 -297.021205) (xy 414.137216 -297.019224) (xy 414.186071 -297.025156)
			(xy 414.233342 -297.038848) (xy 414.277804 -297.059946) (xy 414.318307 -297.087902) (xy 414.3538 -297.121994)
			(xy 414.383365 -297.161338) (xy 414.406236 -297.204915) (xy 414.42182 -297.251596) (xy 414.429715 -297.300173)
			(xy 414.43021 -297.32478) (xy 414.769058 -297.32478) (xy 414.773018 -297.275726) (xy 414.784795 -297.227942)
			(xy 414.804086 -297.182666) (xy 414.830389 -297.14107) (xy 414.863024 -297.104233) (xy 414.901145 -297.073108)
			(xy 414.943766 -297.048501) (xy 414.989782 -297.031049) (xy 415.038001 -297.021205) (xy 415.087176 -297.019224)
			(xy 415.136031 -297.025156) (xy 415.183302 -297.038848) (xy 415.227764 -297.059946) (xy 415.268267 -297.087902)
			(xy 415.30376 -297.121994) (xy 415.333325 -297.161338) (xy 415.356196 -297.204915) (xy 415.37178 -297.251596)
			(xy 415.379675 -297.300173) (xy 415.38017 -297.32478) (xy 415.719018 -297.32478) (xy 415.722978 -297.275726)
			(xy 415.734755 -297.227942) (xy 415.754046 -297.182666) (xy 415.780349 -297.14107) (xy 415.812984 -297.104233)
			(xy 415.851105 -297.073108) (xy 415.893726 -297.048501) (xy 415.939742 -297.031049) (xy 415.987961 -297.021205)
			(xy 416.037136 -297.019224) (xy 416.085991 -297.025156) (xy 416.133262 -297.038848) (xy 416.177724 -297.059946)
			(xy 416.218227 -297.087902) (xy 416.25372 -297.121994) (xy 416.283285 -297.161338) (xy 416.306156 -297.204915)
			(xy 416.32174 -297.251596) (xy 416.329635 -297.300173) (xy 416.33013 -297.32478) (xy 416.329635 -297.349387)
			(xy 416.32174 -297.397964) (xy 416.306156 -297.444645) (xy 416.283285 -297.488222) (xy 416.25372 -297.527566)
			(xy 416.218227 -297.561658) (xy 416.177724 -297.589614) (xy 416.133262 -297.610712) (xy 416.085991 -297.624404)
			(xy 416.037136 -297.630336) (xy 415.987961 -297.628355) (xy 415.939742 -297.618511) (xy 415.893726 -297.601059)
			(xy 415.851105 -297.576452) (xy 415.812984 -297.545327) (xy 415.780349 -297.50849) (xy 415.754046 -297.466894)
			(xy 415.734755 -297.421618) (xy 415.722978 -297.373834) (xy 415.719018 -297.32478) (xy 415.38017 -297.32478)
			(xy 415.379675 -297.349387) (xy 415.37178 -297.397964) (xy 415.356196 -297.444645) (xy 415.333325 -297.488222)
			(xy 415.30376 -297.527566) (xy 415.268267 -297.561658) (xy 415.227764 -297.589614) (xy 415.183302 -297.610712)
			(xy 415.136031 -297.624404) (xy 415.087176 -297.630336) (xy 415.038001 -297.628355) (xy 414.989782 -297.618511)
			(xy 414.943766 -297.601059) (xy 414.901145 -297.576452) (xy 414.863024 -297.545327) (xy 414.830389 -297.50849)
			(xy 414.804086 -297.466894) (xy 414.784795 -297.421618) (xy 414.773018 -297.373834) (xy 414.769058 -297.32478)
			(xy 414.43021 -297.32478) (xy 414.429715 -297.349387) (xy 414.42182 -297.397964) (xy 414.406236 -297.444645)
			(xy 414.383365 -297.488222) (xy 414.3538 -297.527566) (xy 414.318307 -297.561658) (xy 414.277804 -297.589614)
			(xy 414.233342 -297.610712) (xy 414.186071 -297.624404) (xy 414.137216 -297.630336) (xy 414.088041 -297.628355)
			(xy 414.039822 -297.618511) (xy 413.993806 -297.601059) (xy 413.951185 -297.576452) (xy 413.913064 -297.545327)
			(xy 413.880429 -297.50849) (xy 413.854126 -297.466894) (xy 413.834835 -297.421618) (xy 413.823058 -297.373834)
			(xy 413.819098 -297.32478) (xy 412.53029 -297.32478) (xy 412.529795 -297.349387) (xy 412.5219 -297.397964)
			(xy 412.506316 -297.444645) (xy 412.483445 -297.488222) (xy 412.45388 -297.527566) (xy 412.418387 -297.561658)
			(xy 412.377884 -297.589614) (xy 412.333422 -297.610712) (xy 412.286151 -297.624404) (xy 412.237296 -297.630336)
			(xy 412.188121 -297.628355) (xy 412.139902 -297.618511) (xy 412.093886 -297.601059) (xy 412.051265 -297.576452)
			(xy 412.013144 -297.545327) (xy 411.980509 -297.50849) (xy 411.954206 -297.466894) (xy 411.934915 -297.421618)
			(xy 411.923138 -297.373834) (xy 411.919178 -297.32478) (xy 410.630116 -297.32478) (xy 410.629621 -297.349387)
			(xy 410.621726 -297.397964) (xy 410.606142 -297.444645) (xy 410.583271 -297.488222) (xy 410.553706 -297.527566)
			(xy 410.518213 -297.561658) (xy 410.47771 -297.589614) (xy 410.433248 -297.610712) (xy 410.385977 -297.624404)
			(xy 410.337122 -297.630336) (xy 410.287947 -297.628355) (xy 410.239728 -297.618511) (xy 410.193712 -297.601059)
			(xy 410.151091 -297.576452) (xy 410.11297 -297.545327) (xy 410.080335 -297.50849) (xy 410.054032 -297.466894)
			(xy 410.034741 -297.421618) (xy 410.022964 -297.373834) (xy 410.019004 -297.32478) (xy 408.730196 -297.32478)
			(xy 408.729701 -297.349387) (xy 408.721806 -297.397964) (xy 408.706222 -297.444645) (xy 408.683351 -297.488222)
			(xy 408.653786 -297.527566) (xy 408.618293 -297.561658) (xy 408.57779 -297.589614) (xy 408.533328 -297.610712)
			(xy 408.486057 -297.624404) (xy 408.437202 -297.630336) (xy 408.388027 -297.628355) (xy 408.339808 -297.618511)
			(xy 408.293792 -297.601059) (xy 408.251171 -297.576452) (xy 408.21305 -297.545327) (xy 408.180415 -297.50849)
			(xy 408.154112 -297.466894) (xy 408.134821 -297.421618) (xy 408.123044 -297.373834) (xy 408.119084 -297.32478)
			(xy 405.880316 -297.32478) (xy 405.879821 -297.349387) (xy 405.871926 -297.397964) (xy 405.856342 -297.444645)
			(xy 405.833471 -297.488222) (xy 405.803906 -297.527566) (xy 405.768413 -297.561658) (xy 405.72791 -297.589614)
			(xy 405.683448 -297.610712) (xy 405.636177 -297.624404) (xy 405.587322 -297.630336) (xy 405.538147 -297.628355)
			(xy 405.489928 -297.618511) (xy 405.443912 -297.601059) (xy 405.401291 -297.576452) (xy 405.36317 -297.545327)
			(xy 405.330535 -297.50849) (xy 405.304232 -297.466894) (xy 405.284941 -297.421618) (xy 405.273164 -297.373834)
			(xy 405.269204 -297.32478) (xy 403.980142 -297.32478) (xy 403.979647 -297.349387) (xy 403.971752 -297.397964)
			(xy 403.956168 -297.444645) (xy 403.933297 -297.488222) (xy 403.903732 -297.527566) (xy 403.868239 -297.561658)
			(xy 403.827736 -297.589614) (xy 403.783274 -297.610712) (xy 403.736003 -297.624404) (xy 403.687148 -297.630336)
			(xy 403.637973 -297.628355) (xy 403.589754 -297.618511) (xy 403.543738 -297.601059) (xy 403.501117 -297.576452)
			(xy 403.462996 -297.545327) (xy 403.430361 -297.50849) (xy 403.404058 -297.466894) (xy 403.384767 -297.421618)
			(xy 403.37299 -297.373834) (xy 403.36903 -297.32478) (xy 402.080222 -297.32478) (xy 402.079727 -297.349387)
			(xy 402.071832 -297.397964) (xy 402.056248 -297.444645) (xy 402.033377 -297.488222) (xy 402.003812 -297.527566)
			(xy 401.968319 -297.561658) (xy 401.927816 -297.589614) (xy 401.883354 -297.610712) (xy 401.836083 -297.624404)
			(xy 401.787228 -297.630336) (xy 401.738053 -297.628355) (xy 401.689834 -297.618511) (xy 401.643818 -297.601059)
			(xy 401.601197 -297.576452) (xy 401.563076 -297.545327) (xy 401.530441 -297.50849) (xy 401.504138 -297.466894)
			(xy 401.484847 -297.421618) (xy 401.47307 -297.373834) (xy 401.46911 -297.32478) (xy 400.180302 -297.32478)
			(xy 400.179807 -297.349387) (xy 400.171912 -297.397964) (xy 400.156328 -297.444645) (xy 400.133457 -297.488222)
			(xy 400.103892 -297.527566) (xy 400.068399 -297.561658) (xy 400.027896 -297.589614) (xy 399.983434 -297.610712)
			(xy 399.936163 -297.624404) (xy 399.887308 -297.630336) (xy 399.838133 -297.628355) (xy 399.789914 -297.618511)
			(xy 399.743898 -297.601059) (xy 399.701277 -297.576452) (xy 399.663156 -297.545327) (xy 399.630521 -297.50849)
			(xy 399.604218 -297.466894) (xy 399.584927 -297.421618) (xy 399.57315 -297.373834) (xy 399.56919 -297.32478)
			(xy 398.280128 -297.32478) (xy 398.279633 -297.349387) (xy 398.271738 -297.397964) (xy 398.256154 -297.444645)
			(xy 398.233283 -297.488222) (xy 398.203718 -297.527566) (xy 398.168225 -297.561658) (xy 398.127722 -297.589614)
			(xy 398.08326 -297.610712) (xy 398.035989 -297.624404) (xy 397.987134 -297.630336) (xy 397.937959 -297.628355)
			(xy 397.88974 -297.618511) (xy 397.843724 -297.601059) (xy 397.801103 -297.576452) (xy 397.762982 -297.545327)
			(xy 397.730347 -297.50849) (xy 397.704044 -297.466894) (xy 397.684753 -297.421618) (xy 397.672976 -297.373834)
			(xy 397.669016 -297.32478) (xy 396.380208 -297.32478) (xy 396.379713 -297.349387) (xy 396.371818 -297.397964)
			(xy 396.356234 -297.444645) (xy 396.333363 -297.488222) (xy 396.303798 -297.527566) (xy 396.268305 -297.561658)
			(xy 396.227802 -297.589614) (xy 396.18334 -297.610712) (xy 396.136069 -297.624404) (xy 396.087214 -297.630336)
			(xy 396.038039 -297.628355) (xy 395.98982 -297.618511) (xy 395.943804 -297.601059) (xy 395.901183 -297.576452)
			(xy 395.863062 -297.545327) (xy 395.830427 -297.50849) (xy 395.804124 -297.466894) (xy 395.784833 -297.421618)
			(xy 395.773056 -297.373834) (xy 395.769096 -297.32478) (xy 395.430248 -297.32478) (xy 395.429753 -297.349387)
			(xy 395.421858 -297.397964) (xy 395.406274 -297.444645) (xy 395.383403 -297.488222) (xy 395.353838 -297.527566)
			(xy 395.318345 -297.561658) (xy 395.277842 -297.589614) (xy 395.23338 -297.610712) (xy 395.186109 -297.624404)
			(xy 395.137254 -297.630336) (xy 395.088079 -297.628355) (xy 395.03986 -297.618511) (xy 394.993844 -297.601059)
			(xy 394.951223 -297.576452) (xy 394.913102 -297.545327) (xy 394.880467 -297.50849) (xy 394.854164 -297.466894)
			(xy 394.834873 -297.421618) (xy 394.823096 -297.373834) (xy 394.819136 -297.32478) (xy 394.480288 -297.32478)
			(xy 394.479793 -297.349387) (xy 394.471898 -297.397964) (xy 394.456314 -297.444645) (xy 394.433443 -297.488222)
			(xy 394.403878 -297.527566) (xy 394.368385 -297.561658) (xy 394.327882 -297.589614) (xy 394.28342 -297.610712)
			(xy 394.236149 -297.624404) (xy 394.187294 -297.630336) (xy 394.138119 -297.628355) (xy 394.0899 -297.618511)
			(xy 394.043884 -297.601059) (xy 394.001263 -297.576452) (xy 393.963142 -297.545327) (xy 393.930507 -297.50849)
			(xy 393.904204 -297.466894) (xy 393.884913 -297.421618) (xy 393.873136 -297.373834) (xy 393.869176 -297.32478)
			(xy 393.530328 -297.32478) (xy 393.529833 -297.349387) (xy 393.521938 -297.397964) (xy 393.506354 -297.444645)
			(xy 393.483483 -297.488222) (xy 393.453918 -297.527566) (xy 393.418425 -297.561658) (xy 393.377922 -297.589614)
			(xy 393.33346 -297.610712) (xy 393.286189 -297.624404) (xy 393.237334 -297.630336) (xy 393.188159 -297.628355)
			(xy 393.13994 -297.618511) (xy 393.093924 -297.601059) (xy 393.051303 -297.576452) (xy 393.013182 -297.545327)
			(xy 392.980547 -297.50849) (xy 392.954244 -297.466894) (xy 392.934953 -297.421618) (xy 392.923176 -297.373834)
			(xy 392.919216 -297.32478) (xy 392.580114 -297.32478) (xy 392.579619 -297.349387) (xy 392.571724 -297.397964)
			(xy 392.55614 -297.444645) (xy 392.533269 -297.488222) (xy 392.503704 -297.527566) (xy 392.468211 -297.561658)
			(xy 392.427708 -297.589614) (xy 392.383246 -297.610712) (xy 392.335975 -297.624404) (xy 392.28712 -297.630336)
			(xy 392.237945 -297.628355) (xy 392.189726 -297.618511) (xy 392.14371 -297.601059) (xy 392.101089 -297.576452)
			(xy 392.062968 -297.545327) (xy 392.030333 -297.50849) (xy 392.00403 -297.466894) (xy 391.984739 -297.421618)
			(xy 391.972962 -297.373834) (xy 391.969002 -297.32478) (xy 391.630154 -297.32478) (xy 391.629659 -297.349387)
			(xy 391.621764 -297.397964) (xy 391.60618 -297.444645) (xy 391.583309 -297.488222) (xy 391.553744 -297.527566)
			(xy 391.518251 -297.561658) (xy 391.477748 -297.589614) (xy 391.433286 -297.610712) (xy 391.386015 -297.624404)
			(xy 391.33716 -297.630336) (xy 391.287985 -297.628355) (xy 391.239766 -297.618511) (xy 391.19375 -297.601059)
			(xy 391.151129 -297.576452) (xy 391.113008 -297.545327) (xy 391.080373 -297.50849) (xy 391.05407 -297.466894)
			(xy 391.034779 -297.421618) (xy 391.023002 -297.373834) (xy 391.019042 -297.32478) (xy 390.680194 -297.32478)
			(xy 390.679699 -297.349387) (xy 390.671804 -297.397964) (xy 390.65622 -297.444645) (xy 390.633349 -297.488222)
			(xy 390.603784 -297.527566) (xy 390.568291 -297.561658) (xy 390.527788 -297.589614) (xy 390.483326 -297.610712)
			(xy 390.436055 -297.624404) (xy 390.3872 -297.630336) (xy 390.338025 -297.628355) (xy 390.289806 -297.618511)
			(xy 390.24379 -297.601059) (xy 390.201169 -297.576452) (xy 390.163048 -297.545327) (xy 390.130413 -297.50849)
			(xy 390.10411 -297.466894) (xy 390.084819 -297.421618) (xy 390.073042 -297.373834) (xy 390.069082 -297.32478)
			(xy 387.830314 -297.32478) (xy 387.829819 -297.349387) (xy 387.821924 -297.397964) (xy 387.80634 -297.444645)
			(xy 387.783469 -297.488222) (xy 387.753904 -297.527566) (xy 387.718411 -297.561658) (xy 387.677908 -297.589614)
			(xy 387.633446 -297.610712) (xy 387.586175 -297.624404) (xy 387.53732 -297.630336) (xy 387.488145 -297.628355)
			(xy 387.439926 -297.618511) (xy 387.39391 -297.601059) (xy 387.351289 -297.576452) (xy 387.313168 -297.545327)
			(xy 387.280533 -297.50849) (xy 387.25423 -297.466894) (xy 387.234939 -297.421618) (xy 387.223162 -297.373834)
			(xy 387.219202 -297.32478) (xy 386.8801 -297.32478) (xy 386.879605 -297.349387) (xy 386.87171 -297.397964)
			(xy 386.856126 -297.444645) (xy 386.833255 -297.488222) (xy 386.80369 -297.527566) (xy 386.768197 -297.561658)
			(xy 386.727694 -297.589614) (xy 386.683232 -297.610712) (xy 386.635961 -297.624404) (xy 386.587106 -297.630336)
			(xy 386.537931 -297.628355) (xy 386.489712 -297.618511) (xy 386.443696 -297.601059) (xy 386.401075 -297.576452)
			(xy 386.362954 -297.545327) (xy 386.330319 -297.50849) (xy 386.304016 -297.466894) (xy 386.284725 -297.421618)
			(xy 386.272948 -297.373834) (xy 386.268988 -297.32478) (xy 385.954805 -297.32478) (xy 385.954805 -297.350789)
			(xy 385.946673 -297.402126) (xy 385.930611 -297.45156) (xy 385.907013 -297.497872) (xy 385.87646 -297.539922)
			(xy 385.839705 -297.576674) (xy 385.797653 -297.607224) (xy 385.751339 -297.630819) (xy 385.701905 -297.646879)
			(xy 385.650567 -297.655007) (xy 385.624578 -297.655488) (xy 384.674618 -297.655488) (xy 384.650244 -297.655085)
			(xy 384.602024 -297.647936) (xy 384.555373 -297.633791) (xy 384.511303 -297.612954) (xy 384.470767 -297.585877)
			(xy 384.434642 -297.553147) (xy 384.41884 -297.534584) (xy 384.411492 -297.526532) (xy 384.391869 -297.517073)
			(xy 384.380994 -297.516296) (xy 384.292856 -297.513756) (xy 384.27279 -297.522392) (xy 384.265424 -297.53052)
			(xy 384.247939 -297.548946) (xy 384.207975 -297.580297) (xy 384.163372 -297.604598) (xy 384.115362 -297.621181)
			(xy 384.065269 -297.629585) (xy 384.039872 -297.630088) (xy 384.014617 -297.629604) (xy 383.964795 -297.621286)
			(xy 383.917022 -297.604882) (xy 383.872601 -297.580839) (xy 383.832742 -297.549812) (xy 383.798533 -297.512648)
			(xy 383.770908 -297.470361) (xy 383.750619 -297.424104) (xy 383.73822 -297.375139) (xy 383.734049 -297.3248)
			(xy 351.03308 -297.3248) (xy 351.03308 -297.831256) (xy 374.111518 -297.831256) (xy 374.115589 -297.775634)
			(xy 374.127715 -297.721197) (xy 374.147638 -297.669106) (xy 374.174934 -297.620471) (xy 374.20902 -297.576328)
			(xy 374.249169 -297.537619) (xy 374.294527 -297.505168) (xy 374.344127 -297.479667) (xy 374.396911 -297.46166)
			(xy 374.451754 -297.45153) (xy 374.507488 -297.449493) (xy 374.562925 -297.455593) (xy 374.616882 -297.469699)
			(xy 374.668211 -297.491511) (xy 374.715817 -297.520565) (xy 374.758685 -297.55624) (xy 374.795902 -297.597777)
			(xy 374.826675 -297.64429) (xy 374.850347 -297.694787) (xy 374.866415 -297.748194) (xy 374.874535 -297.80337)
			(xy 374.875044 -297.831256) (xy 375.596656 -297.831256) (xy 375.600727 -297.775634) (xy 375.612853 -297.721197)
			(xy 375.632776 -297.669106) (xy 375.660072 -297.620471) (xy 375.694158 -297.576328) (xy 375.734307 -297.537619)
			(xy 375.779665 -297.505168) (xy 375.829265 -297.479667) (xy 375.882049 -297.46166) (xy 375.936892 -297.45153)
			(xy 375.992626 -297.449493) (xy 376.048063 -297.455593) (xy 376.10202 -297.469699) (xy 376.153349 -297.491511)
			(xy 376.200955 -297.520565) (xy 376.243823 -297.55624) (xy 376.28104 -297.597777) (xy 376.311813 -297.64429)
			(xy 376.335485 -297.694787) (xy 376.351553 -297.748194) (xy 376.359673 -297.80337) (xy 376.360182 -297.831256)
			(xy 376.359673 -297.859142) (xy 376.351553 -297.914318) (xy 376.335485 -297.967725) (xy 376.311813 -298.018222)
			(xy 376.28104 -298.064735) (xy 376.243823 -298.106272) (xy 376.200955 -298.141947) (xy 376.153349 -298.171001)
			(xy 376.10202 -298.192813) (xy 376.048063 -298.206919) (xy 375.992626 -298.213019) (xy 375.936892 -298.210982)
			(xy 375.882049 -298.200852) (xy 375.829265 -298.182845) (xy 375.779665 -298.157344) (xy 375.734307 -298.124893)
			(xy 375.694158 -298.086184) (xy 375.660072 -298.042041) (xy 375.632776 -297.993406) (xy 375.612853 -297.941315)
			(xy 375.600727 -297.886878) (xy 375.596656 -297.831256) (xy 374.875044 -297.831256) (xy 374.874535 -297.859142)
			(xy 374.866415 -297.914318) (xy 374.850347 -297.967725) (xy 374.826675 -298.018222) (xy 374.795902 -298.064735)
			(xy 374.758685 -298.106272) (xy 374.715817 -298.141947) (xy 374.668211 -298.171001) (xy 374.616882 -298.192813)
			(xy 374.562925 -298.206919) (xy 374.507488 -298.213019) (xy 374.451754 -298.210982) (xy 374.396911 -298.200852)
			(xy 374.344127 -298.182845) (xy 374.294527 -298.157344) (xy 374.249169 -298.124893) (xy 374.20902 -298.086184)
			(xy 374.174934 -298.042041) (xy 374.147638 -297.993406) (xy 374.127715 -297.941315) (xy 374.115589 -297.886878)
			(xy 374.111518 -297.831256) (xy 351.03308 -297.831256) (xy 351.03308 -298.274486) (xy 384.369068 -298.274486)
			(xy 384.373028 -298.225432) (xy 384.384805 -298.177648) (xy 384.404096 -298.132372) (xy 384.430399 -298.090776)
			(xy 384.463034 -298.053939) (xy 384.501155 -298.022814) (xy 384.543776 -297.998207) (xy 384.589792 -297.980755)
			(xy 384.638011 -297.970911) (xy 384.687186 -297.96893) (xy 384.736041 -297.974862) (xy 384.783312 -297.988554)
			(xy 384.827774 -298.009652) (xy 384.868277 -298.037608) (xy 384.90377 -298.0717) (xy 384.933335 -298.111044)
			(xy 384.956206 -298.154621) (xy 384.97179 -298.201302) (xy 384.979685 -298.249879) (xy 384.98018 -298.274486)
			(xy 384.980175 -298.27474) (xy 385.318774 -298.27474) (xy 385.322734 -298.225686) (xy 385.334511 -298.177902)
			(xy 385.353802 -298.132626) (xy 385.380105 -298.09103) (xy 385.41274 -298.054193) (xy 385.450861 -298.023068)
			(xy 385.493482 -297.998461) (xy 385.539498 -297.981009) (xy 385.587717 -297.971165) (xy 385.636892 -297.969184)
			(xy 385.685747 -297.975116) (xy 385.733018 -297.988808) (xy 385.77748 -298.009906) (xy 385.817983 -298.037862)
			(xy 385.853476 -298.071954) (xy 385.883041 -298.111298) (xy 385.905912 -298.154875) (xy 385.921496 -298.201556)
			(xy 385.929391 -298.250133) (xy 385.929886 -298.27474) (xy 386.268988 -298.27474) (xy 386.272948 -298.225686)
			(xy 386.284725 -298.177902) (xy 386.304016 -298.132626) (xy 386.330319 -298.09103) (xy 386.362954 -298.054193)
			(xy 386.401075 -298.023068) (xy 386.443696 -297.998461) (xy 386.489712 -297.981009) (xy 386.537931 -297.971165)
			(xy 386.587106 -297.969184) (xy 386.635961 -297.975116) (xy 386.683232 -297.988808) (xy 386.727694 -298.009906)
			(xy 386.768197 -298.037862) (xy 386.80369 -298.071954) (xy 386.833255 -298.111298) (xy 386.856126 -298.154875)
			(xy 386.87171 -298.201556) (xy 386.879605 -298.250133) (xy 386.8801 -298.27474) (xy 386.879934 -298.282973)
			(xy 387.219275 -298.282973) (xy 387.221964 -298.233401) (xy 387.232638 -298.184918) (xy 387.251015 -298.138801)
			(xy 387.276612 -298.096264) (xy 387.308753 -298.058429) (xy 387.346591 -298.026292) (xy 387.389131 -298.0007)
			(xy 387.435251 -297.982328) (xy 387.483735 -297.97166) (xy 387.533307 -297.968976) (xy 387.58266 -297.974347)
			(xy 387.630493 -297.987633) (xy 387.675547 -298.008482) (xy 387.716634 -298.036346) (xy 387.752672 -298.07049)
			(xy 387.782711 -298.110015) (xy 387.80596 -298.153879) (xy 387.821806 -298.200927) (xy 387.829831 -298.249918)
			(xy 387.830314 -298.27474) (xy 387.830224 -298.283844) (xy 387.829078 -298.302018) (xy 387.828028 -298.311062)
			(xy 387.828028 -298.311316) (xy 387.827371 -298.322986) (xy 387.835283 -298.344948) (xy 387.843268 -298.35348)
			(xy 387.911086 -298.41825) (xy 387.933946 -298.425362) (xy 387.94563 -298.42333) (xy 387.959123 -298.42127)
			(xy 387.986336 -298.41911) (xy 387.999986 -298.419012) (xy 388.070344 -298.419012) (xy 388.081068 -298.41859)
			(xy 388.100673 -298.409908) (xy 388.10819 -298.402248) (xy 388.165848 -298.337732) (xy 388.172452 -298.317412)
			(xy 388.171436 -298.306998) (xy 388.171436 -298.30649) (xy 388.169658 -298.27474) (xy 388.17018 -298.249485)
			(xy 388.178493 -298.199663) (xy 388.194894 -298.151889) (xy 388.218935 -298.107466) (xy 388.249959 -298.067606)
			(xy 388.287121 -298.033396) (xy 388.329407 -298.00577) (xy 388.375663 -297.98548) (xy 388.424628 -297.97308)
			(xy 388.474966 -297.968909) (xy 388.525304 -297.97308) (xy 388.574269 -297.98548) (xy 388.620525 -298.00577)
			(xy 388.662811 -298.033396) (xy 388.699973 -298.067606) (xy 388.730997 -298.107466) (xy 388.755038 -298.151889)
			(xy 388.771439 -298.199663) (xy 388.779752 -298.249485) (xy 388.780274 -298.27474) (xy 388.778496 -298.306744)
			(xy 388.77748 -298.317412) (xy 388.784084 -298.337732) (xy 388.841742 -298.402248) (xy 388.849335 -298.409797)
			(xy 388.868895 -298.418451) (xy 388.879588 -298.419012) (xy 388.949946 -298.419012) (xy 388.963596 -298.419096)
			(xy 388.990809 -298.421261) (xy 389.004302 -298.42333) (xy 389.015986 -298.425362) (xy 389.038846 -298.41825)
			(xy 389.115046 -298.345352) (xy 389.123174 -298.323) (xy 389.121904 -298.311316) (xy 389.121904 -298.310808)
			(xy 389.120862 -298.301827) (xy 389.119721 -298.283781) (xy 389.119618 -298.27474) (xy 389.12014 -298.249485)
			(xy 389.128453 -298.199663) (xy 389.144854 -298.151889) (xy 389.168895 -298.107466) (xy 389.199919 -298.067606)
			(xy 389.237081 -298.033396) (xy 389.279367 -298.00577) (xy 389.325623 -297.98548) (xy 389.374588 -297.97308)
			(xy 389.424926 -297.968909) (xy 389.475264 -297.97308) (xy 389.524229 -297.98548) (xy 389.570485 -298.00577)
			(xy 389.612771 -298.033396) (xy 389.649933 -298.067606) (xy 389.680957 -298.107466) (xy 389.704998 -298.151889)
			(xy 389.721399 -298.199663) (xy 389.729712 -298.249485) (xy 389.730234 -298.27474) (xy 389.730062 -298.288923)
			(xy 389.727387 -298.317163) (xy 389.7249 -298.331128) (xy 389.722614 -298.343574) (xy 389.72998 -298.367196)
			(xy 389.80745 -298.444666) (xy 389.831072 -298.452032) (xy 389.843518 -298.449746) (xy 389.857484 -298.447271)
			(xy 389.885724 -298.444598) (xy 389.899906 -298.444412) (xy 389.914089 -298.444587) (xy 389.942329 -298.44726)
			(xy 389.956294 -298.449746) (xy 389.96874 -298.452032) (xy 389.992362 -298.444666) (xy 390.069832 -298.367196)
			(xy 390.077198 -298.343574) (xy 390.074912 -298.331128) (xy 390.07243 -298.317163) (xy 390.069762 -298.288923)
			(xy 390.069578 -298.27474) (xy 390.070035 -298.249915) (xy 390.078061 -298.200918) (xy 390.093909 -298.153865)
			(xy 390.117161 -298.109996) (xy 390.147203 -298.070467) (xy 390.183246 -298.036319) (xy 390.224338 -298.008452)
			(xy 390.269397 -297.9876) (xy 390.317236 -297.974314) (xy 390.366595 -297.968942) (xy 390.416172 -297.971626)
			(xy 390.464662 -297.982296) (xy 390.510787 -298.000671) (xy 390.553331 -298.026266) (xy 390.591174 -298.058407)
			(xy 390.623319 -298.096247) (xy 390.648917 -298.13879) (xy 390.667296 -298.184913) (xy 390.67797 -298.233402)
			(xy 390.680212 -298.27474) (xy 391.019042 -298.27474) (xy 391.023002 -298.225686) (xy 391.034779 -298.177902)
			(xy 391.05407 -298.132626) (xy 391.080373 -298.09103) (xy 391.113008 -298.054193) (xy 391.151129 -298.023068)
			(xy 391.19375 -297.998461) (xy 391.239766 -297.981009) (xy 391.287985 -297.971165) (xy 391.33716 -297.969184)
			(xy 391.386015 -297.975116) (xy 391.433286 -297.988808) (xy 391.477748 -298.009906) (xy 391.518251 -298.037862)
			(xy 391.553744 -298.071954) (xy 391.583309 -298.111298) (xy 391.60618 -298.154875) (xy 391.621764 -298.201556)
			(xy 391.629659 -298.250133) (xy 391.630154 -298.27474) (xy 391.969002 -298.27474) (xy 391.972962 -298.225686)
			(xy 391.984739 -298.177902) (xy 392.00403 -298.132626) (xy 392.030333 -298.09103) (xy 392.062968 -298.054193)
			(xy 392.101089 -298.023068) (xy 392.14371 -297.998461) (xy 392.189726 -297.981009) (xy 392.237945 -297.971165)
			(xy 392.28712 -297.969184) (xy 392.335975 -297.975116) (xy 392.383246 -297.988808) (xy 392.427708 -298.009906)
			(xy 392.468211 -298.037862) (xy 392.503704 -298.071954) (xy 392.533269 -298.111298) (xy 392.55614 -298.154875)
			(xy 392.571724 -298.201556) (xy 392.579619 -298.250133) (xy 392.580114 -298.27474) (xy 392.919216 -298.27474)
			(xy 392.923176 -298.225686) (xy 392.934953 -298.177902) (xy 392.954244 -298.132626) (xy 392.980547 -298.09103)
			(xy 393.013182 -298.054193) (xy 393.051303 -298.023068) (xy 393.093924 -297.998461) (xy 393.13994 -297.981009)
			(xy 393.188159 -297.971165) (xy 393.237334 -297.969184) (xy 393.286189 -297.975116) (xy 393.33346 -297.988808)
			(xy 393.377922 -298.009906) (xy 393.418425 -298.037862) (xy 393.453918 -298.071954) (xy 393.483483 -298.111298)
			(xy 393.506354 -298.154875) (xy 393.521938 -298.201556) (xy 393.529833 -298.250133) (xy 393.530328 -298.27474)
			(xy 393.869176 -298.27474) (xy 393.873136 -298.225686) (xy 393.884913 -298.177902) (xy 393.904204 -298.132626)
			(xy 393.930507 -298.09103) (xy 393.963142 -298.054193) (xy 394.001263 -298.023068) (xy 394.043884 -297.998461)
			(xy 394.0899 -297.981009) (xy 394.138119 -297.971165) (xy 394.187294 -297.969184) (xy 394.236149 -297.975116)
			(xy 394.28342 -297.988808) (xy 394.327882 -298.009906) (xy 394.368385 -298.037862) (xy 394.403878 -298.071954)
			(xy 394.433443 -298.111298) (xy 394.456314 -298.154875) (xy 394.471898 -298.201556) (xy 394.479793 -298.250133)
			(xy 394.480288 -298.27474) (xy 395.769096 -298.27474) (xy 395.773056 -298.225686) (xy 395.784833 -298.177902)
			(xy 395.804124 -298.132626) (xy 395.830427 -298.09103) (xy 395.863062 -298.054193) (xy 395.901183 -298.023068)
			(xy 395.943804 -297.998461) (xy 395.98982 -297.981009) (xy 396.038039 -297.971165) (xy 396.087214 -297.969184)
			(xy 396.136069 -297.975116) (xy 396.18334 -297.988808) (xy 396.227802 -298.009906) (xy 396.268305 -298.037862)
			(xy 396.303798 -298.071954) (xy 396.333363 -298.111298) (xy 396.356234 -298.154875) (xy 396.371818 -298.201556)
			(xy 396.379713 -298.250133) (xy 396.380208 -298.27474) (xy 396.719056 -298.27474) (xy 396.723016 -298.225686)
			(xy 396.734793 -298.177902) (xy 396.754084 -298.132626) (xy 396.780387 -298.09103) (xy 396.813022 -298.054193)
			(xy 396.851143 -298.023068) (xy 396.893764 -297.998461) (xy 396.93978 -297.981009) (xy 396.987999 -297.971165)
			(xy 397.037174 -297.969184) (xy 397.086029 -297.975116) (xy 397.1333 -297.988808) (xy 397.177762 -298.009906)
			(xy 397.218265 -298.037862) (xy 397.253758 -298.071954) (xy 397.283323 -298.111298) (xy 397.306194 -298.154875)
			(xy 397.321778 -298.201556) (xy 397.329673 -298.250133) (xy 397.330168 -298.27474) (xy 398.61923 -298.27474)
			(xy 398.62319 -298.225686) (xy 398.634967 -298.177902) (xy 398.654258 -298.132626) (xy 398.680561 -298.09103)
			(xy 398.713196 -298.054193) (xy 398.751317 -298.023068) (xy 398.793938 -297.998461) (xy 398.839954 -297.981009)
			(xy 398.888173 -297.971165) (xy 398.937348 -297.969184) (xy 398.986203 -297.975116) (xy 399.033474 -297.988808)
			(xy 399.077936 -298.009906) (xy 399.118439 -298.037862) (xy 399.153932 -298.071954) (xy 399.183497 -298.111298)
			(xy 399.206368 -298.154875) (xy 399.221952 -298.201556) (xy 399.229847 -298.250133) (xy 399.230342 -298.27474)
			(xy 400.51915 -298.27474) (xy 400.52311 -298.225686) (xy 400.534887 -298.177902) (xy 400.554178 -298.132626)
			(xy 400.580481 -298.09103) (xy 400.613116 -298.054193) (xy 400.651237 -298.023068) (xy 400.693858 -297.998461)
			(xy 400.739874 -297.981009) (xy 400.788093 -297.971165) (xy 400.837268 -297.969184) (xy 400.886123 -297.975116)
			(xy 400.933394 -297.988808) (xy 400.977856 -298.009906) (xy 401.018359 -298.037862) (xy 401.053852 -298.071954)
			(xy 401.083417 -298.111298) (xy 401.106288 -298.154875) (xy 401.121872 -298.201556) (xy 401.129767 -298.250133)
			(xy 401.130262 -298.27474) (xy 402.41907 -298.27474) (xy 402.42303 -298.225686) (xy 402.434807 -298.177902)
			(xy 402.454098 -298.132626) (xy 402.480401 -298.09103) (xy 402.513036 -298.054193) (xy 402.551157 -298.023068)
			(xy 402.593778 -297.998461) (xy 402.639794 -297.981009) (xy 402.688013 -297.971165) (xy 402.737188 -297.969184)
			(xy 402.786043 -297.975116) (xy 402.833314 -297.988808) (xy 402.877776 -298.009906) (xy 402.918279 -298.037862)
			(xy 402.953772 -298.071954) (xy 402.983337 -298.111298) (xy 403.006208 -298.154875) (xy 403.021792 -298.201556)
			(xy 403.029687 -298.250133) (xy 403.030182 -298.27474) (xy 404.31899 -298.27474) (xy 404.32295 -298.225686)
			(xy 404.334727 -298.177902) (xy 404.354018 -298.132626) (xy 404.380321 -298.09103) (xy 404.412956 -298.054193)
			(xy 404.451077 -298.023068) (xy 404.493698 -297.998461) (xy 404.539714 -297.981009) (xy 404.587933 -297.971165)
			(xy 404.637108 -297.969184) (xy 404.685963 -297.975116) (xy 404.733234 -297.988808) (xy 404.777696 -298.009906)
			(xy 404.818199 -298.037862) (xy 404.853692 -298.071954) (xy 404.883257 -298.111298) (xy 404.906128 -298.154875)
			(xy 404.921712 -298.201556) (xy 404.929607 -298.250133) (xy 404.930102 -298.27474) (xy 406.219164 -298.27474)
			(xy 406.223124 -298.225686) (xy 406.234901 -298.177902) (xy 406.254192 -298.132626) (xy 406.280495 -298.09103)
			(xy 406.31313 -298.054193) (xy 406.351251 -298.023068) (xy 406.393872 -297.998461) (xy 406.439888 -297.981009)
			(xy 406.488107 -297.971165) (xy 406.537282 -297.969184) (xy 406.586137 -297.975116) (xy 406.633408 -297.988808)
			(xy 406.67787 -298.009906) (xy 406.718373 -298.037862) (xy 406.753866 -298.071954) (xy 406.783431 -298.111298)
			(xy 406.806302 -298.154875) (xy 406.821886 -298.201556) (xy 406.829781 -298.250133) (xy 406.830276 -298.27474)
			(xy 409.069044 -298.27474) (xy 409.073004 -298.225686) (xy 409.084781 -298.177902) (xy 409.104072 -298.132626)
			(xy 409.130375 -298.09103) (xy 409.16301 -298.054193) (xy 409.201131 -298.023068) (xy 409.243752 -297.998461)
			(xy 409.289768 -297.981009) (xy 409.337987 -297.971165) (xy 409.387162 -297.969184) (xy 409.436017 -297.975116)
			(xy 409.483288 -297.988808) (xy 409.52775 -298.009906) (xy 409.568253 -298.037862) (xy 409.603746 -298.071954)
			(xy 409.633311 -298.111298) (xy 409.656182 -298.154875) (xy 409.671766 -298.201556) (xy 409.679661 -298.250133)
			(xy 409.680156 -298.27474) (xy 410.969218 -298.27474) (xy 410.973178 -298.225686) (xy 410.984955 -298.177902)
			(xy 411.004246 -298.132626) (xy 411.030549 -298.09103) (xy 411.063184 -298.054193) (xy 411.101305 -298.023068)
			(xy 411.143926 -297.998461) (xy 411.189942 -297.981009) (xy 411.238161 -297.971165) (xy 411.287336 -297.969184)
			(xy 411.336191 -297.975116) (xy 411.383462 -297.988808) (xy 411.427924 -298.009906) (xy 411.468427 -298.037862)
			(xy 411.50392 -298.071954) (xy 411.533485 -298.111298) (xy 411.556356 -298.154875) (xy 411.57194 -298.201556)
			(xy 411.579835 -298.250133) (xy 411.58033 -298.27474) (xy 412.869138 -298.27474) (xy 412.873098 -298.225686)
			(xy 412.884875 -298.177902) (xy 412.904166 -298.132626) (xy 412.930469 -298.09103) (xy 412.963104 -298.054193)
			(xy 413.001225 -298.023068) (xy 413.043846 -297.998461) (xy 413.089862 -297.981009) (xy 413.138081 -297.971165)
			(xy 413.187256 -297.969184) (xy 413.236111 -297.975116) (xy 413.283382 -297.988808) (xy 413.327844 -298.009906)
			(xy 413.368347 -298.037862) (xy 413.40384 -298.071954) (xy 413.433405 -298.111298) (xy 413.456276 -298.154875)
			(xy 413.47186 -298.201556) (xy 413.479755 -298.250133) (xy 413.48025 -298.27474) (xy 414.769058 -298.27474)
			(xy 414.773018 -298.225686) (xy 414.784795 -298.177902) (xy 414.804086 -298.132626) (xy 414.830389 -298.09103)
			(xy 414.863024 -298.054193) (xy 414.901145 -298.023068) (xy 414.943766 -297.998461) (xy 414.989782 -297.981009)
			(xy 415.038001 -297.971165) (xy 415.087176 -297.969184) (xy 415.136031 -297.975116) (xy 415.183302 -297.988808)
			(xy 415.227764 -298.009906) (xy 415.268267 -298.037862) (xy 415.30376 -298.071954) (xy 415.333325 -298.111298)
			(xy 415.356196 -298.154875) (xy 415.37178 -298.201556) (xy 415.379675 -298.250133) (xy 415.38017 -298.27474)
			(xy 415.379675 -298.299347) (xy 415.37178 -298.347924) (xy 415.356196 -298.394605) (xy 415.333325 -298.438182)
			(xy 415.30376 -298.477526) (xy 415.268267 -298.511618) (xy 415.227764 -298.539574) (xy 415.183302 -298.560672)
			(xy 415.136031 -298.574364) (xy 415.087176 -298.580296) (xy 415.038001 -298.578315) (xy 414.989782 -298.568471)
			(xy 414.943766 -298.551019) (xy 414.901145 -298.526412) (xy 414.863024 -298.495287) (xy 414.830389 -298.45845)
			(xy 414.804086 -298.416854) (xy 414.784795 -298.371578) (xy 414.773018 -298.323794) (xy 414.769058 -298.27474)
			(xy 413.48025 -298.27474) (xy 413.479755 -298.299347) (xy 413.47186 -298.347924) (xy 413.456276 -298.394605)
			(xy 413.433405 -298.438182) (xy 413.40384 -298.477526) (xy 413.368347 -298.511618) (xy 413.327844 -298.539574)
			(xy 413.283382 -298.560672) (xy 413.236111 -298.574364) (xy 413.187256 -298.580296) (xy 413.138081 -298.578315)
			(xy 413.089862 -298.568471) (xy 413.043846 -298.551019) (xy 413.001225 -298.526412) (xy 412.963104 -298.495287)
			(xy 412.930469 -298.45845) (xy 412.904166 -298.416854) (xy 412.884875 -298.371578) (xy 412.873098 -298.323794)
			(xy 412.869138 -298.27474) (xy 411.58033 -298.27474) (xy 411.579835 -298.299347) (xy 411.57194 -298.347924)
			(xy 411.556356 -298.394605) (xy 411.533485 -298.438182) (xy 411.50392 -298.477526) (xy 411.468427 -298.511618)
			(xy 411.427924 -298.539574) (xy 411.383462 -298.560672) (xy 411.336191 -298.574364) (xy 411.287336 -298.580296)
			(xy 411.238161 -298.578315) (xy 411.189942 -298.568471) (xy 411.143926 -298.551019) (xy 411.101305 -298.526412)
			(xy 411.063184 -298.495287) (xy 411.030549 -298.45845) (xy 411.004246 -298.416854) (xy 410.984955 -298.371578)
			(xy 410.973178 -298.323794) (xy 410.969218 -298.27474) (xy 409.680156 -298.27474) (xy 409.679661 -298.299347)
			(xy 409.671766 -298.347924) (xy 409.656182 -298.394605) (xy 409.633311 -298.438182) (xy 409.603746 -298.477526)
			(xy 409.568253 -298.511618) (xy 409.52775 -298.539574) (xy 409.483288 -298.560672) (xy 409.436017 -298.574364)
			(xy 409.387162 -298.580296) (xy 409.337987 -298.578315) (xy 409.289768 -298.568471) (xy 409.243752 -298.551019)
			(xy 409.201131 -298.526412) (xy 409.16301 -298.495287) (xy 409.130375 -298.45845) (xy 409.104072 -298.416854)
			(xy 409.084781 -298.371578) (xy 409.073004 -298.323794) (xy 409.069044 -298.27474) (xy 406.830276 -298.27474)
			(xy 406.829781 -298.299347) (xy 406.821886 -298.347924) (xy 406.806302 -298.394605) (xy 406.783431 -298.438182)
			(xy 406.753866 -298.477526) (xy 406.718373 -298.511618) (xy 406.67787 -298.539574) (xy 406.633408 -298.560672)
			(xy 406.586137 -298.574364) (xy 406.537282 -298.580296) (xy 406.488107 -298.578315) (xy 406.439888 -298.568471)
			(xy 406.393872 -298.551019) (xy 406.351251 -298.526412) (xy 406.31313 -298.495287) (xy 406.280495 -298.45845)
			(xy 406.254192 -298.416854) (xy 406.234901 -298.371578) (xy 406.223124 -298.323794) (xy 406.219164 -298.27474)
			(xy 404.930102 -298.27474) (xy 404.929607 -298.299347) (xy 404.921712 -298.347924) (xy 404.906128 -298.394605)
			(xy 404.883257 -298.438182) (xy 404.853692 -298.477526) (xy 404.818199 -298.511618) (xy 404.777696 -298.539574)
			(xy 404.733234 -298.560672) (xy 404.685963 -298.574364) (xy 404.637108 -298.580296) (xy 404.587933 -298.578315)
			(xy 404.539714 -298.568471) (xy 404.493698 -298.551019) (xy 404.451077 -298.526412) (xy 404.412956 -298.495287)
			(xy 404.380321 -298.45845) (xy 404.354018 -298.416854) (xy 404.334727 -298.371578) (xy 404.32295 -298.323794)
			(xy 404.31899 -298.27474) (xy 403.030182 -298.27474) (xy 403.029687 -298.299347) (xy 403.021792 -298.347924)
			(xy 403.006208 -298.394605) (xy 402.983337 -298.438182) (xy 402.953772 -298.477526) (xy 402.918279 -298.511618)
			(xy 402.877776 -298.539574) (xy 402.833314 -298.560672) (xy 402.786043 -298.574364) (xy 402.737188 -298.580296)
			(xy 402.688013 -298.578315) (xy 402.639794 -298.568471) (xy 402.593778 -298.551019) (xy 402.551157 -298.526412)
			(xy 402.513036 -298.495287) (xy 402.480401 -298.45845) (xy 402.454098 -298.416854) (xy 402.434807 -298.371578)
			(xy 402.42303 -298.323794) (xy 402.41907 -298.27474) (xy 401.130262 -298.27474) (xy 401.129767 -298.299347)
			(xy 401.121872 -298.347924) (xy 401.106288 -298.394605) (xy 401.083417 -298.438182) (xy 401.053852 -298.477526)
			(xy 401.018359 -298.511618) (xy 400.977856 -298.539574) (xy 400.933394 -298.560672) (xy 400.886123 -298.574364)
			(xy 400.837268 -298.580296) (xy 400.788093 -298.578315) (xy 400.739874 -298.568471) (xy 400.693858 -298.551019)
			(xy 400.651237 -298.526412) (xy 400.613116 -298.495287) (xy 400.580481 -298.45845) (xy 400.554178 -298.416854)
			(xy 400.534887 -298.371578) (xy 400.52311 -298.323794) (xy 400.51915 -298.27474) (xy 399.230342 -298.27474)
			(xy 399.229847 -298.299347) (xy 399.221952 -298.347924) (xy 399.206368 -298.394605) (xy 399.183497 -298.438182)
			(xy 399.153932 -298.477526) (xy 399.118439 -298.511618) (xy 399.077936 -298.539574) (xy 399.033474 -298.560672)
			(xy 398.986203 -298.574364) (xy 398.937348 -298.580296) (xy 398.888173 -298.578315) (xy 398.839954 -298.568471)
			(xy 398.793938 -298.551019) (xy 398.751317 -298.526412) (xy 398.713196 -298.495287) (xy 398.680561 -298.45845)
			(xy 398.654258 -298.416854) (xy 398.634967 -298.371578) (xy 398.62319 -298.323794) (xy 398.61923 -298.27474)
			(xy 397.330168 -298.27474) (xy 397.329673 -298.299347) (xy 397.321778 -298.347924) (xy 397.306194 -298.394605)
			(xy 397.283323 -298.438182) (xy 397.253758 -298.477526) (xy 397.218265 -298.511618) (xy 397.177762 -298.539574)
			(xy 397.1333 -298.560672) (xy 397.086029 -298.574364) (xy 397.037174 -298.580296) (xy 396.987999 -298.578315)
			(xy 396.93978 -298.568471) (xy 396.893764 -298.551019) (xy 396.851143 -298.526412) (xy 396.813022 -298.495287)
			(xy 396.780387 -298.45845) (xy 396.754084 -298.416854) (xy 396.734793 -298.371578) (xy 396.723016 -298.323794)
			(xy 396.719056 -298.27474) (xy 396.380208 -298.27474) (xy 396.379713 -298.299347) (xy 396.371818 -298.347924)
			(xy 396.356234 -298.394605) (xy 396.333363 -298.438182) (xy 396.303798 -298.477526) (xy 396.268305 -298.511618)
			(xy 396.227802 -298.539574) (xy 396.18334 -298.560672) (xy 396.136069 -298.574364) (xy 396.087214 -298.580296)
			(xy 396.038039 -298.578315) (xy 395.98982 -298.568471) (xy 395.943804 -298.551019) (xy 395.901183 -298.526412)
			(xy 395.863062 -298.495287) (xy 395.830427 -298.45845) (xy 395.804124 -298.416854) (xy 395.784833 -298.371578)
			(xy 395.773056 -298.323794) (xy 395.769096 -298.27474) (xy 394.480288 -298.27474) (xy 394.479793 -298.299347)
			(xy 394.471898 -298.347924) (xy 394.456314 -298.394605) (xy 394.433443 -298.438182) (xy 394.403878 -298.477526)
			(xy 394.368385 -298.511618) (xy 394.327882 -298.539574) (xy 394.28342 -298.560672) (xy 394.236149 -298.574364)
			(xy 394.187294 -298.580296) (xy 394.138119 -298.578315) (xy 394.0899 -298.568471) (xy 394.043884 -298.551019)
			(xy 394.001263 -298.526412) (xy 393.963142 -298.495287) (xy 393.930507 -298.45845) (xy 393.904204 -298.416854)
			(xy 393.884913 -298.371578) (xy 393.873136 -298.323794) (xy 393.869176 -298.27474) (xy 393.530328 -298.27474)
			(xy 393.529833 -298.299347) (xy 393.521938 -298.347924) (xy 393.506354 -298.394605) (xy 393.483483 -298.438182)
			(xy 393.453918 -298.477526) (xy 393.418425 -298.511618) (xy 393.377922 -298.539574) (xy 393.33346 -298.560672)
			(xy 393.286189 -298.574364) (xy 393.237334 -298.580296) (xy 393.188159 -298.578315) (xy 393.13994 -298.568471)
			(xy 393.093924 -298.551019) (xy 393.051303 -298.526412) (xy 393.013182 -298.495287) (xy 392.980547 -298.45845)
			(xy 392.954244 -298.416854) (xy 392.934953 -298.371578) (xy 392.923176 -298.323794) (xy 392.919216 -298.27474)
			(xy 392.580114 -298.27474) (xy 392.579619 -298.299347) (xy 392.571724 -298.347924) (xy 392.55614 -298.394605)
			(xy 392.533269 -298.438182) (xy 392.503704 -298.477526) (xy 392.468211 -298.511618) (xy 392.427708 -298.539574)
			(xy 392.383246 -298.560672) (xy 392.335975 -298.574364) (xy 392.28712 -298.580296) (xy 392.237945 -298.578315)
			(xy 392.189726 -298.568471) (xy 392.14371 -298.551019) (xy 392.101089 -298.526412) (xy 392.062968 -298.495287)
			(xy 392.030333 -298.45845) (xy 392.00403 -298.416854) (xy 391.984739 -298.371578) (xy 391.972962 -298.323794)
			(xy 391.969002 -298.27474) (xy 391.630154 -298.27474) (xy 391.629659 -298.299347) (xy 391.621764 -298.347924)
			(xy 391.60618 -298.394605) (xy 391.583309 -298.438182) (xy 391.553744 -298.477526) (xy 391.518251 -298.511618)
			(xy 391.477748 -298.539574) (xy 391.433286 -298.560672) (xy 391.386015 -298.574364) (xy 391.33716 -298.580296)
			(xy 391.287985 -298.578315) (xy 391.239766 -298.568471) (xy 391.19375 -298.551019) (xy 391.151129 -298.526412)
			(xy 391.113008 -298.495287) (xy 391.080373 -298.45845) (xy 391.05407 -298.416854) (xy 391.034779 -298.371578)
			(xy 391.023002 -298.323794) (xy 391.019042 -298.27474) (xy 390.680212 -298.27474) (xy 390.680659 -298.282979)
			(xy 390.675291 -298.332338) (xy 390.662009 -298.380179) (xy 390.641161 -298.42524) (xy 390.613298 -298.466334)
			(xy 390.579153 -298.502379) (xy 390.539626 -298.532425) (xy 390.495759 -298.555681) (xy 390.448707 -298.571533)
			(xy 390.399711 -298.579563) (xy 390.374886 -298.580048) (xy 390.360703 -298.579873) (xy 390.332463 -298.5772)
			(xy 390.318498 -298.574714) (xy 390.306052 -298.572428) (xy 390.28243 -298.579794) (xy 390.20496 -298.657264)
			(xy 390.197594 -298.680886) (xy 390.19988 -298.693332) (xy 390.202357 -298.707298) (xy 390.205028 -298.735537)
			(xy 390.205214 -298.74972) (xy 390.204756 -298.773711) (xy 390.197247 -298.821103) (xy 390.182417 -298.866737)
			(xy 390.160632 -298.909489) (xy 390.132427 -298.948308) (xy 390.098497 -298.982236) (xy 390.059677 -299.010439)
			(xy 390.016924 -299.032223) (xy 389.97129 -299.04705) (xy 389.923897 -299.054557) (xy 389.899906 -299.055028)
			(xy 389.885723 -299.05485) (xy 389.857483 -299.052179) (xy 389.843518 -299.049694) (xy 389.843264 -299.049694)
			(xy 389.831034 -299.04823) (xy 389.807547 -299.055521) (xy 389.798306 -299.063664) (xy 389.72998 -299.132244)
			(xy 389.722614 -299.155866) (xy 389.7249 -299.168312) (xy 389.727384 -299.182341) (xy 389.730056 -299.210708)
			(xy 389.730234 -299.224954) (xy 389.729719 -299.248945) (xy 389.72222 -299.296336) (xy 389.7074 -299.341971)
			(xy 389.685622 -299.384725) (xy 389.657425 -299.423546) (xy 389.623501 -299.457478) (xy 389.584687 -299.485685)
			(xy 389.541937 -299.507472) (xy 389.496306 -299.522304) (xy 389.448916 -299.529814) (xy 389.424926 -299.530262)
			(xy 389.410743 -299.530082) (xy 389.382503 -299.527412) (xy 389.368538 -299.524928) (xy 389.356092 -299.522642)
			(xy 389.33247 -299.530008) (xy 389.255 -299.607478) (xy 389.247634 -299.6311) (xy 389.24992 -299.643546)
			(xy 389.252399 -299.657511) (xy 389.255069 -299.685751) (xy 389.255254 -299.6999) (xy 390.544103 -299.6999)
			(xy 390.548273 -299.649571) (xy 390.56067 -299.600615) (xy 390.580954 -299.554366) (xy 390.608574 -299.512087)
			(xy 390.642776 -299.47493) (xy 390.682627 -299.443909) (xy 390.72704 -299.419869) (xy 390.774803 -299.403467)
			(xy 390.824615 -299.39515) (xy 390.849866 -299.394626) (xy 390.864049 -299.394807) (xy 390.892289 -299.397476)
			(xy 390.906254 -299.39996) (xy 390.906508 -299.39996) (xy 390.918739 -299.401419) (xy 390.942226 -299.394133)
			(xy 390.951466 -299.38599) (xy 391.019792 -299.31741) (xy 391.027158 -299.293788) (xy 391.024872 -299.281342)
			(xy 391.022382 -299.267314) (xy 391.019714 -299.238946) (xy 391.019538 -299.2247) (xy 391.019978 -299.19988)
			(xy 391.028008 -299.150894) (xy 391.043858 -299.103852) (xy 391.067109 -299.059994) (xy 391.097149 -299.020475)
			(xy 391.133187 -298.986337) (xy 391.174273 -298.958478) (xy 391.219324 -298.937633) (xy 391.267154 -298.924351)
			(xy 391.316503 -298.918982) (xy 391.366071 -298.921666) (xy 391.414551 -298.932335) (xy 391.460667 -298.950706)
			(xy 391.503203 -298.976295) (xy 391.541039 -299.008429) (xy 391.573178 -299.04626) (xy 391.598774 -299.088792)
			(xy 391.617152 -299.134905) (xy 391.627827 -299.183384) (xy 391.630086 -299.224954) (xy 391.969002 -299.224954)
			(xy 391.972962 -299.1759) (xy 391.984739 -299.128116) (xy 392.00403 -299.08284) (xy 392.030333 -299.041244)
			(xy 392.062968 -299.004407) (xy 392.101089 -298.973282) (xy 392.14371 -298.948675) (xy 392.189726 -298.931223)
			(xy 392.237945 -298.921379) (xy 392.28712 -298.919398) (xy 392.335975 -298.92533) (xy 392.383246 -298.939022)
			(xy 392.427708 -298.96012) (xy 392.468211 -298.988076) (xy 392.503704 -299.022168) (xy 392.533269 -299.061512)
			(xy 392.55614 -299.105089) (xy 392.571724 -299.15177) (xy 392.579619 -299.200347) (xy 392.580114 -299.224954)
			(xy 392.919216 -299.224954) (xy 392.923176 -299.1759) (xy 392.934953 -299.128116) (xy 392.954244 -299.08284)
			(xy 392.980547 -299.041244) (xy 393.013182 -299.004407) (xy 393.051303 -298.973282) (xy 393.093924 -298.948675)
			(xy 393.13994 -298.931223) (xy 393.188159 -298.921379) (xy 393.237334 -298.919398) (xy 393.286189 -298.92533)
			(xy 393.33346 -298.939022) (xy 393.377922 -298.96012) (xy 393.418425 -298.988076) (xy 393.453918 -299.022168)
			(xy 393.483483 -299.061512) (xy 393.506354 -299.105089) (xy 393.521938 -299.15177) (xy 393.529833 -299.200347)
			(xy 393.530328 -299.224954) (xy 393.869176 -299.224954) (xy 393.873136 -299.1759) (xy 393.884913 -299.128116)
			(xy 393.904204 -299.08284) (xy 393.930507 -299.041244) (xy 393.963142 -299.004407) (xy 394.001263 -298.973282)
			(xy 394.043884 -298.948675) (xy 394.0899 -298.931223) (xy 394.138119 -298.921379) (xy 394.187294 -298.919398)
			(xy 394.236149 -298.92533) (xy 394.28342 -298.939022) (xy 394.327882 -298.96012) (xy 394.368385 -298.988076)
			(xy 394.403878 -299.022168) (xy 394.433443 -299.061512) (xy 394.456314 -299.105089) (xy 394.471898 -299.15177)
			(xy 394.479793 -299.200347) (xy 394.480288 -299.224954) (xy 394.819136 -299.224954) (xy 394.823096 -299.1759)
			(xy 394.834873 -299.128116) (xy 394.854164 -299.08284) (xy 394.880467 -299.041244) (xy 394.913102 -299.004407)
			(xy 394.951223 -298.973282) (xy 394.993844 -298.948675) (xy 395.03986 -298.931223) (xy 395.088079 -298.921379)
			(xy 395.137254 -298.919398) (xy 395.186109 -298.92533) (xy 395.23338 -298.939022) (xy 395.277842 -298.96012)
			(xy 395.318345 -298.988076) (xy 395.353838 -299.022168) (xy 395.383403 -299.061512) (xy 395.406274 -299.105089)
			(xy 395.421858 -299.15177) (xy 395.429753 -299.200347) (xy 395.430248 -299.224954) (xy 395.769096 -299.224954)
			(xy 395.773056 -299.1759) (xy 395.784833 -299.128116) (xy 395.804124 -299.08284) (xy 395.830427 -299.041244)
			(xy 395.863062 -299.004407) (xy 395.901183 -298.973282) (xy 395.943804 -298.948675) (xy 395.98982 -298.931223)
			(xy 396.038039 -298.921379) (xy 396.087214 -298.919398) (xy 396.136069 -298.92533) (xy 396.18334 -298.939022)
			(xy 396.227802 -298.96012) (xy 396.268305 -298.988076) (xy 396.303798 -299.022168) (xy 396.333363 -299.061512)
			(xy 396.356234 -299.105089) (xy 396.371818 -299.15177) (xy 396.379713 -299.200347) (xy 396.380208 -299.224954)
			(xy 397.669016 -299.224954) (xy 397.672976 -299.1759) (xy 397.684753 -299.128116) (xy 397.704044 -299.08284)
			(xy 397.730347 -299.041244) (xy 397.762982 -299.004407) (xy 397.801103 -298.973282) (xy 397.843724 -298.948675)
			(xy 397.88974 -298.931223) (xy 397.937959 -298.921379) (xy 397.987134 -298.919398) (xy 398.035989 -298.92533)
			(xy 398.08326 -298.939022) (xy 398.127722 -298.96012) (xy 398.168225 -298.988076) (xy 398.203718 -299.022168)
			(xy 398.233283 -299.061512) (xy 398.256154 -299.105089) (xy 398.271738 -299.15177) (xy 398.279633 -299.200347)
			(xy 398.280128 -299.224954) (xy 398.61923 -299.224954) (xy 398.62319 -299.1759) (xy 398.634967 -299.128116)
			(xy 398.654258 -299.08284) (xy 398.680561 -299.041244) (xy 398.713196 -299.004407) (xy 398.751317 -298.973282)
			(xy 398.793938 -298.948675) (xy 398.839954 -298.931223) (xy 398.888173 -298.921379) (xy 398.937348 -298.919398)
			(xy 398.986203 -298.92533) (xy 399.033474 -298.939022) (xy 399.077936 -298.96012) (xy 399.118439 -298.988076)
			(xy 399.153932 -299.022168) (xy 399.183497 -299.061512) (xy 399.206368 -299.105089) (xy 399.221952 -299.15177)
			(xy 399.229847 -299.200347) (xy 399.230342 -299.224954) (xy 399.56919 -299.224954) (xy 399.57315 -299.1759)
			(xy 399.584927 -299.128116) (xy 399.604218 -299.08284) (xy 399.630521 -299.041244) (xy 399.663156 -299.004407)
			(xy 399.701277 -298.973282) (xy 399.743898 -298.948675) (xy 399.789914 -298.931223) (xy 399.838133 -298.921379)
			(xy 399.887308 -298.919398) (xy 399.936163 -298.92533) (xy 399.983434 -298.939022) (xy 400.027896 -298.96012)
			(xy 400.068399 -298.988076) (xy 400.103892 -299.022168) (xy 400.133457 -299.061512) (xy 400.156328 -299.105089)
			(xy 400.171912 -299.15177) (xy 400.179807 -299.200347) (xy 400.180302 -299.224954) (xy 400.51915 -299.224954)
			(xy 400.52311 -299.1759) (xy 400.534887 -299.128116) (xy 400.554178 -299.08284) (xy 400.580481 -299.041244)
			(xy 400.613116 -299.004407) (xy 400.651237 -298.973282) (xy 400.693858 -298.948675) (xy 400.739874 -298.931223)
			(xy 400.788093 -298.921379) (xy 400.837268 -298.919398) (xy 400.886123 -298.92533) (xy 400.933394 -298.939022)
			(xy 400.977856 -298.96012) (xy 401.018359 -298.988076) (xy 401.053852 -299.022168) (xy 401.083417 -299.061512)
			(xy 401.106288 -299.105089) (xy 401.121872 -299.15177) (xy 401.129767 -299.200347) (xy 401.130262 -299.224954)
			(xy 401.46911 -299.224954) (xy 401.47307 -299.1759) (xy 401.484847 -299.128116) (xy 401.504138 -299.08284)
			(xy 401.530441 -299.041244) (xy 401.563076 -299.004407) (xy 401.601197 -298.973282) (xy 401.643818 -298.948675)
			(xy 401.689834 -298.931223) (xy 401.738053 -298.921379) (xy 401.787228 -298.919398) (xy 401.836083 -298.92533)
			(xy 401.883354 -298.939022) (xy 401.927816 -298.96012) (xy 401.968319 -298.988076) (xy 402.003812 -299.022168)
			(xy 402.033377 -299.061512) (xy 402.056248 -299.105089) (xy 402.071832 -299.15177) (xy 402.079727 -299.200347)
			(xy 402.080222 -299.224954) (xy 402.41907 -299.224954) (xy 402.42303 -299.1759) (xy 402.434807 -299.128116)
			(xy 402.454098 -299.08284) (xy 402.480401 -299.041244) (xy 402.513036 -299.004407) (xy 402.551157 -298.973282)
			(xy 402.593778 -298.948675) (xy 402.639794 -298.931223) (xy 402.688013 -298.921379) (xy 402.737188 -298.919398)
			(xy 402.786043 -298.92533) (xy 402.833314 -298.939022) (xy 402.877776 -298.96012) (xy 402.918279 -298.988076)
			(xy 402.953772 -299.022168) (xy 402.983337 -299.061512) (xy 403.006208 -299.105089) (xy 403.021792 -299.15177)
			(xy 403.029687 -299.200347) (xy 403.030182 -299.224954) (xy 403.36903 -299.224954) (xy 403.37299 -299.1759)
			(xy 403.384767 -299.128116) (xy 403.404058 -299.08284) (xy 403.430361 -299.041244) (xy 403.462996 -299.004407)
			(xy 403.501117 -298.973282) (xy 403.543738 -298.948675) (xy 403.589754 -298.931223) (xy 403.637973 -298.921379)
			(xy 403.687148 -298.919398) (xy 403.736003 -298.92533) (xy 403.783274 -298.939022) (xy 403.827736 -298.96012)
			(xy 403.868239 -298.988076) (xy 403.903732 -299.022168) (xy 403.933297 -299.061512) (xy 403.956168 -299.105089)
			(xy 403.971752 -299.15177) (xy 403.979647 -299.200347) (xy 403.980142 -299.224954) (xy 404.31899 -299.224954)
			(xy 404.32295 -299.1759) (xy 404.334727 -299.128116) (xy 404.354018 -299.08284) (xy 404.380321 -299.041244)
			(xy 404.412956 -299.004407) (xy 404.451077 -298.973282) (xy 404.493698 -298.948675) (xy 404.539714 -298.931223)
			(xy 404.587933 -298.921379) (xy 404.637108 -298.919398) (xy 404.685963 -298.92533) (xy 404.733234 -298.939022)
			(xy 404.777696 -298.96012) (xy 404.818199 -298.988076) (xy 404.853692 -299.022168) (xy 404.883257 -299.061512)
			(xy 404.906128 -299.105089) (xy 404.921712 -299.15177) (xy 404.929607 -299.200347) (xy 404.930102 -299.224954)
			(xy 405.269204 -299.224954) (xy 405.273164 -299.1759) (xy 405.284941 -299.128116) (xy 405.304232 -299.08284)
			(xy 405.330535 -299.041244) (xy 405.36317 -299.004407) (xy 405.401291 -298.973282) (xy 405.443912 -298.948675)
			(xy 405.489928 -298.931223) (xy 405.538147 -298.921379) (xy 405.587322 -298.919398) (xy 405.636177 -298.92533)
			(xy 405.683448 -298.939022) (xy 405.72791 -298.96012) (xy 405.768413 -298.988076) (xy 405.803906 -299.022168)
			(xy 405.833471 -299.061512) (xy 405.856342 -299.105089) (xy 405.871926 -299.15177) (xy 405.879821 -299.200347)
			(xy 405.880316 -299.224954) (xy 406.219164 -299.224954) (xy 406.223124 -299.1759) (xy 406.234901 -299.128116)
			(xy 406.254192 -299.08284) (xy 406.280495 -299.041244) (xy 406.31313 -299.004407) (xy 406.351251 -298.973282)
			(xy 406.393872 -298.948675) (xy 406.439888 -298.931223) (xy 406.488107 -298.921379) (xy 406.537282 -298.919398)
			(xy 406.586137 -298.92533) (xy 406.633408 -298.939022) (xy 406.67787 -298.96012) (xy 406.718373 -298.988076)
			(xy 406.753866 -299.022168) (xy 406.783431 -299.061512) (xy 406.806302 -299.105089) (xy 406.821886 -299.15177)
			(xy 406.829781 -299.200347) (xy 406.830276 -299.224954) (xy 408.119084 -299.224954) (xy 408.123044 -299.1759)
			(xy 408.134821 -299.128116) (xy 408.154112 -299.08284) (xy 408.180415 -299.041244) (xy 408.21305 -299.004407)
			(xy 408.251171 -298.973282) (xy 408.293792 -298.948675) (xy 408.339808 -298.931223) (xy 408.388027 -298.921379)
			(xy 408.437202 -298.919398) (xy 408.486057 -298.92533) (xy 408.533328 -298.939022) (xy 408.57779 -298.96012)
			(xy 408.618293 -298.988076) (xy 408.653786 -299.022168) (xy 408.683351 -299.061512) (xy 408.706222 -299.105089)
			(xy 408.721806 -299.15177) (xy 408.729701 -299.200347) (xy 408.730196 -299.224954) (xy 409.069044 -299.224954)
			(xy 409.073004 -299.1759) (xy 409.084781 -299.128116) (xy 409.104072 -299.08284) (xy 409.130375 -299.041244)
			(xy 409.16301 -299.004407) (xy 409.201131 -298.973282) (xy 409.243752 -298.948675) (xy 409.289768 -298.931223)
			(xy 409.337987 -298.921379) (xy 409.387162 -298.919398) (xy 409.436017 -298.92533) (xy 409.483288 -298.939022)
			(xy 409.52775 -298.96012) (xy 409.568253 -298.988076) (xy 409.603746 -299.022168) (xy 409.633311 -299.061512)
			(xy 409.656182 -299.105089) (xy 409.671766 -299.15177) (xy 409.679661 -299.200347) (xy 409.680156 -299.224954)
			(xy 410.019004 -299.224954) (xy 410.022964 -299.1759) (xy 410.034741 -299.128116) (xy 410.054032 -299.08284)
			(xy 410.080335 -299.041244) (xy 410.11297 -299.004407) (xy 410.151091 -298.973282) (xy 410.193712 -298.948675)
			(xy 410.239728 -298.931223) (xy 410.287947 -298.921379) (xy 410.337122 -298.919398) (xy 410.385977 -298.92533)
			(xy 410.433248 -298.939022) (xy 410.47771 -298.96012) (xy 410.518213 -298.988076) (xy 410.553706 -299.022168)
			(xy 410.583271 -299.061512) (xy 410.606142 -299.105089) (xy 410.621726 -299.15177) (xy 410.629621 -299.200347)
			(xy 410.630116 -299.224954) (xy 410.969218 -299.224954) (xy 410.973178 -299.1759) (xy 410.984955 -299.128116)
			(xy 411.004246 -299.08284) (xy 411.030549 -299.041244) (xy 411.063184 -299.004407) (xy 411.101305 -298.973282)
			(xy 411.143926 -298.948675) (xy 411.189942 -298.931223) (xy 411.238161 -298.921379) (xy 411.287336 -298.919398)
			(xy 411.336191 -298.92533) (xy 411.383462 -298.939022) (xy 411.427924 -298.96012) (xy 411.468427 -298.988076)
			(xy 411.50392 -299.022168) (xy 411.533485 -299.061512) (xy 411.556356 -299.105089) (xy 411.57194 -299.15177)
			(xy 411.579835 -299.200347) (xy 411.58033 -299.224954) (xy 411.919178 -299.224954) (xy 411.923138 -299.1759)
			(xy 411.934915 -299.128116) (xy 411.954206 -299.08284) (xy 411.980509 -299.041244) (xy 412.013144 -299.004407)
			(xy 412.051265 -298.973282) (xy 412.093886 -298.948675) (xy 412.139902 -298.931223) (xy 412.188121 -298.921379)
			(xy 412.237296 -298.919398) (xy 412.286151 -298.92533) (xy 412.333422 -298.939022) (xy 412.377884 -298.96012)
			(xy 412.418387 -298.988076) (xy 412.45388 -299.022168) (xy 412.483445 -299.061512) (xy 412.506316 -299.105089)
			(xy 412.5219 -299.15177) (xy 412.529795 -299.200347) (xy 412.53029 -299.224954) (xy 412.869138 -299.224954)
			(xy 412.873098 -299.1759) (xy 412.884875 -299.128116) (xy 412.904166 -299.08284) (xy 412.930469 -299.041244)
			(xy 412.963104 -299.004407) (xy 413.001225 -298.973282) (xy 413.043846 -298.948675) (xy 413.089862 -298.931223)
			(xy 413.138081 -298.921379) (xy 413.187256 -298.919398) (xy 413.236111 -298.92533) (xy 413.283382 -298.939022)
			(xy 413.327844 -298.96012) (xy 413.368347 -298.988076) (xy 413.40384 -299.022168) (xy 413.433405 -299.061512)
			(xy 413.456276 -299.105089) (xy 413.47186 -299.15177) (xy 413.479755 -299.200347) (xy 413.48025 -299.224954)
			(xy 413.819098 -299.224954) (xy 413.823058 -299.1759) (xy 413.834835 -299.128116) (xy 413.854126 -299.08284)
			(xy 413.880429 -299.041244) (xy 413.913064 -299.004407) (xy 413.951185 -298.973282) (xy 413.993806 -298.948675)
			(xy 414.039822 -298.931223) (xy 414.088041 -298.921379) (xy 414.137216 -298.919398) (xy 414.186071 -298.92533)
			(xy 414.233342 -298.939022) (xy 414.277804 -298.96012) (xy 414.318307 -298.988076) (xy 414.3538 -299.022168)
			(xy 414.383365 -299.061512) (xy 414.406236 -299.105089) (xy 414.42182 -299.15177) (xy 414.429715 -299.200347)
			(xy 414.43021 -299.224954) (xy 414.769058 -299.224954) (xy 414.773018 -299.1759) (xy 414.784795 -299.128116)
			(xy 414.804086 -299.08284) (xy 414.830389 -299.041244) (xy 414.863024 -299.004407) (xy 414.901145 -298.973282)
			(xy 414.943766 -298.948675) (xy 414.989782 -298.931223) (xy 415.038001 -298.921379) (xy 415.087176 -298.919398)
			(xy 415.136031 -298.92533) (xy 415.183302 -298.939022) (xy 415.227764 -298.96012) (xy 415.268267 -298.988076)
			(xy 415.30376 -299.022168) (xy 415.333325 -299.061512) (xy 415.356196 -299.105089) (xy 415.37178 -299.15177)
			(xy 415.379675 -299.200347) (xy 415.38017 -299.224954) (xy 415.719018 -299.224954) (xy 415.722978 -299.1759)
			(xy 415.734755 -299.128116) (xy 415.754046 -299.08284) (xy 415.780349 -299.041244) (xy 415.812984 -299.004407)
			(xy 415.851105 -298.973282) (xy 415.893726 -298.948675) (xy 415.939742 -298.931223) (xy 415.987961 -298.921379)
			(xy 416.037136 -298.919398) (xy 416.085991 -298.92533) (xy 416.133262 -298.939022) (xy 416.177724 -298.96012)
			(xy 416.218227 -298.988076) (xy 416.25372 -299.022168) (xy 416.283285 -299.061512) (xy 416.306156 -299.105089)
			(xy 416.32174 -299.15177) (xy 416.329635 -299.200347) (xy 416.33013 -299.224954) (xy 416.329635 -299.249561)
			(xy 416.32174 -299.298138) (xy 416.306156 -299.344819) (xy 416.283285 -299.388396) (xy 416.25372 -299.42774)
			(xy 416.218227 -299.461832) (xy 416.177724 -299.489788) (xy 416.133262 -299.510886) (xy 416.085991 -299.524578)
			(xy 416.037136 -299.53051) (xy 415.987961 -299.528529) (xy 415.939742 -299.518685) (xy 415.893726 -299.501233)
			(xy 415.851105 -299.476626) (xy 415.812984 -299.445501) (xy 415.780349 -299.408664) (xy 415.754046 -299.367068)
			(xy 415.734755 -299.321792) (xy 415.722978 -299.274008) (xy 415.719018 -299.224954) (xy 415.38017 -299.224954)
			(xy 415.379675 -299.249561) (xy 415.37178 -299.298138) (xy 415.356196 -299.344819) (xy 415.333325 -299.388396)
			(xy 415.30376 -299.42774) (xy 415.268267 -299.461832) (xy 415.227764 -299.489788) (xy 415.183302 -299.510886)
			(xy 415.136031 -299.524578) (xy 415.087176 -299.53051) (xy 415.038001 -299.528529) (xy 414.989782 -299.518685)
			(xy 414.943766 -299.501233) (xy 414.901145 -299.476626) (xy 414.863024 -299.445501) (xy 414.830389 -299.408664)
			(xy 414.804086 -299.367068) (xy 414.784795 -299.321792) (xy 414.773018 -299.274008) (xy 414.769058 -299.224954)
			(xy 414.43021 -299.224954) (xy 414.429715 -299.249561) (xy 414.42182 -299.298138) (xy 414.406236 -299.344819)
			(xy 414.383365 -299.388396) (xy 414.3538 -299.42774) (xy 414.318307 -299.461832) (xy 414.277804 -299.489788)
			(xy 414.233342 -299.510886) (xy 414.186071 -299.524578) (xy 414.137216 -299.53051) (xy 414.088041 -299.528529)
			(xy 414.039822 -299.518685) (xy 413.993806 -299.501233) (xy 413.951185 -299.476626) (xy 413.913064 -299.445501)
			(xy 413.880429 -299.408664) (xy 413.854126 -299.367068) (xy 413.834835 -299.321792) (xy 413.823058 -299.274008)
			(xy 413.819098 -299.224954) (xy 413.48025 -299.224954) (xy 413.479755 -299.249561) (xy 413.47186 -299.298138)
			(xy 413.456276 -299.344819) (xy 413.433405 -299.388396) (xy 413.40384 -299.42774) (xy 413.368347 -299.461832)
			(xy 413.327844 -299.489788) (xy 413.283382 -299.510886) (xy 413.236111 -299.524578) (xy 413.187256 -299.53051)
			(xy 413.138081 -299.528529) (xy 413.089862 -299.518685) (xy 413.043846 -299.501233) (xy 413.001225 -299.476626)
			(xy 412.963104 -299.445501) (xy 412.930469 -299.408664) (xy 412.904166 -299.367068) (xy 412.884875 -299.321792)
			(xy 412.873098 -299.274008) (xy 412.869138 -299.224954) (xy 412.53029 -299.224954) (xy 412.529795 -299.249561)
			(xy 412.5219 -299.298138) (xy 412.506316 -299.344819) (xy 412.483445 -299.388396) (xy 412.45388 -299.42774)
			(xy 412.418387 -299.461832) (xy 412.377884 -299.489788) (xy 412.333422 -299.510886) (xy 412.286151 -299.524578)
			(xy 412.237296 -299.53051) (xy 412.188121 -299.528529) (xy 412.139902 -299.518685) (xy 412.093886 -299.501233)
			(xy 412.051265 -299.476626) (xy 412.013144 -299.445501) (xy 411.980509 -299.408664) (xy 411.954206 -299.367068)
			(xy 411.934915 -299.321792) (xy 411.923138 -299.274008) (xy 411.919178 -299.224954) (xy 411.58033 -299.224954)
			(xy 411.579835 -299.249561) (xy 411.57194 -299.298138) (xy 411.556356 -299.344819) (xy 411.533485 -299.388396)
			(xy 411.50392 -299.42774) (xy 411.468427 -299.461832) (xy 411.427924 -299.489788) (xy 411.383462 -299.510886)
			(xy 411.336191 -299.524578) (xy 411.287336 -299.53051) (xy 411.238161 -299.528529) (xy 411.189942 -299.518685)
			(xy 411.143926 -299.501233) (xy 411.101305 -299.476626) (xy 411.063184 -299.445501) (xy 411.030549 -299.408664)
			(xy 411.004246 -299.367068) (xy 410.984955 -299.321792) (xy 410.973178 -299.274008) (xy 410.969218 -299.224954)
			(xy 410.630116 -299.224954) (xy 410.629621 -299.249561) (xy 410.621726 -299.298138) (xy 410.606142 -299.344819)
			(xy 410.583271 -299.388396) (xy 410.553706 -299.42774) (xy 410.518213 -299.461832) (xy 410.47771 -299.489788)
			(xy 410.433248 -299.510886) (xy 410.385977 -299.524578) (xy 410.337122 -299.53051) (xy 410.287947 -299.528529)
			(xy 410.239728 -299.518685) (xy 410.193712 -299.501233) (xy 410.151091 -299.476626) (xy 410.11297 -299.445501)
			(xy 410.080335 -299.408664) (xy 410.054032 -299.367068) (xy 410.034741 -299.321792) (xy 410.022964 -299.274008)
			(xy 410.019004 -299.224954) (xy 409.680156 -299.224954) (xy 409.679661 -299.249561) (xy 409.671766 -299.298138)
			(xy 409.656182 -299.344819) (xy 409.633311 -299.388396) (xy 409.603746 -299.42774) (xy 409.568253 -299.461832)
			(xy 409.52775 -299.489788) (xy 409.483288 -299.510886) (xy 409.436017 -299.524578) (xy 409.387162 -299.53051)
			(xy 409.337987 -299.528529) (xy 409.289768 -299.518685) (xy 409.243752 -299.501233) (xy 409.201131 -299.476626)
			(xy 409.16301 -299.445501) (xy 409.130375 -299.408664) (xy 409.104072 -299.367068) (xy 409.084781 -299.321792)
			(xy 409.073004 -299.274008) (xy 409.069044 -299.224954) (xy 408.730196 -299.224954) (xy 408.729701 -299.249561)
			(xy 408.721806 -299.298138) (xy 408.706222 -299.344819) (xy 408.683351 -299.388396) (xy 408.653786 -299.42774)
			(xy 408.618293 -299.461832) (xy 408.57779 -299.489788) (xy 408.533328 -299.510886) (xy 408.486057 -299.524578)
			(xy 408.437202 -299.53051) (xy 408.388027 -299.528529) (xy 408.339808 -299.518685) (xy 408.293792 -299.501233)
			(xy 408.251171 -299.476626) (xy 408.21305 -299.445501) (xy 408.180415 -299.408664) (xy 408.154112 -299.367068)
			(xy 408.134821 -299.321792) (xy 408.123044 -299.274008) (xy 408.119084 -299.224954) (xy 406.830276 -299.224954)
			(xy 406.829781 -299.249561) (xy 406.821886 -299.298138) (xy 406.806302 -299.344819) (xy 406.783431 -299.388396)
			(xy 406.753866 -299.42774) (xy 406.718373 -299.461832) (xy 406.67787 -299.489788) (xy 406.633408 -299.510886)
			(xy 406.586137 -299.524578) (xy 406.537282 -299.53051) (xy 406.488107 -299.528529) (xy 406.439888 -299.518685)
			(xy 406.393872 -299.501233) (xy 406.351251 -299.476626) (xy 406.31313 -299.445501) (xy 406.280495 -299.408664)
			(xy 406.254192 -299.367068) (xy 406.234901 -299.321792) (xy 406.223124 -299.274008) (xy 406.219164 -299.224954)
			(xy 405.880316 -299.224954) (xy 405.879821 -299.249561) (xy 405.871926 -299.298138) (xy 405.856342 -299.344819)
			(xy 405.833471 -299.388396) (xy 405.803906 -299.42774) (xy 405.768413 -299.461832) (xy 405.72791 -299.489788)
			(xy 405.683448 -299.510886) (xy 405.636177 -299.524578) (xy 405.587322 -299.53051) (xy 405.538147 -299.528529)
			(xy 405.489928 -299.518685) (xy 405.443912 -299.501233) (xy 405.401291 -299.476626) (xy 405.36317 -299.445501)
			(xy 405.330535 -299.408664) (xy 405.304232 -299.367068) (xy 405.284941 -299.321792) (xy 405.273164 -299.274008)
			(xy 405.269204 -299.224954) (xy 404.930102 -299.224954) (xy 404.929607 -299.249561) (xy 404.921712 -299.298138)
			(xy 404.906128 -299.344819) (xy 404.883257 -299.388396) (xy 404.853692 -299.42774) (xy 404.818199 -299.461832)
			(xy 404.777696 -299.489788) (xy 404.733234 -299.510886) (xy 404.685963 -299.524578) (xy 404.637108 -299.53051)
			(xy 404.587933 -299.528529) (xy 404.539714 -299.518685) (xy 404.493698 -299.501233) (xy 404.451077 -299.476626)
			(xy 404.412956 -299.445501) (xy 404.380321 -299.408664) (xy 404.354018 -299.367068) (xy 404.334727 -299.321792)
			(xy 404.32295 -299.274008) (xy 404.31899 -299.224954) (xy 403.980142 -299.224954) (xy 403.979647 -299.249561)
			(xy 403.971752 -299.298138) (xy 403.956168 -299.344819) (xy 403.933297 -299.388396) (xy 403.903732 -299.42774)
			(xy 403.868239 -299.461832) (xy 403.827736 -299.489788) (xy 403.783274 -299.510886) (xy 403.736003 -299.524578)
			(xy 403.687148 -299.53051) (xy 403.637973 -299.528529) (xy 403.589754 -299.518685) (xy 403.543738 -299.501233)
			(xy 403.501117 -299.476626) (xy 403.462996 -299.445501) (xy 403.430361 -299.408664) (xy 403.404058 -299.367068)
			(xy 403.384767 -299.321792) (xy 403.37299 -299.274008) (xy 403.36903 -299.224954) (xy 403.030182 -299.224954)
			(xy 403.029687 -299.249561) (xy 403.021792 -299.298138) (xy 403.006208 -299.344819) (xy 402.983337 -299.388396)
			(xy 402.953772 -299.42774) (xy 402.918279 -299.461832) (xy 402.877776 -299.489788) (xy 402.833314 -299.510886)
			(xy 402.786043 -299.524578) (xy 402.737188 -299.53051) (xy 402.688013 -299.528529) (xy 402.639794 -299.518685)
			(xy 402.593778 -299.501233) (xy 402.551157 -299.476626) (xy 402.513036 -299.445501) (xy 402.480401 -299.408664)
			(xy 402.454098 -299.367068) (xy 402.434807 -299.321792) (xy 402.42303 -299.274008) (xy 402.41907 -299.224954)
			(xy 402.080222 -299.224954) (xy 402.079727 -299.249561) (xy 402.071832 -299.298138) (xy 402.056248 -299.344819)
			(xy 402.033377 -299.388396) (xy 402.003812 -299.42774) (xy 401.968319 -299.461832) (xy 401.927816 -299.489788)
			(xy 401.883354 -299.510886) (xy 401.836083 -299.524578) (xy 401.787228 -299.53051) (xy 401.738053 -299.528529)
			(xy 401.689834 -299.518685) (xy 401.643818 -299.501233) (xy 401.601197 -299.476626) (xy 401.563076 -299.445501)
			(xy 401.530441 -299.408664) (xy 401.504138 -299.367068) (xy 401.484847 -299.321792) (xy 401.47307 -299.274008)
			(xy 401.46911 -299.224954) (xy 401.130262 -299.224954) (xy 401.129767 -299.249561) (xy 401.121872 -299.298138)
			(xy 401.106288 -299.344819) (xy 401.083417 -299.388396) (xy 401.053852 -299.42774) (xy 401.018359 -299.461832)
			(xy 400.977856 -299.489788) (xy 400.933394 -299.510886) (xy 400.886123 -299.524578) (xy 400.837268 -299.53051)
			(xy 400.788093 -299.528529) (xy 400.739874 -299.518685) (xy 400.693858 -299.501233) (xy 400.651237 -299.476626)
			(xy 400.613116 -299.445501) (xy 400.580481 -299.408664) (xy 400.554178 -299.367068) (xy 400.534887 -299.321792)
			(xy 400.52311 -299.274008) (xy 400.51915 -299.224954) (xy 400.180302 -299.224954) (xy 400.179807 -299.249561)
			(xy 400.171912 -299.298138) (xy 400.156328 -299.344819) (xy 400.133457 -299.388396) (xy 400.103892 -299.42774)
			(xy 400.068399 -299.461832) (xy 400.027896 -299.489788) (xy 399.983434 -299.510886) (xy 399.936163 -299.524578)
			(xy 399.887308 -299.53051) (xy 399.838133 -299.528529) (xy 399.789914 -299.518685) (xy 399.743898 -299.501233)
			(xy 399.701277 -299.476626) (xy 399.663156 -299.445501) (xy 399.630521 -299.408664) (xy 399.604218 -299.367068)
			(xy 399.584927 -299.321792) (xy 399.57315 -299.274008) (xy 399.56919 -299.224954) (xy 399.230342 -299.224954)
			(xy 399.229847 -299.249561) (xy 399.221952 -299.298138) (xy 399.206368 -299.344819) (xy 399.183497 -299.388396)
			(xy 399.153932 -299.42774) (xy 399.118439 -299.461832) (xy 399.077936 -299.489788) (xy 399.033474 -299.510886)
			(xy 398.986203 -299.524578) (xy 398.937348 -299.53051) (xy 398.888173 -299.528529) (xy 398.839954 -299.518685)
			(xy 398.793938 -299.501233) (xy 398.751317 -299.476626) (xy 398.713196 -299.445501) (xy 398.680561 -299.408664)
			(xy 398.654258 -299.367068) (xy 398.634967 -299.321792) (xy 398.62319 -299.274008) (xy 398.61923 -299.224954)
			(xy 398.280128 -299.224954) (xy 398.279633 -299.249561) (xy 398.271738 -299.298138) (xy 398.256154 -299.344819)
			(xy 398.233283 -299.388396) (xy 398.203718 -299.42774) (xy 398.168225 -299.461832) (xy 398.127722 -299.489788)
			(xy 398.08326 -299.510886) (xy 398.035989 -299.524578) (xy 397.987134 -299.53051) (xy 397.937959 -299.528529)
			(xy 397.88974 -299.518685) (xy 397.843724 -299.501233) (xy 397.801103 -299.476626) (xy 397.762982 -299.445501)
			(xy 397.730347 -299.408664) (xy 397.704044 -299.367068) (xy 397.684753 -299.321792) (xy 397.672976 -299.274008)
			(xy 397.669016 -299.224954) (xy 396.380208 -299.224954) (xy 396.379713 -299.249561) (xy 396.371818 -299.298138)
			(xy 396.356234 -299.344819) (xy 396.333363 -299.388396) (xy 396.303798 -299.42774) (xy 396.268305 -299.461832)
			(xy 396.227802 -299.489788) (xy 396.18334 -299.510886) (xy 396.136069 -299.524578) (xy 396.087214 -299.53051)
			(xy 396.038039 -299.528529) (xy 395.98982 -299.518685) (xy 395.943804 -299.501233) (xy 395.901183 -299.476626)
			(xy 395.863062 -299.445501) (xy 395.830427 -299.408664) (xy 395.804124 -299.367068) (xy 395.784833 -299.321792)
			(xy 395.773056 -299.274008) (xy 395.769096 -299.224954) (xy 395.430248 -299.224954) (xy 395.429753 -299.249561)
			(xy 395.421858 -299.298138) (xy 395.406274 -299.344819) (xy 395.383403 -299.388396) (xy 395.353838 -299.42774)
			(xy 395.318345 -299.461832) (xy 395.277842 -299.489788) (xy 395.23338 -299.510886) (xy 395.186109 -299.524578)
			(xy 395.137254 -299.53051) (xy 395.088079 -299.528529) (xy 395.03986 -299.518685) (xy 394.993844 -299.501233)
			(xy 394.951223 -299.476626) (xy 394.913102 -299.445501) (xy 394.880467 -299.408664) (xy 394.854164 -299.367068)
			(xy 394.834873 -299.321792) (xy 394.823096 -299.274008) (xy 394.819136 -299.224954) (xy 394.480288 -299.224954)
			(xy 394.479793 -299.249561) (xy 394.471898 -299.298138) (xy 394.456314 -299.344819) (xy 394.433443 -299.388396)
			(xy 394.403878 -299.42774) (xy 394.368385 -299.461832) (xy 394.327882 -299.489788) (xy 394.28342 -299.510886)
			(xy 394.236149 -299.524578) (xy 394.187294 -299.53051) (xy 394.138119 -299.528529) (xy 394.0899 -299.518685)
			(xy 394.043884 -299.501233) (xy 394.001263 -299.476626) (xy 393.963142 -299.445501) (xy 393.930507 -299.408664)
			(xy 393.904204 -299.367068) (xy 393.884913 -299.321792) (xy 393.873136 -299.274008) (xy 393.869176 -299.224954)
			(xy 393.530328 -299.224954) (xy 393.529833 -299.249561) (xy 393.521938 -299.298138) (xy 393.506354 -299.344819)
			(xy 393.483483 -299.388396) (xy 393.453918 -299.42774) (xy 393.418425 -299.461832) (xy 393.377922 -299.489788)
			(xy 393.33346 -299.510886) (xy 393.286189 -299.524578) (xy 393.237334 -299.53051) (xy 393.188159 -299.528529)
			(xy 393.13994 -299.518685) (xy 393.093924 -299.501233) (xy 393.051303 -299.476626) (xy 393.013182 -299.445501)
			(xy 392.980547 -299.408664) (xy 392.954244 -299.367068) (xy 392.934953 -299.321792) (xy 392.923176 -299.274008)
			(xy 392.919216 -299.224954) (xy 392.580114 -299.224954) (xy 392.579619 -299.249561) (xy 392.571724 -299.298138)
			(xy 392.55614 -299.344819) (xy 392.533269 -299.388396) (xy 392.503704 -299.42774) (xy 392.468211 -299.461832)
			(xy 392.427708 -299.489788) (xy 392.383246 -299.510886) (xy 392.335975 -299.524578) (xy 392.28712 -299.53051)
			(xy 392.237945 -299.528529) (xy 392.189726 -299.518685) (xy 392.14371 -299.501233) (xy 392.101089 -299.476626)
			(xy 392.062968 -299.445501) (xy 392.030333 -299.408664) (xy 392.00403 -299.367068) (xy 391.984739 -299.321792)
			(xy 391.972962 -299.274008) (xy 391.969002 -299.224954) (xy 391.630086 -299.224954) (xy 391.63052 -299.232951)
			(xy 391.625158 -299.2823) (xy 391.611883 -299.330133) (xy 391.591045 -299.375187) (xy 391.563192 -299.416277)
			(xy 391.529059 -299.45232) (xy 391.489545 -299.482366) (xy 391.44569 -299.505624) (xy 391.398651 -299.52148)
			(xy 391.349666 -299.529518) (xy 391.324846 -299.530008) (xy 391.310663 -299.529825) (xy 391.282423 -299.527157)
			(xy 391.268458 -299.524674) (xy 391.268204 -299.524674) (xy 391.255972 -299.523241) (xy 391.23249 -299.530512)
			(xy 391.223246 -299.538644) (xy 391.15492 -299.607224) (xy 391.147554 -299.630846) (xy 391.14984 -299.643292)
			(xy 391.152321 -299.657321) (xy 391.154995 -299.685688) (xy 391.155174 -299.699934) (xy 391.155003 -299.714117)
			(xy 391.152327 -299.742357) (xy 391.14984 -299.756322) (xy 391.147554 -299.768768) (xy 391.15492 -299.79239)
			(xy 391.23239 -299.86986) (xy 391.256012 -299.877226) (xy 391.268458 -299.87494) (xy 391.282423 -299.87246)
			(xy 391.310663 -299.86979) (xy 391.324846 -299.869606) (xy 391.348839 -299.87002) (xy 391.396234 -299.877534)
			(xy 391.44187 -299.892368) (xy 391.484623 -299.914159) (xy 391.523442 -299.942369) (xy 391.55737 -299.976304)
			(xy 391.585573 -300.015128) (xy 391.607355 -300.057886) (xy 391.62218 -300.103525) (xy 391.629684 -300.150921)
			(xy 391.630154 -300.174914) (xy 391.629979 -300.189097) (xy 391.627306 -300.217337) (xy 391.62482 -300.231302)
			(xy 391.622534 -300.243748) (xy 391.6299 -300.26737) (xy 391.70737 -300.34484) (xy 391.730992 -300.352206)
			(xy 391.743438 -300.34992) (xy 391.757404 -300.347442) (xy 391.785643 -300.344771) (xy 391.799826 -300.344586)
			(xy 391.814009 -300.344759) (xy 391.842249 -300.347434) (xy 391.856214 -300.34992) (xy 391.86866 -300.352206)
			(xy 391.892282 -300.34484) (xy 391.969752 -300.26737) (xy 391.977118 -300.243748) (xy 391.974832 -300.231302)
			(xy 391.97236 -300.217335) (xy 391.969685 -300.189096) (xy 391.969498 -300.174914) (xy 391.969963 -300.150092)
			(xy 391.977992 -300.101101) (xy 391.993842 -300.054055) (xy 392.017093 -300.010193) (xy 392.047135 -299.97067)
			(xy 392.083175 -299.936528) (xy 392.124264 -299.908667) (xy 392.169319 -299.88782) (xy 392.217153 -299.874537)
			(xy 392.266507 -299.869167) (xy 392.316078 -299.871853) (xy 392.364562 -299.882524) (xy 392.410681 -299.900897)
			(xy 392.45322 -299.92649) (xy 392.491058 -299.958628) (xy 392.523198 -299.996464) (xy 392.548794 -300.039001)
			(xy 392.56717 -300.085119) (xy 392.577844 -300.133602) (xy 392.580085 -300.174914) (xy 392.919216 -300.174914)
			(xy 392.923176 -300.12586) (xy 392.934953 -300.078076) (xy 392.954244 -300.0328) (xy 392.980547 -299.991204)
			(xy 393.013182 -299.954367) (xy 393.051303 -299.923242) (xy 393.093924 -299.898635) (xy 393.13994 -299.881183)
			(xy 393.188159 -299.871339) (xy 393.237334 -299.869358) (xy 393.286189 -299.87529) (xy 393.33346 -299.888982)
			(xy 393.377922 -299.91008) (xy 393.418425 -299.938036) (xy 393.453918 -299.972128) (xy 393.483483 -300.011472)
			(xy 393.506354 -300.055049) (xy 393.521938 -300.10173) (xy 393.529833 -300.150307) (xy 393.530328 -300.174914)
			(xy 393.869176 -300.174914) (xy 393.873136 -300.12586) (xy 393.884913 -300.078076) (xy 393.904204 -300.0328)
			(xy 393.930507 -299.991204) (xy 393.963142 -299.954367) (xy 394.001263 -299.923242) (xy 394.043884 -299.898635)
			(xy 394.0899 -299.881183) (xy 394.138119 -299.871339) (xy 394.187294 -299.869358) (xy 394.236149 -299.87529)
			(xy 394.28342 -299.888982) (xy 394.327882 -299.91008) (xy 394.368385 -299.938036) (xy 394.403878 -299.972128)
			(xy 394.433443 -300.011472) (xy 394.456314 -300.055049) (xy 394.471898 -300.10173) (xy 394.479793 -300.150307)
			(xy 394.480288 -300.174914) (xy 395.769096 -300.174914) (xy 395.773056 -300.12586) (xy 395.784833 -300.078076)
			(xy 395.804124 -300.0328) (xy 395.830427 -299.991204) (xy 395.863062 -299.954367) (xy 395.901183 -299.923242)
			(xy 395.943804 -299.898635) (xy 395.98982 -299.881183) (xy 396.038039 -299.871339) (xy 396.087214 -299.869358)
			(xy 396.136069 -299.87529) (xy 396.18334 -299.888982) (xy 396.227802 -299.91008) (xy 396.268305 -299.938036)
			(xy 396.303798 -299.972128) (xy 396.333363 -300.011472) (xy 396.356234 -300.055049) (xy 396.371818 -300.10173)
			(xy 396.379713 -300.150307) (xy 396.380208 -300.174914) (xy 396.719056 -300.174914) (xy 396.723016 -300.12586)
			(xy 396.734793 -300.078076) (xy 396.754084 -300.0328) (xy 396.780387 -299.991204) (xy 396.813022 -299.954367)
			(xy 396.851143 -299.923242) (xy 396.893764 -299.898635) (xy 396.93978 -299.881183) (xy 396.987999 -299.871339)
			(xy 397.037174 -299.869358) (xy 397.086029 -299.87529) (xy 397.1333 -299.888982) (xy 397.177762 -299.91008)
			(xy 397.218265 -299.938036) (xy 397.253758 -299.972128) (xy 397.283323 -300.011472) (xy 397.306194 -300.055049)
			(xy 397.321778 -300.10173) (xy 397.329673 -300.150307) (xy 397.330168 -300.174914) (xy 398.61923 -300.174914)
			(xy 398.62319 -300.12586) (xy 398.634967 -300.078076) (xy 398.654258 -300.0328) (xy 398.680561 -299.991204)
			(xy 398.713196 -299.954367) (xy 398.751317 -299.923242) (xy 398.793938 -299.898635) (xy 398.839954 -299.881183)
			(xy 398.888173 -299.871339) (xy 398.937348 -299.869358) (xy 398.986203 -299.87529) (xy 399.033474 -299.888982)
			(xy 399.077936 -299.91008) (xy 399.118439 -299.938036) (xy 399.153932 -299.972128) (xy 399.183497 -300.011472)
			(xy 399.206368 -300.055049) (xy 399.221952 -300.10173) (xy 399.229847 -300.150307) (xy 399.230342 -300.174914)
			(xy 399.56919 -300.174914) (xy 399.57315 -300.12586) (xy 399.584927 -300.078076) (xy 399.604218 -300.0328)
			(xy 399.630521 -299.991204) (xy 399.663156 -299.954367) (xy 399.701277 -299.923242) (xy 399.743898 -299.898635)
			(xy 399.789914 -299.881183) (xy 399.838133 -299.871339) (xy 399.887308 -299.869358) (xy 399.936163 -299.87529)
			(xy 399.983434 -299.888982) (xy 400.027896 -299.91008) (xy 400.068399 -299.938036) (xy 400.103892 -299.972128)
			(xy 400.133457 -300.011472) (xy 400.156328 -300.055049) (xy 400.171912 -300.10173) (xy 400.179807 -300.150307)
			(xy 400.180302 -300.174914) (xy 400.51915 -300.174914) (xy 400.52311 -300.12586) (xy 400.534887 -300.078076)
			(xy 400.554178 -300.0328) (xy 400.580481 -299.991204) (xy 400.613116 -299.954367) (xy 400.651237 -299.923242)
			(xy 400.693858 -299.898635) (xy 400.739874 -299.881183) (xy 400.788093 -299.871339) (xy 400.837268 -299.869358)
			(xy 400.886123 -299.87529) (xy 400.933394 -299.888982) (xy 400.977856 -299.91008) (xy 401.018359 -299.938036)
			(xy 401.053852 -299.972128) (xy 401.083417 -300.011472) (xy 401.106288 -300.055049) (xy 401.121872 -300.10173)
			(xy 401.129767 -300.150307) (xy 401.130262 -300.174914) (xy 401.46911 -300.174914) (xy 401.47307 -300.12586)
			(xy 401.484847 -300.078076) (xy 401.504138 -300.0328) (xy 401.530441 -299.991204) (xy 401.563076 -299.954367)
			(xy 401.601197 -299.923242) (xy 401.643818 -299.898635) (xy 401.689834 -299.881183) (xy 401.738053 -299.871339)
			(xy 401.787228 -299.869358) (xy 401.836083 -299.87529) (xy 401.883354 -299.888982) (xy 401.927816 -299.91008)
			(xy 401.968319 -299.938036) (xy 402.003812 -299.972128) (xy 402.033377 -300.011472) (xy 402.056248 -300.055049)
			(xy 402.071832 -300.10173) (xy 402.079727 -300.150307) (xy 402.080222 -300.174914) (xy 402.41907 -300.174914)
			(xy 402.42303 -300.12586) (xy 402.434807 -300.078076) (xy 402.454098 -300.0328) (xy 402.480401 -299.991204)
			(xy 402.513036 -299.954367) (xy 402.551157 -299.923242) (xy 402.593778 -299.898635) (xy 402.639794 -299.881183)
			(xy 402.688013 -299.871339) (xy 402.737188 -299.869358) (xy 402.786043 -299.87529) (xy 402.833314 -299.888982)
			(xy 402.877776 -299.91008) (xy 402.918279 -299.938036) (xy 402.953772 -299.972128) (xy 402.983337 -300.011472)
			(xy 403.006208 -300.055049) (xy 403.021792 -300.10173) (xy 403.029687 -300.150307) (xy 403.030182 -300.174914)
			(xy 403.36903 -300.174914) (xy 403.37299 -300.12586) (xy 403.384767 -300.078076) (xy 403.404058 -300.0328)
			(xy 403.430361 -299.991204) (xy 403.462996 -299.954367) (xy 403.501117 -299.923242) (xy 403.543738 -299.898635)
			(xy 403.589754 -299.881183) (xy 403.637973 -299.871339) (xy 403.687148 -299.869358) (xy 403.736003 -299.87529)
			(xy 403.783274 -299.888982) (xy 403.827736 -299.91008) (xy 403.868239 -299.938036) (xy 403.903732 -299.972128)
			(xy 403.933297 -300.011472) (xy 403.956168 -300.055049) (xy 403.971752 -300.10173) (xy 403.979647 -300.150307)
			(xy 403.980142 -300.174914) (xy 404.31899 -300.174914) (xy 404.32295 -300.12586) (xy 404.334727 -300.078076)
			(xy 404.354018 -300.0328) (xy 404.380321 -299.991204) (xy 404.412956 -299.954367) (xy 404.451077 -299.923242)
			(xy 404.493698 -299.898635) (xy 404.539714 -299.881183) (xy 404.587933 -299.871339) (xy 404.637108 -299.869358)
			(xy 404.685963 -299.87529) (xy 404.733234 -299.888982) (xy 404.777696 -299.91008) (xy 404.818199 -299.938036)
			(xy 404.853692 -299.972128) (xy 404.883257 -300.011472) (xy 404.906128 -300.055049) (xy 404.921712 -300.10173)
			(xy 404.929607 -300.150307) (xy 404.930102 -300.174914) (xy 405.269204 -300.174914) (xy 405.273164 -300.12586)
			(xy 405.284941 -300.078076) (xy 405.304232 -300.0328) (xy 405.330535 -299.991204) (xy 405.36317 -299.954367)
			(xy 405.401291 -299.923242) (xy 405.443912 -299.898635) (xy 405.489928 -299.881183) (xy 405.538147 -299.871339)
			(xy 405.587322 -299.869358) (xy 405.636177 -299.87529) (xy 405.683448 -299.888982) (xy 405.72791 -299.91008)
			(xy 405.768413 -299.938036) (xy 405.803906 -299.972128) (xy 405.833471 -300.011472) (xy 405.856342 -300.055049)
			(xy 405.871926 -300.10173) (xy 405.879821 -300.150307) (xy 405.880316 -300.174914) (xy 406.219164 -300.174914)
			(xy 406.223124 -300.12586) (xy 406.234901 -300.078076) (xy 406.254192 -300.0328) (xy 406.280495 -299.991204)
			(xy 406.31313 -299.954367) (xy 406.351251 -299.923242) (xy 406.393872 -299.898635) (xy 406.439888 -299.881183)
			(xy 406.488107 -299.871339) (xy 406.537282 -299.869358) (xy 406.586137 -299.87529) (xy 406.633408 -299.888982)
			(xy 406.67787 -299.91008) (xy 406.718373 -299.938036) (xy 406.753866 -299.972128) (xy 406.783431 -300.011472)
			(xy 406.806302 -300.055049) (xy 406.821886 -300.10173) (xy 406.829781 -300.150307) (xy 406.830276 -300.174914)
			(xy 408.119084 -300.174914) (xy 408.123044 -300.12586) (xy 408.134821 -300.078076) (xy 408.154112 -300.0328)
			(xy 408.180415 -299.991204) (xy 408.21305 -299.954367) (xy 408.251171 -299.923242) (xy 408.293792 -299.898635)
			(xy 408.339808 -299.881183) (xy 408.388027 -299.871339) (xy 408.437202 -299.869358) (xy 408.486057 -299.87529)
			(xy 408.533328 -299.888982) (xy 408.57779 -299.91008) (xy 408.618293 -299.938036) (xy 408.653786 -299.972128)
			(xy 408.683351 -300.011472) (xy 408.706222 -300.055049) (xy 408.721806 -300.10173) (xy 408.729701 -300.150307)
			(xy 408.730196 -300.174914) (xy 409.069044 -300.174914) (xy 409.073004 -300.12586) (xy 409.084781 -300.078076)
			(xy 409.104072 -300.0328) (xy 409.130375 -299.991204) (xy 409.16301 -299.954367) (xy 409.201131 -299.923242)
			(xy 409.243752 -299.898635) (xy 409.289768 -299.881183) (xy 409.337987 -299.871339) (xy 409.387162 -299.869358)
			(xy 409.436017 -299.87529) (xy 409.483288 -299.888982) (xy 409.52775 -299.91008) (xy 409.568253 -299.938036)
			(xy 409.603746 -299.972128) (xy 409.633311 -300.011472) (xy 409.656182 -300.055049) (xy 409.671766 -300.10173)
			(xy 409.679661 -300.150307) (xy 409.680156 -300.174914) (xy 410.019004 -300.174914) (xy 410.022964 -300.12586)
			(xy 410.034741 -300.078076) (xy 410.054032 -300.0328) (xy 410.080335 -299.991204) (xy 410.11297 -299.954367)
			(xy 410.151091 -299.923242) (xy 410.193712 -299.898635) (xy 410.239728 -299.881183) (xy 410.287947 -299.871339)
			(xy 410.337122 -299.869358) (xy 410.385977 -299.87529) (xy 410.433248 -299.888982) (xy 410.47771 -299.91008)
			(xy 410.518213 -299.938036) (xy 410.553706 -299.972128) (xy 410.583271 -300.011472) (xy 410.606142 -300.055049)
			(xy 410.621726 -300.10173) (xy 410.629621 -300.150307) (xy 410.630116 -300.174914) (xy 410.969218 -300.174914)
			(xy 410.973178 -300.12586) (xy 410.984955 -300.078076) (xy 411.004246 -300.0328) (xy 411.030549 -299.991204)
			(xy 411.063184 -299.954367) (xy 411.101305 -299.923242) (xy 411.143926 -299.898635) (xy 411.189942 -299.881183)
			(xy 411.238161 -299.871339) (xy 411.287336 -299.869358) (xy 411.336191 -299.87529) (xy 411.383462 -299.888982)
			(xy 411.427924 -299.91008) (xy 411.468427 -299.938036) (xy 411.50392 -299.972128) (xy 411.533485 -300.011472)
			(xy 411.556356 -300.055049) (xy 411.57194 -300.10173) (xy 411.579835 -300.150307) (xy 411.58033 -300.174914)
			(xy 411.919178 -300.174914) (xy 411.923138 -300.12586) (xy 411.934915 -300.078076) (xy 411.954206 -300.0328)
			(xy 411.980509 -299.991204) (xy 412.013144 -299.954367) (xy 412.051265 -299.923242) (xy 412.093886 -299.898635)
			(xy 412.139902 -299.881183) (xy 412.188121 -299.871339) (xy 412.237296 -299.869358) (xy 412.286151 -299.87529)
			(xy 412.333422 -299.888982) (xy 412.377884 -299.91008) (xy 412.418387 -299.938036) (xy 412.45388 -299.972128)
			(xy 412.483445 -300.011472) (xy 412.506316 -300.055049) (xy 412.5219 -300.10173) (xy 412.529795 -300.150307)
			(xy 412.53029 -300.174914) (xy 412.869138 -300.174914) (xy 412.873098 -300.12586) (xy 412.884875 -300.078076)
			(xy 412.904166 -300.0328) (xy 412.930469 -299.991204) (xy 412.963104 -299.954367) (xy 413.001225 -299.923242)
			(xy 413.043846 -299.898635) (xy 413.089862 -299.881183) (xy 413.138081 -299.871339) (xy 413.187256 -299.869358)
			(xy 413.236111 -299.87529) (xy 413.283382 -299.888982) (xy 413.327844 -299.91008) (xy 413.368347 -299.938036)
			(xy 413.40384 -299.972128) (xy 413.433405 -300.011472) (xy 413.456276 -300.055049) (xy 413.47186 -300.10173)
			(xy 413.479755 -300.150307) (xy 413.48025 -300.174914) (xy 413.819098 -300.174914) (xy 413.823058 -300.12586)
			(xy 413.834835 -300.078076) (xy 413.854126 -300.0328) (xy 413.880429 -299.991204) (xy 413.913064 -299.954367)
			(xy 413.951185 -299.923242) (xy 413.993806 -299.898635) (xy 414.039822 -299.881183) (xy 414.088041 -299.871339)
			(xy 414.137216 -299.869358) (xy 414.186071 -299.87529) (xy 414.233342 -299.888982) (xy 414.277804 -299.91008)
			(xy 414.318307 -299.938036) (xy 414.3538 -299.972128) (xy 414.383365 -300.011472) (xy 414.406236 -300.055049)
			(xy 414.42182 -300.10173) (xy 414.429715 -300.150307) (xy 414.43021 -300.174914) (xy 414.769058 -300.174914)
			(xy 414.773018 -300.12586) (xy 414.784795 -300.078076) (xy 414.804086 -300.0328) (xy 414.830389 -299.991204)
			(xy 414.863024 -299.954367) (xy 414.901145 -299.923242) (xy 414.943766 -299.898635) (xy 414.989782 -299.881183)
			(xy 415.038001 -299.871339) (xy 415.087176 -299.869358) (xy 415.136031 -299.87529) (xy 415.183302 -299.888982)
			(xy 415.227764 -299.91008) (xy 415.268267 -299.938036) (xy 415.30376 -299.972128) (xy 415.333325 -300.011472)
			(xy 415.356196 -300.055049) (xy 415.37178 -300.10173) (xy 415.379675 -300.150307) (xy 415.38017 -300.174914)
			(xy 415.719018 -300.174914) (xy 415.722978 -300.12586) (xy 415.734755 -300.078076) (xy 415.754046 -300.0328)
			(xy 415.780349 -299.991204) (xy 415.812984 -299.954367) (xy 415.851105 -299.923242) (xy 415.893726 -299.898635)
			(xy 415.939742 -299.881183) (xy 415.987961 -299.871339) (xy 416.037136 -299.869358) (xy 416.085991 -299.87529)
			(xy 416.133262 -299.888982) (xy 416.177724 -299.91008) (xy 416.218227 -299.938036) (xy 416.25372 -299.972128)
			(xy 416.283285 -300.011472) (xy 416.306156 -300.055049) (xy 416.32174 -300.10173) (xy 416.329635 -300.150307)
			(xy 416.33013 -300.174914) (xy 416.329635 -300.199521) (xy 416.32174 -300.248098) (xy 416.306156 -300.294779)
			(xy 416.283285 -300.338356) (xy 416.25372 -300.3777) (xy 416.218227 -300.411792) (xy 416.177724 -300.439748)
			(xy 416.133262 -300.460846) (xy 416.085991 -300.474538) (xy 416.037136 -300.48047) (xy 415.987961 -300.478489)
			(xy 415.939742 -300.468645) (xy 415.893726 -300.451193) (xy 415.851105 -300.426586) (xy 415.812984 -300.395461)
			(xy 415.780349 -300.358624) (xy 415.754046 -300.317028) (xy 415.734755 -300.271752) (xy 415.722978 -300.223968)
			(xy 415.719018 -300.174914) (xy 415.38017 -300.174914) (xy 415.379675 -300.199521) (xy 415.37178 -300.248098)
			(xy 415.356196 -300.294779) (xy 415.333325 -300.338356) (xy 415.30376 -300.3777) (xy 415.268267 -300.411792)
			(xy 415.227764 -300.439748) (xy 415.183302 -300.460846) (xy 415.136031 -300.474538) (xy 415.087176 -300.48047)
			(xy 415.038001 -300.478489) (xy 414.989782 -300.468645) (xy 414.943766 -300.451193) (xy 414.901145 -300.426586)
			(xy 414.863024 -300.395461) (xy 414.830389 -300.358624) (xy 414.804086 -300.317028) (xy 414.784795 -300.271752)
			(xy 414.773018 -300.223968) (xy 414.769058 -300.174914) (xy 414.43021 -300.174914) (xy 414.429715 -300.199521)
			(xy 414.42182 -300.248098) (xy 414.406236 -300.294779) (xy 414.383365 -300.338356) (xy 414.3538 -300.3777)
			(xy 414.318307 -300.411792) (xy 414.277804 -300.439748) (xy 414.233342 -300.460846) (xy 414.186071 -300.474538)
			(xy 414.137216 -300.48047) (xy 414.088041 -300.478489) (xy 414.039822 -300.468645) (xy 413.993806 -300.451193)
			(xy 413.951185 -300.426586) (xy 413.913064 -300.395461) (xy 413.880429 -300.358624) (xy 413.854126 -300.317028)
			(xy 413.834835 -300.271752) (xy 413.823058 -300.223968) (xy 413.819098 -300.174914) (xy 413.48025 -300.174914)
			(xy 413.479755 -300.199521) (xy 413.47186 -300.248098) (xy 413.456276 -300.294779) (xy 413.433405 -300.338356)
			(xy 413.40384 -300.3777) (xy 413.368347 -300.411792) (xy 413.327844 -300.439748) (xy 413.283382 -300.460846)
			(xy 413.236111 -300.474538) (xy 413.187256 -300.48047) (xy 413.138081 -300.478489) (xy 413.089862 -300.468645)
			(xy 413.043846 -300.451193) (xy 413.001225 -300.426586) (xy 412.963104 -300.395461) (xy 412.930469 -300.358624)
			(xy 412.904166 -300.317028) (xy 412.884875 -300.271752) (xy 412.873098 -300.223968) (xy 412.869138 -300.174914)
			(xy 412.53029 -300.174914) (xy 412.529795 -300.199521) (xy 412.5219 -300.248098) (xy 412.506316 -300.294779)
			(xy 412.483445 -300.338356) (xy 412.45388 -300.3777) (xy 412.418387 -300.411792) (xy 412.377884 -300.439748)
			(xy 412.333422 -300.460846) (xy 412.286151 -300.474538) (xy 412.237296 -300.48047) (xy 412.188121 -300.478489)
			(xy 412.139902 -300.468645) (xy 412.093886 -300.451193) (xy 412.051265 -300.426586) (xy 412.013144 -300.395461)
			(xy 411.980509 -300.358624) (xy 411.954206 -300.317028) (xy 411.934915 -300.271752) (xy 411.923138 -300.223968)
			(xy 411.919178 -300.174914) (xy 411.58033 -300.174914) (xy 411.579835 -300.199521) (xy 411.57194 -300.248098)
			(xy 411.556356 -300.294779) (xy 411.533485 -300.338356) (xy 411.50392 -300.3777) (xy 411.468427 -300.411792)
			(xy 411.427924 -300.439748) (xy 411.383462 -300.460846) (xy 411.336191 -300.474538) (xy 411.287336 -300.48047)
			(xy 411.238161 -300.478489) (xy 411.189942 -300.468645) (xy 411.143926 -300.451193) (xy 411.101305 -300.426586)
			(xy 411.063184 -300.395461) (xy 411.030549 -300.358624) (xy 411.004246 -300.317028) (xy 410.984955 -300.271752)
			(xy 410.973178 -300.223968) (xy 410.969218 -300.174914) (xy 410.630116 -300.174914) (xy 410.629621 -300.199521)
			(xy 410.621726 -300.248098) (xy 410.606142 -300.294779) (xy 410.583271 -300.338356) (xy 410.553706 -300.3777)
			(xy 410.518213 -300.411792) (xy 410.47771 -300.439748) (xy 410.433248 -300.460846) (xy 410.385977 -300.474538)
			(xy 410.337122 -300.48047) (xy 410.287947 -300.478489) (xy 410.239728 -300.468645) (xy 410.193712 -300.451193)
			(xy 410.151091 -300.426586) (xy 410.11297 -300.395461) (xy 410.080335 -300.358624) (xy 410.054032 -300.317028)
			(xy 410.034741 -300.271752) (xy 410.022964 -300.223968) (xy 410.019004 -300.174914) (xy 409.680156 -300.174914)
			(xy 409.679661 -300.199521) (xy 409.671766 -300.248098) (xy 409.656182 -300.294779) (xy 409.633311 -300.338356)
			(xy 409.603746 -300.3777) (xy 409.568253 -300.411792) (xy 409.52775 -300.439748) (xy 409.483288 -300.460846)
			(xy 409.436017 -300.474538) (xy 409.387162 -300.48047) (xy 409.337987 -300.478489) (xy 409.289768 -300.468645)
			(xy 409.243752 -300.451193) (xy 409.201131 -300.426586) (xy 409.16301 -300.395461) (xy 409.130375 -300.358624)
			(xy 409.104072 -300.317028) (xy 409.084781 -300.271752) (xy 409.073004 -300.223968) (xy 409.069044 -300.174914)
			(xy 408.730196 -300.174914) (xy 408.729701 -300.199521) (xy 408.721806 -300.248098) (xy 408.706222 -300.294779)
			(xy 408.683351 -300.338356) (xy 408.653786 -300.3777) (xy 408.618293 -300.411792) (xy 408.57779 -300.439748)
			(xy 408.533328 -300.460846) (xy 408.486057 -300.474538) (xy 408.437202 -300.48047) (xy 408.388027 -300.478489)
			(xy 408.339808 -300.468645) (xy 408.293792 -300.451193) (xy 408.251171 -300.426586) (xy 408.21305 -300.395461)
			(xy 408.180415 -300.358624) (xy 408.154112 -300.317028) (xy 408.134821 -300.271752) (xy 408.123044 -300.223968)
			(xy 408.119084 -300.174914) (xy 406.830276 -300.174914) (xy 406.829781 -300.199521) (xy 406.821886 -300.248098)
			(xy 406.806302 -300.294779) (xy 406.783431 -300.338356) (xy 406.753866 -300.3777) (xy 406.718373 -300.411792)
			(xy 406.67787 -300.439748) (xy 406.633408 -300.460846) (xy 406.586137 -300.474538) (xy 406.537282 -300.48047)
			(xy 406.488107 -300.478489) (xy 406.439888 -300.468645) (xy 406.393872 -300.451193) (xy 406.351251 -300.426586)
			(xy 406.31313 -300.395461) (xy 406.280495 -300.358624) (xy 406.254192 -300.317028) (xy 406.234901 -300.271752)
			(xy 406.223124 -300.223968) (xy 406.219164 -300.174914) (xy 405.880316 -300.174914) (xy 405.879821 -300.199521)
			(xy 405.871926 -300.248098) (xy 405.856342 -300.294779) (xy 405.833471 -300.338356) (xy 405.803906 -300.3777)
			(xy 405.768413 -300.411792) (xy 405.72791 -300.439748) (xy 405.683448 -300.460846) (xy 405.636177 -300.474538)
			(xy 405.587322 -300.48047) (xy 405.538147 -300.478489) (xy 405.489928 -300.468645) (xy 405.443912 -300.451193)
			(xy 405.401291 -300.426586) (xy 405.36317 -300.395461) (xy 405.330535 -300.358624) (xy 405.304232 -300.317028)
			(xy 405.284941 -300.271752) (xy 405.273164 -300.223968) (xy 405.269204 -300.174914) (xy 404.930102 -300.174914)
			(xy 404.929607 -300.199521) (xy 404.921712 -300.248098) (xy 404.906128 -300.294779) (xy 404.883257 -300.338356)
			(xy 404.853692 -300.3777) (xy 404.818199 -300.411792) (xy 404.777696 -300.439748) (xy 404.733234 -300.460846)
			(xy 404.685963 -300.474538) (xy 404.637108 -300.48047) (xy 404.587933 -300.478489) (xy 404.539714 -300.468645)
			(xy 404.493698 -300.451193) (xy 404.451077 -300.426586) (xy 404.412956 -300.395461) (xy 404.380321 -300.358624)
			(xy 404.354018 -300.317028) (xy 404.334727 -300.271752) (xy 404.32295 -300.223968) (xy 404.31899 -300.174914)
			(xy 403.980142 -300.174914) (xy 403.979647 -300.199521) (xy 403.971752 -300.248098) (xy 403.956168 -300.294779)
			(xy 403.933297 -300.338356) (xy 403.903732 -300.3777) (xy 403.868239 -300.411792) (xy 403.827736 -300.439748)
			(xy 403.783274 -300.460846) (xy 403.736003 -300.474538) (xy 403.687148 -300.48047) (xy 403.637973 -300.478489)
			(xy 403.589754 -300.468645) (xy 403.543738 -300.451193) (xy 403.501117 -300.426586) (xy 403.462996 -300.395461)
			(xy 403.430361 -300.358624) (xy 403.404058 -300.317028) (xy 403.384767 -300.271752) (xy 403.37299 -300.223968)
			(xy 403.36903 -300.174914) (xy 403.030182 -300.174914) (xy 403.029687 -300.199521) (xy 403.021792 -300.248098)
			(xy 403.006208 -300.294779) (xy 402.983337 -300.338356) (xy 402.953772 -300.3777) (xy 402.918279 -300.411792)
			(xy 402.877776 -300.439748) (xy 402.833314 -300.460846) (xy 402.786043 -300.474538) (xy 402.737188 -300.48047)
			(xy 402.688013 -300.478489) (xy 402.639794 -300.468645) (xy 402.593778 -300.451193) (xy 402.551157 -300.426586)
			(xy 402.513036 -300.395461) (xy 402.480401 -300.358624) (xy 402.454098 -300.317028) (xy 402.434807 -300.271752)
			(xy 402.42303 -300.223968) (xy 402.41907 -300.174914) (xy 402.080222 -300.174914) (xy 402.079727 -300.199521)
			(xy 402.071832 -300.248098) (xy 402.056248 -300.294779) (xy 402.033377 -300.338356) (xy 402.003812 -300.3777)
			(xy 401.968319 -300.411792) (xy 401.927816 -300.439748) (xy 401.883354 -300.460846) (xy 401.836083 -300.474538)
			(xy 401.787228 -300.48047) (xy 401.738053 -300.478489) (xy 401.689834 -300.468645) (xy 401.643818 -300.451193)
			(xy 401.601197 -300.426586) (xy 401.563076 -300.395461) (xy 401.530441 -300.358624) (xy 401.504138 -300.317028)
			(xy 401.484847 -300.271752) (xy 401.47307 -300.223968) (xy 401.46911 -300.174914) (xy 401.130262 -300.174914)
			(xy 401.129767 -300.199521) (xy 401.121872 -300.248098) (xy 401.106288 -300.294779) (xy 401.083417 -300.338356)
			(xy 401.053852 -300.3777) (xy 401.018359 -300.411792) (xy 400.977856 -300.439748) (xy 400.933394 -300.460846)
			(xy 400.886123 -300.474538) (xy 400.837268 -300.48047) (xy 400.788093 -300.478489) (xy 400.739874 -300.468645)
			(xy 400.693858 -300.451193) (xy 400.651237 -300.426586) (xy 400.613116 -300.395461) (xy 400.580481 -300.358624)
			(xy 400.554178 -300.317028) (xy 400.534887 -300.271752) (xy 400.52311 -300.223968) (xy 400.51915 -300.174914)
			(xy 400.180302 -300.174914) (xy 400.179807 -300.199521) (xy 400.171912 -300.248098) (xy 400.156328 -300.294779)
			(xy 400.133457 -300.338356) (xy 400.103892 -300.3777) (xy 400.068399 -300.411792) (xy 400.027896 -300.439748)
			(xy 399.983434 -300.460846) (xy 399.936163 -300.474538) (xy 399.887308 -300.48047) (xy 399.838133 -300.478489)
			(xy 399.789914 -300.468645) (xy 399.743898 -300.451193) (xy 399.701277 -300.426586) (xy 399.663156 -300.395461)
			(xy 399.630521 -300.358624) (xy 399.604218 -300.317028) (xy 399.584927 -300.271752) (xy 399.57315 -300.223968)
			(xy 399.56919 -300.174914) (xy 399.230342 -300.174914) (xy 399.229847 -300.199521) (xy 399.221952 -300.248098)
			(xy 399.206368 -300.294779) (xy 399.183497 -300.338356) (xy 399.153932 -300.3777) (xy 399.118439 -300.411792)
			(xy 399.077936 -300.439748) (xy 399.033474 -300.460846) (xy 398.986203 -300.474538) (xy 398.937348 -300.48047)
			(xy 398.888173 -300.478489) (xy 398.839954 -300.468645) (xy 398.793938 -300.451193) (xy 398.751317 -300.426586)
			(xy 398.713196 -300.395461) (xy 398.680561 -300.358624) (xy 398.654258 -300.317028) (xy 398.634967 -300.271752)
			(xy 398.62319 -300.223968) (xy 398.61923 -300.174914) (xy 397.330168 -300.174914) (xy 397.329673 -300.199521)
			(xy 397.321778 -300.248098) (xy 397.306194 -300.294779) (xy 397.283323 -300.338356) (xy 397.253758 -300.3777)
			(xy 397.218265 -300.411792) (xy 397.177762 -300.439748) (xy 397.1333 -300.460846) (xy 397.086029 -300.474538)
			(xy 397.037174 -300.48047) (xy 396.987999 -300.478489) (xy 396.93978 -300.468645) (xy 396.893764 -300.451193)
			(xy 396.851143 -300.426586) (xy 396.813022 -300.395461) (xy 396.780387 -300.358624) (xy 396.754084 -300.317028)
			(xy 396.734793 -300.271752) (xy 396.723016 -300.223968) (xy 396.719056 -300.174914) (xy 396.380208 -300.174914)
			(xy 396.379713 -300.199521) (xy 396.371818 -300.248098) (xy 396.356234 -300.294779) (xy 396.333363 -300.338356)
			(xy 396.303798 -300.3777) (xy 396.268305 -300.411792) (xy 396.227802 -300.439748) (xy 396.18334 -300.460846)
			(xy 396.136069 -300.474538) (xy 396.087214 -300.48047) (xy 396.038039 -300.478489) (xy 395.98982 -300.468645)
			(xy 395.943804 -300.451193) (xy 395.901183 -300.426586) (xy 395.863062 -300.395461) (xy 395.830427 -300.358624)
			(xy 395.804124 -300.317028) (xy 395.784833 -300.271752) (xy 395.773056 -300.223968) (xy 395.769096 -300.174914)
			(xy 394.480288 -300.174914) (xy 394.479793 -300.199521) (xy 394.471898 -300.248098) (xy 394.456314 -300.294779)
			(xy 394.433443 -300.338356) (xy 394.403878 -300.3777) (xy 394.368385 -300.411792) (xy 394.327882 -300.439748)
			(xy 394.28342 -300.460846) (xy 394.236149 -300.474538) (xy 394.187294 -300.48047) (xy 394.138119 -300.478489)
			(xy 394.0899 -300.468645) (xy 394.043884 -300.451193) (xy 394.001263 -300.426586) (xy 393.963142 -300.395461)
			(xy 393.930507 -300.358624) (xy 393.904204 -300.317028) (xy 393.884913 -300.271752) (xy 393.873136 -300.223968)
			(xy 393.869176 -300.174914) (xy 393.530328 -300.174914) (xy 393.529833 -300.199521) (xy 393.521938 -300.248098)
			(xy 393.506354 -300.294779) (xy 393.483483 -300.338356) (xy 393.453918 -300.3777) (xy 393.418425 -300.411792)
			(xy 393.377922 -300.439748) (xy 393.33346 -300.460846) (xy 393.286189 -300.474538) (xy 393.237334 -300.48047)
			(xy 393.188159 -300.478489) (xy 393.13994 -300.468645) (xy 393.093924 -300.451193) (xy 393.051303 -300.426586)
			(xy 393.013182 -300.395461) (xy 392.980547 -300.358624) (xy 392.954244 -300.317028) (xy 392.934953 -300.271752)
			(xy 392.923176 -300.223968) (xy 392.919216 -300.174914) (xy 392.580085 -300.174914) (xy 392.580533 -300.183173)
			(xy 392.575167 -300.232527) (xy 392.561887 -300.280362) (xy 392.541043 -300.325418) (xy 392.513184 -300.366509)
			(xy 392.479045 -300.402551) (xy 392.439524 -300.432596) (xy 392.395663 -300.455851) (xy 392.348618 -300.471703)
			(xy 392.299628 -300.479736) (xy 392.274806 -300.480222) (xy 392.260623 -300.480044) (xy 392.232383 -300.477373)
			(xy 392.218418 -300.474888) (xy 392.205972 -300.472602) (xy 392.18235 -300.479968) (xy 392.10488 -300.557438)
			(xy 392.097514 -300.58106) (xy 392.0998 -300.593506) (xy 392.102273 -300.607472) (xy 392.104947 -300.635712)
			(xy 392.105134 -300.649894) (xy 392.104612 -300.675149) (xy 392.096299 -300.724971) (xy 392.079898 -300.772745)
			(xy 392.055857 -300.817168) (xy 392.024833 -300.857028) (xy 391.987671 -300.891238) (xy 391.945385 -300.918864)
			(xy 391.899129 -300.939154) (xy 391.850164 -300.951554) (xy 391.799826 -300.955725) (xy 391.749488 -300.951554)
			(xy 391.700523 -300.939154) (xy 391.654267 -300.918864) (xy 391.611981 -300.891238) (xy 391.574819 -300.857028)
			(xy 391.543795 -300.817168) (xy 391.519754 -300.772745) (xy 391.503353 -300.724971) (xy 391.49504 -300.675149)
			(xy 391.494518 -300.649894) (xy 391.494693 -300.635711) (xy 391.497366 -300.607471) (xy 391.499852 -300.593506)
			(xy 391.502138 -300.58106) (xy 391.494772 -300.557438) (xy 391.417302 -300.479968) (xy 391.39368 -300.472602)
			(xy 391.381234 -300.474888) (xy 391.367269 -300.477369) (xy 391.339029 -300.480038) (xy 391.324846 -300.480222)
			(xy 391.310663 -300.480039) (xy 391.282423 -300.477371) (xy 391.268458 -300.474888) (xy 391.256012 -300.472602)
			(xy 391.23239 -300.479968) (xy 391.15492 -300.557438) (xy 391.147554 -300.58106) (xy 391.14984 -300.593506)
			(xy 391.152313 -300.607472) (xy 391.154987 -300.635712) (xy 391.155174 -300.649894) (xy 391.154729 -300.674715)
			(xy 391.146699 -300.723703) (xy 391.130849 -300.770746) (xy 391.107598 -300.814606) (xy 391.077557 -300.854126)
			(xy 391.041519 -300.888266) (xy 391.000432 -300.916126) (xy 390.955379 -300.936972) (xy 390.907548 -300.950255)
			(xy 390.858197 -300.955624) (xy 390.808628 -300.952939) (xy 390.760146 -300.942271) (xy 390.714029 -300.923899)
			(xy 390.671492 -300.898309) (xy 390.633655 -300.866174) (xy 390.601515 -300.828341) (xy 390.575919 -300.785807)
			(xy 390.557541 -300.739692) (xy 390.546866 -300.691212) (xy 390.544174 -300.641643) (xy 390.549538 -300.592292)
			(xy 390.562814 -300.544458) (xy 390.583654 -300.499403) (xy 390.611509 -300.458312) (xy 390.645644 -300.42227)
			(xy 390.68516 -300.392224) (xy 390.729017 -300.368967) (xy 390.776058 -300.353111) (xy 390.825045 -300.345075)
			(xy 390.849866 -300.344586) (xy 390.864049 -300.344767) (xy 390.892289 -300.347436) (xy 390.906254 -300.34992)
			(xy 390.9187 -300.352206) (xy 390.942322 -300.34484) (xy 391.019792 -300.26737) (xy 391.027158 -300.243748)
			(xy 391.024872 -300.231302) (xy 391.022399 -300.217335) (xy 391.019725 -300.189096) (xy 391.019538 -300.174914)
			(xy 391.019716 -300.160731) (xy 391.022387 -300.132491) (xy 391.024872 -300.118526) (xy 391.027158 -300.10608)
			(xy 391.019792 -300.082458) (xy 390.942322 -300.004988) (xy 390.9187 -299.997622) (xy 390.906254 -299.999908)
			(xy 390.892289 -300.002387) (xy 390.864049 -300.005057) (xy 390.849866 -300.005242) (xy 390.824615 -300.00465)
			(xy 390.774803 -299.996333) (xy 390.72704 -299.979931) (xy 390.682627 -299.955891) (xy 390.642776 -299.92487)
			(xy 390.608574 -299.887713) (xy 390.580954 -299.845434) (xy 390.56067 -299.799185) (xy 390.548273 -299.750229)
			(xy 390.544103 -299.6999) (xy 389.255254 -299.6999) (xy 389.255254 -299.699934) (xy 389.254685 -299.724752)
			(xy 389.24665 -299.773734) (xy 389.230795 -299.820771) (xy 389.20754 -299.864622) (xy 389.177497 -299.904134)
			(xy 389.141457 -299.938265) (xy 389.10037 -299.966116) (xy 389.055318 -299.986952) (xy 389.007489 -300.000225)
			(xy 388.958143 -300.005586) (xy 388.908579 -300.002892) (xy 388.860105 -299.992216) (xy 388.813996 -299.973838)
			(xy 388.771467 -299.948242) (xy 388.733641 -299.916103) (xy 388.701511 -299.878267) (xy 388.675927 -299.835733)
			(xy 388.657561 -299.789619) (xy 388.646897 -299.741141) (xy 388.644216 -299.691577) (xy 388.64959 -299.642232)
			(xy 388.662876 -299.594407) (xy 388.683724 -299.549361) (xy 388.711585 -299.508281) (xy 388.745725 -299.47225)
			(xy 388.785245 -299.442217) (xy 388.829103 -299.418973) (xy 388.876144 -299.403131) (xy 388.925128 -299.395108)
			(xy 388.949946 -299.394626) (xy 388.964129 -299.39481) (xy 388.992369 -299.397477) (xy 389.006334 -299.39996)
			(xy 389.01878 -299.402246) (xy 389.042402 -299.39488) (xy 389.119872 -299.31741) (xy 389.127238 -299.293788)
			(xy 389.124952 -299.281342) (xy 389.122472 -299.267377) (xy 389.119802 -299.239137) (xy 389.119618 -299.224954)
			(xy 389.119704 -299.215786) (xy 389.120849 -299.197486) (xy 389.121904 -299.188378) (xy 389.123428 -299.17644)
			(xy 389.1153 -299.154088) (xy 389.0391 -299.08119) (xy 389.01624 -299.074078) (xy 389.004302 -299.07611)
			(xy 388.990808 -299.078167) (xy 388.963595 -299.080329) (xy 388.949946 -299.080428) (xy 387.999986 -299.080428)
			(xy 387.973989 -299.079966) (xy 387.922636 -299.071833) (xy 387.873186 -299.055772) (xy 387.826856 -299.032175)
			(xy 387.784786 -299.001625) (xy 387.748009 -298.964871) (xy 387.717433 -298.92282) (xy 387.693807 -298.876504)
			(xy 387.677715 -298.827064) (xy 387.669551 -298.775716) (xy 387.669024 -298.74972) (xy 387.669178 -298.736066)
			(xy 387.671467 -298.708852) (xy 387.673596 -298.695364) (xy 387.675628 -298.68368) (xy 387.668516 -298.66082)
			(xy 387.595618 -298.58462) (xy 387.573266 -298.576492) (xy 387.561582 -298.577762) (xy 387.561074 -298.577762)
			(xy 387.552092 -298.578798) (xy 387.534047 -298.579943) (xy 387.525006 -298.580048) (xy 387.500184 -298.579529)
			(xy 387.451193 -298.571498) (xy 387.404148 -298.555647) (xy 387.360286 -298.532393) (xy 387.320765 -298.50235)
			(xy 387.286625 -298.466308) (xy 387.258766 -298.425217) (xy 387.237921 -298.380161) (xy 387.224641 -298.332326)
			(xy 387.219275 -298.282973) (xy 386.879934 -298.282973) (xy 386.879605 -298.299347) (xy 386.87171 -298.347924)
			(xy 386.856126 -298.394605) (xy 386.833255 -298.438182) (xy 386.80369 -298.477526) (xy 386.768197 -298.511618)
			(xy 386.727694 -298.539574) (xy 386.683232 -298.560672) (xy 386.635961 -298.574364) (xy 386.587106 -298.580296)
			(xy 386.537931 -298.578315) (xy 386.489712 -298.568471) (xy 386.443696 -298.551019) (xy 386.401075 -298.526412)
			(xy 386.362954 -298.495287) (xy 386.330319 -298.45845) (xy 386.304016 -298.416854) (xy 386.284725 -298.371578)
			(xy 386.272948 -298.323794) (xy 386.268988 -298.27474) (xy 385.929886 -298.27474) (xy 385.929391 -298.299347)
			(xy 385.921496 -298.347924) (xy 385.905912 -298.394605) (xy 385.883041 -298.438182) (xy 385.853476 -298.477526)
			(xy 385.817983 -298.511618) (xy 385.77748 -298.539574) (xy 385.733018 -298.560672) (xy 385.685747 -298.574364)
			(xy 385.636892 -298.580296) (xy 385.587717 -298.578315) (xy 385.539498 -298.568471) (xy 385.493482 -298.551019)
			(xy 385.450861 -298.526412) (xy 385.41274 -298.495287) (xy 385.380105 -298.45845) (xy 385.353802 -298.416854)
			(xy 385.334511 -298.371578) (xy 385.322734 -298.323794) (xy 385.318774 -298.27474) (xy 384.980175 -298.27474)
			(xy 384.979685 -298.299093) (xy 384.97179 -298.34767) (xy 384.956206 -298.394351) (xy 384.933335 -298.437928)
			(xy 384.90377 -298.477272) (xy 384.868277 -298.511364) (xy 384.827774 -298.53932) (xy 384.783312 -298.560418)
			(xy 384.736041 -298.57411) (xy 384.687186 -298.580042) (xy 384.638011 -298.578061) (xy 384.589792 -298.568217)
			(xy 384.543776 -298.550765) (xy 384.501155 -298.526158) (xy 384.463034 -298.495033) (xy 384.430399 -298.458196)
			(xy 384.404096 -298.4166) (xy 384.384805 -298.371324) (xy 384.373028 -298.32354) (xy 384.369068 -298.274486)
			(xy 351.03308 -298.274486) (xy 351.03308 -299.133514) (xy 374.111518 -299.133514) (xy 374.115589 -299.077892)
			(xy 374.127715 -299.023455) (xy 374.147638 -298.971364) (xy 374.174934 -298.922729) (xy 374.20902 -298.878586)
			(xy 374.249169 -298.839877) (xy 374.294527 -298.807426) (xy 374.344127 -298.781925) (xy 374.396911 -298.763918)
			(xy 374.451754 -298.753788) (xy 374.507488 -298.751751) (xy 374.562925 -298.757851) (xy 374.616882 -298.771957)
			(xy 374.668211 -298.793769) (xy 374.715817 -298.822823) (xy 374.758685 -298.858498) (xy 374.795902 -298.900035)
			(xy 374.826675 -298.946548) (xy 374.850347 -298.997045) (xy 374.866415 -299.050452) (xy 374.874535 -299.105628)
			(xy 374.875044 -299.133514) (xy 375.587004 -299.133514) (xy 375.591075 -299.077892) (xy 375.603201 -299.023455)
			(xy 375.623124 -298.971364) (xy 375.65042 -298.922729) (xy 375.684506 -298.878586) (xy 375.724655 -298.839877)
			(xy 375.770013 -298.807426) (xy 375.819613 -298.781925) (xy 375.872397 -298.763918) (xy 375.92724 -298.753788)
			(xy 375.982974 -298.751751) (xy 376.038411 -298.757851) (xy 376.092368 -298.771957) (xy 376.143697 -298.793769)
			(xy 376.191303 -298.822823) (xy 376.234171 -298.858498) (xy 376.271388 -298.900035) (xy 376.302161 -298.946548)
			(xy 376.325833 -298.997045) (xy 376.341901 -299.050452) (xy 376.350021 -299.105628) (xy 376.35053 -299.133514)
			(xy 376.476004 -299.133514) (xy 376.480075 -299.077892) (xy 376.492201 -299.023455) (xy 376.512124 -298.971364)
			(xy 376.53942 -298.922729) (xy 376.573506 -298.878586) (xy 376.613655 -298.839877) (xy 376.659013 -298.807426)
			(xy 376.708613 -298.781925) (xy 376.761397 -298.763918) (xy 376.81624 -298.753788) (xy 376.871974 -298.751751)
			(xy 376.927411 -298.757851) (xy 376.981368 -298.771957) (xy 377.032697 -298.793769) (xy 377.080303 -298.822823)
			(xy 377.123171 -298.858498) (xy 377.160388 -298.900035) (xy 377.191161 -298.946548) (xy 377.214833 -298.997045)
			(xy 377.230901 -299.050452) (xy 377.239021 -299.105628) (xy 377.23953 -299.133514) (xy 377.239021 -299.1614)
			(xy 377.230901 -299.216576) (xy 377.214833 -299.269983) (xy 377.191161 -299.32048) (xy 377.160388 -299.366993)
			(xy 377.123171 -299.40853) (xy 377.080303 -299.444205) (xy 377.032697 -299.473259) (xy 376.981368 -299.495071)
			(xy 376.927411 -299.509177) (xy 376.871974 -299.515277) (xy 376.81624 -299.51324) (xy 376.761397 -299.50311)
			(xy 376.708613 -299.485103) (xy 376.659013 -299.459602) (xy 376.613655 -299.427151) (xy 376.573506 -299.388442)
			(xy 376.53942 -299.344299) (xy 376.512124 -299.295664) (xy 376.492201 -299.243573) (xy 376.480075 -299.189136)
			(xy 376.476004 -299.133514) (xy 376.35053 -299.133514) (xy 376.350021 -299.1614) (xy 376.341901 -299.216576)
			(xy 376.325833 -299.269983) (xy 376.302161 -299.32048) (xy 376.271388 -299.366993) (xy 376.234171 -299.40853)
			(xy 376.191303 -299.444205) (xy 376.143697 -299.473259) (xy 376.092368 -299.495071) (xy 376.038411 -299.509177)
			(xy 375.982974 -299.515277) (xy 375.92724 -299.51324) (xy 375.872397 -299.50311) (xy 375.819613 -299.485103)
			(xy 375.770013 -299.459602) (xy 375.724655 -299.427151) (xy 375.684506 -299.388442) (xy 375.65042 -299.344299)
			(xy 375.623124 -299.295664) (xy 375.603201 -299.243573) (xy 375.591075 -299.189136) (xy 375.587004 -299.133514)
			(xy 374.875044 -299.133514) (xy 374.874535 -299.1614) (xy 374.866415 -299.216576) (xy 374.850347 -299.269983)
			(xy 374.826675 -299.32048) (xy 374.795902 -299.366993) (xy 374.758685 -299.40853) (xy 374.715817 -299.444205)
			(xy 374.668211 -299.473259) (xy 374.616882 -299.495071) (xy 374.562925 -299.509177) (xy 374.507488 -299.515277)
			(xy 374.451754 -299.51324) (xy 374.396911 -299.50311) (xy 374.344127 -299.485103) (xy 374.294527 -299.459602)
			(xy 374.249169 -299.427151) (xy 374.20902 -299.388442) (xy 374.174934 -299.344299) (xy 374.147638 -299.295664)
			(xy 374.127715 -299.243573) (xy 374.115589 -299.189136) (xy 374.111518 -299.133514) (xy 351.03308 -299.133514)
			(xy 351.03308 -299.895514) (xy 379.638052 -299.895514) (xy 379.638619 -299.866133) (xy 379.647646 -299.808068)
			(xy 379.665474 -299.752075) (xy 379.691681 -299.69948) (xy 379.725646 -299.651528) (xy 379.766565 -299.609354)
			(xy 379.78969 -299.591222) (xy 379.798622 -299.58375) (xy 379.809075 -299.562969) (xy 379.809756 -299.551344)
			(xy 379.811026 -299.459396) (xy 379.80112 -299.438314) (xy 379.791976 -299.430948) (xy 379.770116 -299.412756)
			(xy 379.731578 -299.370934) (xy 379.699673 -299.323855) (xy 379.675108 -299.272563) (xy 379.658427 -299.218193)
			(xy 379.65 -299.16195) (xy 379.649482 -299.133514) (xy 379.649968 -299.106263) (xy 379.657724 -299.052315)
			(xy 379.673079 -299.00002) (xy 379.695721 -298.950443) (xy 379.725187 -298.904593) (xy 379.760878 -298.863402)
			(xy 379.802069 -298.827711) (xy 379.847919 -298.798245) (xy 379.897496 -298.775603) (xy 379.949791 -298.760248)
			(xy 380.003739 -298.752492) (xy 380.058241 -298.752492) (xy 380.112189 -298.760248) (xy 380.164484 -298.775603)
			(xy 380.214061 -298.798245) (xy 380.259911 -298.827711) (xy 380.301102 -298.863402) (xy 380.336793 -298.904593)
			(xy 380.366259 -298.950443) (xy 380.388901 -299.00002) (xy 380.404256 -299.052315) (xy 380.412012 -299.106263)
			(xy 380.412498 -299.133514) (xy 380.411971 -299.162897) (xy 380.402938 -299.220964) (xy 380.401748 -299.2247)
			(xy 383.734069 -299.2247) (xy 383.73824 -299.174365) (xy 383.750638 -299.125402) (xy 383.770925 -299.079148)
			(xy 383.798549 -299.036864) (xy 383.832755 -298.999703) (xy 383.872611 -298.968678) (xy 383.91703 -298.944636)
			(xy 383.9648 -298.928233) (xy 384.014618 -298.919916) (xy 384.039872 -298.919392) (xy 384.065268 -298.919898)
			(xy 384.115358 -298.928313) (xy 384.163365 -298.944897) (xy 384.207968 -298.969196) (xy 384.247936 -299.000538)
			(xy 384.265424 -299.01896) (xy 384.265678 -299.019214) (xy 384.273384 -299.026773) (xy 384.293241 -299.03519)
			(xy 384.304032 -299.03547) (xy 384.39217 -299.033184) (xy 384.411982 -299.023532) (xy 384.419094 -299.014896)
			(xy 384.434899 -298.996367) (xy 384.47099 -298.963668) (xy 384.511482 -298.936611) (xy 384.555502 -298.915779)
			(xy 384.602099 -298.901621) (xy 384.650268 -298.894444) (xy 384.674618 -298.893992) (xy 385.624578 -298.893992)
			(xy 385.650585 -298.894566) (xy 385.701958 -298.902699) (xy 385.751427 -298.91877) (xy 385.797772 -298.942381)
			(xy 385.839853 -298.972952) (xy 385.876634 -299.00973) (xy 385.907207 -299.051809) (xy 385.930822 -299.098153)
			(xy 385.946896 -299.14762) (xy 385.955033 -299.198993) (xy 385.955033 -299.233291) (xy 386.269089 -299.233291)
			(xy 386.271775 -299.183725) (xy 386.282444 -299.135247) (xy 386.300815 -299.089133) (xy 386.326404 -299.046598)
			(xy 386.358537 -299.008764) (xy 386.396368 -298.976626) (xy 386.438899 -298.951032) (xy 386.485011 -298.932655)
			(xy 386.533488 -298.92198) (xy 386.583053 -298.919288) (xy 386.632401 -298.924651) (xy 386.680232 -298.937925)
			(xy 386.725285 -298.958763) (xy 386.766373 -298.986615) (xy 386.802415 -299.020747) (xy 386.83246 -299.06026)
			(xy 386.855717 -299.104113) (xy 386.871573 -299.151151) (xy 386.87961 -299.200135) (xy 386.8801 -299.224954)
			(xy 386.879917 -299.239137) (xy 386.877249 -299.267377) (xy 386.874766 -299.281342) (xy 386.872579 -299.295304)
			(xy 386.875168 -299.323435) (xy 386.885364 -299.349782) (xy 386.902388 -299.372327) (xy 386.924937 -299.389346)
			(xy 386.951285 -299.399537) (xy 386.979417 -299.40212) (xy 386.993384 -299.39996) (xy 387.007414 -299.39748)
			(xy 387.03578 -299.394805) (xy 387.050026 -299.394626) (xy 387.074844 -299.395106) (xy 387.123825 -299.40314)
			(xy 387.170861 -299.418992) (xy 387.214713 -299.442244) (xy 387.254225 -299.472285) (xy 387.288358 -299.508322)
			(xy 387.316211 -299.549405) (xy 387.33705 -299.594454) (xy 387.350328 -299.642281) (xy 387.355693 -299.691625)
			(xy 387.355242 -299.699934) (xy 387.694182 -299.699934) (xy 387.698142 -299.65088) (xy 387.709919 -299.603096)
			(xy 387.72921 -299.55782) (xy 387.755513 -299.516224) (xy 387.788148 -299.479387) (xy 387.826269 -299.448262)
			(xy 387.86889 -299.423655) (xy 387.914906 -299.406203) (xy 387.963125 -299.396359) (xy 388.0123 -299.394378)
			(xy 388.061155 -299.40031) (xy 388.108426 -299.414002) (xy 388.152888 -299.4351) (xy 388.193391 -299.463056)
			(xy 388.228884 -299.497148) (xy 388.258449 -299.536492) (xy 388.28132 -299.580069) (xy 388.296904 -299.62675)
			(xy 388.304799 -299.675327) (xy 388.305294 -299.699934) (xy 388.304799 -299.724541) (xy 388.296904 -299.773118)
			(xy 388.28132 -299.819799) (xy 388.258449 -299.863376) (xy 388.228884 -299.90272) (xy 388.193391 -299.936812)
			(xy 388.152888 -299.964768) (xy 388.108426 -299.985866) (xy 388.061155 -299.999558) (xy 388.0123 -300.00549)
			(xy 387.963125 -300.003509) (xy 387.914906 -299.993665) (xy 387.86889 -299.976213) (xy 387.826269 -299.951606)
			(xy 387.788148 -299.920481) (xy 387.755513 -299.883644) (xy 387.72921 -299.842048) (xy 387.709919 -299.796772)
			(xy 387.698142 -299.748988) (xy 387.694182 -299.699934) (xy 387.355242 -299.699934) (xy 387.353005 -299.741188)
			(xy 387.342334 -299.789663) (xy 387.323962 -299.835773) (xy 387.298373 -299.878303) (xy 387.26624 -299.916134)
			(xy 387.22841 -299.948268) (xy 387.18588 -299.973859) (xy 387.13977 -299.992232) (xy 387.091296 -300.002904)
			(xy 387.041733 -300.005593) (xy 386.992389 -300.000229) (xy 386.944562 -299.986953) (xy 386.899512 -299.966115)
			(xy 386.858428 -299.938263) (xy 386.82239 -299.904131) (xy 386.792349 -299.864619) (xy 386.769095 -299.820768)
			(xy 386.753242 -299.773732) (xy 386.745206 -299.724752) (xy 386.744718 -299.699934) (xy 386.744899 -299.685751)
			(xy 386.747568 -299.657511) (xy 386.750052 -299.643546) (xy 386.75223 -299.629584) (xy 386.749639 -299.601455)
			(xy 386.739442 -299.575112) (xy 386.72242 -299.552569) (xy 386.699874 -299.53555) (xy 386.673529 -299.525358)
			(xy 386.6454 -299.522771) (xy 386.631434 -299.524928) (xy 386.617406 -299.527419) (xy 386.589038 -299.530087)
			(xy 386.574792 -299.530262) (xy 386.549973 -299.529814) (xy 386.500988 -299.521782) (xy 386.453948 -299.505932)
			(xy 386.410092 -299.48268) (xy 386.370575 -299.45264) (xy 386.336439 -299.416603) (xy 386.308582 -299.375518)
			(xy 386.287738 -299.330468) (xy 386.274458 -299.282639) (xy 386.269089 -299.233291) (xy 385.955033 -299.233291)
			(xy 385.955033 -299.251007) (xy 385.946896 -299.30238) (xy 385.930822 -299.351847) (xy 385.907207 -299.398191)
			(xy 385.876634 -299.44027) (xy 385.839853 -299.477048) (xy 385.797772 -299.507619) (xy 385.751427 -299.53123)
			(xy 385.701958 -299.547301) (xy 385.650585 -299.555434) (xy 385.624578 -299.555916) (xy 384.674618 -299.555916)
			(xy 384.650234 -299.555483) (xy 384.601997 -299.54831) (xy 384.555336 -299.53413) (xy 384.511263 -299.513252)
			(xy 384.470734 -299.486128) (xy 384.434627 -299.453346) (xy 384.41884 -299.434758) (xy 384.411489 -299.426569)
			(xy 384.39172 -299.416957) (xy 384.38074 -299.416216) (xy 384.304032 -299.41393) (xy 384.293049 -299.414196)
			(xy 384.272896 -299.422884) (xy 384.26517 -299.430694) (xy 384.247686 -299.449071) (xy 384.207755 -299.480345)
			(xy 384.163203 -299.504586) (xy 384.115255 -299.521125) (xy 384.065232 -299.529508) (xy 384.039872 -299.530008)
			(xy 384.014618 -299.529484) (xy 383.9648 -299.521167) (xy 383.91703 -299.504764) (xy 383.872611 -299.480722)
			(xy 383.832755 -299.449697) (xy 383.798549 -299.412536) (xy 383.770925 -299.370252) (xy 383.750638 -299.323998)
			(xy 383.73824 -299.275035) (xy 383.734069 -299.2247) (xy 380.401748 -299.2247) (xy 380.385103 -299.276959)
			(xy 380.358889 -299.329554) (xy 380.324916 -299.377505) (xy 380.283989 -299.419676) (xy 380.26086 -299.437806)
			(xy 380.251924 -299.445275) (xy 380.241471 -299.466057) (xy 380.240794 -299.477684) (xy 380.239524 -299.569632)
			(xy 380.24943 -299.590714) (xy 380.258574 -299.59808) (xy 380.280389 -299.616324) (xy 380.318933 -299.658134)
			(xy 380.350844 -299.705201) (xy 380.375417 -299.756484) (xy 380.392107 -299.810845) (xy 380.400545 -299.867081)
			(xy 380.401068 -299.895514) (xy 381.034542 -299.895514) (xy 381.038613 -299.839892) (xy 381.050739 -299.785455)
			(xy 381.070662 -299.733364) (xy 381.097958 -299.684729) (xy 381.132044 -299.640586) (xy 381.172193 -299.601877)
			(xy 381.217551 -299.569426) (xy 381.267151 -299.543925) (xy 381.319935 -299.525918) (xy 381.374778 -299.515788)
			(xy 381.430512 -299.513751) (xy 381.485949 -299.519851) (xy 381.539906 -299.533957) (xy 381.591235 -299.555769)
			(xy 381.638841 -299.584823) (xy 381.681709 -299.620498) (xy 381.718926 -299.662035) (xy 381.749699 -299.708548)
			(xy 381.773371 -299.759045) (xy 381.789439 -299.812452) (xy 381.797559 -299.867628) (xy 381.798068 -299.895514)
			(xy 381.921002 -299.895514) (xy 381.925073 -299.839892) (xy 381.937199 -299.785455) (xy 381.957122 -299.733364)
			(xy 381.984418 -299.684729) (xy 382.018504 -299.640586) (xy 382.058653 -299.601877) (xy 382.104011 -299.569426)
			(xy 382.153611 -299.543925) (xy 382.206395 -299.525918) (xy 382.261238 -299.515788) (xy 382.316972 -299.513751)
			(xy 382.372409 -299.519851) (xy 382.426366 -299.533957) (xy 382.477695 -299.555769) (xy 382.525301 -299.584823)
			(xy 382.568169 -299.620498) (xy 382.605386 -299.662035) (xy 382.636159 -299.708548) (xy 382.659831 -299.759045)
			(xy 382.675899 -299.812452) (xy 382.684019 -299.867628) (xy 382.684528 -299.895514) (xy 382.684019 -299.9234)
			(xy 382.675899 -299.978576) (xy 382.659831 -300.031983) (xy 382.636159 -300.08248) (xy 382.605386 -300.128993)
			(xy 382.568169 -300.17053) (xy 382.553215 -300.182975) (xy 384.369209 -300.182975) (xy 384.371897 -300.133413)
			(xy 384.382567 -300.084939) (xy 384.400939 -300.038829) (xy 384.426528 -299.996299) (xy 384.45866 -299.958469)
			(xy 384.496489 -299.926335) (xy 384.539019 -299.900744) (xy 384.585127 -299.882371) (xy 384.633601 -299.871699)
			(xy 384.683163 -299.869009) (xy 384.732507 -299.874372) (xy 384.780334 -299.887647) (xy 384.825383 -299.908485)
			(xy 384.866467 -299.936336) (xy 384.902505 -299.970467) (xy 384.932547 -300.009977) (xy 384.955801 -300.053828)
			(xy 384.971655 -300.100863) (xy 384.979691 -300.149843) (xy 384.98018 -300.17466) (xy 384.980015 -300.188907)
			(xy 384.977341 -300.217274) (xy 384.974846 -300.231302) (xy 384.97256 -300.243748) (xy 384.979926 -300.26737)
			(xy 385.048252 -300.33595) (xy 385.057503 -300.344089) (xy 385.080982 -300.351409) (xy 385.09321 -300.34992)
			(xy 385.093718 -300.34992) (xy 385.107622 -300.347457) (xy 385.135733 -300.344786) (xy 385.149852 -300.344586)
			(xy 385.163966 -300.34472) (xy 385.192077 -300.347267) (xy 385.205986 -300.349666) (xy 385.218432 -300.351952)
			(xy 385.242562 -300.344586) (xy 385.319524 -300.26737) (xy 385.32689 -300.243748) (xy 385.324604 -300.231302)
			(xy 385.322132 -300.217335) (xy 385.319457 -300.189096) (xy 385.31927 -300.174914) (xy 385.319792 -300.149659)
			(xy 385.328105 -300.099837) (xy 385.344506 -300.052063) (xy 385.368547 -300.00764) (xy 385.399571 -299.96778)
			(xy 385.436733 -299.93357) (xy 385.479019 -299.905944) (xy 385.525275 -299.885654) (xy 385.57424 -299.873254)
			(xy 385.624578 -299.869083) (xy 385.674916 -299.873254) (xy 385.723881 -299.885654) (xy 385.770137 -299.905944)
			(xy 385.812423 -299.93357) (xy 385.849585 -299.96778) (xy 385.880609 -300.00764) (xy 385.90465 -300.052063)
			(xy 385.921051 -300.099837) (xy 385.929364 -300.149659) (xy 385.929886 -300.174914) (xy 385.929712 -300.189097)
			(xy 385.927038 -300.217337) (xy 385.924552 -300.231302) (xy 385.924552 -300.231556) (xy 385.923058 -300.243786)
			(xy 385.930367 -300.267277) (xy 385.938522 -300.276514) (xy 386.007102 -300.34484) (xy 386.030724 -300.352206)
			(xy 386.04317 -300.34992) (xy 386.057198 -300.347428) (xy 386.085566 -300.344761) (xy 386.099812 -300.344586)
			(xy 386.124632 -300.345091) (xy 386.173617 -300.353123) (xy 386.220658 -300.368975) (xy 386.264514 -300.392228)
			(xy 386.30403 -300.422271) (xy 386.338166 -300.45831) (xy 386.366022 -300.499397) (xy 386.386863 -300.544449)
			(xy 386.400142 -300.59228) (xy 386.405507 -300.641629) (xy 386.405059 -300.649894) (xy 386.744222 -300.649894)
			(xy 386.748182 -300.60084) (xy 386.759959 -300.553056) (xy 386.77925 -300.50778) (xy 386.805553 -300.466184)
			(xy 386.838188 -300.429347) (xy 386.876309 -300.398222) (xy 386.91893 -300.373615) (xy 386.964946 -300.356163)
			(xy 387.013165 -300.346319) (xy 387.06234 -300.344338) (xy 387.111195 -300.35027) (xy 387.158466 -300.363962)
			(xy 387.202928 -300.38506) (xy 387.243431 -300.413016) (xy 387.278924 -300.447108) (xy 387.308489 -300.486452)
			(xy 387.33136 -300.530029) (xy 387.346944 -300.57671) (xy 387.354839 -300.625287) (xy 387.355334 -300.649894)
			(xy 387.694182 -300.649894) (xy 387.698142 -300.60084) (xy 387.709919 -300.553056) (xy 387.72921 -300.50778)
			(xy 387.755513 -300.466184) (xy 387.788148 -300.429347) (xy 387.826269 -300.398222) (xy 387.86889 -300.373615)
			(xy 387.914906 -300.356163) (xy 387.963125 -300.346319) (xy 388.0123 -300.344338) (xy 388.061155 -300.35027)
			(xy 388.108426 -300.363962) (xy 388.152888 -300.38506) (xy 388.193391 -300.413016) (xy 388.228884 -300.447108)
			(xy 388.258449 -300.486452) (xy 388.28132 -300.530029) (xy 388.296904 -300.57671) (xy 388.304799 -300.625287)
			(xy 388.305294 -300.649894) (xy 388.644142 -300.649894) (xy 388.648102 -300.60084) (xy 388.659879 -300.553056)
			(xy 388.67917 -300.50778) (xy 388.705473 -300.466184) (xy 388.738108 -300.429347) (xy 388.776229 -300.398222)
			(xy 388.81885 -300.373615) (xy 388.864866 -300.356163) (xy 388.913085 -300.346319) (xy 388.96226 -300.344338)
			(xy 389.011115 -300.35027) (xy 389.058386 -300.363962) (xy 389.102848 -300.38506) (xy 389.143351 -300.413016)
			(xy 389.178844 -300.447108) (xy 389.208409 -300.486452) (xy 389.23128 -300.530029) (xy 389.246864 -300.57671)
			(xy 389.254759 -300.625287) (xy 389.255254 -300.649894) (xy 389.594102 -300.649894) (xy 389.598062 -300.60084)
			(xy 389.609839 -300.553056) (xy 389.62913 -300.50778) (xy 389.655433 -300.466184) (xy 389.688068 -300.429347)
			(xy 389.726189 -300.398222) (xy 389.76881 -300.373615) (xy 389.814826 -300.356163) (xy 389.863045 -300.346319)
			(xy 389.91222 -300.344338) (xy 389.961075 -300.35027) (xy 390.008346 -300.363962) (xy 390.052808 -300.38506)
			(xy 390.093311 -300.413016) (xy 390.128804 -300.447108) (xy 390.158369 -300.486452) (xy 390.18124 -300.530029)
			(xy 390.196824 -300.57671) (xy 390.204719 -300.625287) (xy 390.205214 -300.649894) (xy 390.204719 -300.674501)
			(xy 390.196824 -300.723078) (xy 390.18124 -300.769759) (xy 390.158369 -300.813336) (xy 390.128804 -300.85268)
			(xy 390.093311 -300.886772) (xy 390.052808 -300.914728) (xy 390.008346 -300.935826) (xy 389.961075 -300.949518)
			(xy 389.91222 -300.95545) (xy 389.863045 -300.953469) (xy 389.814826 -300.943625) (xy 389.76881 -300.926173)
			(xy 389.726189 -300.901566) (xy 389.688068 -300.870441) (xy 389.655433 -300.833604) (xy 389.62913 -300.792008)
			(xy 389.609839 -300.746732) (xy 389.598062 -300.698948) (xy 389.594102 -300.649894) (xy 389.255254 -300.649894)
			(xy 389.254759 -300.674501) (xy 389.246864 -300.723078) (xy 389.23128 -300.769759) (xy 389.208409 -300.813336)
			(xy 389.178844 -300.85268) (xy 389.143351 -300.886772) (xy 389.102848 -300.914728) (xy 389.058386 -300.935826)
			(xy 389.011115 -300.949518) (xy 388.96226 -300.95545) (xy 388.913085 -300.953469) (xy 388.864866 -300.943625)
			(xy 388.81885 -300.926173) (xy 388.776229 -300.901566) (xy 388.738108 -300.870441) (xy 388.705473 -300.833604)
			(xy 388.67917 -300.792008) (xy 388.659879 -300.746732) (xy 388.648102 -300.698948) (xy 388.644142 -300.649894)
			(xy 388.305294 -300.649894) (xy 388.304799 -300.674501) (xy 388.296904 -300.723078) (xy 388.28132 -300.769759)
			(xy 388.258449 -300.813336) (xy 388.228884 -300.85268) (xy 388.193391 -300.886772) (xy 388.152888 -300.914728)
			(xy 388.108426 -300.935826) (xy 388.061155 -300.949518) (xy 388.0123 -300.95545) (xy 387.963125 -300.953469)
			(xy 387.914906 -300.943625) (xy 387.86889 -300.926173) (xy 387.826269 -300.901566) (xy 387.788148 -300.870441)
			(xy 387.755513 -300.833604) (xy 387.72921 -300.792008) (xy 387.709919 -300.746732) (xy 387.698142 -300.698948)
			(xy 387.694182 -300.649894) (xy 387.355334 -300.649894) (xy 387.354839 -300.674501) (xy 387.346944 -300.723078)
			(xy 387.33136 -300.769759) (xy 387.308489 -300.813336) (xy 387.278924 -300.85268) (xy 387.243431 -300.886772)
			(xy 387.202928 -300.914728) (xy 387.158466 -300.935826) (xy 387.111195 -300.949518) (xy 387.06234 -300.95545)
			(xy 387.013165 -300.953469) (xy 386.964946 -300.943625) (xy 386.91893 -300.926173) (xy 386.876309 -300.901566)
			(xy 386.838188 -300.870441) (xy 386.805553 -300.833604) (xy 386.77925 -300.792008) (xy 386.759959 -300.746732)
			(xy 386.748182 -300.698948) (xy 386.744222 -300.649894) (xy 386.405059 -300.649894) (xy 386.402818 -300.691195)
			(xy 386.392145 -300.739674) (xy 386.373771 -300.785787) (xy 386.348177 -300.828321) (xy 386.31604 -300.866153)
			(xy 386.278206 -300.898288) (xy 386.235671 -300.923879) (xy 386.189557 -300.942251) (xy 386.141077 -300.952921)
			(xy 386.091511 -300.955607) (xy 386.042162 -300.950238) (xy 385.994332 -300.936957) (xy 385.949281 -300.916113)
			(xy 385.908196 -300.888255) (xy 385.872158 -300.854117) (xy 385.842119 -300.814599) (xy 385.818868 -300.770741)
			(xy 385.803019 -300.7237) (xy 385.794989 -300.674714) (xy 385.794504 -300.649894) (xy 385.79468 -300.635711)
			(xy 385.797352 -300.607471) (xy 385.799838 -300.593506) (xy 385.799838 -300.593252) (xy 385.801329 -300.581022)
			(xy 385.794022 -300.557531) (xy 385.785868 -300.548294) (xy 385.717288 -300.479968) (xy 385.693666 -300.472602)
			(xy 385.68122 -300.474888) (xy 385.66719 -300.477368) (xy 385.638824 -300.480043) (xy 385.624578 -300.480222)
			(xy 385.610465 -300.480084) (xy 385.582353 -300.47754) (xy 385.568444 -300.475142) (xy 385.555998 -300.472856)
			(xy 385.531868 -300.480222) (xy 385.454906 -300.557438) (xy 385.44754 -300.58106) (xy 385.449826 -300.593506)
			(xy 385.4523 -300.607472) (xy 385.454973 -300.635712) (xy 385.45516 -300.649894) (xy 385.454638 -300.675149)
			(xy 385.446325 -300.724971) (xy 385.429924 -300.772745) (xy 385.405883 -300.817168) (xy 385.374859 -300.857028)
			(xy 385.337697 -300.891238) (xy 385.295411 -300.918864) (xy 385.249155 -300.939154) (xy 385.20019 -300.951554)
			(xy 385.149852 -300.955725) (xy 385.099514 -300.951554) (xy 385.050549 -300.939154) (xy 385.004293 -300.918864)
			(xy 384.962007 -300.891238) (xy 384.924845 -300.857028) (xy 384.893821 -300.817168) (xy 384.86978 -300.772745)
			(xy 384.853379 -300.724971) (xy 384.845066 -300.675149) (xy 384.844544 -300.649894) (xy 384.844711 -300.635647)
			(xy 384.84738 -300.607279) (xy 384.849878 -300.593252) (xy 384.852164 -300.580806) (xy 384.844798 -300.557184)
			(xy 384.776472 -300.488604) (xy 384.767257 -300.480418) (xy 384.743749 -300.473127) (xy 384.731514 -300.474634)
			(xy 384.731006 -300.474634) (xy 384.717102 -300.477093) (xy 384.688991 -300.479767) (xy 384.674872 -300.479968)
			(xy 384.650055 -300.479492) (xy 384.601074 -300.471458) (xy 384.554039 -300.455606) (xy 384.510188 -300.432353)
			(xy 384.470675 -300.402313) (xy 384.436544 -300.366277) (xy 384.408691 -300.325193) (xy 384.387852 -300.280145)
			(xy 384.374574 -300.232319) (xy 384.369209 -300.182975) (xy 382.553215 -300.182975) (xy 382.525301 -300.206205)
			(xy 382.477695 -300.235259) (xy 382.426366 -300.257071) (xy 382.372409 -300.271177) (xy 382.316972 -300.277277)
			(xy 382.261238 -300.27524) (xy 382.206395 -300.26511) (xy 382.153611 -300.247103) (xy 382.104011 -300.221602)
			(xy 382.058653 -300.189151) (xy 382.018504 -300.150442) (xy 381.984418 -300.106299) (xy 381.957122 -300.057664)
			(xy 381.937199 -300.005573) (xy 381.925073 -299.951136) (xy 381.921002 -299.895514) (xy 381.798068 -299.895514)
			(xy 381.797559 -299.9234) (xy 381.789439 -299.978576) (xy 381.773371 -300.031983) (xy 381.749699 -300.08248)
			(xy 381.718926 -300.128993) (xy 381.681709 -300.17053) (xy 381.638841 -300.206205) (xy 381.591235 -300.235259)
			(xy 381.539906 -300.257071) (xy 381.485949 -300.271177) (xy 381.430512 -300.277277) (xy 381.374778 -300.27524)
			(xy 381.319935 -300.26511) (xy 381.267151 -300.247103) (xy 381.217551 -300.221602) (xy 381.172193 -300.189151)
			(xy 381.132044 -300.150442) (xy 381.097958 -300.106299) (xy 381.070662 -300.057664) (xy 381.050739 -300.005573)
			(xy 381.038613 -299.951136) (xy 381.034542 -299.895514) (xy 380.401068 -299.895514) (xy 380.400582 -299.922765)
			(xy 380.392826 -299.976713) (xy 380.377471 -300.029008) (xy 380.354829 -300.078585) (xy 380.325363 -300.124435)
			(xy 380.289672 -300.165626) (xy 380.248481 -300.201317) (xy 380.202631 -300.230783) (xy 380.153054 -300.253425)
			(xy 380.100759 -300.26878) (xy 380.046811 -300.276536) (xy 379.992309 -300.276536) (xy 379.938361 -300.26878)
			(xy 379.886066 -300.253425) (xy 379.836489 -300.230783) (xy 379.790639 -300.201317) (xy 379.749448 -300.165626)
			(xy 379.713757 -300.124435) (xy 379.684291 -300.078585) (xy 379.661649 -300.029008) (xy 379.646294 -299.976713)
			(xy 379.638538 -299.922765) (xy 379.638052 -299.895514) (xy 351.03308 -299.895514) (xy 351.03308 -301.031656)
			(xy 374.111518 -301.031656) (xy 374.115589 -300.976034) (xy 374.127715 -300.921597) (xy 374.147638 -300.869506)
			(xy 374.174934 -300.820871) (xy 374.20902 -300.776728) (xy 374.249169 -300.738019) (xy 374.294527 -300.705568)
			(xy 374.344127 -300.680067) (xy 374.396911 -300.66206) (xy 374.451754 -300.65193) (xy 374.507488 -300.649893)
			(xy 374.562925 -300.655993) (xy 374.616882 -300.670099) (xy 374.668211 -300.691911) (xy 374.715817 -300.720965)
			(xy 374.758685 -300.75664) (xy 374.795902 -300.798177) (xy 374.826675 -300.84469) (xy 374.850347 -300.895187)
			(xy 374.866415 -300.948594) (xy 374.874535 -301.00377) (xy 374.875044 -301.031656) (xy 375.596656 -301.031656)
			(xy 375.600727 -300.976034) (xy 375.612853 -300.921597) (xy 375.632776 -300.869506) (xy 375.660072 -300.820871)
			(xy 375.694158 -300.776728) (xy 375.734307 -300.738019) (xy 375.779665 -300.705568) (xy 375.829265 -300.680067)
			(xy 375.882049 -300.66206) (xy 375.936892 -300.65193) (xy 375.992626 -300.649893) (xy 376.048063 -300.655993)
			(xy 376.10202 -300.670099) (xy 376.153349 -300.691911) (xy 376.200955 -300.720965) (xy 376.243823 -300.75664)
			(xy 376.28104 -300.798177) (xy 376.311813 -300.84469) (xy 376.335485 -300.895187) (xy 376.351553 -300.948594)
			(xy 376.359673 -301.00377) (xy 376.360182 -301.031656) (xy 376.359673 -301.059542) (xy 376.351553 -301.114718)
			(xy 376.335485 -301.168125) (xy 376.311813 -301.218622) (xy 376.28104 -301.265135) (xy 376.243823 -301.306672)
			(xy 376.200955 -301.342347) (xy 376.153349 -301.371401) (xy 376.10202 -301.393213) (xy 376.048063 -301.407319)
			(xy 375.992626 -301.413419) (xy 375.936892 -301.411382) (xy 375.882049 -301.401252) (xy 375.829265 -301.383245)
			(xy 375.779665 -301.357744) (xy 375.734307 -301.325293) (xy 375.694158 -301.286584) (xy 375.660072 -301.242441)
			(xy 375.632776 -301.193806) (xy 375.612853 -301.141715) (xy 375.600727 -301.087278) (xy 375.596656 -301.031656)
			(xy 374.875044 -301.031656) (xy 374.874535 -301.059542) (xy 374.866415 -301.114718) (xy 374.850347 -301.168125)
			(xy 374.826675 -301.218622) (xy 374.795902 -301.265135) (xy 374.758685 -301.306672) (xy 374.715817 -301.342347)
			(xy 374.668211 -301.371401) (xy 374.616882 -301.393213) (xy 374.562925 -301.407319) (xy 374.507488 -301.413419)
			(xy 374.451754 -301.411382) (xy 374.396911 -301.401252) (xy 374.344127 -301.383245) (xy 374.294527 -301.357744)
			(xy 374.249169 -301.325293) (xy 374.20902 -301.286584) (xy 374.174934 -301.242441) (xy 374.147638 -301.193806)
			(xy 374.127715 -301.141715) (xy 374.115589 -301.087278) (xy 374.111518 -301.031656) (xy 351.03308 -301.031656)
			(xy 351.03308 -301.599854) (xy 384.844048 -301.599854) (xy 384.848008 -301.5508) (xy 384.859785 -301.503016)
			(xy 384.879076 -301.45774) (xy 384.905379 -301.416144) (xy 384.938014 -301.379307) (xy 384.976135 -301.348182)
			(xy 385.018756 -301.323575) (xy 385.064772 -301.306123) (xy 385.112991 -301.296279) (xy 385.162166 -301.294298)
			(xy 385.211021 -301.30023) (xy 385.258292 -301.313922) (xy 385.302754 -301.33502) (xy 385.343257 -301.362976)
			(xy 385.37875 -301.397068) (xy 385.408315 -301.436412) (xy 385.431186 -301.479989) (xy 385.44677 -301.52667)
			(xy 385.454665 -301.575247) (xy 385.45516 -301.599854) (xy 385.794008 -301.599854) (xy 385.797968 -301.5508)
			(xy 385.809745 -301.503016) (xy 385.829036 -301.45774) (xy 385.855339 -301.416144) (xy 385.887974 -301.379307)
			(xy 385.926095 -301.348182) (xy 385.968716 -301.323575) (xy 386.014732 -301.306123) (xy 386.062951 -301.296279)
			(xy 386.112126 -301.294298) (xy 386.160981 -301.30023) (xy 386.208252 -301.313922) (xy 386.252714 -301.33502)
			(xy 386.293217 -301.362976) (xy 386.32871 -301.397068) (xy 386.358275 -301.436412) (xy 386.381146 -301.479989)
			(xy 386.39673 -301.52667) (xy 386.404625 -301.575247) (xy 386.40512 -301.599854) (xy 386.744222 -301.599854)
			(xy 386.748182 -301.5508) (xy 386.759959 -301.503016) (xy 386.77925 -301.45774) (xy 386.805553 -301.416144)
			(xy 386.838188 -301.379307) (xy 386.876309 -301.348182) (xy 386.91893 -301.323575) (xy 386.964946 -301.306123)
			(xy 387.013165 -301.296279) (xy 387.06234 -301.294298) (xy 387.111195 -301.30023) (xy 387.158466 -301.313922)
			(xy 387.202928 -301.33502) (xy 387.243431 -301.362976) (xy 387.278924 -301.397068) (xy 387.308489 -301.436412)
			(xy 387.33136 -301.479989) (xy 387.346944 -301.52667) (xy 387.354839 -301.575247) (xy 387.355334 -301.599854)
			(xy 387.694182 -301.599854) (xy 387.698142 -301.5508) (xy 387.709919 -301.503016) (xy 387.72921 -301.45774)
			(xy 387.755513 -301.416144) (xy 387.788148 -301.379307) (xy 387.826269 -301.348182) (xy 387.86889 -301.323575)
			(xy 387.914906 -301.306123) (xy 387.963125 -301.296279) (xy 388.0123 -301.294298) (xy 388.061155 -301.30023)
			(xy 388.108426 -301.313922) (xy 388.152888 -301.33502) (xy 388.193391 -301.362976) (xy 388.228884 -301.397068)
			(xy 388.258449 -301.436412) (xy 388.28132 -301.479989) (xy 388.296904 -301.52667) (xy 388.304799 -301.575247)
			(xy 388.305294 -301.599854) (xy 388.644142 -301.599854) (xy 388.648102 -301.5508) (xy 388.659879 -301.503016)
			(xy 388.67917 -301.45774) (xy 388.705473 -301.416144) (xy 388.738108 -301.379307) (xy 388.776229 -301.348182)
			(xy 388.81885 -301.323575) (xy 388.864866 -301.306123) (xy 388.913085 -301.296279) (xy 388.96226 -301.294298)
			(xy 389.011115 -301.30023) (xy 389.058386 -301.313922) (xy 389.102848 -301.33502) (xy 389.143351 -301.362976)
			(xy 389.178844 -301.397068) (xy 389.208409 -301.436412) (xy 389.23128 -301.479989) (xy 389.246864 -301.52667)
			(xy 389.254759 -301.575247) (xy 389.255254 -301.599854) (xy 389.594102 -301.599854) (xy 389.598062 -301.5508)
			(xy 389.609839 -301.503016) (xy 389.62913 -301.45774) (xy 389.655433 -301.416144) (xy 389.688068 -301.379307)
			(xy 389.726189 -301.348182) (xy 389.76881 -301.323575) (xy 389.814826 -301.306123) (xy 389.863045 -301.296279)
			(xy 389.91222 -301.294298) (xy 389.961075 -301.30023) (xy 390.008346 -301.313922) (xy 390.052808 -301.33502)
			(xy 390.093311 -301.362976) (xy 390.128804 -301.397068) (xy 390.158369 -301.436412) (xy 390.18124 -301.479989)
			(xy 390.196824 -301.52667) (xy 390.204719 -301.575247) (xy 390.205214 -301.599854) (xy 390.544062 -301.599854)
			(xy 390.548022 -301.5508) (xy 390.559799 -301.503016) (xy 390.57909 -301.45774) (xy 390.605393 -301.416144)
			(xy 390.638028 -301.379307) (xy 390.676149 -301.348182) (xy 390.71877 -301.323575) (xy 390.764786 -301.306123)
			(xy 390.813005 -301.296279) (xy 390.86218 -301.294298) (xy 390.911035 -301.30023) (xy 390.958306 -301.313922)
			(xy 391.002768 -301.33502) (xy 391.043271 -301.362976) (xy 391.078764 -301.397068) (xy 391.108329 -301.436412)
			(xy 391.1312 -301.479989) (xy 391.146784 -301.52667) (xy 391.154679 -301.575247) (xy 391.155174 -301.599854)
			(xy 391.494022 -301.599854) (xy 391.497982 -301.5508) (xy 391.509759 -301.503016) (xy 391.52905 -301.45774)
			(xy 391.555353 -301.416144) (xy 391.587988 -301.379307) (xy 391.626109 -301.348182) (xy 391.66873 -301.323575)
			(xy 391.714746 -301.306123) (xy 391.762965 -301.296279) (xy 391.81214 -301.294298) (xy 391.860995 -301.30023)
			(xy 391.908266 -301.313922) (xy 391.952728 -301.33502) (xy 391.993231 -301.362976) (xy 392.028724 -301.397068)
			(xy 392.058289 -301.436412) (xy 392.08116 -301.479989) (xy 392.096744 -301.52667) (xy 392.104639 -301.575247)
			(xy 392.104969 -301.591642) (xy 392.444034 -301.591642) (xy 392.449398 -301.542282) (xy 392.462678 -301.49444)
			(xy 392.483522 -301.449377) (xy 392.511382 -301.40828) (xy 392.545525 -301.372232) (xy 392.585049 -301.342183)
			(xy 392.628914 -301.318924) (xy 392.675965 -301.303068) (xy 392.724961 -301.295033) (xy 392.749786 -301.294546)
			(xy 392.764033 -301.294716) (xy 392.792401 -301.297383) (xy 392.806428 -301.29988) (xy 392.818874 -301.302166)
			(xy 392.842496 -301.2948) (xy 392.911076 -301.226474) (xy 392.919259 -301.217256) (xy 392.926553 -301.193751)
			(xy 392.925046 -301.181516) (xy 392.925046 -301.181008) (xy 392.922587 -301.167104) (xy 392.919913 -301.138993)
			(xy 392.919712 -301.124874) (xy 392.920234 -301.099619) (xy 392.928547 -301.049797) (xy 392.944948 -301.002023)
			(xy 392.968989 -300.9576) (xy 393.000013 -300.91774) (xy 393.037175 -300.88353) (xy 393.079461 -300.855904)
			(xy 393.125717 -300.835614) (xy 393.174682 -300.823214) (xy 393.22502 -300.819043) (xy 393.275358 -300.823214)
			(xy 393.324323 -300.835614) (xy 393.370579 -300.855904) (xy 393.412865 -300.88353) (xy 393.450027 -300.91774)
			(xy 393.481051 -300.9576) (xy 393.505092 -301.002023) (xy 393.521493 -301.049797) (xy 393.529806 -301.099619)
			(xy 393.530328 -301.124874) (xy 393.530147 -301.139057) (xy 393.527478 -301.167297) (xy 393.524994 -301.181262)
			(xy 393.522708 -301.193708) (xy 393.530074 -301.21733) (xy 393.607544 -301.2948) (xy 393.631166 -301.302166)
			(xy 393.643612 -301.29988) (xy 393.657578 -301.297406) (xy 393.685818 -301.294732) (xy 393.7 -301.294546)
			(xy 393.714183 -301.294723) (xy 393.742423 -301.297395) (xy 393.756388 -301.29988) (xy 393.768834 -301.302166)
			(xy 393.792456 -301.2948) (xy 393.869926 -301.21733) (xy 393.877292 -301.193708) (xy 393.875006 -301.181262)
			(xy 393.872528 -301.167296) (xy 393.869857 -301.139057) (xy 393.869672 -301.124874) (xy 393.870206 -301.100055)
			(xy 393.87824 -301.051073) (xy 393.894094 -301.004035) (xy 393.917348 -300.960182) (xy 393.94739 -300.920668)
			(xy 393.98343 -300.886536) (xy 394.024516 -300.858683) (xy 394.069567 -300.837845) (xy 394.117396 -300.824569)
			(xy 394.166743 -300.819206) (xy 394.216307 -300.821898) (xy 394.264783 -300.832572) (xy 394.310894 -300.850948)
			(xy 394.353424 -300.876542) (xy 394.391253 -300.90868) (xy 394.423385 -300.946514) (xy 394.448972 -300.989048)
			(xy 394.467342 -301.035161) (xy 394.478009 -301.083638) (xy 394.480241 -301.124874) (xy 394.819136 -301.124874)
			(xy 394.823096 -301.07582) (xy 394.834873 -301.028036) (xy 394.854164 -300.98276) (xy 394.880467 -300.941164)
			(xy 394.913102 -300.904327) (xy 394.951223 -300.873202) (xy 394.993844 -300.848595) (xy 395.03986 -300.831143)
			(xy 395.088079 -300.821299) (xy 395.137254 -300.819318) (xy 395.186109 -300.82525) (xy 395.23338 -300.838942)
			(xy 395.277842 -300.86004) (xy 395.318345 -300.887996) (xy 395.353838 -300.922088) (xy 395.383403 -300.961432)
			(xy 395.406274 -301.005009) (xy 395.421858 -301.05169) (xy 395.429753 -301.100267) (xy 395.430248 -301.124874)
			(xy 395.769096 -301.124874) (xy 395.773056 -301.07582) (xy 395.784833 -301.028036) (xy 395.804124 -300.98276)
			(xy 395.830427 -300.941164) (xy 395.863062 -300.904327) (xy 395.901183 -300.873202) (xy 395.943804 -300.848595)
			(xy 395.98982 -300.831143) (xy 396.038039 -300.821299) (xy 396.087214 -300.819318) (xy 396.136069 -300.82525)
			(xy 396.18334 -300.838942) (xy 396.227802 -300.86004) (xy 396.268305 -300.887996) (xy 396.303798 -300.922088)
			(xy 396.333363 -300.961432) (xy 396.356234 -301.005009) (xy 396.371818 -301.05169) (xy 396.379713 -301.100267)
			(xy 396.380208 -301.124874) (xy 397.669016 -301.124874) (xy 397.672976 -301.07582) (xy 397.684753 -301.028036)
			(xy 397.704044 -300.98276) (xy 397.730347 -300.941164) (xy 397.762982 -300.904327) (xy 397.801103 -300.873202)
			(xy 397.843724 -300.848595) (xy 397.88974 -300.831143) (xy 397.937959 -300.821299) (xy 397.987134 -300.819318)
			(xy 398.035989 -300.82525) (xy 398.08326 -300.838942) (xy 398.127722 -300.86004) (xy 398.168225 -300.887996)
			(xy 398.203718 -300.922088) (xy 398.233283 -300.961432) (xy 398.256154 -301.005009) (xy 398.271738 -301.05169)
			(xy 398.279633 -301.100267) (xy 398.280128 -301.124874) (xy 398.61923 -301.124874) (xy 398.62319 -301.07582)
			(xy 398.634967 -301.028036) (xy 398.654258 -300.98276) (xy 398.680561 -300.941164) (xy 398.713196 -300.904327)
			(xy 398.751317 -300.873202) (xy 398.793938 -300.848595) (xy 398.839954 -300.831143) (xy 398.888173 -300.821299)
			(xy 398.937348 -300.819318) (xy 398.986203 -300.82525) (xy 399.033474 -300.838942) (xy 399.077936 -300.86004)
			(xy 399.118439 -300.887996) (xy 399.153932 -300.922088) (xy 399.183497 -300.961432) (xy 399.206368 -301.005009)
			(xy 399.221952 -301.05169) (xy 399.229847 -301.100267) (xy 399.230342 -301.124874) (xy 399.56919 -301.124874)
			(xy 399.57315 -301.07582) (xy 399.584927 -301.028036) (xy 399.604218 -300.98276) (xy 399.630521 -300.941164)
			(xy 399.663156 -300.904327) (xy 399.701277 -300.873202) (xy 399.743898 -300.848595) (xy 399.789914 -300.831143)
			(xy 399.838133 -300.821299) (xy 399.887308 -300.819318) (xy 399.936163 -300.82525) (xy 399.983434 -300.838942)
			(xy 400.027896 -300.86004) (xy 400.068399 -300.887996) (xy 400.103892 -300.922088) (xy 400.133457 -300.961432)
			(xy 400.156328 -301.005009) (xy 400.171912 -301.05169) (xy 400.179807 -301.100267) (xy 400.180302 -301.124874)
			(xy 400.51915 -301.124874) (xy 400.52311 -301.07582) (xy 400.534887 -301.028036) (xy 400.554178 -300.98276)
			(xy 400.580481 -300.941164) (xy 400.613116 -300.904327) (xy 400.651237 -300.873202) (xy 400.693858 -300.848595)
			(xy 400.739874 -300.831143) (xy 400.788093 -300.821299) (xy 400.837268 -300.819318) (xy 400.886123 -300.82525)
			(xy 400.933394 -300.838942) (xy 400.977856 -300.86004) (xy 401.018359 -300.887996) (xy 401.053852 -300.922088)
			(xy 401.083417 -300.961432) (xy 401.106288 -301.005009) (xy 401.121872 -301.05169) (xy 401.129767 -301.100267)
			(xy 401.130262 -301.124874) (xy 401.46911 -301.124874) (xy 401.47307 -301.07582) (xy 401.484847 -301.028036)
			(xy 401.504138 -300.98276) (xy 401.530441 -300.941164) (xy 401.563076 -300.904327) (xy 401.601197 -300.873202)
			(xy 401.643818 -300.848595) (xy 401.689834 -300.831143) (xy 401.738053 -300.821299) (xy 401.787228 -300.819318)
			(xy 401.836083 -300.82525) (xy 401.883354 -300.838942) (xy 401.927816 -300.86004) (xy 401.968319 -300.887996)
			(xy 402.003812 -300.922088) (xy 402.033377 -300.961432) (xy 402.056248 -301.005009) (xy 402.071832 -301.05169)
			(xy 402.079727 -301.100267) (xy 402.080222 -301.124874) (xy 402.41907 -301.124874) (xy 402.42303 -301.07582)
			(xy 402.434807 -301.028036) (xy 402.454098 -300.98276) (xy 402.480401 -300.941164) (xy 402.513036 -300.904327)
			(xy 402.551157 -300.873202) (xy 402.593778 -300.848595) (xy 402.639794 -300.831143) (xy 402.688013 -300.821299)
			(xy 402.737188 -300.819318) (xy 402.786043 -300.82525) (xy 402.833314 -300.838942) (xy 402.877776 -300.86004)
			(xy 402.918279 -300.887996) (xy 402.953772 -300.922088) (xy 402.983337 -300.961432) (xy 403.006208 -301.005009)
			(xy 403.021792 -301.05169) (xy 403.029687 -301.100267) (xy 403.030182 -301.124874) (xy 403.36903 -301.124874)
			(xy 403.37299 -301.07582) (xy 403.384767 -301.028036) (xy 403.404058 -300.98276) (xy 403.430361 -300.941164)
			(xy 403.462996 -300.904327) (xy 403.501117 -300.873202) (xy 403.543738 -300.848595) (xy 403.589754 -300.831143)
			(xy 403.637973 -300.821299) (xy 403.687148 -300.819318) (xy 403.736003 -300.82525) (xy 403.783274 -300.838942)
			(xy 403.827736 -300.86004) (xy 403.868239 -300.887996) (xy 403.903732 -300.922088) (xy 403.933297 -300.961432)
			(xy 403.956168 -301.005009) (xy 403.971752 -301.05169) (xy 403.979647 -301.100267) (xy 403.980142 -301.124874)
			(xy 404.31899 -301.124874) (xy 404.32295 -301.07582) (xy 404.334727 -301.028036) (xy 404.354018 -300.98276)
			(xy 404.380321 -300.941164) (xy 404.412956 -300.904327) (xy 404.451077 -300.873202) (xy 404.493698 -300.848595)
			(xy 404.539714 -300.831143) (xy 404.587933 -300.821299) (xy 404.637108 -300.819318) (xy 404.685963 -300.82525)
			(xy 404.733234 -300.838942) (xy 404.777696 -300.86004) (xy 404.818199 -300.887996) (xy 404.853692 -300.922088)
			(xy 404.883257 -300.961432) (xy 404.906128 -301.005009) (xy 404.921712 -301.05169) (xy 404.929607 -301.100267)
			(xy 404.930102 -301.124874) (xy 405.269204 -301.124874) (xy 405.273164 -301.07582) (xy 405.284941 -301.028036)
			(xy 405.304232 -300.98276) (xy 405.330535 -300.941164) (xy 405.36317 -300.904327) (xy 405.401291 -300.873202)
			(xy 405.443912 -300.848595) (xy 405.489928 -300.831143) (xy 405.538147 -300.821299) (xy 405.587322 -300.819318)
			(xy 405.636177 -300.82525) (xy 405.683448 -300.838942) (xy 405.72791 -300.86004) (xy 405.768413 -300.887996)
			(xy 405.803906 -300.922088) (xy 405.833471 -300.961432) (xy 405.856342 -301.005009) (xy 405.871926 -301.05169)
			(xy 405.879821 -301.100267) (xy 405.880316 -301.124874) (xy 406.219164 -301.124874) (xy 406.223124 -301.07582)
			(xy 406.234901 -301.028036) (xy 406.254192 -300.98276) (xy 406.280495 -300.941164) (xy 406.31313 -300.904327)
			(xy 406.351251 -300.873202) (xy 406.393872 -300.848595) (xy 406.439888 -300.831143) (xy 406.488107 -300.821299)
			(xy 406.537282 -300.819318) (xy 406.586137 -300.82525) (xy 406.633408 -300.838942) (xy 406.67787 -300.86004)
			(xy 406.718373 -300.887996) (xy 406.753866 -300.922088) (xy 406.783431 -300.961432) (xy 406.806302 -301.005009)
			(xy 406.821886 -301.05169) (xy 406.829781 -301.100267) (xy 406.830276 -301.124874) (xy 408.119084 -301.124874)
			(xy 408.123044 -301.07582) (xy 408.134821 -301.028036) (xy 408.154112 -300.98276) (xy 408.180415 -300.941164)
			(xy 408.21305 -300.904327) (xy 408.251171 -300.873202) (xy 408.293792 -300.848595) (xy 408.339808 -300.831143)
			(xy 408.388027 -300.821299) (xy 408.437202 -300.819318) (xy 408.486057 -300.82525) (xy 408.533328 -300.838942)
			(xy 408.57779 -300.86004) (xy 408.618293 -300.887996) (xy 408.653786 -300.922088) (xy 408.683351 -300.961432)
			(xy 408.706222 -301.005009) (xy 408.721806 -301.05169) (xy 408.729701 -301.100267) (xy 408.730196 -301.124874)
			(xy 409.069044 -301.124874) (xy 409.073004 -301.07582) (xy 409.084781 -301.028036) (xy 409.104072 -300.98276)
			(xy 409.130375 -300.941164) (xy 409.16301 -300.904327) (xy 409.201131 -300.873202) (xy 409.243752 -300.848595)
			(xy 409.289768 -300.831143) (xy 409.337987 -300.821299) (xy 409.387162 -300.819318) (xy 409.436017 -300.82525)
			(xy 409.483288 -300.838942) (xy 409.52775 -300.86004) (xy 409.568253 -300.887996) (xy 409.603746 -300.922088)
			(xy 409.633311 -300.961432) (xy 409.656182 -301.005009) (xy 409.671766 -301.05169) (xy 409.679661 -301.100267)
			(xy 409.680156 -301.124874) (xy 410.019004 -301.124874) (xy 410.022964 -301.07582) (xy 410.034741 -301.028036)
			(xy 410.054032 -300.98276) (xy 410.080335 -300.941164) (xy 410.11297 -300.904327) (xy 410.151091 -300.873202)
			(xy 410.193712 -300.848595) (xy 410.239728 -300.831143) (xy 410.287947 -300.821299) (xy 410.337122 -300.819318)
			(xy 410.385977 -300.82525) (xy 410.433248 -300.838942) (xy 410.47771 -300.86004) (xy 410.518213 -300.887996)
			(xy 410.553706 -300.922088) (xy 410.583271 -300.961432) (xy 410.606142 -301.005009) (xy 410.621726 -301.05169)
			(xy 410.629621 -301.100267) (xy 410.630116 -301.124874) (xy 410.969218 -301.124874) (xy 410.973178 -301.07582)
			(xy 410.984955 -301.028036) (xy 411.004246 -300.98276) (xy 411.030549 -300.941164) (xy 411.063184 -300.904327)
			(xy 411.101305 -300.873202) (xy 411.143926 -300.848595) (xy 411.189942 -300.831143) (xy 411.238161 -300.821299)
			(xy 411.287336 -300.819318) (xy 411.336191 -300.82525) (xy 411.383462 -300.838942) (xy 411.427924 -300.86004)
			(xy 411.468427 -300.887996) (xy 411.50392 -300.922088) (xy 411.533485 -300.961432) (xy 411.556356 -301.005009)
			(xy 411.57194 -301.05169) (xy 411.579835 -301.100267) (xy 411.58033 -301.124874) (xy 411.919178 -301.124874)
			(xy 411.923138 -301.07582) (xy 411.934915 -301.028036) (xy 411.954206 -300.98276) (xy 411.980509 -300.941164)
			(xy 412.013144 -300.904327) (xy 412.051265 -300.873202) (xy 412.093886 -300.848595) (xy 412.139902 -300.831143)
			(xy 412.188121 -300.821299) (xy 412.237296 -300.819318) (xy 412.286151 -300.82525) (xy 412.333422 -300.838942)
			(xy 412.377884 -300.86004) (xy 412.418387 -300.887996) (xy 412.45388 -300.922088) (xy 412.483445 -300.961432)
			(xy 412.506316 -301.005009) (xy 412.5219 -301.05169) (xy 412.529795 -301.100267) (xy 412.53029 -301.124874)
			(xy 412.869138 -301.124874) (xy 412.873098 -301.07582) (xy 412.884875 -301.028036) (xy 412.904166 -300.98276)
			(xy 412.930469 -300.941164) (xy 412.963104 -300.904327) (xy 413.001225 -300.873202) (xy 413.043846 -300.848595)
			(xy 413.089862 -300.831143) (xy 413.138081 -300.821299) (xy 413.187256 -300.819318) (xy 413.236111 -300.82525)
			(xy 413.283382 -300.838942) (xy 413.327844 -300.86004) (xy 413.368347 -300.887996) (xy 413.40384 -300.922088)
			(xy 413.433405 -300.961432) (xy 413.456276 -301.005009) (xy 413.47186 -301.05169) (xy 413.479755 -301.100267)
			(xy 413.48025 -301.124874) (xy 413.819098 -301.124874) (xy 413.823058 -301.07582) (xy 413.834835 -301.028036)
			(xy 413.854126 -300.98276) (xy 413.880429 -300.941164) (xy 413.913064 -300.904327) (xy 413.951185 -300.873202)
			(xy 413.993806 -300.848595) (xy 414.039822 -300.831143) (xy 414.088041 -300.821299) (xy 414.137216 -300.819318)
			(xy 414.186071 -300.82525) (xy 414.233342 -300.838942) (xy 414.277804 -300.86004) (xy 414.318307 -300.887996)
			(xy 414.3538 -300.922088) (xy 414.383365 -300.961432) (xy 414.406236 -301.005009) (xy 414.42182 -301.05169)
			(xy 414.429715 -301.100267) (xy 414.43021 -301.124874) (xy 414.769058 -301.124874) (xy 414.773018 -301.07582)
			(xy 414.784795 -301.028036) (xy 414.804086 -300.98276) (xy 414.830389 -300.941164) (xy 414.863024 -300.904327)
			(xy 414.901145 -300.873202) (xy 414.943766 -300.848595) (xy 414.989782 -300.831143) (xy 415.038001 -300.821299)
			(xy 415.087176 -300.819318) (xy 415.136031 -300.82525) (xy 415.183302 -300.838942) (xy 415.227764 -300.86004)
			(xy 415.268267 -300.887996) (xy 415.30376 -300.922088) (xy 415.333325 -300.961432) (xy 415.356196 -301.005009)
			(xy 415.37178 -301.05169) (xy 415.379675 -301.100267) (xy 415.38017 -301.124874) (xy 415.719018 -301.124874)
			(xy 415.722978 -301.07582) (xy 415.734755 -301.028036) (xy 415.754046 -300.98276) (xy 415.780349 -300.941164)
			(xy 415.812984 -300.904327) (xy 415.851105 -300.873202) (xy 415.893726 -300.848595) (xy 415.939742 -300.831143)
			(xy 415.987961 -300.821299) (xy 416.037136 -300.819318) (xy 416.085991 -300.82525) (xy 416.133262 -300.838942)
			(xy 416.177724 -300.86004) (xy 416.218227 -300.887996) (xy 416.25372 -300.922088) (xy 416.283285 -300.961432)
			(xy 416.306156 -301.005009) (xy 416.32174 -301.05169) (xy 416.329635 -301.100267) (xy 416.33013 -301.124874)
			(xy 416.329635 -301.149481) (xy 416.32174 -301.198058) (xy 416.306156 -301.244739) (xy 416.283285 -301.288316)
			(xy 416.25372 -301.32766) (xy 416.218227 -301.361752) (xy 416.177724 -301.389708) (xy 416.133262 -301.410806)
			(xy 416.085991 -301.424498) (xy 416.037136 -301.43043) (xy 415.987961 -301.428449) (xy 415.939742 -301.418605)
			(xy 415.893726 -301.401153) (xy 415.851105 -301.376546) (xy 415.812984 -301.345421) (xy 415.780349 -301.308584)
			(xy 415.754046 -301.266988) (xy 415.734755 -301.221712) (xy 415.722978 -301.173928) (xy 415.719018 -301.124874)
			(xy 415.38017 -301.124874) (xy 415.379675 -301.149481) (xy 415.37178 -301.198058) (xy 415.356196 -301.244739)
			(xy 415.333325 -301.288316) (xy 415.30376 -301.32766) (xy 415.268267 -301.361752) (xy 415.227764 -301.389708)
			(xy 415.183302 -301.410806) (xy 415.136031 -301.424498) (xy 415.087176 -301.43043) (xy 415.038001 -301.428449)
			(xy 414.989782 -301.418605) (xy 414.943766 -301.401153) (xy 414.901145 -301.376546) (xy 414.863024 -301.345421)
			(xy 414.830389 -301.308584) (xy 414.804086 -301.266988) (xy 414.784795 -301.221712) (xy 414.773018 -301.173928)
			(xy 414.769058 -301.124874) (xy 414.43021 -301.124874) (xy 414.429715 -301.149481) (xy 414.42182 -301.198058)
			(xy 414.406236 -301.244739) (xy 414.383365 -301.288316) (xy 414.3538 -301.32766) (xy 414.318307 -301.361752)
			(xy 414.277804 -301.389708) (xy 414.233342 -301.410806) (xy 414.186071 -301.424498) (xy 414.137216 -301.43043)
			(xy 414.088041 -301.428449) (xy 414.039822 -301.418605) (xy 413.993806 -301.401153) (xy 413.951185 -301.376546)
			(xy 413.913064 -301.345421) (xy 413.880429 -301.308584) (xy 413.854126 -301.266988) (xy 413.834835 -301.221712)
			(xy 413.823058 -301.173928) (xy 413.819098 -301.124874) (xy 413.48025 -301.124874) (xy 413.479755 -301.149481)
			(xy 413.47186 -301.198058) (xy 413.456276 -301.244739) (xy 413.433405 -301.288316) (xy 413.40384 -301.32766)
			(xy 413.368347 -301.361752) (xy 413.327844 -301.389708) (xy 413.283382 -301.410806) (xy 413.236111 -301.424498)
			(xy 413.187256 -301.43043) (xy 413.138081 -301.428449) (xy 413.089862 -301.418605) (xy 413.043846 -301.401153)
			(xy 413.001225 -301.376546) (xy 412.963104 -301.345421) (xy 412.930469 -301.308584) (xy 412.904166 -301.266988)
			(xy 412.884875 -301.221712) (xy 412.873098 -301.173928) (xy 412.869138 -301.124874) (xy 412.53029 -301.124874)
			(xy 412.529795 -301.149481) (xy 412.5219 -301.198058) (xy 412.506316 -301.244739) (xy 412.483445 -301.288316)
			(xy 412.45388 -301.32766) (xy 412.418387 -301.361752) (xy 412.377884 -301.389708) (xy 412.333422 -301.410806)
			(xy 412.286151 -301.424498) (xy 412.237296 -301.43043) (xy 412.188121 -301.428449) (xy 412.139902 -301.418605)
			(xy 412.093886 -301.401153) (xy 412.051265 -301.376546) (xy 412.013144 -301.345421) (xy 411.980509 -301.308584)
			(xy 411.954206 -301.266988) (xy 411.934915 -301.221712) (xy 411.923138 -301.173928) (xy 411.919178 -301.124874)
			(xy 411.58033 -301.124874) (xy 411.579835 -301.149481) (xy 411.57194 -301.198058) (xy 411.556356 -301.244739)
			(xy 411.533485 -301.288316) (xy 411.50392 -301.32766) (xy 411.468427 -301.361752) (xy 411.427924 -301.389708)
			(xy 411.383462 -301.410806) (xy 411.336191 -301.424498) (xy 411.287336 -301.43043) (xy 411.238161 -301.428449)
			(xy 411.189942 -301.418605) (xy 411.143926 -301.401153) (xy 411.101305 -301.376546) (xy 411.063184 -301.345421)
			(xy 411.030549 -301.308584) (xy 411.004246 -301.266988) (xy 410.984955 -301.221712) (xy 410.973178 -301.173928)
			(xy 410.969218 -301.124874) (xy 410.630116 -301.124874) (xy 410.629621 -301.149481) (xy 410.621726 -301.198058)
			(xy 410.606142 -301.244739) (xy 410.583271 -301.288316) (xy 410.553706 -301.32766) (xy 410.518213 -301.361752)
			(xy 410.47771 -301.389708) (xy 410.433248 -301.410806) (xy 410.385977 -301.424498) (xy 410.337122 -301.43043)
			(xy 410.287947 -301.428449) (xy 410.239728 -301.418605) (xy 410.193712 -301.401153) (xy 410.151091 -301.376546)
			(xy 410.11297 -301.345421) (xy 410.080335 -301.308584) (xy 410.054032 -301.266988) (xy 410.034741 -301.221712)
			(xy 410.022964 -301.173928) (xy 410.019004 -301.124874) (xy 409.680156 -301.124874) (xy 409.679661 -301.149481)
			(xy 409.671766 -301.198058) (xy 409.656182 -301.244739) (xy 409.633311 -301.288316) (xy 409.603746 -301.32766)
			(xy 409.568253 -301.361752) (xy 409.52775 -301.389708) (xy 409.483288 -301.410806) (xy 409.436017 -301.424498)
			(xy 409.387162 -301.43043) (xy 409.337987 -301.428449) (xy 409.289768 -301.418605) (xy 409.243752 -301.401153)
			(xy 409.201131 -301.376546) (xy 409.16301 -301.345421) (xy 409.130375 -301.308584) (xy 409.104072 -301.266988)
			(xy 409.084781 -301.221712) (xy 409.073004 -301.173928) (xy 409.069044 -301.124874) (xy 408.730196 -301.124874)
			(xy 408.729701 -301.149481) (xy 408.721806 -301.198058) (xy 408.706222 -301.244739) (xy 408.683351 -301.288316)
			(xy 408.653786 -301.32766) (xy 408.618293 -301.361752) (xy 408.57779 -301.389708) (xy 408.533328 -301.410806)
			(xy 408.486057 -301.424498) (xy 408.437202 -301.43043) (xy 408.388027 -301.428449) (xy 408.339808 -301.418605)
			(xy 408.293792 -301.401153) (xy 408.251171 -301.376546) (xy 408.21305 -301.345421) (xy 408.180415 -301.308584)
			(xy 408.154112 -301.266988) (xy 408.134821 -301.221712) (xy 408.123044 -301.173928) (xy 408.119084 -301.124874)
			(xy 406.830276 -301.124874) (xy 406.829781 -301.149481) (xy 406.821886 -301.198058) (xy 406.806302 -301.244739)
			(xy 406.783431 -301.288316) (xy 406.753866 -301.32766) (xy 406.718373 -301.361752) (xy 406.67787 -301.389708)
			(xy 406.633408 -301.410806) (xy 406.586137 -301.424498) (xy 406.537282 -301.43043) (xy 406.488107 -301.428449)
			(xy 406.439888 -301.418605) (xy 406.393872 -301.401153) (xy 406.351251 -301.376546) (xy 406.31313 -301.345421)
			(xy 406.280495 -301.308584) (xy 406.254192 -301.266988) (xy 406.234901 -301.221712) (xy 406.223124 -301.173928)
			(xy 406.219164 -301.124874) (xy 405.880316 -301.124874) (xy 405.879821 -301.149481) (xy 405.871926 -301.198058)
			(xy 405.856342 -301.244739) (xy 405.833471 -301.288316) (xy 405.803906 -301.32766) (xy 405.768413 -301.361752)
			(xy 405.72791 -301.389708) (xy 405.683448 -301.410806) (xy 405.636177 -301.424498) (xy 405.587322 -301.43043)
			(xy 405.538147 -301.428449) (xy 405.489928 -301.418605) (xy 405.443912 -301.401153) (xy 405.401291 -301.376546)
			(xy 405.36317 -301.345421) (xy 405.330535 -301.308584) (xy 405.304232 -301.266988) (xy 405.284941 -301.221712)
			(xy 405.273164 -301.173928) (xy 405.269204 -301.124874) (xy 404.930102 -301.124874) (xy 404.929607 -301.149481)
			(xy 404.921712 -301.198058) (xy 404.906128 -301.244739) (xy 404.883257 -301.288316) (xy 404.853692 -301.32766)
			(xy 404.818199 -301.361752) (xy 404.777696 -301.389708) (xy 404.733234 -301.410806) (xy 404.685963 -301.424498)
			(xy 404.637108 -301.43043) (xy 404.587933 -301.428449) (xy 404.539714 -301.418605) (xy 404.493698 -301.401153)
			(xy 404.451077 -301.376546) (xy 404.412956 -301.345421) (xy 404.380321 -301.308584) (xy 404.354018 -301.266988)
			(xy 404.334727 -301.221712) (xy 404.32295 -301.173928) (xy 404.31899 -301.124874) (xy 403.980142 -301.124874)
			(xy 403.979647 -301.149481) (xy 403.971752 -301.198058) (xy 403.956168 -301.244739) (xy 403.933297 -301.288316)
			(xy 403.903732 -301.32766) (xy 403.868239 -301.361752) (xy 403.827736 -301.389708) (xy 403.783274 -301.410806)
			(xy 403.736003 -301.424498) (xy 403.687148 -301.43043) (xy 403.637973 -301.428449) (xy 403.589754 -301.418605)
			(xy 403.543738 -301.401153) (xy 403.501117 -301.376546) (xy 403.462996 -301.345421) (xy 403.430361 -301.308584)
			(xy 403.404058 -301.266988) (xy 403.384767 -301.221712) (xy 403.37299 -301.173928) (xy 403.36903 -301.124874)
			(xy 403.030182 -301.124874) (xy 403.029687 -301.149481) (xy 403.021792 -301.198058) (xy 403.006208 -301.244739)
			(xy 402.983337 -301.288316) (xy 402.953772 -301.32766) (xy 402.918279 -301.361752) (xy 402.877776 -301.389708)
			(xy 402.833314 -301.410806) (xy 402.786043 -301.424498) (xy 402.737188 -301.43043) (xy 402.688013 -301.428449)
			(xy 402.639794 -301.418605) (xy 402.593778 -301.401153) (xy 402.551157 -301.376546) (xy 402.513036 -301.345421)
			(xy 402.480401 -301.308584) (xy 402.454098 -301.266988) (xy 402.434807 -301.221712) (xy 402.42303 -301.173928)
			(xy 402.41907 -301.124874) (xy 402.080222 -301.124874) (xy 402.079727 -301.149481) (xy 402.071832 -301.198058)
			(xy 402.056248 -301.244739) (xy 402.033377 -301.288316) (xy 402.003812 -301.32766) (xy 401.968319 -301.361752)
			(xy 401.927816 -301.389708) (xy 401.883354 -301.410806) (xy 401.836083 -301.424498) (xy 401.787228 -301.43043)
			(xy 401.738053 -301.428449) (xy 401.689834 -301.418605) (xy 401.643818 -301.401153) (xy 401.601197 -301.376546)
			(xy 401.563076 -301.345421) (xy 401.530441 -301.308584) (xy 401.504138 -301.266988) (xy 401.484847 -301.221712)
			(xy 401.47307 -301.173928) (xy 401.46911 -301.124874) (xy 401.130262 -301.124874) (xy 401.129767 -301.149481)
			(xy 401.121872 -301.198058) (xy 401.106288 -301.244739) (xy 401.083417 -301.288316) (xy 401.053852 -301.32766)
			(xy 401.018359 -301.361752) (xy 400.977856 -301.389708) (xy 400.933394 -301.410806) (xy 400.886123 -301.424498)
			(xy 400.837268 -301.43043) (xy 400.788093 -301.428449) (xy 400.739874 -301.418605) (xy 400.693858 -301.401153)
			(xy 400.651237 -301.376546) (xy 400.613116 -301.345421) (xy 400.580481 -301.308584) (xy 400.554178 -301.266988)
			(xy 400.534887 -301.221712) (xy 400.52311 -301.173928) (xy 400.51915 -301.124874) (xy 400.180302 -301.124874)
			(xy 400.179807 -301.149481) (xy 400.171912 -301.198058) (xy 400.156328 -301.244739) (xy 400.133457 -301.288316)
			(xy 400.103892 -301.32766) (xy 400.068399 -301.361752) (xy 400.027896 -301.389708) (xy 399.983434 -301.410806)
			(xy 399.936163 -301.424498) (xy 399.887308 -301.43043) (xy 399.838133 -301.428449) (xy 399.789914 -301.418605)
			(xy 399.743898 -301.401153) (xy 399.701277 -301.376546) (xy 399.663156 -301.345421) (xy 399.630521 -301.308584)
			(xy 399.604218 -301.266988) (xy 399.584927 -301.221712) (xy 399.57315 -301.173928) (xy 399.56919 -301.124874)
			(xy 399.230342 -301.124874) (xy 399.229847 -301.149481) (xy 399.221952 -301.198058) (xy 399.206368 -301.244739)
			(xy 399.183497 -301.288316) (xy 399.153932 -301.32766) (xy 399.118439 -301.361752) (xy 399.077936 -301.389708)
			(xy 399.033474 -301.410806) (xy 398.986203 -301.424498) (xy 398.937348 -301.43043) (xy 398.888173 -301.428449)
			(xy 398.839954 -301.418605) (xy 398.793938 -301.401153) (xy 398.751317 -301.376546) (xy 398.713196 -301.345421)
			(xy 398.680561 -301.308584) (xy 398.654258 -301.266988) (xy 398.634967 -301.221712) (xy 398.62319 -301.173928)
			(xy 398.61923 -301.124874) (xy 398.280128 -301.124874) (xy 398.279633 -301.149481) (xy 398.271738 -301.198058)
			(xy 398.256154 -301.244739) (xy 398.233283 -301.288316) (xy 398.203718 -301.32766) (xy 398.168225 -301.361752)
			(xy 398.127722 -301.389708) (xy 398.08326 -301.410806) (xy 398.035989 -301.424498) (xy 397.987134 -301.43043)
			(xy 397.937959 -301.428449) (xy 397.88974 -301.418605) (xy 397.843724 -301.401153) (xy 397.801103 -301.376546)
			(xy 397.762982 -301.345421) (xy 397.730347 -301.308584) (xy 397.704044 -301.266988) (xy 397.684753 -301.221712)
			(xy 397.672976 -301.173928) (xy 397.669016 -301.124874) (xy 396.380208 -301.124874) (xy 396.379713 -301.149481)
			(xy 396.371818 -301.198058) (xy 396.356234 -301.244739) (xy 396.333363 -301.288316) (xy 396.303798 -301.32766)
			(xy 396.268305 -301.361752) (xy 396.227802 -301.389708) (xy 396.18334 -301.410806) (xy 396.136069 -301.424498)
			(xy 396.087214 -301.43043) (xy 396.038039 -301.428449) (xy 395.98982 -301.418605) (xy 395.943804 -301.401153)
			(xy 395.901183 -301.376546) (xy 395.863062 -301.345421) (xy 395.830427 -301.308584) (xy 395.804124 -301.266988)
			(xy 395.784833 -301.221712) (xy 395.773056 -301.173928) (xy 395.769096 -301.124874) (xy 395.430248 -301.124874)
			(xy 395.429753 -301.149481) (xy 395.421858 -301.198058) (xy 395.406274 -301.244739) (xy 395.383403 -301.288316)
			(xy 395.353838 -301.32766) (xy 395.318345 -301.361752) (xy 395.277842 -301.389708) (xy 395.23338 -301.410806)
			(xy 395.186109 -301.424498) (xy 395.137254 -301.43043) (xy 395.088079 -301.428449) (xy 395.03986 -301.418605)
			(xy 394.993844 -301.401153) (xy 394.951223 -301.376546) (xy 394.913102 -301.345421) (xy 394.880467 -301.308584)
			(xy 394.854164 -301.266988) (xy 394.834873 -301.221712) (xy 394.823096 -301.173928) (xy 394.819136 -301.124874)
			(xy 394.480241 -301.124874) (xy 394.480692 -301.133203) (xy 394.475322 -301.182549) (xy 394.462039 -301.230376)
			(xy 394.441194 -301.275424) (xy 394.413335 -301.316506) (xy 394.379197 -301.35254) (xy 394.339679 -301.382577)
			(xy 394.295823 -301.405825) (xy 394.248783 -301.421671) (xy 394.199799 -301.429698) (xy 394.17498 -301.430182)
			(xy 394.160797 -301.430009) (xy 394.132557 -301.427334) (xy 394.118592 -301.424848) (xy 394.106146 -301.422562)
			(xy 394.082524 -301.429928) (xy 394.005054 -301.507398) (xy 393.997688 -301.53102) (xy 393.999974 -301.543466)
			(xy 394.002455 -301.557431) (xy 394.005124 -301.585671) (xy 394.005308 -301.599854) (xy 394.005125 -301.614037)
			(xy 394.002457 -301.642277) (xy 393.999974 -301.656242) (xy 393.997688 -301.668688) (xy 394.005054 -301.69231)
			(xy 394.082524 -301.76978) (xy 394.106146 -301.777146) (xy 394.118592 -301.77486) (xy 394.132559 -301.772389)
			(xy 394.160798 -301.769714) (xy 394.17498 -301.769526) (xy 394.200242 -301.769949) (xy 394.250076 -301.778262)
			(xy 394.297863 -301.794665) (xy 394.342298 -301.818709) (xy 394.382169 -301.849739) (xy 394.416388 -301.886909)
			(xy 394.444023 -301.929205) (xy 394.464318 -301.975472) (xy 394.476722 -302.024449) (xy 394.480894 -302.0748)
			(xy 394.480891 -302.074834) (xy 397.669016 -302.074834) (xy 397.672976 -302.02578) (xy 397.684753 -301.977996)
			(xy 397.704044 -301.93272) (xy 397.730347 -301.891124) (xy 397.762982 -301.854287) (xy 397.801103 -301.823162)
			(xy 397.843724 -301.798555) (xy 397.88974 -301.781103) (xy 397.937959 -301.771259) (xy 397.987134 -301.769278)
			(xy 398.035989 -301.77521) (xy 398.08326 -301.788902) (xy 398.127722 -301.81) (xy 398.168225 -301.837956)
			(xy 398.203718 -301.872048) (xy 398.233283 -301.911392) (xy 398.256154 -301.954969) (xy 398.271738 -302.00165)
			(xy 398.279633 -302.050227) (xy 398.280128 -302.074834) (xy 398.61923 -302.074834) (xy 398.62319 -302.02578)
			(xy 398.634967 -301.977996) (xy 398.654258 -301.93272) (xy 398.680561 -301.891124) (xy 398.713196 -301.854287)
			(xy 398.751317 -301.823162) (xy 398.793938 -301.798555) (xy 398.839954 -301.781103) (xy 398.888173 -301.771259)
			(xy 398.937348 -301.769278) (xy 398.986203 -301.77521) (xy 399.033474 -301.788902) (xy 399.077936 -301.81)
			(xy 399.118439 -301.837956) (xy 399.153932 -301.872048) (xy 399.183497 -301.911392) (xy 399.206368 -301.954969)
			(xy 399.221952 -302.00165) (xy 399.229847 -302.050227) (xy 399.230342 -302.074834) (xy 399.56919 -302.074834)
			(xy 399.57315 -302.02578) (xy 399.584927 -301.977996) (xy 399.604218 -301.93272) (xy 399.630521 -301.891124)
			(xy 399.663156 -301.854287) (xy 399.701277 -301.823162) (xy 399.743898 -301.798555) (xy 399.789914 -301.781103)
			(xy 399.838133 -301.771259) (xy 399.887308 -301.769278) (xy 399.936163 -301.77521) (xy 399.983434 -301.788902)
			(xy 400.027896 -301.81) (xy 400.068399 -301.837956) (xy 400.103892 -301.872048) (xy 400.133457 -301.911392)
			(xy 400.156328 -301.954969) (xy 400.171912 -302.00165) (xy 400.179807 -302.050227) (xy 400.180302 -302.074834)
			(xy 400.51915 -302.074834) (xy 400.52311 -302.02578) (xy 400.534887 -301.977996) (xy 400.554178 -301.93272)
			(xy 400.580481 -301.891124) (xy 400.613116 -301.854287) (xy 400.651237 -301.823162) (xy 400.693858 -301.798555)
			(xy 400.739874 -301.781103) (xy 400.788093 -301.771259) (xy 400.837268 -301.769278) (xy 400.886123 -301.77521)
			(xy 400.933394 -301.788902) (xy 400.977856 -301.81) (xy 401.018359 -301.837956) (xy 401.053852 -301.872048)
			(xy 401.083417 -301.911392) (xy 401.106288 -301.954969) (xy 401.121872 -302.00165) (xy 401.129767 -302.050227)
			(xy 401.130262 -302.074834) (xy 401.46911 -302.074834) (xy 401.47307 -302.02578) (xy 401.484847 -301.977996)
			(xy 401.504138 -301.93272) (xy 401.530441 -301.891124) (xy 401.563076 -301.854287) (xy 401.601197 -301.823162)
			(xy 401.643818 -301.798555) (xy 401.689834 -301.781103) (xy 401.738053 -301.771259) (xy 401.787228 -301.769278)
			(xy 401.836083 -301.77521) (xy 401.883354 -301.788902) (xy 401.927816 -301.81) (xy 401.968319 -301.837956)
			(xy 402.003812 -301.872048) (xy 402.033377 -301.911392) (xy 402.056248 -301.954969) (xy 402.071832 -302.00165)
			(xy 402.079727 -302.050227) (xy 402.080222 -302.074834) (xy 402.41907 -302.074834) (xy 402.42303 -302.02578)
			(xy 402.434807 -301.977996) (xy 402.454098 -301.93272) (xy 402.480401 -301.891124) (xy 402.513036 -301.854287)
			(xy 402.551157 -301.823162) (xy 402.593778 -301.798555) (xy 402.639794 -301.781103) (xy 402.688013 -301.771259)
			(xy 402.737188 -301.769278) (xy 402.786043 -301.77521) (xy 402.833314 -301.788902) (xy 402.877776 -301.81)
			(xy 402.918279 -301.837956) (xy 402.953772 -301.872048) (xy 402.983337 -301.911392) (xy 403.006208 -301.954969)
			(xy 403.021792 -302.00165) (xy 403.029687 -302.050227) (xy 403.030182 -302.074834) (xy 403.36903 -302.074834)
			(xy 403.37299 -302.02578) (xy 403.384767 -301.977996) (xy 403.404058 -301.93272) (xy 403.430361 -301.891124)
			(xy 403.462996 -301.854287) (xy 403.501117 -301.823162) (xy 403.543738 -301.798555) (xy 403.589754 -301.781103)
			(xy 403.637973 -301.771259) (xy 403.687148 -301.769278) (xy 403.736003 -301.77521) (xy 403.783274 -301.788902)
			(xy 403.827736 -301.81) (xy 403.868239 -301.837956) (xy 403.903732 -301.872048) (xy 403.933297 -301.911392)
			(xy 403.956168 -301.954969) (xy 403.971752 -302.00165) (xy 403.979647 -302.050227) (xy 403.980142 -302.074834)
			(xy 404.31899 -302.074834) (xy 404.32295 -302.02578) (xy 404.334727 -301.977996) (xy 404.354018 -301.93272)
			(xy 404.380321 -301.891124) (xy 404.412956 -301.854287) (xy 404.451077 -301.823162) (xy 404.493698 -301.798555)
			(xy 404.539714 -301.781103) (xy 404.587933 -301.771259) (xy 404.637108 -301.769278) (xy 404.685963 -301.77521)
			(xy 404.733234 -301.788902) (xy 404.777696 -301.81) (xy 404.818199 -301.837956) (xy 404.853692 -301.872048)
			(xy 404.883257 -301.911392) (xy 404.906128 -301.954969) (xy 404.921712 -302.00165) (xy 404.929607 -302.050227)
			(xy 404.930102 -302.074834) (xy 405.269204 -302.074834) (xy 405.273164 -302.02578) (xy 405.284941 -301.977996)
			(xy 405.304232 -301.93272) (xy 405.330535 -301.891124) (xy 405.36317 -301.854287) (xy 405.401291 -301.823162)
			(xy 405.443912 -301.798555) (xy 405.489928 -301.781103) (xy 405.538147 -301.771259) (xy 405.587322 -301.769278)
			(xy 405.636177 -301.77521) (xy 405.683448 -301.788902) (xy 405.72791 -301.81) (xy 405.768413 -301.837956)
			(xy 405.803906 -301.872048) (xy 405.833471 -301.911392) (xy 405.856342 -301.954969) (xy 405.871926 -302.00165)
			(xy 405.879821 -302.050227) (xy 405.880316 -302.074834) (xy 406.219164 -302.074834) (xy 406.223124 -302.02578)
			(xy 406.234901 -301.977996) (xy 406.254192 -301.93272) (xy 406.280495 -301.891124) (xy 406.31313 -301.854287)
			(xy 406.351251 -301.823162) (xy 406.393872 -301.798555) (xy 406.439888 -301.781103) (xy 406.488107 -301.771259)
			(xy 406.537282 -301.769278) (xy 406.586137 -301.77521) (xy 406.633408 -301.788902) (xy 406.67787 -301.81)
			(xy 406.718373 -301.837956) (xy 406.753866 -301.872048) (xy 406.783431 -301.911392) (xy 406.806302 -301.954969)
			(xy 406.821886 -302.00165) (xy 406.829781 -302.050227) (xy 406.830276 -302.074834) (xy 408.119084 -302.074834)
			(xy 408.123044 -302.02578) (xy 408.134821 -301.977996) (xy 408.154112 -301.93272) (xy 408.180415 -301.891124)
			(xy 408.21305 -301.854287) (xy 408.251171 -301.823162) (xy 408.293792 -301.798555) (xy 408.339808 -301.781103)
			(xy 408.388027 -301.771259) (xy 408.437202 -301.769278) (xy 408.486057 -301.77521) (xy 408.533328 -301.788902)
			(xy 408.57779 -301.81) (xy 408.618293 -301.837956) (xy 408.653786 -301.872048) (xy 408.683351 -301.911392)
			(xy 408.706222 -301.954969) (xy 408.721806 -302.00165) (xy 408.729701 -302.050227) (xy 408.730196 -302.074834)
			(xy 409.069044 -302.074834) (xy 409.073004 -302.02578) (xy 409.084781 -301.977996) (xy 409.104072 -301.93272)
			(xy 409.130375 -301.891124) (xy 409.16301 -301.854287) (xy 409.201131 -301.823162) (xy 409.243752 -301.798555)
			(xy 409.289768 -301.781103) (xy 409.337987 -301.771259) (xy 409.387162 -301.769278) (xy 409.436017 -301.77521)
			(xy 409.483288 -301.788902) (xy 409.52775 -301.81) (xy 409.568253 -301.837956) (xy 409.603746 -301.872048)
			(xy 409.633311 -301.911392) (xy 409.656182 -301.954969) (xy 409.671766 -302.00165) (xy 409.679661 -302.050227)
			(xy 409.680156 -302.074834) (xy 410.019004 -302.074834) (xy 410.022964 -302.02578) (xy 410.034741 -301.977996)
			(xy 410.054032 -301.93272) (xy 410.080335 -301.891124) (xy 410.11297 -301.854287) (xy 410.151091 -301.823162)
			(xy 410.193712 -301.798555) (xy 410.239728 -301.781103) (xy 410.287947 -301.771259) (xy 410.337122 -301.769278)
			(xy 410.385977 -301.77521) (xy 410.433248 -301.788902) (xy 410.47771 -301.81) (xy 410.518213 -301.837956)
			(xy 410.553706 -301.872048) (xy 410.583271 -301.911392) (xy 410.606142 -301.954969) (xy 410.621726 -302.00165)
			(xy 410.629621 -302.050227) (xy 410.630116 -302.074834) (xy 410.969218 -302.074834) (xy 410.973178 -302.02578)
			(xy 410.984955 -301.977996) (xy 411.004246 -301.93272) (xy 411.030549 -301.891124) (xy 411.063184 -301.854287)
			(xy 411.101305 -301.823162) (xy 411.143926 -301.798555) (xy 411.189942 -301.781103) (xy 411.238161 -301.771259)
			(xy 411.287336 -301.769278) (xy 411.336191 -301.77521) (xy 411.383462 -301.788902) (xy 411.427924 -301.81)
			(xy 411.468427 -301.837956) (xy 411.50392 -301.872048) (xy 411.533485 -301.911392) (xy 411.556356 -301.954969)
			(xy 411.57194 -302.00165) (xy 411.579835 -302.050227) (xy 411.58033 -302.074834) (xy 411.919178 -302.074834)
			(xy 411.923138 -302.02578) (xy 411.934915 -301.977996) (xy 411.954206 -301.93272) (xy 411.980509 -301.891124)
			(xy 412.013144 -301.854287) (xy 412.051265 -301.823162) (xy 412.093886 -301.798555) (xy 412.139902 -301.781103)
			(xy 412.188121 -301.771259) (xy 412.237296 -301.769278) (xy 412.286151 -301.77521) (xy 412.333422 -301.788902)
			(xy 412.377884 -301.81) (xy 412.418387 -301.837956) (xy 412.45388 -301.872048) (xy 412.483445 -301.911392)
			(xy 412.506316 -301.954969) (xy 412.5219 -302.00165) (xy 412.529795 -302.050227) (xy 412.53029 -302.074834)
			(xy 412.869138 -302.074834) (xy 412.873098 -302.02578) (xy 412.884875 -301.977996) (xy 412.904166 -301.93272)
			(xy 412.930469 -301.891124) (xy 412.963104 -301.854287) (xy 413.001225 -301.823162) (xy 413.043846 -301.798555)
			(xy 413.089862 -301.781103) (xy 413.138081 -301.771259) (xy 413.187256 -301.769278) (xy 413.236111 -301.77521)
			(xy 413.283382 -301.788902) (xy 413.327844 -301.81) (xy 413.368347 -301.837956) (xy 413.40384 -301.872048)
			(xy 413.433405 -301.911392) (xy 413.456276 -301.954969) (xy 413.47186 -302.00165) (xy 413.479755 -302.050227)
			(xy 413.48025 -302.074834) (xy 413.819098 -302.074834) (xy 413.823058 -302.02578) (xy 413.834835 -301.977996)
			(xy 413.854126 -301.93272) (xy 413.880429 -301.891124) (xy 413.913064 -301.854287) (xy 413.951185 -301.823162)
			(xy 413.993806 -301.798555) (xy 414.039822 -301.781103) (xy 414.088041 -301.771259) (xy 414.137216 -301.769278)
			(xy 414.186071 -301.77521) (xy 414.233342 -301.788902) (xy 414.277804 -301.81) (xy 414.318307 -301.837956)
			(xy 414.3538 -301.872048) (xy 414.383365 -301.911392) (xy 414.406236 -301.954969) (xy 414.42182 -302.00165)
			(xy 414.429715 -302.050227) (xy 414.43021 -302.074834) (xy 414.769058 -302.074834) (xy 414.773018 -302.02578)
			(xy 414.784795 -301.977996) (xy 414.804086 -301.93272) (xy 414.830389 -301.891124) (xy 414.863024 -301.854287)
			(xy 414.901145 -301.823162) (xy 414.943766 -301.798555) (xy 414.989782 -301.781103) (xy 415.038001 -301.771259)
			(xy 415.087176 -301.769278) (xy 415.136031 -301.77521) (xy 415.183302 -301.788902) (xy 415.227764 -301.81)
			(xy 415.268267 -301.837956) (xy 415.30376 -301.872048) (xy 415.333325 -301.911392) (xy 415.356196 -301.954969)
			(xy 415.37178 -302.00165) (xy 415.379675 -302.050227) (xy 415.38017 -302.074834) (xy 415.719018 -302.074834)
			(xy 415.722978 -302.02578) (xy 415.734755 -301.977996) (xy 415.754046 -301.93272) (xy 415.780349 -301.891124)
			(xy 415.812984 -301.854287) (xy 415.851105 -301.823162) (xy 415.893726 -301.798555) (xy 415.939742 -301.781103)
			(xy 415.987961 -301.771259) (xy 416.037136 -301.769278) (xy 416.085991 -301.77521) (xy 416.133262 -301.788902)
			(xy 416.177724 -301.81) (xy 416.218227 -301.837956) (xy 416.25372 -301.872048) (xy 416.283285 -301.911392)
			(xy 416.306156 -301.954969) (xy 416.32174 -302.00165) (xy 416.329635 -302.050227) (xy 416.33013 -302.074834)
			(xy 416.329635 -302.099441) (xy 416.32174 -302.148018) (xy 416.306156 -302.194699) (xy 416.283285 -302.238276)
			(xy 416.25372 -302.27762) (xy 416.218227 -302.311712) (xy 416.177724 -302.339668) (xy 416.133262 -302.360766)
			(xy 416.085991 -302.374458) (xy 416.037136 -302.38039) (xy 415.987961 -302.378409) (xy 415.939742 -302.368565)
			(xy 415.893726 -302.351113) (xy 415.851105 -302.326506) (xy 415.812984 -302.295381) (xy 415.780349 -302.258544)
			(xy 415.754046 -302.216948) (xy 415.734755 -302.171672) (xy 415.722978 -302.123888) (xy 415.719018 -302.074834)
			(xy 415.38017 -302.074834) (xy 415.379675 -302.099441) (xy 415.37178 -302.148018) (xy 415.356196 -302.194699)
			(xy 415.333325 -302.238276) (xy 415.30376 -302.27762) (xy 415.268267 -302.311712) (xy 415.227764 -302.339668)
			(xy 415.183302 -302.360766) (xy 415.136031 -302.374458) (xy 415.087176 -302.38039) (xy 415.038001 -302.378409)
			(xy 414.989782 -302.368565) (xy 414.943766 -302.351113) (xy 414.901145 -302.326506) (xy 414.863024 -302.295381)
			(xy 414.830389 -302.258544) (xy 414.804086 -302.216948) (xy 414.784795 -302.171672) (xy 414.773018 -302.123888)
			(xy 414.769058 -302.074834) (xy 414.43021 -302.074834) (xy 414.429715 -302.099441) (xy 414.42182 -302.148018)
			(xy 414.406236 -302.194699) (xy 414.383365 -302.238276) (xy 414.3538 -302.27762) (xy 414.318307 -302.311712)
			(xy 414.277804 -302.339668) (xy 414.233342 -302.360766) (xy 414.186071 -302.374458) (xy 414.137216 -302.38039)
			(xy 414.088041 -302.378409) (xy 414.039822 -302.368565) (xy 413.993806 -302.351113) (xy 413.951185 -302.326506)
			(xy 413.913064 -302.295381) (xy 413.880429 -302.258544) (xy 413.854126 -302.216948) (xy 413.834835 -302.171672)
			(xy 413.823058 -302.123888) (xy 413.819098 -302.074834) (xy 413.48025 -302.074834) (xy 413.479755 -302.099441)
			(xy 413.47186 -302.148018) (xy 413.456276 -302.194699) (xy 413.433405 -302.238276) (xy 413.40384 -302.27762)
			(xy 413.368347 -302.311712) (xy 413.327844 -302.339668) (xy 413.283382 -302.360766) (xy 413.236111 -302.374458)
			(xy 413.187256 -302.38039) (xy 413.138081 -302.378409) (xy 413.089862 -302.368565) (xy 413.043846 -302.351113)
			(xy 413.001225 -302.326506) (xy 412.963104 -302.295381) (xy 412.930469 -302.258544) (xy 412.904166 -302.216948)
			(xy 412.884875 -302.171672) (xy 412.873098 -302.123888) (xy 412.869138 -302.074834) (xy 412.53029 -302.074834)
			(xy 412.529795 -302.099441) (xy 412.5219 -302.148018) (xy 412.506316 -302.194699) (xy 412.483445 -302.238276)
			(xy 412.45388 -302.27762) (xy 412.418387 -302.311712) (xy 412.377884 -302.339668) (xy 412.333422 -302.360766)
			(xy 412.286151 -302.374458) (xy 412.237296 -302.38039) (xy 412.188121 -302.378409) (xy 412.139902 -302.368565)
			(xy 412.093886 -302.351113) (xy 412.051265 -302.326506) (xy 412.013144 -302.295381) (xy 411.980509 -302.258544)
			(xy 411.954206 -302.216948) (xy 411.934915 -302.171672) (xy 411.923138 -302.123888) (xy 411.919178 -302.074834)
			(xy 411.58033 -302.074834) (xy 411.579835 -302.099441) (xy 411.57194 -302.148018) (xy 411.556356 -302.194699)
			(xy 411.533485 -302.238276) (xy 411.50392 -302.27762) (xy 411.468427 -302.311712) (xy 411.427924 -302.339668)
			(xy 411.383462 -302.360766) (xy 411.336191 -302.374458) (xy 411.287336 -302.38039) (xy 411.238161 -302.378409)
			(xy 411.189942 -302.368565) (xy 411.143926 -302.351113) (xy 411.101305 -302.326506) (xy 411.063184 -302.295381)
			(xy 411.030549 -302.258544) (xy 411.004246 -302.216948) (xy 410.984955 -302.171672) (xy 410.973178 -302.123888)
			(xy 410.969218 -302.074834) (xy 410.630116 -302.074834) (xy 410.629621 -302.099441) (xy 410.621726 -302.148018)
			(xy 410.606142 -302.194699) (xy 410.583271 -302.238276) (xy 410.553706 -302.27762) (xy 410.518213 -302.311712)
			(xy 410.47771 -302.339668) (xy 410.433248 -302.360766) (xy 410.385977 -302.374458) (xy 410.337122 -302.38039)
			(xy 410.287947 -302.378409) (xy 410.239728 -302.368565) (xy 410.193712 -302.351113) (xy 410.151091 -302.326506)
			(xy 410.11297 -302.295381) (xy 410.080335 -302.258544) (xy 410.054032 -302.216948) (xy 410.034741 -302.171672)
			(xy 410.022964 -302.123888) (xy 410.019004 -302.074834) (xy 409.680156 -302.074834) (xy 409.679661 -302.099441)
			(xy 409.671766 -302.148018) (xy 409.656182 -302.194699) (xy 409.633311 -302.238276) (xy 409.603746 -302.27762)
			(xy 409.568253 -302.311712) (xy 409.52775 -302.339668) (xy 409.483288 -302.360766) (xy 409.436017 -302.374458)
			(xy 409.387162 -302.38039) (xy 409.337987 -302.378409) (xy 409.289768 -302.368565) (xy 409.243752 -302.351113)
			(xy 409.201131 -302.326506) (xy 409.16301 -302.295381) (xy 409.130375 -302.258544) (xy 409.104072 -302.216948)
			(xy 409.084781 -302.171672) (xy 409.073004 -302.123888) (xy 409.069044 -302.074834) (xy 408.730196 -302.074834)
			(xy 408.729701 -302.099441) (xy 408.721806 -302.148018) (xy 408.706222 -302.194699) (xy 408.683351 -302.238276)
			(xy 408.653786 -302.27762) (xy 408.618293 -302.311712) (xy 408.57779 -302.339668) (xy 408.533328 -302.360766)
			(xy 408.486057 -302.374458) (xy 408.437202 -302.38039) (xy 408.388027 -302.378409) (xy 408.339808 -302.368565)
			(xy 408.293792 -302.351113) (xy 408.251171 -302.326506) (xy 408.21305 -302.295381) (xy 408.180415 -302.258544)
			(xy 408.154112 -302.216948) (xy 408.134821 -302.171672) (xy 408.123044 -302.123888) (xy 408.119084 -302.074834)
			(xy 406.830276 -302.074834) (xy 406.829781 -302.099441) (xy 406.821886 -302.148018) (xy 406.806302 -302.194699)
			(xy 406.783431 -302.238276) (xy 406.753866 -302.27762) (xy 406.718373 -302.311712) (xy 406.67787 -302.339668)
			(xy 406.633408 -302.360766) (xy 406.586137 -302.374458) (xy 406.537282 -302.38039) (xy 406.488107 -302.378409)
			(xy 406.439888 -302.368565) (xy 406.393872 -302.351113) (xy 406.351251 -302.326506) (xy 406.31313 -302.295381)
			(xy 406.280495 -302.258544) (xy 406.254192 -302.216948) (xy 406.234901 -302.171672) (xy 406.223124 -302.123888)
			(xy 406.219164 -302.074834) (xy 405.880316 -302.074834) (xy 405.879821 -302.099441) (xy 405.871926 -302.148018)
			(xy 405.856342 -302.194699) (xy 405.833471 -302.238276) (xy 405.803906 -302.27762) (xy 405.768413 -302.311712)
			(xy 405.72791 -302.339668) (xy 405.683448 -302.360766) (xy 405.636177 -302.374458) (xy 405.587322 -302.38039)
			(xy 405.538147 -302.378409) (xy 405.489928 -302.368565) (xy 405.443912 -302.351113) (xy 405.401291 -302.326506)
			(xy 405.36317 -302.295381) (xy 405.330535 -302.258544) (xy 405.304232 -302.216948) (xy 405.284941 -302.171672)
			(xy 405.273164 -302.123888) (xy 405.269204 -302.074834) (xy 404.930102 -302.074834) (xy 404.929607 -302.099441)
			(xy 404.921712 -302.148018) (xy 404.906128 -302.194699) (xy 404.883257 -302.238276) (xy 404.853692 -302.27762)
			(xy 404.818199 -302.311712) (xy 404.777696 -302.339668) (xy 404.733234 -302.360766) (xy 404.685963 -302.374458)
			(xy 404.637108 -302.38039) (xy 404.587933 -302.378409) (xy 404.539714 -302.368565) (xy 404.493698 -302.351113)
			(xy 404.451077 -302.326506) (xy 404.412956 -302.295381) (xy 404.380321 -302.258544) (xy 404.354018 -302.216948)
			(xy 404.334727 -302.171672) (xy 404.32295 -302.123888) (xy 404.31899 -302.074834) (xy 403.980142 -302.074834)
			(xy 403.979647 -302.099441) (xy 403.971752 -302.148018) (xy 403.956168 -302.194699) (xy 403.933297 -302.238276)
			(xy 403.903732 -302.27762) (xy 403.868239 -302.311712) (xy 403.827736 -302.339668) (xy 403.783274 -302.360766)
			(xy 403.736003 -302.374458) (xy 403.687148 -302.38039) (xy 403.637973 -302.378409) (xy 403.589754 -302.368565)
			(xy 403.543738 -302.351113) (xy 403.501117 -302.326506) (xy 403.462996 -302.295381) (xy 403.430361 -302.258544)
			(xy 403.404058 -302.216948) (xy 403.384767 -302.171672) (xy 403.37299 -302.123888) (xy 403.36903 -302.074834)
			(xy 403.030182 -302.074834) (xy 403.029687 -302.099441) (xy 403.021792 -302.148018) (xy 403.006208 -302.194699)
			(xy 402.983337 -302.238276) (xy 402.953772 -302.27762) (xy 402.918279 -302.311712) (xy 402.877776 -302.339668)
			(xy 402.833314 -302.360766) (xy 402.786043 -302.374458) (xy 402.737188 -302.38039) (xy 402.688013 -302.378409)
			(xy 402.639794 -302.368565) (xy 402.593778 -302.351113) (xy 402.551157 -302.326506) (xy 402.513036 -302.295381)
			(xy 402.480401 -302.258544) (xy 402.454098 -302.216948) (xy 402.434807 -302.171672) (xy 402.42303 -302.123888)
			(xy 402.41907 -302.074834) (xy 402.080222 -302.074834) (xy 402.079727 -302.099441) (xy 402.071832 -302.148018)
			(xy 402.056248 -302.194699) (xy 402.033377 -302.238276) (xy 402.003812 -302.27762) (xy 401.968319 -302.311712)
			(xy 401.927816 -302.339668) (xy 401.883354 -302.360766) (xy 401.836083 -302.374458) (xy 401.787228 -302.38039)
			(xy 401.738053 -302.378409) (xy 401.689834 -302.368565) (xy 401.643818 -302.351113) (xy 401.601197 -302.326506)
			(xy 401.563076 -302.295381) (xy 401.530441 -302.258544) (xy 401.504138 -302.216948) (xy 401.484847 -302.171672)
			(xy 401.47307 -302.123888) (xy 401.46911 -302.074834) (xy 401.130262 -302.074834) (xy 401.129767 -302.099441)
			(xy 401.121872 -302.148018) (xy 401.106288 -302.194699) (xy 401.083417 -302.238276) (xy 401.053852 -302.27762)
			(xy 401.018359 -302.311712) (xy 400.977856 -302.339668) (xy 400.933394 -302.360766) (xy 400.886123 -302.374458)
			(xy 400.837268 -302.38039) (xy 400.788093 -302.378409) (xy 400.739874 -302.368565) (xy 400.693858 -302.351113)
			(xy 400.651237 -302.326506) (xy 400.613116 -302.295381) (xy 400.580481 -302.258544) (xy 400.554178 -302.216948)
			(xy 400.534887 -302.171672) (xy 400.52311 -302.123888) (xy 400.51915 -302.074834) (xy 400.180302 -302.074834)
			(xy 400.179807 -302.099441) (xy 400.171912 -302.148018) (xy 400.156328 -302.194699) (xy 400.133457 -302.238276)
			(xy 400.103892 -302.27762) (xy 400.068399 -302.311712) (xy 400.027896 -302.339668) (xy 399.983434 -302.360766)
			(xy 399.936163 -302.374458) (xy 399.887308 -302.38039) (xy 399.838133 -302.378409) (xy 399.789914 -302.368565)
			(xy 399.743898 -302.351113) (xy 399.701277 -302.326506) (xy 399.663156 -302.295381) (xy 399.630521 -302.258544)
			(xy 399.604218 -302.216948) (xy 399.584927 -302.171672) (xy 399.57315 -302.123888) (xy 399.56919 -302.074834)
			(xy 399.230342 -302.074834) (xy 399.229847 -302.099441) (xy 399.221952 -302.148018) (xy 399.206368 -302.194699)
			(xy 399.183497 -302.238276) (xy 399.153932 -302.27762) (xy 399.118439 -302.311712) (xy 399.077936 -302.339668)
			(xy 399.033474 -302.360766) (xy 398.986203 -302.374458) (xy 398.937348 -302.38039) (xy 398.888173 -302.378409)
			(xy 398.839954 -302.368565) (xy 398.793938 -302.351113) (xy 398.751317 -302.326506) (xy 398.713196 -302.295381)
			(xy 398.680561 -302.258544) (xy 398.654258 -302.216948) (xy 398.634967 -302.171672) (xy 398.62319 -302.123888)
			(xy 398.61923 -302.074834) (xy 398.280128 -302.074834) (xy 398.279633 -302.099441) (xy 398.271738 -302.148018)
			(xy 398.256154 -302.194699) (xy 398.233283 -302.238276) (xy 398.203718 -302.27762) (xy 398.168225 -302.311712)
			(xy 398.127722 -302.339668) (xy 398.08326 -302.360766) (xy 398.035989 -302.374458) (xy 397.987134 -302.38039)
			(xy 397.937959 -302.378409) (xy 397.88974 -302.368565) (xy 397.843724 -302.351113) (xy 397.801103 -302.326506)
			(xy 397.762982 -302.295381) (xy 397.730347 -302.258544) (xy 397.704044 -302.216948) (xy 397.684753 -302.171672)
			(xy 397.672976 -302.123888) (xy 397.669016 -302.074834) (xy 394.480891 -302.074834) (xy 394.476722 -302.125151)
			(xy 394.464318 -302.174128) (xy 394.444023 -302.220395) (xy 394.416388 -302.262691) (xy 394.382169 -302.299861)
			(xy 394.342298 -302.330891) (xy 394.297863 -302.354935) (xy 394.250076 -302.371338) (xy 394.200242 -302.379651)
			(xy 394.17498 -302.380142) (xy 394.160797 -302.379968) (xy 394.132557 -302.377294) (xy 394.118592 -302.374808)
			(xy 394.106146 -302.372522) (xy 394.082524 -302.379888) (xy 394.005054 -302.457358) (xy 393.997688 -302.48098)
			(xy 393.999974 -302.493426) (xy 394.00245 -302.507392) (xy 394.005122 -302.535631) (xy 394.005308 -302.549814)
			(xy 394.005133 -302.563997) (xy 394.00246 -302.592237) (xy 393.999974 -302.606202) (xy 393.997688 -302.618648)
			(xy 394.005054 -302.64227) (xy 394.082524 -302.71974) (xy 394.106146 -302.727106) (xy 394.118592 -302.72482)
			(xy 394.132559 -302.722349) (xy 394.160798 -302.719673) (xy 394.17498 -302.719486) (xy 394.200238 -302.719989)
			(xy 394.250066 -302.728301) (xy 394.297847 -302.744701) (xy 394.342276 -302.768742) (xy 394.382142 -302.799769)
			(xy 394.416357 -302.836934) (xy 394.443988 -302.879224) (xy 394.464281 -302.925485) (xy 394.476682 -302.974456)
			(xy 394.480854 -303.024794) (xy 394.819136 -303.024794) (xy 394.823096 -302.97574) (xy 394.834873 -302.927956)
			(xy 394.854164 -302.88268) (xy 394.880467 -302.841084) (xy 394.913102 -302.804247) (xy 394.951223 -302.773122)
			(xy 394.993844 -302.748515) (xy 395.03986 -302.731063) (xy 395.088079 -302.721219) (xy 395.137254 -302.719238)
			(xy 395.186109 -302.72517) (xy 395.23338 -302.738862) (xy 395.277842 -302.75996) (xy 395.318345 -302.787916)
			(xy 395.353838 -302.822008) (xy 395.383403 -302.861352) (xy 395.406274 -302.904929) (xy 395.421858 -302.95161)
			(xy 395.429753 -303.000187) (xy 395.430248 -303.024794) (xy 395.769096 -303.024794) (xy 395.773056 -302.97574)
			(xy 395.784833 -302.927956) (xy 395.804124 -302.88268) (xy 395.830427 -302.841084) (xy 395.863062 -302.804247)
			(xy 395.901183 -302.773122) (xy 395.943804 -302.748515) (xy 395.98982 -302.731063) (xy 396.038039 -302.721219)
			(xy 396.087214 -302.719238) (xy 396.136069 -302.72517) (xy 396.18334 -302.738862) (xy 396.227802 -302.75996)
			(xy 396.268305 -302.787916) (xy 396.303798 -302.822008) (xy 396.333363 -302.861352) (xy 396.356234 -302.904929)
			(xy 396.371818 -302.95161) (xy 396.379713 -303.000187) (xy 396.380208 -303.024794) (xy 396.719056 -303.024794)
			(xy 396.723016 -302.97574) (xy 396.734793 -302.927956) (xy 396.754084 -302.88268) (xy 396.780387 -302.841084)
			(xy 396.813022 -302.804247) (xy 396.851143 -302.773122) (xy 396.893764 -302.748515) (xy 396.93978 -302.731063)
			(xy 396.987999 -302.721219) (xy 397.037174 -302.719238) (xy 397.086029 -302.72517) (xy 397.1333 -302.738862)
			(xy 397.177762 -302.75996) (xy 397.218265 -302.787916) (xy 397.253758 -302.822008) (xy 397.283323 -302.861352)
			(xy 397.306194 -302.904929) (xy 397.321778 -302.95161) (xy 397.329673 -303.000187) (xy 397.330168 -303.024794)
			(xy 397.669016 -303.024794) (xy 397.672976 -302.97574) (xy 397.684753 -302.927956) (xy 397.704044 -302.88268)
			(xy 397.730347 -302.841084) (xy 397.762982 -302.804247) (xy 397.801103 -302.773122) (xy 397.843724 -302.748515)
			(xy 397.88974 -302.731063) (xy 397.937959 -302.721219) (xy 397.987134 -302.719238) (xy 398.035989 -302.72517)
			(xy 398.08326 -302.738862) (xy 398.127722 -302.75996) (xy 398.168225 -302.787916) (xy 398.203718 -302.822008)
			(xy 398.233283 -302.861352) (xy 398.256154 -302.904929) (xy 398.271738 -302.95161) (xy 398.279633 -303.000187)
			(xy 398.280128 -303.024794) (xy 398.61923 -303.024794) (xy 398.62319 -302.97574) (xy 398.634967 -302.927956)
			(xy 398.654258 -302.88268) (xy 398.680561 -302.841084) (xy 398.713196 -302.804247) (xy 398.751317 -302.773122)
			(xy 398.793938 -302.748515) (xy 398.839954 -302.731063) (xy 398.888173 -302.721219) (xy 398.937348 -302.719238)
			(xy 398.986203 -302.72517) (xy 399.033474 -302.738862) (xy 399.077936 -302.75996) (xy 399.118439 -302.787916)
			(xy 399.153932 -302.822008) (xy 399.183497 -302.861352) (xy 399.206368 -302.904929) (xy 399.221952 -302.95161)
			(xy 399.229847 -303.000187) (xy 399.230342 -303.024794) (xy 399.56919 -303.024794) (xy 399.57315 -302.97574)
			(xy 399.584927 -302.927956) (xy 399.604218 -302.88268) (xy 399.630521 -302.841084) (xy 399.663156 -302.804247)
			(xy 399.701277 -302.773122) (xy 399.743898 -302.748515) (xy 399.789914 -302.731063) (xy 399.838133 -302.721219)
			(xy 399.887308 -302.719238) (xy 399.936163 -302.72517) (xy 399.983434 -302.738862) (xy 400.027896 -302.75996)
			(xy 400.068399 -302.787916) (xy 400.103892 -302.822008) (xy 400.133457 -302.861352) (xy 400.156328 -302.904929)
			(xy 400.171912 -302.95161) (xy 400.179807 -303.000187) (xy 400.180302 -303.024794) (xy 400.51915 -303.024794)
			(xy 400.52311 -302.97574) (xy 400.534887 -302.927956) (xy 400.554178 -302.88268) (xy 400.580481 -302.841084)
			(xy 400.613116 -302.804247) (xy 400.651237 -302.773122) (xy 400.693858 -302.748515) (xy 400.739874 -302.731063)
			(xy 400.788093 -302.721219) (xy 400.837268 -302.719238) (xy 400.886123 -302.72517) (xy 400.933394 -302.738862)
			(xy 400.977856 -302.75996) (xy 401.018359 -302.787916) (xy 401.053852 -302.822008) (xy 401.083417 -302.861352)
			(xy 401.106288 -302.904929) (xy 401.121872 -302.95161) (xy 401.129767 -303.000187) (xy 401.130262 -303.024794)
			(xy 401.46911 -303.024794) (xy 401.47307 -302.97574) (xy 401.484847 -302.927956) (xy 401.504138 -302.88268)
			(xy 401.530441 -302.841084) (xy 401.563076 -302.804247) (xy 401.601197 -302.773122) (xy 401.643818 -302.748515)
			(xy 401.689834 -302.731063) (xy 401.738053 -302.721219) (xy 401.787228 -302.719238) (xy 401.836083 -302.72517)
			(xy 401.883354 -302.738862) (xy 401.927816 -302.75996) (xy 401.968319 -302.787916) (xy 402.003812 -302.822008)
			(xy 402.033377 -302.861352) (xy 402.056248 -302.904929) (xy 402.071832 -302.95161) (xy 402.079727 -303.000187)
			(xy 402.080222 -303.024794) (xy 402.41907 -303.024794) (xy 402.42303 -302.97574) (xy 402.434807 -302.927956)
			(xy 402.454098 -302.88268) (xy 402.480401 -302.841084) (xy 402.513036 -302.804247) (xy 402.551157 -302.773122)
			(xy 402.593778 -302.748515) (xy 402.639794 -302.731063) (xy 402.688013 -302.721219) (xy 402.737188 -302.719238)
			(xy 402.786043 -302.72517) (xy 402.833314 -302.738862) (xy 402.877776 -302.75996) (xy 402.918279 -302.787916)
			(xy 402.953772 -302.822008) (xy 402.983337 -302.861352) (xy 403.006208 -302.904929) (xy 403.021792 -302.95161)
			(xy 403.029687 -303.000187) (xy 403.030182 -303.024794) (xy 403.36903 -303.024794) (xy 403.37299 -302.97574)
			(xy 403.384767 -302.927956) (xy 403.404058 -302.88268) (xy 403.430361 -302.841084) (xy 403.462996 -302.804247)
			(xy 403.501117 -302.773122) (xy 403.543738 -302.748515) (xy 403.589754 -302.731063) (xy 403.637973 -302.721219)
			(xy 403.687148 -302.719238) (xy 403.736003 -302.72517) (xy 403.783274 -302.738862) (xy 403.827736 -302.75996)
			(xy 403.868239 -302.787916) (xy 403.903732 -302.822008) (xy 403.933297 -302.861352) (xy 403.956168 -302.904929)
			(xy 403.971752 -302.95161) (xy 403.979647 -303.000187) (xy 403.980142 -303.024794) (xy 404.31899 -303.024794)
			(xy 404.32295 -302.97574) (xy 404.334727 -302.927956) (xy 404.354018 -302.88268) (xy 404.380321 -302.841084)
			(xy 404.412956 -302.804247) (xy 404.451077 -302.773122) (xy 404.493698 -302.748515) (xy 404.539714 -302.731063)
			(xy 404.587933 -302.721219) (xy 404.637108 -302.719238) (xy 404.685963 -302.72517) (xy 404.733234 -302.738862)
			(xy 404.777696 -302.75996) (xy 404.818199 -302.787916) (xy 404.853692 -302.822008) (xy 404.883257 -302.861352)
			(xy 404.906128 -302.904929) (xy 404.921712 -302.95161) (xy 404.929607 -303.000187) (xy 404.930102 -303.024794)
			(xy 405.269204 -303.024794) (xy 405.273164 -302.97574) (xy 405.284941 -302.927956) (xy 405.304232 -302.88268)
			(xy 405.330535 -302.841084) (xy 405.36317 -302.804247) (xy 405.401291 -302.773122) (xy 405.443912 -302.748515)
			(xy 405.489928 -302.731063) (xy 405.538147 -302.721219) (xy 405.587322 -302.719238) (xy 405.636177 -302.72517)
			(xy 405.683448 -302.738862) (xy 405.72791 -302.75996) (xy 405.768413 -302.787916) (xy 405.803906 -302.822008)
			(xy 405.833471 -302.861352) (xy 405.856342 -302.904929) (xy 405.871926 -302.95161) (xy 405.879821 -303.000187)
			(xy 405.880316 -303.024794) (xy 406.219164 -303.024794) (xy 406.223124 -302.97574) (xy 406.234901 -302.927956)
			(xy 406.254192 -302.88268) (xy 406.280495 -302.841084) (xy 406.31313 -302.804247) (xy 406.351251 -302.773122)
			(xy 406.393872 -302.748515) (xy 406.439888 -302.731063) (xy 406.488107 -302.721219) (xy 406.537282 -302.719238)
			(xy 406.586137 -302.72517) (xy 406.633408 -302.738862) (xy 406.67787 -302.75996) (xy 406.718373 -302.787916)
			(xy 406.753866 -302.822008) (xy 406.783431 -302.861352) (xy 406.806302 -302.904929) (xy 406.821886 -302.95161)
			(xy 406.829781 -303.000187) (xy 406.830276 -303.024794) (xy 408.119084 -303.024794) (xy 408.123044 -302.97574)
			(xy 408.134821 -302.927956) (xy 408.154112 -302.88268) (xy 408.180415 -302.841084) (xy 408.21305 -302.804247)
			(xy 408.251171 -302.773122) (xy 408.293792 -302.748515) (xy 408.339808 -302.731063) (xy 408.388027 -302.721219)
			(xy 408.437202 -302.719238) (xy 408.486057 -302.72517) (xy 408.533328 -302.738862) (xy 408.57779 -302.75996)
			(xy 408.618293 -302.787916) (xy 408.653786 -302.822008) (xy 408.683351 -302.861352) (xy 408.706222 -302.904929)
			(xy 408.721806 -302.95161) (xy 408.729701 -303.000187) (xy 408.730196 -303.024794) (xy 409.069044 -303.024794)
			(xy 409.073004 -302.97574) (xy 409.084781 -302.927956) (xy 409.104072 -302.88268) (xy 409.130375 -302.841084)
			(xy 409.16301 -302.804247) (xy 409.201131 -302.773122) (xy 409.243752 -302.748515) (xy 409.289768 -302.731063)
			(xy 409.337987 -302.721219) (xy 409.387162 -302.719238) (xy 409.436017 -302.72517) (xy 409.483288 -302.738862)
			(xy 409.52775 -302.75996) (xy 409.568253 -302.787916) (xy 409.603746 -302.822008) (xy 409.633311 -302.861352)
			(xy 409.656182 -302.904929) (xy 409.671766 -302.95161) (xy 409.679661 -303.000187) (xy 409.680156 -303.024794)
			(xy 410.019004 -303.024794) (xy 410.022964 -302.97574) (xy 410.034741 -302.927956) (xy 410.054032 -302.88268)
			(xy 410.080335 -302.841084) (xy 410.11297 -302.804247) (xy 410.151091 -302.773122) (xy 410.193712 -302.748515)
			(xy 410.239728 -302.731063) (xy 410.287947 -302.721219) (xy 410.337122 -302.719238) (xy 410.385977 -302.72517)
			(xy 410.433248 -302.738862) (xy 410.47771 -302.75996) (xy 410.518213 -302.787916) (xy 410.553706 -302.822008)
			(xy 410.583271 -302.861352) (xy 410.606142 -302.904929) (xy 410.621726 -302.95161) (xy 410.629621 -303.000187)
			(xy 410.630116 -303.024794) (xy 410.969218 -303.024794) (xy 410.973178 -302.97574) (xy 410.984955 -302.927956)
			(xy 411.004246 -302.88268) (xy 411.030549 -302.841084) (xy 411.063184 -302.804247) (xy 411.101305 -302.773122)
			(xy 411.143926 -302.748515) (xy 411.189942 -302.731063) (xy 411.238161 -302.721219) (xy 411.287336 -302.719238)
			(xy 411.336191 -302.72517) (xy 411.383462 -302.738862) (xy 411.427924 -302.75996) (xy 411.468427 -302.787916)
			(xy 411.50392 -302.822008) (xy 411.533485 -302.861352) (xy 411.556356 -302.904929) (xy 411.57194 -302.95161)
			(xy 411.579835 -303.000187) (xy 411.58033 -303.024794) (xy 411.919178 -303.024794) (xy 411.923138 -302.97574)
			(xy 411.934915 -302.927956) (xy 411.954206 -302.88268) (xy 411.980509 -302.841084) (xy 412.013144 -302.804247)
			(xy 412.051265 -302.773122) (xy 412.093886 -302.748515) (xy 412.139902 -302.731063) (xy 412.188121 -302.721219)
			(xy 412.237296 -302.719238) (xy 412.286151 -302.72517) (xy 412.333422 -302.738862) (xy 412.377884 -302.75996)
			(xy 412.418387 -302.787916) (xy 412.45388 -302.822008) (xy 412.483445 -302.861352) (xy 412.506316 -302.904929)
			(xy 412.5219 -302.95161) (xy 412.529795 -303.000187) (xy 412.53029 -303.024794) (xy 412.869138 -303.024794)
			(xy 412.873098 -302.97574) (xy 412.884875 -302.927956) (xy 412.904166 -302.88268) (xy 412.930469 -302.841084)
			(xy 412.963104 -302.804247) (xy 413.001225 -302.773122) (xy 413.043846 -302.748515) (xy 413.089862 -302.731063)
			(xy 413.138081 -302.721219) (xy 413.187256 -302.719238) (xy 413.236111 -302.72517) (xy 413.283382 -302.738862)
			(xy 413.327844 -302.75996) (xy 413.368347 -302.787916) (xy 413.40384 -302.822008) (xy 413.433405 -302.861352)
			(xy 413.456276 -302.904929) (xy 413.47186 -302.95161) (xy 413.479755 -303.000187) (xy 413.48025 -303.024794)
			(xy 413.819098 -303.024794) (xy 413.823058 -302.97574) (xy 413.834835 -302.927956) (xy 413.854126 -302.88268)
			(xy 413.880429 -302.841084) (xy 413.913064 -302.804247) (xy 413.951185 -302.773122) (xy 413.993806 -302.748515)
			(xy 414.039822 -302.731063) (xy 414.088041 -302.721219) (xy 414.137216 -302.719238) (xy 414.186071 -302.72517)
			(xy 414.233342 -302.738862) (xy 414.277804 -302.75996) (xy 414.318307 -302.787916) (xy 414.3538 -302.822008)
			(xy 414.383365 -302.861352) (xy 414.406236 -302.904929) (xy 414.42182 -302.95161) (xy 414.429715 -303.000187)
			(xy 414.43021 -303.024794) (xy 414.769058 -303.024794) (xy 414.773018 -302.97574) (xy 414.784795 -302.927956)
			(xy 414.804086 -302.88268) (xy 414.830389 -302.841084) (xy 414.863024 -302.804247) (xy 414.901145 -302.773122)
			(xy 414.943766 -302.748515) (xy 414.989782 -302.731063) (xy 415.038001 -302.721219) (xy 415.087176 -302.719238)
			(xy 415.136031 -302.72517) (xy 415.183302 -302.738862) (xy 415.227764 -302.75996) (xy 415.268267 -302.787916)
			(xy 415.30376 -302.822008) (xy 415.333325 -302.861352) (xy 415.356196 -302.904929) (xy 415.37178 -302.95161)
			(xy 415.379675 -303.000187) (xy 415.38017 -303.024794) (xy 415.719018 -303.024794) (xy 415.722978 -302.97574)
			(xy 415.734755 -302.927956) (xy 415.754046 -302.88268) (xy 415.780349 -302.841084) (xy 415.812984 -302.804247)
			(xy 415.851105 -302.773122) (xy 415.893726 -302.748515) (xy 415.939742 -302.731063) (xy 415.987961 -302.721219)
			(xy 416.037136 -302.719238) (xy 416.085991 -302.72517) (xy 416.133262 -302.738862) (xy 416.177724 -302.75996)
			(xy 416.218227 -302.787916) (xy 416.25372 -302.822008) (xy 416.283285 -302.861352) (xy 416.306156 -302.904929)
			(xy 416.32174 -302.95161) (xy 416.329635 -303.000187) (xy 416.33013 -303.024794) (xy 416.329635 -303.049401)
			(xy 416.32174 -303.097978) (xy 416.306156 -303.144659) (xy 416.283285 -303.188236) (xy 416.25372 -303.22758)
			(xy 416.218227 -303.261672) (xy 416.177724 -303.289628) (xy 416.133262 -303.310726) (xy 416.085991 -303.324418)
			(xy 416.037136 -303.33035) (xy 415.987961 -303.328369) (xy 415.939742 -303.318525) (xy 415.893726 -303.301073)
			(xy 415.851105 -303.276466) (xy 415.812984 -303.245341) (xy 415.780349 -303.208504) (xy 415.754046 -303.166908)
			(xy 415.734755 -303.121632) (xy 415.722978 -303.073848) (xy 415.719018 -303.024794) (xy 415.38017 -303.024794)
			(xy 415.379675 -303.049401) (xy 415.37178 -303.097978) (xy 415.356196 -303.144659) (xy 415.333325 -303.188236)
			(xy 415.30376 -303.22758) (xy 415.268267 -303.261672) (xy 415.227764 -303.289628) (xy 415.183302 -303.310726)
			(xy 415.136031 -303.324418) (xy 415.087176 -303.33035) (xy 415.038001 -303.328369) (xy 414.989782 -303.318525)
			(xy 414.943766 -303.301073) (xy 414.901145 -303.276466) (xy 414.863024 -303.245341) (xy 414.830389 -303.208504)
			(xy 414.804086 -303.166908) (xy 414.784795 -303.121632) (xy 414.773018 -303.073848) (xy 414.769058 -303.024794)
			(xy 414.43021 -303.024794) (xy 414.429715 -303.049401) (xy 414.42182 -303.097978) (xy 414.406236 -303.144659)
			(xy 414.383365 -303.188236) (xy 414.3538 -303.22758) (xy 414.318307 -303.261672) (xy 414.277804 -303.289628)
			(xy 414.233342 -303.310726) (xy 414.186071 -303.324418) (xy 414.137216 -303.33035) (xy 414.088041 -303.328369)
			(xy 414.039822 -303.318525) (xy 413.993806 -303.301073) (xy 413.951185 -303.276466) (xy 413.913064 -303.245341)
			(xy 413.880429 -303.208504) (xy 413.854126 -303.166908) (xy 413.834835 -303.121632) (xy 413.823058 -303.073848)
			(xy 413.819098 -303.024794) (xy 413.48025 -303.024794) (xy 413.479755 -303.049401) (xy 413.47186 -303.097978)
			(xy 413.456276 -303.144659) (xy 413.433405 -303.188236) (xy 413.40384 -303.22758) (xy 413.368347 -303.261672)
			(xy 413.327844 -303.289628) (xy 413.283382 -303.310726) (xy 413.236111 -303.324418) (xy 413.187256 -303.33035)
			(xy 413.138081 -303.328369) (xy 413.089862 -303.318525) (xy 413.043846 -303.301073) (xy 413.001225 -303.276466)
			(xy 412.963104 -303.245341) (xy 412.930469 -303.208504) (xy 412.904166 -303.166908) (xy 412.884875 -303.121632)
			(xy 412.873098 -303.073848) (xy 412.869138 -303.024794) (xy 412.53029 -303.024794) (xy 412.529795 -303.049401)
			(xy 412.5219 -303.097978) (xy 412.506316 -303.144659) (xy 412.483445 -303.188236) (xy 412.45388 -303.22758)
			(xy 412.418387 -303.261672) (xy 412.377884 -303.289628) (xy 412.333422 -303.310726) (xy 412.286151 -303.324418)
			(xy 412.237296 -303.33035) (xy 412.188121 -303.328369) (xy 412.139902 -303.318525) (xy 412.093886 -303.301073)
			(xy 412.051265 -303.276466) (xy 412.013144 -303.245341) (xy 411.980509 -303.208504) (xy 411.954206 -303.166908)
			(xy 411.934915 -303.121632) (xy 411.923138 -303.073848) (xy 411.919178 -303.024794) (xy 411.58033 -303.024794)
			(xy 411.579835 -303.049401) (xy 411.57194 -303.097978) (xy 411.556356 -303.144659) (xy 411.533485 -303.188236)
			(xy 411.50392 -303.22758) (xy 411.468427 -303.261672) (xy 411.427924 -303.289628) (xy 411.383462 -303.310726)
			(xy 411.336191 -303.324418) (xy 411.287336 -303.33035) (xy 411.238161 -303.328369) (xy 411.189942 -303.318525)
			(xy 411.143926 -303.301073) (xy 411.101305 -303.276466) (xy 411.063184 -303.245341) (xy 411.030549 -303.208504)
			(xy 411.004246 -303.166908) (xy 410.984955 -303.121632) (xy 410.973178 -303.073848) (xy 410.969218 -303.024794)
			(xy 410.630116 -303.024794) (xy 410.629621 -303.049401) (xy 410.621726 -303.097978) (xy 410.606142 -303.144659)
			(xy 410.583271 -303.188236) (xy 410.553706 -303.22758) (xy 410.518213 -303.261672) (xy 410.47771 -303.289628)
			(xy 410.433248 -303.310726) (xy 410.385977 -303.324418) (xy 410.337122 -303.33035) (xy 410.287947 -303.328369)
			(xy 410.239728 -303.318525) (xy 410.193712 -303.301073) (xy 410.151091 -303.276466) (xy 410.11297 -303.245341)
			(xy 410.080335 -303.208504) (xy 410.054032 -303.166908) (xy 410.034741 -303.121632) (xy 410.022964 -303.073848)
			(xy 410.019004 -303.024794) (xy 409.680156 -303.024794) (xy 409.679661 -303.049401) (xy 409.671766 -303.097978)
			(xy 409.656182 -303.144659) (xy 409.633311 -303.188236) (xy 409.603746 -303.22758) (xy 409.568253 -303.261672)
			(xy 409.52775 -303.289628) (xy 409.483288 -303.310726) (xy 409.436017 -303.324418) (xy 409.387162 -303.33035)
			(xy 409.337987 -303.328369) (xy 409.289768 -303.318525) (xy 409.243752 -303.301073) (xy 409.201131 -303.276466)
			(xy 409.16301 -303.245341) (xy 409.130375 -303.208504) (xy 409.104072 -303.166908) (xy 409.084781 -303.121632)
			(xy 409.073004 -303.073848) (xy 409.069044 -303.024794) (xy 408.730196 -303.024794) (xy 408.729701 -303.049401)
			(xy 408.721806 -303.097978) (xy 408.706222 -303.144659) (xy 408.683351 -303.188236) (xy 408.653786 -303.22758)
			(xy 408.618293 -303.261672) (xy 408.57779 -303.289628) (xy 408.533328 -303.310726) (xy 408.486057 -303.324418)
			(xy 408.437202 -303.33035) (xy 408.388027 -303.328369) (xy 408.339808 -303.318525) (xy 408.293792 -303.301073)
			(xy 408.251171 -303.276466) (xy 408.21305 -303.245341) (xy 408.180415 -303.208504) (xy 408.154112 -303.166908)
			(xy 408.134821 -303.121632) (xy 408.123044 -303.073848) (xy 408.119084 -303.024794) (xy 406.830276 -303.024794)
			(xy 406.829781 -303.049401) (xy 406.821886 -303.097978) (xy 406.806302 -303.144659) (xy 406.783431 -303.188236)
			(xy 406.753866 -303.22758) (xy 406.718373 -303.261672) (xy 406.67787 -303.289628) (xy 406.633408 -303.310726)
			(xy 406.586137 -303.324418) (xy 406.537282 -303.33035) (xy 406.488107 -303.328369) (xy 406.439888 -303.318525)
			(xy 406.393872 -303.301073) (xy 406.351251 -303.276466) (xy 406.31313 -303.245341) (xy 406.280495 -303.208504)
			(xy 406.254192 -303.166908) (xy 406.234901 -303.121632) (xy 406.223124 -303.073848) (xy 406.219164 -303.024794)
			(xy 405.880316 -303.024794) (xy 405.879821 -303.049401) (xy 405.871926 -303.097978) (xy 405.856342 -303.144659)
			(xy 405.833471 -303.188236) (xy 405.803906 -303.22758) (xy 405.768413 -303.261672) (xy 405.72791 -303.289628)
			(xy 405.683448 -303.310726) (xy 405.636177 -303.324418) (xy 405.587322 -303.33035) (xy 405.538147 -303.328369)
			(xy 405.489928 -303.318525) (xy 405.443912 -303.301073) (xy 405.401291 -303.276466) (xy 405.36317 -303.245341)
			(xy 405.330535 -303.208504) (xy 405.304232 -303.166908) (xy 405.284941 -303.121632) (xy 405.273164 -303.073848)
			(xy 405.269204 -303.024794) (xy 404.930102 -303.024794) (xy 404.929607 -303.049401) (xy 404.921712 -303.097978)
			(xy 404.906128 -303.144659) (xy 404.883257 -303.188236) (xy 404.853692 -303.22758) (xy 404.818199 -303.261672)
			(xy 404.777696 -303.289628) (xy 404.733234 -303.310726) (xy 404.685963 -303.324418) (xy 404.637108 -303.33035)
			(xy 404.587933 -303.328369) (xy 404.539714 -303.318525) (xy 404.493698 -303.301073) (xy 404.451077 -303.276466)
			(xy 404.412956 -303.245341) (xy 404.380321 -303.208504) (xy 404.354018 -303.166908) (xy 404.334727 -303.121632)
			(xy 404.32295 -303.073848) (xy 404.31899 -303.024794) (xy 403.980142 -303.024794) (xy 403.979647 -303.049401)
			(xy 403.971752 -303.097978) (xy 403.956168 -303.144659) (xy 403.933297 -303.188236) (xy 403.903732 -303.22758)
			(xy 403.868239 -303.261672) (xy 403.827736 -303.289628) (xy 403.783274 -303.310726) (xy 403.736003 -303.324418)
			(xy 403.687148 -303.33035) (xy 403.637973 -303.328369) (xy 403.589754 -303.318525) (xy 403.543738 -303.301073)
			(xy 403.501117 -303.276466) (xy 403.462996 -303.245341) (xy 403.430361 -303.208504) (xy 403.404058 -303.166908)
			(xy 403.384767 -303.121632) (xy 403.37299 -303.073848) (xy 403.36903 -303.024794) (xy 403.030182 -303.024794)
			(xy 403.029687 -303.049401) (xy 403.021792 -303.097978) (xy 403.006208 -303.144659) (xy 402.983337 -303.188236)
			(xy 402.953772 -303.22758) (xy 402.918279 -303.261672) (xy 402.877776 -303.289628) (xy 402.833314 -303.310726)
			(xy 402.786043 -303.324418) (xy 402.737188 -303.33035) (xy 402.688013 -303.328369) (xy 402.639794 -303.318525)
			(xy 402.593778 -303.301073) (xy 402.551157 -303.276466) (xy 402.513036 -303.245341) (xy 402.480401 -303.208504)
			(xy 402.454098 -303.166908) (xy 402.434807 -303.121632) (xy 402.42303 -303.073848) (xy 402.41907 -303.024794)
			(xy 402.080222 -303.024794) (xy 402.079727 -303.049401) (xy 402.071832 -303.097978) (xy 402.056248 -303.144659)
			(xy 402.033377 -303.188236) (xy 402.003812 -303.22758) (xy 401.968319 -303.261672) (xy 401.927816 -303.289628)
			(xy 401.883354 -303.310726) (xy 401.836083 -303.324418) (xy 401.787228 -303.33035) (xy 401.738053 -303.328369)
			(xy 401.689834 -303.318525) (xy 401.643818 -303.301073) (xy 401.601197 -303.276466) (xy 401.563076 -303.245341)
			(xy 401.530441 -303.208504) (xy 401.504138 -303.166908) (xy 401.484847 -303.121632) (xy 401.47307 -303.073848)
			(xy 401.46911 -303.024794) (xy 401.130262 -303.024794) (xy 401.129767 -303.049401) (xy 401.121872 -303.097978)
			(xy 401.106288 -303.144659) (xy 401.083417 -303.188236) (xy 401.053852 -303.22758) (xy 401.018359 -303.261672)
			(xy 400.977856 -303.289628) (xy 400.933394 -303.310726) (xy 400.886123 -303.324418) (xy 400.837268 -303.33035)
			(xy 400.788093 -303.328369) (xy 400.739874 -303.318525) (xy 400.693858 -303.301073) (xy 400.651237 -303.276466)
			(xy 400.613116 -303.245341) (xy 400.580481 -303.208504) (xy 400.554178 -303.166908) (xy 400.534887 -303.121632)
			(xy 400.52311 -303.073848) (xy 400.51915 -303.024794) (xy 400.180302 -303.024794) (xy 400.179807 -303.049401)
			(xy 400.171912 -303.097978) (xy 400.156328 -303.144659) (xy 400.133457 -303.188236) (xy 400.103892 -303.22758)
			(xy 400.068399 -303.261672) (xy 400.027896 -303.289628) (xy 399.983434 -303.310726) (xy 399.936163 -303.324418)
			(xy 399.887308 -303.33035) (xy 399.838133 -303.328369) (xy 399.789914 -303.318525) (xy 399.743898 -303.301073)
			(xy 399.701277 -303.276466) (xy 399.663156 -303.245341) (xy 399.630521 -303.208504) (xy 399.604218 -303.166908)
			(xy 399.584927 -303.121632) (xy 399.57315 -303.073848) (xy 399.56919 -303.024794) (xy 399.230342 -303.024794)
			(xy 399.229847 -303.049401) (xy 399.221952 -303.097978) (xy 399.206368 -303.144659) (xy 399.183497 -303.188236)
			(xy 399.153932 -303.22758) (xy 399.118439 -303.261672) (xy 399.077936 -303.289628) (xy 399.033474 -303.310726)
			(xy 398.986203 -303.324418) (xy 398.937348 -303.33035) (xy 398.888173 -303.328369) (xy 398.839954 -303.318525)
			(xy 398.793938 -303.301073) (xy 398.751317 -303.276466) (xy 398.713196 -303.245341) (xy 398.680561 -303.208504)
			(xy 398.654258 -303.166908) (xy 398.634967 -303.121632) (xy 398.62319 -303.073848) (xy 398.61923 -303.024794)
			(xy 398.280128 -303.024794) (xy 398.279633 -303.049401) (xy 398.271738 -303.097978) (xy 398.256154 -303.144659)
			(xy 398.233283 -303.188236) (xy 398.203718 -303.22758) (xy 398.168225 -303.261672) (xy 398.127722 -303.289628)
			(xy 398.08326 -303.310726) (xy 398.035989 -303.324418) (xy 397.987134 -303.33035) (xy 397.937959 -303.328369)
			(xy 397.88974 -303.318525) (xy 397.843724 -303.301073) (xy 397.801103 -303.276466) (xy 397.762982 -303.245341)
			(xy 397.730347 -303.208504) (xy 397.704044 -303.166908) (xy 397.684753 -303.121632) (xy 397.672976 -303.073848)
			(xy 397.669016 -303.024794) (xy 397.330168 -303.024794) (xy 397.329673 -303.049401) (xy 397.321778 -303.097978)
			(xy 397.306194 -303.144659) (xy 397.283323 -303.188236) (xy 397.253758 -303.22758) (xy 397.218265 -303.261672)
			(xy 397.177762 -303.289628) (xy 397.1333 -303.310726) (xy 397.086029 -303.324418) (xy 397.037174 -303.33035)
			(xy 396.987999 -303.328369) (xy 396.93978 -303.318525) (xy 396.893764 -303.301073) (xy 396.851143 -303.276466)
			(xy 396.813022 -303.245341) (xy 396.780387 -303.208504) (xy 396.754084 -303.166908) (xy 396.734793 -303.121632)
			(xy 396.723016 -303.073848) (xy 396.719056 -303.024794) (xy 396.380208 -303.024794) (xy 396.379713 -303.049401)
			(xy 396.371818 -303.097978) (xy 396.356234 -303.144659) (xy 396.333363 -303.188236) (xy 396.303798 -303.22758)
			(xy 396.268305 -303.261672) (xy 396.227802 -303.289628) (xy 396.18334 -303.310726) (xy 396.136069 -303.324418)
			(xy 396.087214 -303.33035) (xy 396.038039 -303.328369) (xy 395.98982 -303.318525) (xy 395.943804 -303.301073)
			(xy 395.901183 -303.276466) (xy 395.863062 -303.245341) (xy 395.830427 -303.208504) (xy 395.804124 -303.166908)
			(xy 395.784833 -303.121632) (xy 395.773056 -303.073848) (xy 395.769096 -303.024794) (xy 395.430248 -303.024794)
			(xy 395.429753 -303.049401) (xy 395.421858 -303.097978) (xy 395.406274 -303.144659) (xy 395.383403 -303.188236)
			(xy 395.353838 -303.22758) (xy 395.318345 -303.261672) (xy 395.277842 -303.289628) (xy 395.23338 -303.310726)
			(xy 395.186109 -303.324418) (xy 395.137254 -303.33035) (xy 395.088079 -303.328369) (xy 395.03986 -303.318525)
			(xy 394.993844 -303.301073) (xy 394.951223 -303.276466) (xy 394.913102 -303.245341) (xy 394.880467 -303.208504)
			(xy 394.854164 -303.166908) (xy 394.834873 -303.121632) (xy 394.823096 -303.073848) (xy 394.819136 -303.024794)
			(xy 394.480854 -303.024794) (xy 394.480854 -303.0248) (xy 394.476682 -303.075144) (xy 394.464281 -303.124115)
			(xy 394.443988 -303.170376) (xy 394.416357 -303.212666) (xy 394.382142 -303.249831) (xy 394.342276 -303.280858)
			(xy 394.297847 -303.304899) (xy 394.250066 -303.321299) (xy 394.200238 -303.329611) (xy 394.17498 -303.330102)
			(xy 394.160797 -303.329928) (xy 394.132557 -303.327254) (xy 394.118592 -303.324768) (xy 394.106146 -303.322482)
			(xy 394.082524 -303.329848) (xy 394.005054 -303.407318) (xy 393.997688 -303.43094) (xy 393.999974 -303.443386)
			(xy 394.002444 -303.457353) (xy 394.00512 -303.485592) (xy 394.005308 -303.499774) (xy 394.00485 -303.524597)
			(xy 393.996822 -303.573591) (xy 393.980974 -303.62064) (xy 393.957722 -303.664505) (xy 393.92768 -303.704031)
			(xy 393.891639 -303.738176) (xy 393.850549 -303.76604) (xy 393.805492 -303.786889) (xy 393.757655 -303.800174)
			(xy 393.7083 -303.805544) (xy 393.658726 -303.802859) (xy 393.610239 -303.792189) (xy 393.564117 -303.773815)
			(xy 393.521576 -303.748222) (xy 393.483736 -303.716083) (xy 393.451593 -303.678245) (xy 393.425996 -303.635706)
			(xy 393.407618 -303.589586) (xy 393.396944 -303.5411) (xy 393.394255 -303.491526) (xy 393.399621 -303.44217)
			(xy 393.412902 -303.394333) (xy 393.433747 -303.349274) (xy 393.461608 -303.308181) (xy 393.495749 -303.272138)
			(xy 393.535273 -303.242092) (xy 393.579136 -303.218837) (xy 393.626184 -303.202984) (xy 393.675177 -303.194952)
			(xy 393.7 -303.194466) (xy 393.714183 -303.194643) (xy 393.742423 -303.197315) (xy 393.756388 -303.1998)
			(xy 393.768834 -303.202086) (xy 393.792456 -303.19472) (xy 393.869926 -303.11725) (xy 393.877292 -303.093628)
			(xy 393.875006 -303.081182) (xy 393.872531 -303.067216) (xy 393.869858 -303.038976) (xy 393.869672 -303.024794)
			(xy 393.869848 -303.010611) (xy 393.872521 -302.982371) (xy 393.875006 -302.968406) (xy 393.877292 -302.95596)
			(xy 393.869926 -302.932338) (xy 393.792456 -302.854868) (xy 393.768834 -302.847502) (xy 393.756388 -302.849788)
			(xy 393.742422 -302.852262) (xy 393.714182 -302.854935) (xy 393.7 -302.855122) (xy 393.674746 -302.854572)
			(xy 393.624926 -302.846259) (xy 393.577155 -302.829859) (xy 393.532734 -302.80582) (xy 393.492876 -302.774797)
			(xy 393.458667 -302.737637) (xy 393.431042 -302.695353) (xy 393.410753 -302.649099) (xy 393.398354 -302.600136)
			(xy 393.394183 -302.5498) (xy 393.398354 -302.499464) (xy 393.410753 -302.450501) (xy 393.431042 -302.404247)
			(xy 393.458667 -302.361963) (xy 393.492876 -302.324803) (xy 393.532734 -302.29378) (xy 393.577155 -302.269741)
			(xy 393.624926 -302.253341) (xy 393.674746 -302.245028) (xy 393.7 -302.244506) (xy 393.714183 -302.244682)
			(xy 393.742423 -302.247355) (xy 393.756388 -302.24984) (xy 393.768834 -302.252126) (xy 393.792456 -302.24476)
			(xy 393.869926 -302.16729) (xy 393.877292 -302.143668) (xy 393.875006 -302.131222) (xy 393.872523 -302.117257)
			(xy 393.869855 -302.089017) (xy 393.869672 -302.074834) (xy 393.869854 -302.060651) (xy 393.872522 -302.032411)
			(xy 393.875006 -302.018446) (xy 393.877292 -302.006) (xy 393.869926 -301.982378) (xy 393.792456 -301.904908)
			(xy 393.768834 -301.897542) (xy 393.756388 -301.899828) (xy 393.742422 -301.902302) (xy 393.714182 -301.904976)
			(xy 393.7 -301.905162) (xy 393.676005 -301.904762) (xy 393.628605 -301.897253) (xy 393.582963 -301.882422)
			(xy 393.540204 -301.860633) (xy 393.50138 -301.832422) (xy 393.467448 -301.798485) (xy 393.439243 -301.759657)
			(xy 393.41746 -301.716894) (xy 393.402636 -301.671251) (xy 393.395135 -301.62385) (xy 393.394692 -301.599854)
			(xy 393.394876 -301.585671) (xy 393.397543 -301.557431) (xy 393.400026 -301.543466) (xy 393.402312 -301.53102)
			(xy 393.394946 -301.507398) (xy 393.317476 -301.429928) (xy 393.293854 -301.422562) (xy 393.281408 -301.424848)
			(xy 393.267441 -301.427319) (xy 393.239202 -301.429995) (xy 393.22502 -301.430182) (xy 393.210773 -301.43002)
			(xy 393.182405 -301.427344) (xy 393.168378 -301.424848) (xy 393.155932 -301.422562) (xy 393.13231 -301.429928)
			(xy 393.06373 -301.498254) (xy 393.055588 -301.507503) (xy 393.04827 -301.530983) (xy 393.04976 -301.543212)
			(xy 393.04976 -301.54372) (xy 393.052223 -301.557624) (xy 393.054894 -301.585735) (xy 393.055094 -301.599854)
			(xy 393.054672 -301.624679) (xy 393.046647 -301.673677) (xy 393.0308 -301.72073) (xy 393.00755 -301.7646)
			(xy 392.977508 -301.804131) (xy 392.941466 -301.83828) (xy 392.900375 -301.866148) (xy 392.855316 -301.887002)
			(xy 392.807477 -301.90029) (xy 392.758119 -301.905664) (xy 392.708541 -301.902982) (xy 392.66005 -301.892314)
			(xy 392.613924 -301.873942) (xy 392.571378 -301.848348) (xy 392.533533 -301.816209) (xy 392.501387 -301.778371)
			(xy 392.475785 -301.73583) (xy 392.457404 -301.689708) (xy 392.446726 -301.641219) (xy 392.444034 -301.591642)
			(xy 392.104969 -301.591642) (xy 392.105134 -301.599854) (xy 392.104639 -301.624461) (xy 392.096744 -301.673038)
			(xy 392.08116 -301.719719) (xy 392.058289 -301.763296) (xy 392.028724 -301.80264) (xy 391.993231 -301.836732)
			(xy 391.952728 -301.864688) (xy 391.908266 -301.885786) (xy 391.860995 -301.899478) (xy 391.81214 -301.90541)
			(xy 391.762965 -301.903429) (xy 391.714746 -301.893585) (xy 391.66873 -301.876133) (xy 391.626109 -301.851526)
			(xy 391.587988 -301.820401) (xy 391.555353 -301.783564) (xy 391.52905 -301.741968) (xy 391.509759 -301.696692)
			(xy 391.497982 -301.648908) (xy 391.494022 -301.599854) (xy 391.155174 -301.599854) (xy 391.154679 -301.624461)
			(xy 391.146784 -301.673038) (xy 391.1312 -301.719719) (xy 391.108329 -301.763296) (xy 391.078764 -301.80264)
			(xy 391.043271 -301.836732) (xy 391.002768 -301.864688) (xy 390.958306 -301.885786) (xy 390.911035 -301.899478)
			(xy 390.86218 -301.90541) (xy 390.813005 -301.903429) (xy 390.764786 -301.893585) (xy 390.71877 -301.876133)
			(xy 390.676149 -301.851526) (xy 390.638028 -301.820401) (xy 390.605393 -301.783564) (xy 390.57909 -301.741968)
			(xy 390.559799 -301.696692) (xy 390.548022 -301.648908) (xy 390.544062 -301.599854) (xy 390.205214 -301.599854)
			(xy 390.204719 -301.624461) (xy 390.196824 -301.673038) (xy 390.18124 -301.719719) (xy 390.158369 -301.763296)
			(xy 390.128804 -301.80264) (xy 390.093311 -301.836732) (xy 390.052808 -301.864688) (xy 390.008346 -301.885786)
			(xy 389.961075 -301.899478) (xy 389.91222 -301.90541) (xy 389.863045 -301.903429) (xy 389.814826 -301.893585)
			(xy 389.76881 -301.876133) (xy 389.726189 -301.851526) (xy 389.688068 -301.820401) (xy 389.655433 -301.783564)
			(xy 389.62913 -301.741968) (xy 389.609839 -301.696692) (xy 389.598062 -301.648908) (xy 389.594102 -301.599854)
			(xy 389.255254 -301.599854) (xy 389.254759 -301.624461) (xy 389.246864 -301.673038) (xy 389.23128 -301.719719)
			(xy 389.208409 -301.763296) (xy 389.178844 -301.80264) (xy 389.143351 -301.836732) (xy 389.102848 -301.864688)
			(xy 389.058386 -301.885786) (xy 389.011115 -301.899478) (xy 388.96226 -301.90541) (xy 388.913085 -301.903429)
			(xy 388.864866 -301.893585) (xy 388.81885 -301.876133) (xy 388.776229 -301.851526) (xy 388.738108 -301.820401)
			(xy 388.705473 -301.783564) (xy 388.67917 -301.741968) (xy 388.659879 -301.696692) (xy 388.648102 -301.648908)
			(xy 388.644142 -301.599854) (xy 388.305294 -301.599854) (xy 388.304799 -301.624461) (xy 388.296904 -301.673038)
			(xy 388.28132 -301.719719) (xy 388.258449 -301.763296) (xy 388.228884 -301.80264) (xy 388.193391 -301.836732)
			(xy 388.152888 -301.864688) (xy 388.108426 -301.885786) (xy 388.061155 -301.899478) (xy 388.0123 -301.90541)
			(xy 387.963125 -301.903429) (xy 387.914906 -301.893585) (xy 387.86889 -301.876133) (xy 387.826269 -301.851526)
			(xy 387.788148 -301.820401) (xy 387.755513 -301.783564) (xy 387.72921 -301.741968) (xy 387.709919 -301.696692)
			(xy 387.698142 -301.648908) (xy 387.694182 -301.599854) (xy 387.355334 -301.599854) (xy 387.354839 -301.624461)
			(xy 387.346944 -301.673038) (xy 387.33136 -301.719719) (xy 387.308489 -301.763296) (xy 387.278924 -301.80264)
			(xy 387.243431 -301.836732) (xy 387.202928 -301.864688) (xy 387.158466 -301.885786) (xy 387.111195 -301.899478)
			(xy 387.06234 -301.90541) (xy 387.013165 -301.903429) (xy 386.964946 -301.893585) (xy 386.91893 -301.876133)
			(xy 386.876309 -301.851526) (xy 386.838188 -301.820401) (xy 386.805553 -301.783564) (xy 386.77925 -301.741968)
			(xy 386.759959 -301.696692) (xy 386.748182 -301.648908) (xy 386.744222 -301.599854) (xy 386.40512 -301.599854)
			(xy 386.404625 -301.624461) (xy 386.39673 -301.673038) (xy 386.381146 -301.719719) (xy 386.358275 -301.763296)
			(xy 386.32871 -301.80264) (xy 386.293217 -301.836732) (xy 386.252714 -301.864688) (xy 386.208252 -301.885786)
			(xy 386.160981 -301.899478) (xy 386.112126 -301.90541) (xy 386.062951 -301.903429) (xy 386.014732 -301.893585)
			(xy 385.968716 -301.876133) (xy 385.926095 -301.851526) (xy 385.887974 -301.820401) (xy 385.855339 -301.783564)
			(xy 385.829036 -301.741968) (xy 385.809745 -301.696692) (xy 385.797968 -301.648908) (xy 385.794008 -301.599854)
			(xy 385.45516 -301.599854) (xy 385.454665 -301.624461) (xy 385.44677 -301.673038) (xy 385.431186 -301.719719)
			(xy 385.408315 -301.763296) (xy 385.37875 -301.80264) (xy 385.343257 -301.836732) (xy 385.302754 -301.864688)
			(xy 385.258292 -301.885786) (xy 385.211021 -301.899478) (xy 385.162166 -301.90541) (xy 385.112991 -301.903429)
			(xy 385.064772 -301.893585) (xy 385.018756 -301.876133) (xy 384.976135 -301.851526) (xy 384.938014 -301.820401)
			(xy 384.905379 -301.783564) (xy 384.879076 -301.741968) (xy 384.859785 -301.696692) (xy 384.848008 -301.648908)
			(xy 384.844048 -301.599854) (xy 351.03308 -301.599854) (xy 351.03308 -302.550068) (xy 383.893834 -302.550068)
			(xy 383.897794 -302.501014) (xy 383.909571 -302.45323) (xy 383.928862 -302.407954) (xy 383.955165 -302.366358)
			(xy 383.9878 -302.329521) (xy 384.025921 -302.298396) (xy 384.068542 -302.273789) (xy 384.114558 -302.256337)
			(xy 384.162777 -302.246493) (xy 384.211952 -302.244512) (xy 384.260807 -302.250444) (xy 384.308078 -302.264136)
			(xy 384.35254 -302.285234) (xy 384.393043 -302.31319) (xy 384.428536 -302.347282) (xy 384.458101 -302.386626)
			(xy 384.480972 -302.430203) (xy 384.496556 -302.476884) (xy 384.504451 -302.525461) (xy 384.504941 -302.549814)
			(xy 384.844048 -302.549814) (xy 384.848008 -302.50076) (xy 384.859785 -302.452976) (xy 384.879076 -302.4077)
			(xy 384.905379 -302.366104) (xy 384.938014 -302.329267) (xy 384.976135 -302.298142) (xy 385.018756 -302.273535)
			(xy 385.064772 -302.256083) (xy 385.112991 -302.246239) (xy 385.162166 -302.244258) (xy 385.211021 -302.25019)
			(xy 385.258292 -302.263882) (xy 385.302754 -302.28498) (xy 385.343257 -302.312936) (xy 385.37875 -302.347028)
			(xy 385.408315 -302.386372) (xy 385.431186 -302.429949) (xy 385.44677 -302.47663) (xy 385.454665 -302.525207)
			(xy 385.45516 -302.549814) (xy 385.794008 -302.549814) (xy 385.797968 -302.50076) (xy 385.809745 -302.452976)
			(xy 385.829036 -302.4077) (xy 385.855339 -302.366104) (xy 385.887974 -302.329267) (xy 385.926095 -302.298142)
			(xy 385.968716 -302.273535) (xy 386.014732 -302.256083) (xy 386.062951 -302.246239) (xy 386.112126 -302.244258)
			(xy 386.160981 -302.25019) (xy 386.208252 -302.263882) (xy 386.252714 -302.28498) (xy 386.293217 -302.312936)
			(xy 386.32871 -302.347028) (xy 386.358275 -302.386372) (xy 386.381146 -302.429949) (xy 386.39673 -302.47663)
			(xy 386.404625 -302.525207) (xy 386.40512 -302.549814) (xy 386.744222 -302.549814) (xy 386.748182 -302.50076)
			(xy 386.759959 -302.452976) (xy 386.77925 -302.4077) (xy 386.805553 -302.366104) (xy 386.838188 -302.329267)
			(xy 386.876309 -302.298142) (xy 386.91893 -302.273535) (xy 386.964946 -302.256083) (xy 387.013165 -302.246239)
			(xy 387.06234 -302.244258) (xy 387.111195 -302.25019) (xy 387.158466 -302.263882) (xy 387.202928 -302.28498)
			(xy 387.243431 -302.312936) (xy 387.278924 -302.347028) (xy 387.308489 -302.386372) (xy 387.33136 -302.429949)
			(xy 387.346944 -302.47663) (xy 387.354839 -302.525207) (xy 387.355334 -302.549814) (xy 387.694182 -302.549814)
			(xy 387.698142 -302.50076) (xy 387.709919 -302.452976) (xy 387.72921 -302.4077) (xy 387.755513 -302.366104)
			(xy 387.788148 -302.329267) (xy 387.826269 -302.298142) (xy 387.86889 -302.273535) (xy 387.914906 -302.256083)
			(xy 387.963125 -302.246239) (xy 388.0123 -302.244258) (xy 388.061155 -302.25019) (xy 388.108426 -302.263882)
			(xy 388.152888 -302.28498) (xy 388.193391 -302.312936) (xy 388.228884 -302.347028) (xy 388.258449 -302.386372)
			(xy 388.28132 -302.429949) (xy 388.296904 -302.47663) (xy 388.304799 -302.525207) (xy 388.305294 -302.549814)
			(xy 388.644142 -302.549814) (xy 388.648102 -302.50076) (xy 388.659879 -302.452976) (xy 388.67917 -302.4077)
			(xy 388.705473 -302.366104) (xy 388.738108 -302.329267) (xy 388.776229 -302.298142) (xy 388.81885 -302.273535)
			(xy 388.864866 -302.256083) (xy 388.913085 -302.246239) (xy 388.96226 -302.244258) (xy 389.011115 -302.25019)
			(xy 389.058386 -302.263882) (xy 389.102848 -302.28498) (xy 389.143351 -302.312936) (xy 389.178844 -302.347028)
			(xy 389.208409 -302.386372) (xy 389.23128 -302.429949) (xy 389.246864 -302.47663) (xy 389.254759 -302.525207)
			(xy 389.255254 -302.549814) (xy 389.594102 -302.549814) (xy 389.598062 -302.50076) (xy 389.609839 -302.452976)
			(xy 389.62913 -302.4077) (xy 389.655433 -302.366104) (xy 389.688068 -302.329267) (xy 389.726189 -302.298142)
			(xy 389.76881 -302.273535) (xy 389.814826 -302.256083) (xy 389.863045 -302.246239) (xy 389.91222 -302.244258)
			(xy 389.961075 -302.25019) (xy 390.008346 -302.263882) (xy 390.052808 -302.28498) (xy 390.093311 -302.312936)
			(xy 390.128804 -302.347028) (xy 390.158369 -302.386372) (xy 390.18124 -302.429949) (xy 390.196824 -302.47663)
			(xy 390.204719 -302.525207) (xy 390.205214 -302.549814) (xy 390.544062 -302.549814) (xy 390.548022 -302.50076)
			(xy 390.559799 -302.452976) (xy 390.57909 -302.4077) (xy 390.605393 -302.366104) (xy 390.638028 -302.329267)
			(xy 390.676149 -302.298142) (xy 390.71877 -302.273535) (xy 390.764786 -302.256083) (xy 390.813005 -302.246239)
			(xy 390.86218 -302.244258) (xy 390.911035 -302.25019) (xy 390.958306 -302.263882) (xy 391.002768 -302.28498)
			(xy 391.043271 -302.312936) (xy 391.078764 -302.347028) (xy 391.108329 -302.386372) (xy 391.1312 -302.429949)
			(xy 391.146784 -302.47663) (xy 391.154679 -302.525207) (xy 391.155174 -302.549814) (xy 391.494022 -302.549814)
			(xy 391.497982 -302.50076) (xy 391.509759 -302.452976) (xy 391.52905 -302.4077) (xy 391.555353 -302.366104)
			(xy 391.587988 -302.329267) (xy 391.626109 -302.298142) (xy 391.66873 -302.273535) (xy 391.714746 -302.256083)
			(xy 391.762965 -302.246239) (xy 391.81214 -302.244258) (xy 391.860995 -302.25019) (xy 391.908266 -302.263882)
			(xy 391.952728 -302.28498) (xy 391.993231 -302.312936) (xy 392.028724 -302.347028) (xy 392.058289 -302.386372)
			(xy 392.08116 -302.429949) (xy 392.096744 -302.47663) (xy 392.104639 -302.525207) (xy 392.105134 -302.549814)
			(xy 392.443982 -302.549814) (xy 392.447942 -302.50076) (xy 392.459719 -302.452976) (xy 392.47901 -302.4077)
			(xy 392.505313 -302.366104) (xy 392.537948 -302.329267) (xy 392.576069 -302.298142) (xy 392.61869 -302.273535)
			(xy 392.664706 -302.256083) (xy 392.712925 -302.246239) (xy 392.7621 -302.244258) (xy 392.810955 -302.25019)
			(xy 392.858226 -302.263882) (xy 392.902688 -302.28498) (xy 392.943191 -302.312936) (xy 392.978684 -302.347028)
			(xy 393.008249 -302.386372) (xy 393.03112 -302.429949) (xy 393.046704 -302.47663) (xy 393.054599 -302.525207)
			(xy 393.055094 -302.549814) (xy 393.054599 -302.574421) (xy 393.046704 -302.622998) (xy 393.03112 -302.669679)
			(xy 393.008249 -302.713256) (xy 392.978684 -302.7526) (xy 392.943191 -302.786692) (xy 392.902688 -302.814648)
			(xy 392.858226 -302.835746) (xy 392.810955 -302.849438) (xy 392.7621 -302.85537) (xy 392.712925 -302.853389)
			(xy 392.664706 -302.843545) (xy 392.61869 -302.826093) (xy 392.576069 -302.801486) (xy 392.537948 -302.770361)
			(xy 392.505313 -302.733524) (xy 392.47901 -302.691928) (xy 392.459719 -302.646652) (xy 392.447942 -302.598868)
			(xy 392.443982 -302.549814) (xy 392.105134 -302.549814) (xy 392.104639 -302.574421) (xy 392.096744 -302.622998)
			(xy 392.08116 -302.669679) (xy 392.058289 -302.713256) (xy 392.028724 -302.7526) (xy 391.993231 -302.786692)
			(xy 391.952728 -302.814648) (xy 391.908266 -302.835746) (xy 391.860995 -302.849438) (xy 391.81214 -302.85537)
			(xy 391.762965 -302.853389) (xy 391.714746 -302.843545) (xy 391.66873 -302.826093) (xy 391.626109 -302.801486)
			(xy 391.587988 -302.770361) (xy 391.555353 -302.733524) (xy 391.52905 -302.691928) (xy 391.509759 -302.646652)
			(xy 391.497982 -302.598868) (xy 391.494022 -302.549814) (xy 391.155174 -302.549814) (xy 391.154679 -302.574421)
			(xy 391.146784 -302.622998) (xy 391.1312 -302.669679) (xy 391.108329 -302.713256) (xy 391.078764 -302.7526)
			(xy 391.043271 -302.786692) (xy 391.002768 -302.814648) (xy 390.958306 -302.835746) (xy 390.911035 -302.849438)
			(xy 390.86218 -302.85537) (xy 390.813005 -302.853389) (xy 390.764786 -302.843545) (xy 390.71877 -302.826093)
			(xy 390.676149 -302.801486) (xy 390.638028 -302.770361) (xy 390.605393 -302.733524) (xy 390.57909 -302.691928)
			(xy 390.559799 -302.646652) (xy 390.548022 -302.598868) (xy 390.544062 -302.549814) (xy 390.205214 -302.549814)
			(xy 390.204719 -302.574421) (xy 390.196824 -302.622998) (xy 390.18124 -302.669679) (xy 390.158369 -302.713256)
			(xy 390.128804 -302.7526) (xy 390.093311 -302.786692) (xy 390.052808 -302.814648) (xy 390.008346 -302.835746)
			(xy 389.961075 -302.849438) (xy 389.91222 -302.85537) (xy 389.863045 -302.853389) (xy 389.814826 -302.843545)
			(xy 389.76881 -302.826093) (xy 389.726189 -302.801486) (xy 389.688068 -302.770361) (xy 389.655433 -302.733524)
			(xy 389.62913 -302.691928) (xy 389.609839 -302.646652) (xy 389.598062 -302.598868) (xy 389.594102 -302.549814)
			(xy 389.255254 -302.549814) (xy 389.254759 -302.574421) (xy 389.246864 -302.622998) (xy 389.23128 -302.669679)
			(xy 389.208409 -302.713256) (xy 389.178844 -302.7526) (xy 389.143351 -302.786692) (xy 389.102848 -302.814648)
			(xy 389.058386 -302.835746) (xy 389.011115 -302.849438) (xy 388.96226 -302.85537) (xy 388.913085 -302.853389)
			(xy 388.864866 -302.843545) (xy 388.81885 -302.826093) (xy 388.776229 -302.801486) (xy 388.738108 -302.770361)
			(xy 388.705473 -302.733524) (xy 388.67917 -302.691928) (xy 388.659879 -302.646652) (xy 388.648102 -302.598868)
			(xy 388.644142 -302.549814) (xy 388.305294 -302.549814) (xy 388.304799 -302.574421) (xy 388.296904 -302.622998)
			(xy 388.28132 -302.669679) (xy 388.258449 -302.713256) (xy 388.228884 -302.7526) (xy 388.193391 -302.786692)
			(xy 388.152888 -302.814648) (xy 388.108426 -302.835746) (xy 388.061155 -302.849438) (xy 388.0123 -302.85537)
			(xy 387.963125 -302.853389) (xy 387.914906 -302.843545) (xy 387.86889 -302.826093) (xy 387.826269 -302.801486)
			(xy 387.788148 -302.770361) (xy 387.755513 -302.733524) (xy 387.72921 -302.691928) (xy 387.709919 -302.646652)
			(xy 387.698142 -302.598868) (xy 387.694182 -302.549814) (xy 387.355334 -302.549814) (xy 387.354839 -302.574421)
			(xy 387.346944 -302.622998) (xy 387.33136 -302.669679) (xy 387.308489 -302.713256) (xy 387.278924 -302.7526)
			(xy 387.243431 -302.786692) (xy 387.202928 -302.814648) (xy 387.158466 -302.835746) (xy 387.111195 -302.849438)
			(xy 387.06234 -302.85537) (xy 387.013165 -302.853389) (xy 386.964946 -302.843545) (xy 386.91893 -302.826093)
			(xy 386.876309 -302.801486) (xy 386.838188 -302.770361) (xy 386.805553 -302.733524) (xy 386.77925 -302.691928)
			(xy 386.759959 -302.646652) (xy 386.748182 -302.598868) (xy 386.744222 -302.549814) (xy 386.40512 -302.549814)
			(xy 386.404625 -302.574421) (xy 386.39673 -302.622998) (xy 386.381146 -302.669679) (xy 386.358275 -302.713256)
			(xy 386.32871 -302.7526) (xy 386.293217 -302.786692) (xy 386.252714 -302.814648) (xy 386.208252 -302.835746)
			(xy 386.160981 -302.849438) (xy 386.112126 -302.85537) (xy 386.062951 -302.853389) (xy 386.014732 -302.843545)
			(xy 385.968716 -302.826093) (xy 385.926095 -302.801486) (xy 385.887974 -302.770361) (xy 385.855339 -302.733524)
			(xy 385.829036 -302.691928) (xy 385.809745 -302.646652) (xy 385.797968 -302.598868) (xy 385.794008 -302.549814)
			(xy 385.45516 -302.549814) (xy 385.454665 -302.574421) (xy 385.44677 -302.622998) (xy 385.431186 -302.669679)
			(xy 385.408315 -302.713256) (xy 385.37875 -302.7526) (xy 385.343257 -302.786692) (xy 385.302754 -302.814648)
			(xy 385.258292 -302.835746) (xy 385.211021 -302.849438) (xy 385.162166 -302.85537) (xy 385.112991 -302.853389)
			(xy 385.064772 -302.843545) (xy 385.018756 -302.826093) (xy 384.976135 -302.801486) (xy 384.938014 -302.770361)
			(xy 384.905379 -302.733524) (xy 384.879076 -302.691928) (xy 384.859785 -302.646652) (xy 384.848008 -302.598868)
			(xy 384.844048 -302.549814) (xy 384.504941 -302.549814) (xy 384.504946 -302.550068) (xy 384.504451 -302.574675)
			(xy 384.496556 -302.623252) (xy 384.480972 -302.669933) (xy 384.458101 -302.71351) (xy 384.428536 -302.752854)
			(xy 384.393043 -302.786946) (xy 384.35254 -302.814902) (xy 384.308078 -302.836) (xy 384.260807 -302.849692)
			(xy 384.211952 -302.855624) (xy 384.162777 -302.853643) (xy 384.114558 -302.843799) (xy 384.068542 -302.826347)
			(xy 384.025921 -302.80174) (xy 383.9878 -302.770615) (xy 383.955165 -302.733778) (xy 383.928862 -302.692182)
			(xy 383.909571 -302.646906) (xy 383.897794 -302.599122) (xy 383.893834 -302.550068) (xy 351.03308 -302.550068)
			(xy 351.03308 -303.499774) (xy 384.844048 -303.499774) (xy 384.848008 -303.45072) (xy 384.859785 -303.402936)
			(xy 384.879076 -303.35766) (xy 384.905379 -303.316064) (xy 384.938014 -303.279227) (xy 384.976135 -303.248102)
			(xy 385.018756 -303.223495) (xy 385.064772 -303.206043) (xy 385.112991 -303.196199) (xy 385.162166 -303.194218)
			(xy 385.211021 -303.20015) (xy 385.258292 -303.213842) (xy 385.302754 -303.23494) (xy 385.343257 -303.262896)
			(xy 385.37875 -303.296988) (xy 385.408315 -303.336332) (xy 385.431186 -303.379909) (xy 385.44677 -303.42659)
			(xy 385.454665 -303.475167) (xy 385.45516 -303.499774) (xy 385.794008 -303.499774) (xy 385.797968 -303.45072)
			(xy 385.809745 -303.402936) (xy 385.829036 -303.35766) (xy 385.855339 -303.316064) (xy 385.887974 -303.279227)
			(xy 385.926095 -303.248102) (xy 385.968716 -303.223495) (xy 386.014732 -303.206043) (xy 386.062951 -303.196199)
			(xy 386.112126 -303.194218) (xy 386.160981 -303.20015) (xy 386.208252 -303.213842) (xy 386.252714 -303.23494)
			(xy 386.293217 -303.262896) (xy 386.32871 -303.296988) (xy 386.358275 -303.336332) (xy 386.381146 -303.379909)
			(xy 386.39673 -303.42659) (xy 386.404625 -303.475167) (xy 386.40512 -303.499774) (xy 386.744222 -303.499774)
			(xy 386.748182 -303.45072) (xy 386.759959 -303.402936) (xy 386.77925 -303.35766) (xy 386.805553 -303.316064)
			(xy 386.838188 -303.279227) (xy 386.876309 -303.248102) (xy 386.91893 -303.223495) (xy 386.964946 -303.206043)
			(xy 387.013165 -303.196199) (xy 387.06234 -303.194218) (xy 387.111195 -303.20015) (xy 387.158466 -303.213842)
			(xy 387.202928 -303.23494) (xy 387.243431 -303.262896) (xy 387.278924 -303.296988) (xy 387.308489 -303.336332)
			(xy 387.33136 -303.379909) (xy 387.346944 -303.42659) (xy 387.354839 -303.475167) (xy 387.355334 -303.499774)
			(xy 387.694182 -303.499774) (xy 387.698142 -303.45072) (xy 387.709919 -303.402936) (xy 387.72921 -303.35766)
			(xy 387.755513 -303.316064) (xy 387.788148 -303.279227) (xy 387.826269 -303.248102) (xy 387.86889 -303.223495)
			(xy 387.914906 -303.206043) (xy 387.963125 -303.196199) (xy 388.0123 -303.194218) (xy 388.061155 -303.20015)
			(xy 388.108426 -303.213842) (xy 388.152888 -303.23494) (xy 388.193391 -303.262896) (xy 388.228884 -303.296988)
			(xy 388.258449 -303.336332) (xy 388.28132 -303.379909) (xy 388.296904 -303.42659) (xy 388.304799 -303.475167)
			(xy 388.305294 -303.499774) (xy 388.644142 -303.499774) (xy 388.648102 -303.45072) (xy 388.659879 -303.402936)
			(xy 388.67917 -303.35766) (xy 388.705473 -303.316064) (xy 388.738108 -303.279227) (xy 388.776229 -303.248102)
			(xy 388.81885 -303.223495) (xy 388.864866 -303.206043) (xy 388.913085 -303.196199) (xy 388.96226 -303.194218)
			(xy 389.011115 -303.20015) (xy 389.058386 -303.213842) (xy 389.102848 -303.23494) (xy 389.143351 -303.262896)
			(xy 389.178844 -303.296988) (xy 389.208409 -303.336332) (xy 389.23128 -303.379909) (xy 389.246864 -303.42659)
			(xy 389.254759 -303.475167) (xy 389.255254 -303.499774) (xy 389.594102 -303.499774) (xy 389.598062 -303.45072)
			(xy 389.609839 -303.402936) (xy 389.62913 -303.35766) (xy 389.655433 -303.316064) (xy 389.688068 -303.279227)
			(xy 389.726189 -303.248102) (xy 389.76881 -303.223495) (xy 389.814826 -303.206043) (xy 389.863045 -303.196199)
			(xy 389.91222 -303.194218) (xy 389.961075 -303.20015) (xy 390.008346 -303.213842) (xy 390.052808 -303.23494)
			(xy 390.093311 -303.262896) (xy 390.128804 -303.296988) (xy 390.158369 -303.336332) (xy 390.18124 -303.379909)
			(xy 390.196824 -303.42659) (xy 390.204719 -303.475167) (xy 390.205214 -303.499774) (xy 390.544062 -303.499774)
			(xy 390.548022 -303.45072) (xy 390.559799 -303.402936) (xy 390.57909 -303.35766) (xy 390.605393 -303.316064)
			(xy 390.638028 -303.279227) (xy 390.676149 -303.248102) (xy 390.71877 -303.223495) (xy 390.764786 -303.206043)
			(xy 390.813005 -303.196199) (xy 390.86218 -303.194218) (xy 390.911035 -303.20015) (xy 390.958306 -303.213842)
			(xy 391.002768 -303.23494) (xy 391.043271 -303.262896) (xy 391.078764 -303.296988) (xy 391.108329 -303.336332)
			(xy 391.1312 -303.379909) (xy 391.146784 -303.42659) (xy 391.154679 -303.475167) (xy 391.155174 -303.499774)
			(xy 391.494022 -303.499774) (xy 391.497982 -303.45072) (xy 391.509759 -303.402936) (xy 391.52905 -303.35766)
			(xy 391.555353 -303.316064) (xy 391.587988 -303.279227) (xy 391.626109 -303.248102) (xy 391.66873 -303.223495)
			(xy 391.714746 -303.206043) (xy 391.762965 -303.196199) (xy 391.81214 -303.194218) (xy 391.860995 -303.20015)
			(xy 391.908266 -303.213842) (xy 391.952728 -303.23494) (xy 391.993231 -303.262896) (xy 392.028724 -303.296988)
			(xy 392.058289 -303.336332) (xy 392.08116 -303.379909) (xy 392.096744 -303.42659) (xy 392.104639 -303.475167)
			(xy 392.105134 -303.499774) (xy 392.443982 -303.499774) (xy 392.447942 -303.45072) (xy 392.459719 -303.402936)
			(xy 392.47901 -303.35766) (xy 392.505313 -303.316064) (xy 392.537948 -303.279227) (xy 392.576069 -303.248102)
			(xy 392.61869 -303.223495) (xy 392.664706 -303.206043) (xy 392.712925 -303.196199) (xy 392.7621 -303.194218)
			(xy 392.810955 -303.20015) (xy 392.858226 -303.213842) (xy 392.902688 -303.23494) (xy 392.943191 -303.262896)
			(xy 392.978684 -303.296988) (xy 393.008249 -303.336332) (xy 393.03112 -303.379909) (xy 393.046704 -303.42659)
			(xy 393.054599 -303.475167) (xy 393.055094 -303.499774) (xy 393.054599 -303.524381) (xy 393.046704 -303.572958)
			(xy 393.03112 -303.619639) (xy 393.008249 -303.663216) (xy 392.978684 -303.70256) (xy 392.943191 -303.736652)
			(xy 392.902688 -303.764608) (xy 392.858226 -303.785706) (xy 392.810955 -303.799398) (xy 392.7621 -303.80533)
			(xy 392.712925 -303.803349) (xy 392.664706 -303.793505) (xy 392.61869 -303.776053) (xy 392.576069 -303.751446)
			(xy 392.537948 -303.720321) (xy 392.505313 -303.683484) (xy 392.47901 -303.641888) (xy 392.459719 -303.596612)
			(xy 392.447942 -303.548828) (xy 392.443982 -303.499774) (xy 392.105134 -303.499774) (xy 392.104639 -303.524381)
			(xy 392.096744 -303.572958) (xy 392.08116 -303.619639) (xy 392.058289 -303.663216) (xy 392.028724 -303.70256)
			(xy 391.993231 -303.736652) (xy 391.952728 -303.764608) (xy 391.908266 -303.785706) (xy 391.860995 -303.799398)
			(xy 391.81214 -303.80533) (xy 391.762965 -303.803349) (xy 391.714746 -303.793505) (xy 391.66873 -303.776053)
			(xy 391.626109 -303.751446) (xy 391.587988 -303.720321) (xy 391.555353 -303.683484) (xy 391.52905 -303.641888)
			(xy 391.509759 -303.596612) (xy 391.497982 -303.548828) (xy 391.494022 -303.499774) (xy 391.155174 -303.499774)
			(xy 391.154679 -303.524381) (xy 391.146784 -303.572958) (xy 391.1312 -303.619639) (xy 391.108329 -303.663216)
			(xy 391.078764 -303.70256) (xy 391.043271 -303.736652) (xy 391.002768 -303.764608) (xy 390.958306 -303.785706)
			(xy 390.911035 -303.799398) (xy 390.86218 -303.80533) (xy 390.813005 -303.803349) (xy 390.764786 -303.793505)
			(xy 390.71877 -303.776053) (xy 390.676149 -303.751446) (xy 390.638028 -303.720321) (xy 390.605393 -303.683484)
			(xy 390.57909 -303.641888) (xy 390.559799 -303.596612) (xy 390.548022 -303.548828) (xy 390.544062 -303.499774)
			(xy 390.205214 -303.499774) (xy 390.204719 -303.524381) (xy 390.196824 -303.572958) (xy 390.18124 -303.619639)
			(xy 390.158369 -303.663216) (xy 390.128804 -303.70256) (xy 390.093311 -303.736652) (xy 390.052808 -303.764608)
			(xy 390.008346 -303.785706) (xy 389.961075 -303.799398) (xy 389.91222 -303.80533) (xy 389.863045 -303.803349)
			(xy 389.814826 -303.793505) (xy 389.76881 -303.776053) (xy 389.726189 -303.751446) (xy 389.688068 -303.720321)
			(xy 389.655433 -303.683484) (xy 389.62913 -303.641888) (xy 389.609839 -303.596612) (xy 389.598062 -303.548828)
			(xy 389.594102 -303.499774) (xy 389.255254 -303.499774) (xy 389.254759 -303.524381) (xy 389.246864 -303.572958)
			(xy 389.23128 -303.619639) (xy 389.208409 -303.663216) (xy 389.178844 -303.70256) (xy 389.143351 -303.736652)
			(xy 389.102848 -303.764608) (xy 389.058386 -303.785706) (xy 389.011115 -303.799398) (xy 388.96226 -303.80533)
			(xy 388.913085 -303.803349) (xy 388.864866 -303.793505) (xy 388.81885 -303.776053) (xy 388.776229 -303.751446)
			(xy 388.738108 -303.720321) (xy 388.705473 -303.683484) (xy 388.67917 -303.641888) (xy 388.659879 -303.596612)
			(xy 388.648102 -303.548828) (xy 388.644142 -303.499774) (xy 388.305294 -303.499774) (xy 388.304799 -303.524381)
			(xy 388.296904 -303.572958) (xy 388.28132 -303.619639) (xy 388.258449 -303.663216) (xy 388.228884 -303.70256)
			(xy 388.193391 -303.736652) (xy 388.152888 -303.764608) (xy 388.108426 -303.785706) (xy 388.061155 -303.799398)
			(xy 388.0123 -303.80533) (xy 387.963125 -303.803349) (xy 387.914906 -303.793505) (xy 387.86889 -303.776053)
			(xy 387.826269 -303.751446) (xy 387.788148 -303.720321) (xy 387.755513 -303.683484) (xy 387.72921 -303.641888)
			(xy 387.709919 -303.596612) (xy 387.698142 -303.548828) (xy 387.694182 -303.499774) (xy 387.355334 -303.499774)
			(xy 387.354839 -303.524381) (xy 387.346944 -303.572958) (xy 387.33136 -303.619639) (xy 387.308489 -303.663216)
			(xy 387.278924 -303.70256) (xy 387.243431 -303.736652) (xy 387.202928 -303.764608) (xy 387.158466 -303.785706)
			(xy 387.111195 -303.799398) (xy 387.06234 -303.80533) (xy 387.013165 -303.803349) (xy 386.964946 -303.793505)
			(xy 386.91893 -303.776053) (xy 386.876309 -303.751446) (xy 386.838188 -303.720321) (xy 386.805553 -303.683484)
			(xy 386.77925 -303.641888) (xy 386.759959 -303.596612) (xy 386.748182 -303.548828) (xy 386.744222 -303.499774)
			(xy 386.40512 -303.499774) (xy 386.404625 -303.524381) (xy 386.39673 -303.572958) (xy 386.381146 -303.619639)
			(xy 386.358275 -303.663216) (xy 386.32871 -303.70256) (xy 386.293217 -303.736652) (xy 386.252714 -303.764608)
			(xy 386.208252 -303.785706) (xy 386.160981 -303.799398) (xy 386.112126 -303.80533) (xy 386.062951 -303.803349)
			(xy 386.014732 -303.793505) (xy 385.968716 -303.776053) (xy 385.926095 -303.751446) (xy 385.887974 -303.720321)
			(xy 385.855339 -303.683484) (xy 385.829036 -303.641888) (xy 385.809745 -303.596612) (xy 385.797968 -303.548828)
			(xy 385.794008 -303.499774) (xy 385.45516 -303.499774) (xy 385.454665 -303.524381) (xy 385.44677 -303.572958)
			(xy 385.431186 -303.619639) (xy 385.408315 -303.663216) (xy 385.37875 -303.70256) (xy 385.343257 -303.736652)
			(xy 385.302754 -303.764608) (xy 385.258292 -303.785706) (xy 385.211021 -303.799398) (xy 385.162166 -303.80533)
			(xy 385.112991 -303.803349) (xy 385.064772 -303.793505) (xy 385.018756 -303.776053) (xy 384.976135 -303.751446)
			(xy 384.938014 -303.720321) (xy 384.905379 -303.683484) (xy 384.879076 -303.641888) (xy 384.859785 -303.596612)
			(xy 384.848008 -303.548828) (xy 384.844048 -303.499774) (xy 351.03308 -303.499774) (xy 351.03308 -303.974754)
			(xy 394.819136 -303.974754) (xy 394.823096 -303.9257) (xy 394.834873 -303.877916) (xy 394.854164 -303.83264)
			(xy 394.880467 -303.791044) (xy 394.913102 -303.754207) (xy 394.951223 -303.723082) (xy 394.993844 -303.698475)
			(xy 395.03986 -303.681023) (xy 395.088079 -303.671179) (xy 395.137254 -303.669198) (xy 395.186109 -303.67513)
			(xy 395.23338 -303.688822) (xy 395.277842 -303.70992) (xy 395.318345 -303.737876) (xy 395.353838 -303.771968)
			(xy 395.383403 -303.811312) (xy 395.406274 -303.854889) (xy 395.421858 -303.90157) (xy 395.429753 -303.950147)
			(xy 395.430248 -303.974754) (xy 395.769096 -303.974754) (xy 395.773056 -303.9257) (xy 395.784833 -303.877916)
			(xy 395.804124 -303.83264) (xy 395.830427 -303.791044) (xy 395.863062 -303.754207) (xy 395.901183 -303.723082)
			(xy 395.943804 -303.698475) (xy 395.98982 -303.681023) (xy 396.038039 -303.671179) (xy 396.087214 -303.669198)
			(xy 396.136069 -303.67513) (xy 396.18334 -303.688822) (xy 396.227802 -303.70992) (xy 396.268305 -303.737876)
			(xy 396.303798 -303.771968) (xy 396.333363 -303.811312) (xy 396.356234 -303.854889) (xy 396.371818 -303.90157)
			(xy 396.379713 -303.950147) (xy 396.380208 -303.974754) (xy 396.719056 -303.974754) (xy 396.723016 -303.9257)
			(xy 396.734793 -303.877916) (xy 396.754084 -303.83264) (xy 396.780387 -303.791044) (xy 396.813022 -303.754207)
			(xy 396.851143 -303.723082) (xy 396.893764 -303.698475) (xy 396.93978 -303.681023) (xy 396.987999 -303.671179)
			(xy 397.037174 -303.669198) (xy 397.086029 -303.67513) (xy 397.1333 -303.688822) (xy 397.177762 -303.70992)
			(xy 397.218265 -303.737876) (xy 397.253758 -303.771968) (xy 397.283323 -303.811312) (xy 397.306194 -303.854889)
			(xy 397.321778 -303.90157) (xy 397.329673 -303.950147) (xy 397.330168 -303.974754) (xy 397.669016 -303.974754)
			(xy 397.672976 -303.9257) (xy 397.684753 -303.877916) (xy 397.704044 -303.83264) (xy 397.730347 -303.791044)
			(xy 397.762982 -303.754207) (xy 397.801103 -303.723082) (xy 397.843724 -303.698475) (xy 397.88974 -303.681023)
			(xy 397.937959 -303.671179) (xy 397.987134 -303.669198) (xy 398.035989 -303.67513) (xy 398.08326 -303.688822)
			(xy 398.127722 -303.70992) (xy 398.168225 -303.737876) (xy 398.203718 -303.771968) (xy 398.233283 -303.811312)
			(xy 398.256154 -303.854889) (xy 398.271738 -303.90157) (xy 398.279633 -303.950147) (xy 398.280128 -303.974754)
			(xy 398.279633 -303.999361) (xy 398.271738 -304.047938) (xy 398.256154 -304.094619) (xy 398.233283 -304.138196)
			(xy 398.203718 -304.17754) (xy 398.168225 -304.211632) (xy 398.127722 -304.239588) (xy 398.08326 -304.260686)
			(xy 398.035989 -304.274378) (xy 397.987134 -304.28031) (xy 397.937959 -304.278329) (xy 397.88974 -304.268485)
			(xy 397.843724 -304.251033) (xy 397.801103 -304.226426) (xy 397.762982 -304.195301) (xy 397.730347 -304.158464)
			(xy 397.704044 -304.116868) (xy 397.684753 -304.071592) (xy 397.672976 -304.023808) (xy 397.669016 -303.974754)
			(xy 397.330168 -303.974754) (xy 397.329673 -303.999361) (xy 397.321778 -304.047938) (xy 397.306194 -304.094619)
			(xy 397.283323 -304.138196) (xy 397.253758 -304.17754) (xy 397.218265 -304.211632) (xy 397.177762 -304.239588)
			(xy 397.1333 -304.260686) (xy 397.086029 -304.274378) (xy 397.037174 -304.28031) (xy 396.987999 -304.278329)
			(xy 396.93978 -304.268485) (xy 396.893764 -304.251033) (xy 396.851143 -304.226426) (xy 396.813022 -304.195301)
			(xy 396.780387 -304.158464) (xy 396.754084 -304.116868) (xy 396.734793 -304.071592) (xy 396.723016 -304.023808)
			(xy 396.719056 -303.974754) (xy 396.380208 -303.974754) (xy 396.379713 -303.999361) (xy 396.371818 -304.047938)
			(xy 396.356234 -304.094619) (xy 396.333363 -304.138196) (xy 396.303798 -304.17754) (xy 396.268305 -304.211632)
			(xy 396.227802 -304.239588) (xy 396.18334 -304.260686) (xy 396.136069 -304.274378) (xy 396.087214 -304.28031)
			(xy 396.038039 -304.278329) (xy 395.98982 -304.268485) (xy 395.943804 -304.251033) (xy 395.901183 -304.226426)
			(xy 395.863062 -304.195301) (xy 395.830427 -304.158464) (xy 395.804124 -304.116868) (xy 395.784833 -304.071592)
			(xy 395.773056 -304.023808) (xy 395.769096 -303.974754) (xy 395.430248 -303.974754) (xy 395.429753 -303.999361)
			(xy 395.421858 -304.047938) (xy 395.406274 -304.094619) (xy 395.383403 -304.138196) (xy 395.353838 -304.17754)
			(xy 395.318345 -304.211632) (xy 395.277842 -304.239588) (xy 395.23338 -304.260686) (xy 395.186109 -304.274378)
			(xy 395.137254 -304.28031) (xy 395.088079 -304.278329) (xy 395.03986 -304.268485) (xy 394.993844 -304.251033)
			(xy 394.951223 -304.226426) (xy 394.913102 -304.195301) (xy 394.880467 -304.158464) (xy 394.854164 -304.116868)
			(xy 394.834873 -304.071592) (xy 394.823096 -304.023808) (xy 394.819136 -303.974754) (xy 351.03308 -303.974754)
			(xy 351.03308 -305.008534) (xy 353.029012 -305.008534) (xy 353.029495 -304.981164) (xy 353.037308 -304.926986)
			(xy 353.052793 -304.874483) (xy 353.075631 -304.824736) (xy 353.105352 -304.778768) (xy 353.122992 -304.757836)
			(xy 353.123246 -304.757582) (xy 353.128852 -304.750509) (xy 353.135086 -304.733582) (xy 353.135438 -304.724562)
			(xy 353.135438 -304.657506) (xy 353.13507 -304.64849) (xy 353.128829 -304.631574) (xy 353.123246 -304.624486)
			(xy 353.122992 -304.624486) (xy 353.122992 -304.624232) (xy 353.105353 -304.6033) (xy 353.075642 -304.557327)
			(xy 353.052806 -304.507579) (xy 353.037315 -304.455079) (xy 353.029486 -304.400903) (xy 353.029012 -304.373534)
			(xy 353.029498 -304.346283) (xy 353.037254 -304.292335) (xy 353.052609 -304.24004) (xy 353.075251 -304.190463)
			(xy 353.104717 -304.144613) (xy 353.140408 -304.103422) (xy 353.181599 -304.067731) (xy 353.227449 -304.038265)
			(xy 353.277026 -304.015623) (xy 353.329321 -304.000268) (xy 353.383269 -303.992512) (xy 353.437771 -303.992512)
			(xy 353.491719 -304.000268) (xy 353.544014 -304.015623) (xy 353.593591 -304.038265) (xy 353.639441 -304.067731)
			(xy 353.680632 -304.103422) (xy 353.716323 -304.144613) (xy 353.745789 -304.190463) (xy 353.768431 -304.24004)
			(xy 353.783786 -304.292335) (xy 353.791542 -304.346283) (xy 353.792028 -304.373534) (xy 353.791599 -304.400906)
			(xy 353.783775 -304.455087) (xy 353.768278 -304.507591) (xy 353.745428 -304.557338) (xy 353.715694 -304.603302)
			(xy 353.698048 -304.624232) (xy 353.697794 -304.624486) (xy 353.692206 -304.631572) (xy 353.685961 -304.648489)
			(xy 353.685602 -304.657506) (xy 353.685602 -304.724562) (xy 353.685977 -304.733577) (xy 353.692212 -304.750494)
			(xy 353.697794 -304.757582) (xy 353.698048 -304.757582) (xy 353.698048 -304.757836) (xy 353.715662 -304.778788)
			(xy 353.74538 -304.824755) (xy 353.768221 -304.874497) (xy 353.783718 -304.926993) (xy 353.791551 -304.981166)
			(xy 353.792028 -305.008534) (xy 356.449122 -305.008534) (xy 356.449603 -304.981164) (xy 356.457416 -304.926986)
			(xy 356.472902 -304.874482) (xy 356.49574 -304.824735) (xy 356.525462 -304.778768) (xy 356.543102 -304.757836)
			(xy 356.543356 -304.757582) (xy 356.548963 -304.75051) (xy 356.555196 -304.733582) (xy 356.555548 -304.724562)
			(xy 356.555548 -304.657506) (xy 356.555199 -304.648488) (xy 356.548947 -304.631571) (xy 356.543356 -304.624486)
			(xy 356.543102 -304.624486) (xy 356.543102 -304.624232) (xy 356.525465 -304.603298) (xy 356.495753 -304.557326)
			(xy 356.472916 -304.507579) (xy 356.457425 -304.455079) (xy 356.449596 -304.400903) (xy 356.449122 -304.373534)
			(xy 356.449608 -304.346283) (xy 356.457364 -304.292335) (xy 356.472719 -304.24004) (xy 356.495361 -304.190463)
			(xy 356.524827 -304.144613) (xy 356.560518 -304.103422) (xy 356.601709 -304.067731) (xy 356.647559 -304.038265)
			(xy 356.697136 -304.015623) (xy 356.749431 -304.000268) (xy 356.803379 -303.992512) (xy 356.857881 -303.992512)
			(xy 356.911829 -304.000268) (xy 356.964124 -304.015623) (xy 357.013701 -304.038265) (xy 357.059551 -304.067731)
			(xy 357.100742 -304.103422) (xy 357.136433 -304.144613) (xy 357.165899 -304.190463) (xy 357.188541 -304.24004)
			(xy 357.203896 -304.292335) (xy 357.211652 -304.346283) (xy 357.212138 -304.373534) (xy 357.211707 -304.400906)
			(xy 357.203883 -304.455087) (xy 357.188387 -304.507591) (xy 357.165537 -304.557337) (xy 357.135804 -304.603302)
			(xy 357.118158 -304.624232) (xy 357.117904 -304.624486) (xy 357.112318 -304.631573) (xy 357.106071 -304.648489)
			(xy 357.105712 -304.657506) (xy 357.105712 -304.724562) (xy 357.106085 -304.733577) (xy 357.112321 -304.750494)
			(xy 357.117904 -304.757582) (xy 357.118158 -304.757582) (xy 357.118158 -304.757836) (xy 357.135774 -304.778787)
			(xy 357.165491 -304.824754) (xy 357.188332 -304.874496) (xy 357.203828 -304.926993) (xy 357.211661 -304.981166)
			(xy 357.212138 -305.008534) (xy 357.837232 -305.008534) (xy 357.83771 -304.981164) (xy 357.845524 -304.926985)
			(xy 357.86101 -304.874482) (xy 357.883849 -304.824735) (xy 357.913572 -304.778768) (xy 357.931212 -304.757836)
			(xy 357.931466 -304.757582) (xy 357.937074 -304.75051) (xy 357.943306 -304.733582) (xy 357.943658 -304.724562)
			(xy 357.943658 -304.657506) (xy 357.943307 -304.648488) (xy 357.937056 -304.631571) (xy 357.931466 -304.624486)
			(xy 357.931212 -304.624486) (xy 357.931212 -304.624232) (xy 357.913576 -304.603297) (xy 357.883864 -304.557325)
			(xy 357.861027 -304.507579) (xy 357.845535 -304.455078) (xy 357.837706 -304.400903) (xy 357.837232 -304.373534)
			(xy 357.837718 -304.346283) (xy 357.845474 -304.292335) (xy 357.860829 -304.24004) (xy 357.883471 -304.190463)
			(xy 357.912937 -304.144613) (xy 357.948628 -304.103422) (xy 357.989819 -304.067731) (xy 358.035669 -304.038265)
			(xy 358.085246 -304.015623) (xy 358.137541 -304.000268) (xy 358.191489 -303.992512) (xy 358.245991 -303.992512)
			(xy 358.299939 -304.000268) (xy 358.352234 -304.015623) (xy 358.401811 -304.038265) (xy 358.447661 -304.067731)
			(xy 358.488852 -304.103422) (xy 358.524543 -304.144613) (xy 358.554009 -304.190463) (xy 358.576651 -304.24004)
			(xy 358.592006 -304.292335) (xy 358.599762 -304.346283) (xy 358.600248 -304.373534) (xy 358.599815 -304.400906)
			(xy 358.591991 -304.455087) (xy 358.576495 -304.507591) (xy 358.553645 -304.557337) (xy 358.523913 -304.603302)
			(xy 358.506268 -304.624232) (xy 358.506014 -304.624486) (xy 358.500429 -304.631574) (xy 358.494181 -304.64849)
			(xy 358.493822 -304.657506) (xy 358.493822 -304.724562) (xy 358.494193 -304.733578) (xy 358.50043 -304.750495)
			(xy 358.506014 -304.757582) (xy 358.506268 -304.757582) (xy 358.506268 -304.757836) (xy 358.523886 -304.778785)
			(xy 358.553602 -304.824753) (xy 358.576442 -304.874496) (xy 358.591938 -304.926993) (xy 358.599772 -304.981166)
			(xy 358.600248 -305.008534) (xy 359.869232 -305.008534) (xy 359.86971 -304.981164) (xy 359.877524 -304.926985)
			(xy 359.89301 -304.874482) (xy 359.915849 -304.824735) (xy 359.945572 -304.778768) (xy 359.963212 -304.757836)
			(xy 359.963466 -304.757582) (xy 359.969074 -304.75051) (xy 359.975306 -304.733582) (xy 359.975658 -304.724562)
			(xy 359.975658 -304.657506) (xy 359.975307 -304.648488) (xy 359.969056 -304.631571) (xy 359.963466 -304.624486)
			(xy 359.963212 -304.624486) (xy 359.963212 -304.624232) (xy 359.945576 -304.603297) (xy 359.915864 -304.557325)
			(xy 359.893027 -304.507579) (xy 359.877535 -304.455078) (xy 359.869706 -304.400903) (xy 359.869232 -304.373534)
			(xy 359.869718 -304.346283) (xy 359.877474 -304.292335) (xy 359.892829 -304.24004) (xy 359.915471 -304.190463)
			(xy 359.944937 -304.144613) (xy 359.980628 -304.103422) (xy 360.021819 -304.067731) (xy 360.067669 -304.038265)
			(xy 360.117246 -304.015623) (xy 360.169541 -304.000268) (xy 360.223489 -303.992512) (xy 360.277991 -303.992512)
			(xy 360.331939 -304.000268) (xy 360.384234 -304.015623) (xy 360.433811 -304.038265) (xy 360.479661 -304.067731)
			(xy 360.520852 -304.103422) (xy 360.556543 -304.144613) (xy 360.586009 -304.190463) (xy 360.608651 -304.24004)
			(xy 360.624006 -304.292335) (xy 360.631762 -304.346283) (xy 360.632248 -304.373534) (xy 360.631815 -304.400906)
			(xy 360.623991 -304.455087) (xy 360.608495 -304.507591) (xy 360.585645 -304.557337) (xy 360.555913 -304.603302)
			(xy 360.538268 -304.624232) (xy 360.538014 -304.624486) (xy 360.532429 -304.631574) (xy 360.526181 -304.64849)
			(xy 360.525822 -304.657506) (xy 360.525822 -304.724562) (xy 360.526193 -304.733578) (xy 360.53243 -304.750495)
			(xy 360.538014 -304.757582) (xy 360.538268 -304.757582) (xy 360.538268 -304.757836) (xy 360.555886 -304.778785)
			(xy 360.585602 -304.824753) (xy 360.608442 -304.874496) (xy 360.623938 -304.926993) (xy 360.631772 -304.981166)
			(xy 360.632248 -305.008534) (xy 364.677452 -305.008534) (xy 364.677925 -304.981164) (xy 364.685739 -304.926985)
			(xy 364.701226 -304.874481) (xy 364.724067 -304.824734) (xy 364.753791 -304.778767) (xy 364.771432 -304.757836)
			(xy 364.771686 -304.757582) (xy 364.777285 -304.750504) (xy 364.783525 -304.733581) (xy 364.783878 -304.724562)
			(xy 364.783878 -304.657506) (xy 364.783523 -304.648489) (xy 364.777275 -304.631572) (xy 364.771686 -304.624486)
			(xy 364.771432 -304.624486) (xy 364.771432 -304.624232) (xy 364.753799 -304.603295) (xy 364.724086 -304.557324)
			(xy 364.701248 -304.507578) (xy 364.685755 -304.455078) (xy 364.677926 -304.400903) (xy 364.677452 -304.373534)
			(xy 364.677938 -304.346283) (xy 364.685694 -304.292335) (xy 364.701049 -304.24004) (xy 364.723691 -304.190463)
			(xy 364.753157 -304.144613) (xy 364.788848 -304.103422) (xy 364.830039 -304.067731) (xy 364.875889 -304.038265)
			(xy 364.925466 -304.015623) (xy 364.977761 -304.000268) (xy 365.031709 -303.992512) (xy 365.086211 -303.992512)
			(xy 365.140159 -304.000268) (xy 365.192454 -304.015623) (xy 365.242031 -304.038265) (xy 365.287881 -304.067731)
			(xy 365.329072 -304.103422) (xy 365.364763 -304.144613) (xy 365.394229 -304.190463) (xy 365.416871 -304.24004)
			(xy 365.432226 -304.292335) (xy 365.439982 -304.346283) (xy 365.440468 -304.373534) (xy 365.44003 -304.400905)
			(xy 365.432206 -304.455086) (xy 365.416711 -304.50759) (xy 365.393863 -304.557336) (xy 365.364132 -304.603301)
			(xy 365.346488 -304.624232) (xy 365.346234 -304.624486) (xy 365.340639 -304.631567) (xy 365.334399 -304.648488)
			(xy 365.334042 -304.657506) (xy 365.334042 -304.724562) (xy 365.334408 -304.733578) (xy 365.340648 -304.750496)
			(xy 365.346234 -304.757582) (xy 365.346488 -304.757582) (xy 365.346488 -304.757836) (xy 365.364109 -304.778783)
			(xy 365.393824 -304.824751) (xy 365.416663 -304.874495) (xy 365.432159 -304.926993) (xy 365.439992 -304.981166)
			(xy 365.440468 -305.008534) (xy 365.439982 -305.035785) (xy 365.432226 -305.089733) (xy 365.416871 -305.142028)
			(xy 365.394229 -305.191605) (xy 365.364763 -305.237455) (xy 365.329072 -305.278646) (xy 365.287881 -305.314337)
			(xy 365.242031 -305.343803) (xy 365.203422 -305.361436) (xy 375.710316 -305.361436) (xy 375.710319 -305.306922)
			(xy 375.71808 -305.252964) (xy 375.733442 -305.200659) (xy 375.756091 -305.151073) (xy 375.785568 -305.105216)
			(xy 375.82127 -305.06402) (xy 375.862473 -305.028325) (xy 375.908336 -304.998858) (xy 375.957926 -304.976217)
			(xy 376.010233 -304.960865) (xy 376.064193 -304.953113) (xy 376.09145 -304.952654) (xy 376.091704 -304.952654)
			(xy 376.11939 -304.95367) (xy 376.130566 -304.954432) (xy 376.151648 -304.946558) (xy 376.221752 -304.873914)
			(xy 376.229118 -304.852578) (xy 376.227848 -304.841402) (xy 376.226788 -304.831148) (xy 376.225643 -304.810562)
			(xy 376.225562 -304.800254) (xy 376.226127 -304.773006) (xy 376.233889 -304.719067) (xy 376.249249 -304.66678)
			(xy 376.271893 -304.617212) (xy 376.30136 -304.571371) (xy 376.337052 -304.530191) (xy 376.378241 -304.494508)
			(xy 376.424089 -304.465051) (xy 376.473662 -304.442418) (xy 376.525951 -304.427071) (xy 376.579893 -304.419321)
			(xy 376.634388 -304.419327) (xy 376.688328 -304.427088) (xy 376.740615 -304.442447) (xy 376.757123 -304.449988)
			(xy 383.893834 -304.449988) (xy 383.897794 -304.400934) (xy 383.909571 -304.35315) (xy 383.928862 -304.307874)
			(xy 383.955165 -304.266278) (xy 383.9878 -304.229441) (xy 384.025921 -304.198316) (xy 384.068542 -304.173709)
			(xy 384.114558 -304.156257) (xy 384.162777 -304.146413) (xy 384.211952 -304.144432) (xy 384.260807 -304.150364)
			(xy 384.308078 -304.164056) (xy 384.35254 -304.185154) (xy 384.393043 -304.21311) (xy 384.428536 -304.247202)
			(xy 384.458101 -304.286546) (xy 384.480972 -304.330123) (xy 384.496556 -304.376804) (xy 384.504451 -304.425381)
			(xy 384.504941 -304.449734) (xy 384.844048 -304.449734) (xy 384.848008 -304.40068) (xy 384.859785 -304.352896)
			(xy 384.879076 -304.30762) (xy 384.905379 -304.266024) (xy 384.938014 -304.229187) (xy 384.976135 -304.198062)
			(xy 385.018756 -304.173455) (xy 385.064772 -304.156003) (xy 385.112991 -304.146159) (xy 385.162166 -304.144178)
			(xy 385.211021 -304.15011) (xy 385.258292 -304.163802) (xy 385.302754 -304.1849) (xy 385.343257 -304.212856)
			(xy 385.37875 -304.246948) (xy 385.408315 -304.286292) (xy 385.431186 -304.329869) (xy 385.44677 -304.37655)
			(xy 385.454665 -304.425127) (xy 385.45516 -304.449734) (xy 385.794008 -304.449734) (xy 385.797968 -304.40068)
			(xy 385.809745 -304.352896) (xy 385.829036 -304.30762) (xy 385.855339 -304.266024) (xy 385.887974 -304.229187)
			(xy 385.926095 -304.198062) (xy 385.968716 -304.173455) (xy 386.014732 -304.156003) (xy 386.062951 -304.146159)
			(xy 386.112126 -304.144178) (xy 386.160981 -304.15011) (xy 386.208252 -304.163802) (xy 386.252714 -304.1849)
			(xy 386.293217 -304.212856) (xy 386.32871 -304.246948) (xy 386.358275 -304.286292) (xy 386.381146 -304.329869)
			(xy 386.39673 -304.37655) (xy 386.404625 -304.425127) (xy 386.40512 -304.449734) (xy 386.744222 -304.449734)
			(xy 386.748182 -304.40068) (xy 386.759959 -304.352896) (xy 386.77925 -304.30762) (xy 386.805553 -304.266024)
			(xy 386.838188 -304.229187) (xy 386.876309 -304.198062) (xy 386.91893 -304.173455) (xy 386.964946 -304.156003)
			(xy 387.013165 -304.146159) (xy 387.06234 -304.144178) (xy 387.111195 -304.15011) (xy 387.158466 -304.163802)
			(xy 387.202928 -304.1849) (xy 387.243431 -304.212856) (xy 387.278924 -304.246948) (xy 387.308489 -304.286292)
			(xy 387.33136 -304.329869) (xy 387.346944 -304.37655) (xy 387.354839 -304.425127) (xy 387.355334 -304.449734)
			(xy 387.694182 -304.449734) (xy 387.698142 -304.40068) (xy 387.709919 -304.352896) (xy 387.72921 -304.30762)
			(xy 387.755513 -304.266024) (xy 387.788148 -304.229187) (xy 387.826269 -304.198062) (xy 387.86889 -304.173455)
			(xy 387.914906 -304.156003) (xy 387.963125 -304.146159) (xy 388.0123 -304.144178) (xy 388.061155 -304.15011)
			(xy 388.108426 -304.163802) (xy 388.152888 -304.1849) (xy 388.193391 -304.212856) (xy 388.228884 -304.246948)
			(xy 388.258449 -304.286292) (xy 388.28132 -304.329869) (xy 388.296904 -304.37655) (xy 388.304799 -304.425127)
			(xy 388.305294 -304.449734) (xy 388.644142 -304.449734) (xy 388.648102 -304.40068) (xy 388.659879 -304.352896)
			(xy 388.67917 -304.30762) (xy 388.705473 -304.266024) (xy 388.738108 -304.229187) (xy 388.776229 -304.198062)
			(xy 388.81885 -304.173455) (xy 388.864866 -304.156003) (xy 388.913085 -304.146159) (xy 388.96226 -304.144178)
			(xy 389.011115 -304.15011) (xy 389.058386 -304.163802) (xy 389.102848 -304.1849) (xy 389.143351 -304.212856)
			(xy 389.178844 -304.246948) (xy 389.208409 -304.286292) (xy 389.23128 -304.329869) (xy 389.246864 -304.37655)
			(xy 389.254759 -304.425127) (xy 389.255254 -304.449734) (xy 389.594102 -304.449734) (xy 389.598062 -304.40068)
			(xy 389.609839 -304.352896) (xy 389.62913 -304.30762) (xy 389.655433 -304.266024) (xy 389.688068 -304.229187)
			(xy 389.726189 -304.198062) (xy 389.76881 -304.173455) (xy 389.814826 -304.156003) (xy 389.863045 -304.146159)
			(xy 389.91222 -304.144178) (xy 389.961075 -304.15011) (xy 390.008346 -304.163802) (xy 390.052808 -304.1849)
			(xy 390.093311 -304.212856) (xy 390.128804 -304.246948) (xy 390.158369 -304.286292) (xy 390.18124 -304.329869)
			(xy 390.196824 -304.37655) (xy 390.204719 -304.425127) (xy 390.205214 -304.449734) (xy 390.544062 -304.449734)
			(xy 390.548022 -304.40068) (xy 390.559799 -304.352896) (xy 390.57909 -304.30762) (xy 390.605393 -304.266024)
			(xy 390.638028 -304.229187) (xy 390.676149 -304.198062) (xy 390.71877 -304.173455) (xy 390.764786 -304.156003)
			(xy 390.813005 -304.146159) (xy 390.86218 -304.144178) (xy 390.911035 -304.15011) (xy 390.958306 -304.163802)
			(xy 391.002768 -304.1849) (xy 391.043271 -304.212856) (xy 391.078764 -304.246948) (xy 391.108329 -304.286292)
			(xy 391.1312 -304.329869) (xy 391.146784 -304.37655) (xy 391.154679 -304.425127) (xy 391.155174 -304.449734)
			(xy 391.494022 -304.449734) (xy 391.497982 -304.40068) (xy 391.509759 -304.352896) (xy 391.52905 -304.30762)
			(xy 391.555353 -304.266024) (xy 391.587988 -304.229187) (xy 391.626109 -304.198062) (xy 391.66873 -304.173455)
			(xy 391.714746 -304.156003) (xy 391.762965 -304.146159) (xy 391.81214 -304.144178) (xy 391.860995 -304.15011)
			(xy 391.908266 -304.163802) (xy 391.952728 -304.1849) (xy 391.993231 -304.212856) (xy 392.028724 -304.246948)
			(xy 392.058289 -304.286292) (xy 392.08116 -304.329869) (xy 392.096744 -304.37655) (xy 392.104639 -304.425127)
			(xy 392.105134 -304.449734) (xy 392.443982 -304.449734) (xy 392.447942 -304.40068) (xy 392.459719 -304.352896)
			(xy 392.47901 -304.30762) (xy 392.505313 -304.266024) (xy 392.537948 -304.229187) (xy 392.576069 -304.198062)
			(xy 392.61869 -304.173455) (xy 392.664706 -304.156003) (xy 392.712925 -304.146159) (xy 392.7621 -304.144178)
			(xy 392.810955 -304.15011) (xy 392.858226 -304.163802) (xy 392.902688 -304.1849) (xy 392.943191 -304.212856)
			(xy 392.978684 -304.246948) (xy 393.008249 -304.286292) (xy 393.03112 -304.329869) (xy 393.046704 -304.37655)
			(xy 393.054599 -304.425127) (xy 393.055094 -304.449734) (xy 393.394196 -304.449734) (xy 393.398156 -304.40068)
			(xy 393.409933 -304.352896) (xy 393.429224 -304.30762) (xy 393.455527 -304.266024) (xy 393.488162 -304.229187)
			(xy 393.526283 -304.198062) (xy 393.568904 -304.173455) (xy 393.61492 -304.156003) (xy 393.663139 -304.146159)
			(xy 393.712314 -304.144178) (xy 393.761169 -304.15011) (xy 393.80844 -304.163802) (xy 393.852902 -304.1849)
			(xy 393.893405 -304.212856) (xy 393.928898 -304.246948) (xy 393.958463 -304.286292) (xy 393.981334 -304.329869)
			(xy 393.996918 -304.37655) (xy 394.004813 -304.425127) (xy 394.005308 -304.449734) (xy 394.004813 -304.474341)
			(xy 393.996918 -304.522918) (xy 393.981334 -304.569599) (xy 393.958463 -304.613176) (xy 393.928898 -304.65252)
			(xy 393.893405 -304.686612) (xy 393.852902 -304.714568) (xy 393.80844 -304.735666) (xy 393.761169 -304.749358)
			(xy 393.712314 -304.75529) (xy 393.663139 -304.753309) (xy 393.61492 -304.743465) (xy 393.568904 -304.726013)
			(xy 393.526283 -304.701406) (xy 393.488162 -304.670281) (xy 393.455527 -304.633444) (xy 393.429224 -304.591848)
			(xy 393.409933 -304.546572) (xy 393.398156 -304.498788) (xy 393.394196 -304.449734) (xy 393.055094 -304.449734)
			(xy 393.054599 -304.474341) (xy 393.046704 -304.522918) (xy 393.03112 -304.569599) (xy 393.008249 -304.613176)
			(xy 392.978684 -304.65252) (xy 392.943191 -304.686612) (xy 392.902688 -304.714568) (xy 392.858226 -304.735666)
			(xy 392.810955 -304.749358) (xy 392.7621 -304.75529) (xy 392.712925 -304.753309) (xy 392.664706 -304.743465)
			(xy 392.61869 -304.726013) (xy 392.576069 -304.701406) (xy 392.537948 -304.670281) (xy 392.505313 -304.633444)
			(xy 392.47901 -304.591848) (xy 392.459719 -304.546572) (xy 392.447942 -304.498788) (xy 392.443982 -304.449734)
			(xy 392.105134 -304.449734) (xy 392.104639 -304.474341) (xy 392.096744 -304.522918) (xy 392.08116 -304.569599)
			(xy 392.058289 -304.613176) (xy 392.028724 -304.65252) (xy 391.993231 -304.686612) (xy 391.952728 -304.714568)
			(xy 391.908266 -304.735666) (xy 391.860995 -304.749358) (xy 391.81214 -304.75529) (xy 391.762965 -304.753309)
			(xy 391.714746 -304.743465) (xy 391.66873 -304.726013) (xy 391.626109 -304.701406) (xy 391.587988 -304.670281)
			(xy 391.555353 -304.633444) (xy 391.52905 -304.591848) (xy 391.509759 -304.546572) (xy 391.497982 -304.498788)
			(xy 391.494022 -304.449734) (xy 391.155174 -304.449734) (xy 391.154679 -304.474341) (xy 391.146784 -304.522918)
			(xy 391.1312 -304.569599) (xy 391.108329 -304.613176) (xy 391.078764 -304.65252) (xy 391.043271 -304.686612)
			(xy 391.002768 -304.714568) (xy 390.958306 -304.735666) (xy 390.911035 -304.749358) (xy 390.86218 -304.75529)
			(xy 390.813005 -304.753309) (xy 390.764786 -304.743465) (xy 390.71877 -304.726013) (xy 390.676149 -304.701406)
			(xy 390.638028 -304.670281) (xy 390.605393 -304.633444) (xy 390.57909 -304.591848) (xy 390.559799 -304.546572)
			(xy 390.548022 -304.498788) (xy 390.544062 -304.449734) (xy 390.205214 -304.449734) (xy 390.204719 -304.474341)
			(xy 390.196824 -304.522918) (xy 390.18124 -304.569599) (xy 390.158369 -304.613176) (xy 390.128804 -304.65252)
			(xy 390.093311 -304.686612) (xy 390.052808 -304.714568) (xy 390.008346 -304.735666) (xy 389.961075 -304.749358)
			(xy 389.91222 -304.75529) (xy 389.863045 -304.753309) (xy 389.814826 -304.743465) (xy 389.76881 -304.726013)
			(xy 389.726189 -304.701406) (xy 389.688068 -304.670281) (xy 389.655433 -304.633444) (xy 389.62913 -304.591848)
			(xy 389.609839 -304.546572) (xy 389.598062 -304.498788) (xy 389.594102 -304.449734) (xy 389.255254 -304.449734)
			(xy 389.254759 -304.474341) (xy 389.246864 -304.522918) (xy 389.23128 -304.569599) (xy 389.208409 -304.613176)
			(xy 389.178844 -304.65252) (xy 389.143351 -304.686612) (xy 389.102848 -304.714568) (xy 389.058386 -304.735666)
			(xy 389.011115 -304.749358) (xy 388.96226 -304.75529) (xy 388.913085 -304.753309) (xy 388.864866 -304.743465)
			(xy 388.81885 -304.726013) (xy 388.776229 -304.701406) (xy 388.738108 -304.670281) (xy 388.705473 -304.633444)
			(xy 388.67917 -304.591848) (xy 388.659879 -304.546572) (xy 388.648102 -304.498788) (xy 388.644142 -304.449734)
			(xy 388.305294 -304.449734) (xy 388.304799 -304.474341) (xy 388.296904 -304.522918) (xy 388.28132 -304.569599)
			(xy 388.258449 -304.613176) (xy 388.228884 -304.65252) (xy 388.193391 -304.686612) (xy 388.152888 -304.714568)
			(xy 388.108426 -304.735666) (xy 388.061155 -304.749358) (xy 388.0123 -304.75529) (xy 387.963125 -304.753309)
			(xy 387.914906 -304.743465) (xy 387.86889 -304.726013) (xy 387.826269 -304.701406) (xy 387.788148 -304.670281)
			(xy 387.755513 -304.633444) (xy 387.72921 -304.591848) (xy 387.709919 -304.546572) (xy 387.698142 -304.498788)
			(xy 387.694182 -304.449734) (xy 387.355334 -304.449734) (xy 387.354839 -304.474341) (xy 387.346944 -304.522918)
			(xy 387.33136 -304.569599) (xy 387.308489 -304.613176) (xy 387.278924 -304.65252) (xy 387.243431 -304.686612)
			(xy 387.202928 -304.714568) (xy 387.158466 -304.735666) (xy 387.111195 -304.749358) (xy 387.06234 -304.75529)
			(xy 387.013165 -304.753309) (xy 386.964946 -304.743465) (xy 386.91893 -304.726013) (xy 386.876309 -304.701406)
			(xy 386.838188 -304.670281) (xy 386.805553 -304.633444) (xy 386.77925 -304.591848) (xy 386.759959 -304.546572)
			(xy 386.748182 -304.498788) (xy 386.744222 -304.449734) (xy 386.40512 -304.449734) (xy 386.404625 -304.474341)
			(xy 386.39673 -304.522918) (xy 386.381146 -304.569599) (xy 386.358275 -304.613176) (xy 386.32871 -304.65252)
			(xy 386.293217 -304.686612) (xy 386.252714 -304.714568) (xy 386.208252 -304.735666) (xy 386.160981 -304.749358)
			(xy 386.112126 -304.75529) (xy 386.062951 -304.753309) (xy 386.014732 -304.743465) (xy 385.968716 -304.726013)
			(xy 385.926095 -304.701406) (xy 385.887974 -304.670281) (xy 385.855339 -304.633444) (xy 385.829036 -304.591848)
			(xy 385.809745 -304.546572) (xy 385.797968 -304.498788) (xy 385.794008 -304.449734) (xy 385.45516 -304.449734)
			(xy 385.454665 -304.474341) (xy 385.44677 -304.522918) (xy 385.431186 -304.569599) (xy 385.408315 -304.613176)
			(xy 385.37875 -304.65252) (xy 385.343257 -304.686612) (xy 385.302754 -304.714568) (xy 385.258292 -304.735666)
			(xy 385.211021 -304.749358) (xy 385.162166 -304.75529) (xy 385.112991 -304.753309) (xy 385.064772 -304.743465)
			(xy 385.018756 -304.726013) (xy 384.976135 -304.701406) (xy 384.938014 -304.670281) (xy 384.905379 -304.633444)
			(xy 384.879076 -304.591848) (xy 384.859785 -304.546572) (xy 384.848008 -304.498788) (xy 384.844048 -304.449734)
			(xy 384.504941 -304.449734) (xy 384.504946 -304.449988) (xy 384.504451 -304.474595) (xy 384.496556 -304.523172)
			(xy 384.480972 -304.569853) (xy 384.458101 -304.61343) (xy 384.428536 -304.652774) (xy 384.393043 -304.686866)
			(xy 384.35254 -304.714822) (xy 384.308078 -304.73592) (xy 384.260807 -304.749612) (xy 384.211952 -304.755544)
			(xy 384.162777 -304.753563) (xy 384.114558 -304.743719) (xy 384.068542 -304.726267) (xy 384.025921 -304.70166)
			(xy 383.9878 -304.670535) (xy 383.955165 -304.633698) (xy 383.928862 -304.592102) (xy 383.909571 -304.546826)
			(xy 383.897794 -304.499042) (xy 383.893834 -304.449988) (xy 376.757123 -304.449988) (xy 376.790183 -304.46509)
			(xy 376.836024 -304.494557) (xy 376.877206 -304.530248) (xy 376.912888 -304.571437) (xy 376.942346 -304.617284)
			(xy 376.96498 -304.666857) (xy 376.980328 -304.719146) (xy 376.988078 -304.773088) (xy 376.988073 -304.827583)
			(xy 376.980313 -304.881523) (xy 376.967627 -304.924714) (xy 394.819136 -304.924714) (xy 394.823096 -304.87566)
			(xy 394.834873 -304.827876) (xy 394.854164 -304.7826) (xy 394.880467 -304.741004) (xy 394.913102 -304.704167)
			(xy 394.951223 -304.673042) (xy 394.993844 -304.648435) (xy 395.03986 -304.630983) (xy 395.088079 -304.621139)
			(xy 395.137254 -304.619158) (xy 395.186109 -304.62509) (xy 395.23338 -304.638782) (xy 395.277842 -304.65988)
			(xy 395.318345 -304.687836) (xy 395.353838 -304.721928) (xy 395.383403 -304.761272) (xy 395.406274 -304.804849)
			(xy 395.421858 -304.85153) (xy 395.429753 -304.900107) (xy 395.430248 -304.924714) (xy 395.769096 -304.924714)
			(xy 395.773056 -304.87566) (xy 395.784833 -304.827876) (xy 395.804124 -304.7826) (xy 395.830427 -304.741004)
			(xy 395.863062 -304.704167) (xy 395.901183 -304.673042) (xy 395.943804 -304.648435) (xy 395.98982 -304.630983)
			(xy 396.038039 -304.621139) (xy 396.087214 -304.619158) (xy 396.136069 -304.62509) (xy 396.18334 -304.638782)
			(xy 396.227802 -304.65988) (xy 396.268305 -304.687836) (xy 396.303798 -304.721928) (xy 396.333363 -304.761272)
			(xy 396.356234 -304.804849) (xy 396.371818 -304.85153) (xy 396.379713 -304.900107) (xy 396.380208 -304.924714)
			(xy 396.719056 -304.924714) (xy 396.723016 -304.87566) (xy 396.734793 -304.827876) (xy 396.754084 -304.7826)
			(xy 396.780387 -304.741004) (xy 396.813022 -304.704167) (xy 396.851143 -304.673042) (xy 396.893764 -304.648435)
			(xy 396.93978 -304.630983) (xy 396.987999 -304.621139) (xy 397.037174 -304.619158) (xy 397.086029 -304.62509)
			(xy 397.1333 -304.638782) (xy 397.177762 -304.65988) (xy 397.218265 -304.687836) (xy 397.253758 -304.721928)
			(xy 397.283323 -304.761272) (xy 397.306194 -304.804849) (xy 397.321778 -304.85153) (xy 397.329673 -304.900107)
			(xy 397.330168 -304.924714) (xy 397.329673 -304.949321) (xy 397.321778 -304.997898) (xy 397.306194 -305.044579)
			(xy 397.283323 -305.088156) (xy 397.253758 -305.1275) (xy 397.218265 -305.161592) (xy 397.177762 -305.189548)
			(xy 397.1333 -305.210646) (xy 397.086029 -305.224338) (xy 397.037174 -305.23027) (xy 396.987999 -305.228289)
			(xy 396.93978 -305.218445) (xy 396.893764 -305.200993) (xy 396.851143 -305.176386) (xy 396.813022 -305.145261)
			(xy 396.780387 -305.108424) (xy 396.754084 -305.066828) (xy 396.734793 -305.021552) (xy 396.723016 -304.973768)
			(xy 396.719056 -304.924714) (xy 396.380208 -304.924714) (xy 396.379713 -304.949321) (xy 396.371818 -304.997898)
			(xy 396.356234 -305.044579) (xy 396.333363 -305.088156) (xy 396.303798 -305.1275) (xy 396.268305 -305.161592)
			(xy 396.227802 -305.189548) (xy 396.18334 -305.210646) (xy 396.136069 -305.224338) (xy 396.087214 -305.23027)
			(xy 396.038039 -305.228289) (xy 395.98982 -305.218445) (xy 395.943804 -305.200993) (xy 395.901183 -305.176386)
			(xy 395.863062 -305.145261) (xy 395.830427 -305.108424) (xy 395.804124 -305.066828) (xy 395.784833 -305.021552)
			(xy 395.773056 -304.973768) (xy 395.769096 -304.924714) (xy 395.430248 -304.924714) (xy 395.429753 -304.949321)
			(xy 395.421858 -304.997898) (xy 395.406274 -305.044579) (xy 395.383403 -305.088156) (xy 395.353838 -305.1275)
			(xy 395.318345 -305.161592) (xy 395.277842 -305.189548) (xy 395.23338 -305.210646) (xy 395.186109 -305.224338)
			(xy 395.137254 -305.23027) (xy 395.088079 -305.228289) (xy 395.03986 -305.218445) (xy 394.993844 -305.200993)
			(xy 394.951223 -305.176386) (xy 394.913102 -305.145261) (xy 394.880467 -305.108424) (xy 394.854164 -305.066828)
			(xy 394.834873 -305.021552) (xy 394.823096 -304.973768) (xy 394.819136 -304.924714) (xy 376.967627 -304.924714)
			(xy 376.964955 -304.93381) (xy 376.942312 -304.983378) (xy 376.912846 -305.02922) (xy 376.877156 -305.070402)
			(xy 376.835968 -305.106085) (xy 376.790121 -305.135544) (xy 376.740548 -305.158178) (xy 376.688259 -305.173527)
			(xy 376.634318 -305.181278) (xy 376.60707 -305.181762) (xy 376.606816 -305.181762) (xy 376.57913 -305.180746)
			(xy 376.567954 -305.179984) (xy 376.546872 -305.187858) (xy 376.476768 -305.260502) (xy 376.469402 -305.281838)
			(xy 376.470672 -305.293014) (xy 376.471734 -305.303268) (xy 376.472877 -305.323853) (xy 376.472958 -305.334162)
			(xy 376.472486 -305.361419) (xy 376.46695 -305.399948) (xy 384.844048 -305.399948) (xy 384.848008 -305.350894)
			(xy 384.859785 -305.30311) (xy 384.879076 -305.257834) (xy 384.905379 -305.216238) (xy 384.938014 -305.179401)
			(xy 384.976135 -305.148276) (xy 385.018756 -305.123669) (xy 385.064772 -305.106217) (xy 385.112991 -305.096373)
			(xy 385.162166 -305.094392) (xy 385.211021 -305.100324) (xy 385.258292 -305.114016) (xy 385.302754 -305.135114)
			(xy 385.343257 -305.16307) (xy 385.37875 -305.197162) (xy 385.408315 -305.236506) (xy 385.431186 -305.280083)
			(xy 385.44677 -305.326764) (xy 385.454665 -305.375341) (xy 385.45516 -305.399948) (xy 385.794008 -305.399948)
			(xy 385.797968 -305.350894) (xy 385.809745 -305.30311) (xy 385.829036 -305.257834) (xy 385.855339 -305.216238)
			(xy 385.887974 -305.179401) (xy 385.926095 -305.148276) (xy 385.968716 -305.123669) (xy 386.014732 -305.106217)
			(xy 386.062951 -305.096373) (xy 386.112126 -305.094392) (xy 386.160981 -305.100324) (xy 386.208252 -305.114016)
			(xy 386.252714 -305.135114) (xy 386.293217 -305.16307) (xy 386.32871 -305.197162) (xy 386.358275 -305.236506)
			(xy 386.381146 -305.280083) (xy 386.39673 -305.326764) (xy 386.404625 -305.375341) (xy 386.40512 -305.399948)
			(xy 386.744222 -305.399948) (xy 386.748182 -305.350894) (xy 386.759959 -305.30311) (xy 386.77925 -305.257834)
			(xy 386.805553 -305.216238) (xy 386.838188 -305.179401) (xy 386.876309 -305.148276) (xy 386.91893 -305.123669)
			(xy 386.964946 -305.106217) (xy 387.013165 -305.096373) (xy 387.06234 -305.094392) (xy 387.111195 -305.100324)
			(xy 387.158466 -305.114016) (xy 387.202928 -305.135114) (xy 387.243431 -305.16307) (xy 387.278924 -305.197162)
			(xy 387.308489 -305.236506) (xy 387.33136 -305.280083) (xy 387.346944 -305.326764) (xy 387.354839 -305.375341)
			(xy 387.355334 -305.399948) (xy 387.694182 -305.399948) (xy 387.698142 -305.350894) (xy 387.709919 -305.30311)
			(xy 387.72921 -305.257834) (xy 387.755513 -305.216238) (xy 387.788148 -305.179401) (xy 387.826269 -305.148276)
			(xy 387.86889 -305.123669) (xy 387.914906 -305.106217) (xy 387.963125 -305.096373) (xy 388.0123 -305.094392)
			(xy 388.061155 -305.100324) (xy 388.108426 -305.114016) (xy 388.152888 -305.135114) (xy 388.193391 -305.16307)
			(xy 388.228884 -305.197162) (xy 388.258449 -305.236506) (xy 388.28132 -305.280083) (xy 388.296904 -305.326764)
			(xy 388.304799 -305.375341) (xy 388.305294 -305.399948) (xy 388.644142 -305.399948) (xy 388.648102 -305.350894)
			(xy 388.659879 -305.30311) (xy 388.67917 -305.257834) (xy 388.705473 -305.216238) (xy 388.738108 -305.179401)
			(xy 388.776229 -305.148276) (xy 388.81885 -305.123669) (xy 388.864866 -305.106217) (xy 388.913085 -305.096373)
			(xy 388.96226 -305.094392) (xy 389.011115 -305.100324) (xy 389.058386 -305.114016) (xy 389.102848 -305.135114)
			(xy 389.143351 -305.16307) (xy 389.178844 -305.197162) (xy 389.208409 -305.236506) (xy 389.23128 -305.280083)
			(xy 389.246864 -305.326764) (xy 389.254759 -305.375341) (xy 389.255254 -305.399948) (xy 389.594102 -305.399948)
			(xy 389.598062 -305.350894) (xy 389.609839 -305.30311) (xy 389.62913 -305.257834) (xy 389.655433 -305.216238)
			(xy 389.688068 -305.179401) (xy 389.726189 -305.148276) (xy 389.76881 -305.123669) (xy 389.814826 -305.106217)
			(xy 389.863045 -305.096373) (xy 389.91222 -305.094392) (xy 389.961075 -305.100324) (xy 390.008346 -305.114016)
			(xy 390.052808 -305.135114) (xy 390.093311 -305.16307) (xy 390.128804 -305.197162) (xy 390.158369 -305.236506)
			(xy 390.18124 -305.280083) (xy 390.196824 -305.326764) (xy 390.204719 -305.375341) (xy 390.205214 -305.399948)
			(xy 390.544062 -305.399948) (xy 390.548022 -305.350894) (xy 390.559799 -305.30311) (xy 390.57909 -305.257834)
			(xy 390.605393 -305.216238) (xy 390.638028 -305.179401) (xy 390.676149 -305.148276) (xy 390.71877 -305.123669)
			(xy 390.764786 -305.106217) (xy 390.813005 -305.096373) (xy 390.86218 -305.094392) (xy 390.911035 -305.100324)
			(xy 390.958306 -305.114016) (xy 391.002768 -305.135114) (xy 391.043271 -305.16307) (xy 391.078764 -305.197162)
			(xy 391.108329 -305.236506) (xy 391.1312 -305.280083) (xy 391.146784 -305.326764) (xy 391.154679 -305.375341)
			(xy 391.155174 -305.399948) (xy 391.494022 -305.399948) (xy 391.497982 -305.350894) (xy 391.509759 -305.30311)
			(xy 391.52905 -305.257834) (xy 391.555353 -305.216238) (xy 391.587988 -305.179401) (xy 391.626109 -305.148276)
			(xy 391.66873 -305.123669) (xy 391.714746 -305.106217) (xy 391.762965 -305.096373) (xy 391.81214 -305.094392)
			(xy 391.860995 -305.100324) (xy 391.908266 -305.114016) (xy 391.952728 -305.135114) (xy 391.993231 -305.16307)
			(xy 392.028724 -305.197162) (xy 392.058289 -305.236506) (xy 392.08116 -305.280083) (xy 392.096744 -305.326764)
			(xy 392.104639 -305.375341) (xy 392.105134 -305.399948) (xy 392.443982 -305.399948) (xy 392.447942 -305.350894)
			(xy 392.459719 -305.30311) (xy 392.47901 -305.257834) (xy 392.505313 -305.216238) (xy 392.537948 -305.179401)
			(xy 392.576069 -305.148276) (xy 392.61869 -305.123669) (xy 392.664706 -305.106217) (xy 392.712925 -305.096373)
			(xy 392.7621 -305.094392) (xy 392.810955 -305.100324) (xy 392.858226 -305.114016) (xy 392.902688 -305.135114)
			(xy 392.943191 -305.16307) (xy 392.978684 -305.197162) (xy 393.008249 -305.236506) (xy 393.03112 -305.280083)
			(xy 393.046704 -305.326764) (xy 393.054599 -305.375341) (xy 393.055094 -305.399948) (xy 393.394196 -305.399948)
			(xy 393.398156 -305.350894) (xy 393.409933 -305.30311) (xy 393.429224 -305.257834) (xy 393.455527 -305.216238)
			(xy 393.488162 -305.179401) (xy 393.526283 -305.148276) (xy 393.568904 -305.123669) (xy 393.61492 -305.106217)
			(xy 393.663139 -305.096373) (xy 393.712314 -305.094392) (xy 393.761169 -305.100324) (xy 393.80844 -305.114016)
			(xy 393.852902 -305.135114) (xy 393.893405 -305.16307) (xy 393.928898 -305.197162) (xy 393.958463 -305.236506)
			(xy 393.981334 -305.280083) (xy 393.996918 -305.326764) (xy 394.004813 -305.375341) (xy 394.005308 -305.399948)
			(xy 394.004813 -305.424555) (xy 393.996918 -305.473132) (xy 393.981334 -305.519813) (xy 393.958463 -305.56339)
			(xy 393.928898 -305.602734) (xy 393.893405 -305.636826) (xy 393.852902 -305.664782) (xy 393.80844 -305.68588)
			(xy 393.761169 -305.699572) (xy 393.712314 -305.705504) (xy 393.663139 -305.703523) (xy 393.61492 -305.693679)
			(xy 393.568904 -305.676227) (xy 393.526283 -305.65162) (xy 393.488162 -305.620495) (xy 393.455527 -305.583658)
			(xy 393.429224 -305.542062) (xy 393.409933 -305.496786) (xy 393.398156 -305.449002) (xy 393.394196 -305.399948)
			(xy 393.055094 -305.399948) (xy 393.054599 -305.424555) (xy 393.046704 -305.473132) (xy 393.03112 -305.519813)
			(xy 393.008249 -305.56339) (xy 392.978684 -305.602734) (xy 392.943191 -305.636826) (xy 392.902688 -305.664782)
			(xy 392.858226 -305.68588) (xy 392.810955 -305.699572) (xy 392.7621 -305.705504) (xy 392.712925 -305.703523)
			(xy 392.664706 -305.693679) (xy 392.61869 -305.676227) (xy 392.576069 -305.65162) (xy 392.537948 -305.620495)
			(xy 392.505313 -305.583658) (xy 392.47901 -305.542062) (xy 392.459719 -305.496786) (xy 392.447942 -305.449002)
			(xy 392.443982 -305.399948) (xy 392.105134 -305.399948) (xy 392.104639 -305.424555) (xy 392.096744 -305.473132)
			(xy 392.08116 -305.519813) (xy 392.058289 -305.56339) (xy 392.028724 -305.602734) (xy 391.993231 -305.636826)
			(xy 391.952728 -305.664782) (xy 391.908266 -305.68588) (xy 391.860995 -305.699572) (xy 391.81214 -305.705504)
			(xy 391.762965 -305.703523) (xy 391.714746 -305.693679) (xy 391.66873 -305.676227) (xy 391.626109 -305.65162)
			(xy 391.587988 -305.620495) (xy 391.555353 -305.583658) (xy 391.52905 -305.542062) (xy 391.509759 -305.496786)
			(xy 391.497982 -305.449002) (xy 391.494022 -305.399948) (xy 391.155174 -305.399948) (xy 391.154679 -305.424555)
			(xy 391.146784 -305.473132) (xy 391.1312 -305.519813) (xy 391.108329 -305.56339) (xy 391.078764 -305.602734)
			(xy 391.043271 -305.636826) (xy 391.002768 -305.664782) (xy 390.958306 -305.68588) (xy 390.911035 -305.699572)
			(xy 390.86218 -305.705504) (xy 390.813005 -305.703523) (xy 390.764786 -305.693679) (xy 390.71877 -305.676227)
			(xy 390.676149 -305.65162) (xy 390.638028 -305.620495) (xy 390.605393 -305.583658) (xy 390.57909 -305.542062)
			(xy 390.559799 -305.496786) (xy 390.548022 -305.449002) (xy 390.544062 -305.399948) (xy 390.205214 -305.399948)
			(xy 390.204719 -305.424555) (xy 390.196824 -305.473132) (xy 390.18124 -305.519813) (xy 390.158369 -305.56339)
			(xy 390.128804 -305.602734) (xy 390.093311 -305.636826) (xy 390.052808 -305.664782) (xy 390.008346 -305.68588)
			(xy 389.961075 -305.699572) (xy 389.91222 -305.705504) (xy 389.863045 -305.703523) (xy 389.814826 -305.693679)
			(xy 389.76881 -305.676227) (xy 389.726189 -305.65162) (xy 389.688068 -305.620495) (xy 389.655433 -305.583658)
			(xy 389.62913 -305.542062) (xy 389.609839 -305.496786) (xy 389.598062 -305.449002) (xy 389.594102 -305.399948)
			(xy 389.255254 -305.399948) (xy 389.254759 -305.424555) (xy 389.246864 -305.473132) (xy 389.23128 -305.519813)
			(xy 389.208409 -305.56339) (xy 389.178844 -305.602734) (xy 389.143351 -305.636826) (xy 389.102848 -305.664782)
			(xy 389.058386 -305.68588) (xy 389.011115 -305.699572) (xy 388.96226 -305.705504) (xy 388.913085 -305.703523)
			(xy 388.864866 -305.693679) (xy 388.81885 -305.676227) (xy 388.776229 -305.65162) (xy 388.738108 -305.620495)
			(xy 388.705473 -305.583658) (xy 388.67917 -305.542062) (xy 388.659879 -305.496786) (xy 388.648102 -305.449002)
			(xy 388.644142 -305.399948) (xy 388.305294 -305.399948) (xy 388.304799 -305.424555) (xy 388.296904 -305.473132)
			(xy 388.28132 -305.519813) (xy 388.258449 -305.56339) (xy 388.228884 -305.602734) (xy 388.193391 -305.636826)
			(xy 388.152888 -305.664782) (xy 388.108426 -305.68588) (xy 388.061155 -305.699572) (xy 388.0123 -305.705504)
			(xy 387.963125 -305.703523) (xy 387.914906 -305.693679) (xy 387.86889 -305.676227) (xy 387.826269 -305.65162)
			(xy 387.788148 -305.620495) (xy 387.755513 -305.583658) (xy 387.72921 -305.542062) (xy 387.709919 -305.496786)
			(xy 387.698142 -305.449002) (xy 387.694182 -305.399948) (xy 387.355334 -305.399948) (xy 387.354839 -305.424555)
			(xy 387.346944 -305.473132) (xy 387.33136 -305.519813) (xy 387.308489 -305.56339) (xy 387.278924 -305.602734)
			(xy 387.243431 -305.636826) (xy 387.202928 -305.664782) (xy 387.158466 -305.68588) (xy 387.111195 -305.699572)
			(xy 387.06234 -305.705504) (xy 387.013165 -305.703523) (xy 386.964946 -305.693679) (xy 386.91893 -305.676227)
			(xy 386.876309 -305.65162) (xy 386.838188 -305.620495) (xy 386.805553 -305.583658) (xy 386.77925 -305.542062)
			(xy 386.759959 -305.496786) (xy 386.748182 -305.449002) (xy 386.744222 -305.399948) (xy 386.40512 -305.399948)
			(xy 386.404625 -305.424555) (xy 386.39673 -305.473132) (xy 386.381146 -305.519813) (xy 386.358275 -305.56339)
			(xy 386.32871 -305.602734) (xy 386.293217 -305.636826) (xy 386.252714 -305.664782) (xy 386.208252 -305.68588)
			(xy 386.160981 -305.699572) (xy 386.112126 -305.705504) (xy 386.062951 -305.703523) (xy 386.014732 -305.693679)
			(xy 385.968716 -305.676227) (xy 385.926095 -305.65162) (xy 385.887974 -305.620495) (xy 385.855339 -305.583658)
			(xy 385.829036 -305.542062) (xy 385.809745 -305.496786) (xy 385.797968 -305.449002) (xy 385.794008 -305.399948)
			(xy 385.45516 -305.399948) (xy 385.454665 -305.424555) (xy 385.44677 -305.473132) (xy 385.431186 -305.519813)
			(xy 385.408315 -305.56339) (xy 385.37875 -305.602734) (xy 385.343257 -305.636826) (xy 385.302754 -305.664782)
			(xy 385.258292 -305.68588) (xy 385.211021 -305.699572) (xy 385.162166 -305.705504) (xy 385.112991 -305.703523)
			(xy 385.064772 -305.693679) (xy 385.018756 -305.676227) (xy 384.976135 -305.65162) (xy 384.938014 -305.620495)
			(xy 384.905379 -305.583658) (xy 384.879076 -305.542062) (xy 384.859785 -305.496786) (xy 384.848008 -305.449002)
			(xy 384.844048 -305.399948) (xy 376.46695 -305.399948) (xy 376.464733 -305.415379) (xy 376.449379 -305.467686)
			(xy 376.426737 -305.517275) (xy 376.397268 -305.563137) (xy 376.361571 -305.604338) (xy 376.320374 -305.64004)
			(xy 376.274516 -305.669514) (xy 376.224929 -305.692162) (xy 376.172624 -305.707523) (xy 376.118666 -305.715282)
			(xy 376.064152 -305.715284) (xy 376.010193 -305.707526) (xy 375.957887 -305.692168) (xy 375.908299 -305.669523)
			(xy 375.862439 -305.64005) (xy 375.821241 -305.60435) (xy 375.785543 -305.563151) (xy 375.756072 -305.51729)
			(xy 375.733427 -305.467702) (xy 375.718071 -305.415396) (xy 375.710316 -305.361436) (xy 365.203422 -305.361436)
			(xy 365.192454 -305.366445) (xy 365.140159 -305.3818) (xy 365.086211 -305.389556) (xy 365.031709 -305.389556)
			(xy 364.977761 -305.3818) (xy 364.925466 -305.366445) (xy 364.875889 -305.343803) (xy 364.830039 -305.314337)
			(xy 364.788848 -305.278646) (xy 364.753157 -305.237455) (xy 364.723691 -305.191605) (xy 364.701049 -305.142028)
			(xy 364.685694 -305.089733) (xy 364.677938 -305.035785) (xy 364.677452 -305.008534) (xy 360.632248 -305.008534)
			(xy 360.631762 -305.035785) (xy 360.624006 -305.089733) (xy 360.608651 -305.142028) (xy 360.586009 -305.191605)
			(xy 360.556543 -305.237455) (xy 360.520852 -305.278646) (xy 360.479661 -305.314337) (xy 360.433811 -305.343803)
			(xy 360.384234 -305.366445) (xy 360.331939 -305.3818) (xy 360.277991 -305.389556) (xy 360.223489 -305.389556)
			(xy 360.169541 -305.3818) (xy 360.117246 -305.366445) (xy 360.067669 -305.343803) (xy 360.021819 -305.314337)
			(xy 359.980628 -305.278646) (xy 359.944937 -305.237455) (xy 359.915471 -305.191605) (xy 359.892829 -305.142028)
			(xy 359.877474 -305.089733) (xy 359.869718 -305.035785) (xy 359.869232 -305.008534) (xy 358.600248 -305.008534)
			(xy 358.599762 -305.035785) (xy 358.592006 -305.089733) (xy 358.576651 -305.142028) (xy 358.554009 -305.191605)
			(xy 358.524543 -305.237455) (xy 358.488852 -305.278646) (xy 358.447661 -305.314337) (xy 358.401811 -305.343803)
			(xy 358.352234 -305.366445) (xy 358.299939 -305.3818) (xy 358.245991 -305.389556) (xy 358.191489 -305.389556)
			(xy 358.137541 -305.3818) (xy 358.085246 -305.366445) (xy 358.035669 -305.343803) (xy 357.989819 -305.314337)
			(xy 357.948628 -305.278646) (xy 357.912937 -305.237455) (xy 357.883471 -305.191605) (xy 357.860829 -305.142028)
			(xy 357.845474 -305.089733) (xy 357.837718 -305.035785) (xy 357.837232 -305.008534) (xy 357.212138 -305.008534)
			(xy 357.211652 -305.035785) (xy 357.203896 -305.089733) (xy 357.188541 -305.142028) (xy 357.165899 -305.191605)
			(xy 357.136433 -305.237455) (xy 357.100742 -305.278646) (xy 357.059551 -305.314337) (xy 357.013701 -305.343803)
			(xy 356.964124 -305.366445) (xy 356.911829 -305.3818) (xy 356.857881 -305.389556) (xy 356.803379 -305.389556)
			(xy 356.749431 -305.3818) (xy 356.697136 -305.366445) (xy 356.647559 -305.343803) (xy 356.601709 -305.314337)
			(xy 356.560518 -305.278646) (xy 356.524827 -305.237455) (xy 356.495361 -305.191605) (xy 356.472719 -305.142028)
			(xy 356.457364 -305.089733) (xy 356.449608 -305.035785) (xy 356.449122 -305.008534) (xy 353.792028 -305.008534)
			(xy 353.791542 -305.035785) (xy 353.783786 -305.089733) (xy 353.768431 -305.142028) (xy 353.745789 -305.191605)
			(xy 353.716323 -305.237455) (xy 353.680632 -305.278646) (xy 353.639441 -305.314337) (xy 353.593591 -305.343803)
			(xy 353.544014 -305.366445) (xy 353.491719 -305.3818) (xy 353.437771 -305.389556) (xy 353.383269 -305.389556)
			(xy 353.329321 -305.3818) (xy 353.277026 -305.366445) (xy 353.227449 -305.343803) (xy 353.181599 -305.314337)
			(xy 353.140408 -305.278646) (xy 353.104717 -305.237455) (xy 353.075251 -305.191605) (xy 353.052609 -305.142028)
			(xy 353.037254 -305.089733) (xy 353.029498 -305.035785) (xy 353.029012 -305.008534) (xy 351.03308 -305.008534)
			(xy 351.03308 -307.82387) (xy 353.617022 -307.82387) (xy 353.617465 -307.796499) (xy 353.625288 -307.742319)
			(xy 353.640782 -307.689815) (xy 353.663629 -307.640069) (xy 353.693358 -307.594103) (xy 353.711002 -307.573172)
			(xy 353.711256 -307.572918) (xy 353.716848 -307.565835) (xy 353.72309 -307.548915) (xy 353.723448 -307.539898)
			(xy 353.723448 -307.472842) (xy 353.723082 -307.463826) (xy 353.716842 -307.446908) (xy 353.711256 -307.439822)
			(xy 353.711002 -307.439822) (xy 353.711002 -307.439568) (xy 353.693333 -307.418659) (xy 353.663611 -307.372686)
			(xy 353.640769 -307.322936) (xy 353.625276 -307.27043) (xy 353.617451 -307.216249) (xy 353.617454 -307.161506)
			(xy 353.625286 -307.107325) (xy 353.640785 -307.054822) (xy 353.663633 -307.005074) (xy 353.69336 -306.959105)
			(xy 353.711002 -306.938172) (xy 353.711256 -306.937918) (xy 353.716848 -306.930835) (xy 353.72309 -306.913915)
			(xy 353.723448 -306.904898) (xy 353.723448 -306.837842) (xy 353.723082 -306.828826) (xy 353.716842 -306.811908)
			(xy 353.711256 -306.804822) (xy 353.711002 -306.804822) (xy 353.711002 -306.804568) (xy 353.693333 -306.783659)
			(xy 353.663611 -306.737686) (xy 353.640769 -306.687936) (xy 353.625276 -306.63543) (xy 353.617451 -306.581249)
			(xy 353.617454 -306.526506) (xy 353.625286 -306.472325) (xy 353.640785 -306.419822) (xy 353.663633 -306.370074)
			(xy 353.69336 -306.324105) (xy 353.711002 -306.303172) (xy 353.711256 -306.302918) (xy 353.716848 -306.295835)
			(xy 353.72309 -306.278915) (xy 353.723448 -306.269898) (xy 353.723448 -306.202842) (xy 353.723082 -306.193826)
			(xy 353.716842 -306.176908) (xy 353.711256 -306.169822) (xy 353.711002 -306.169822) (xy 353.711002 -306.169568)
			(xy 353.693382 -306.148621) (xy 353.663667 -306.102652) (xy 353.640827 -306.052909) (xy 353.625332 -306.000411)
			(xy 353.617499 -305.946238) (xy 353.617022 -305.91887) (xy 353.617508 -305.891619) (xy 353.625264 -305.837671)
			(xy 353.640619 -305.785376) (xy 353.663261 -305.735799) (xy 353.692727 -305.689949) (xy 353.728418 -305.648758)
			(xy 353.769609 -305.613067) (xy 353.815459 -305.583601) (xy 353.865036 -305.560959) (xy 353.917331 -305.545604)
			(xy 353.971279 -305.537848) (xy 354.025781 -305.537848) (xy 354.079729 -305.545604) (xy 354.132024 -305.560959)
			(xy 354.181601 -305.583601) (xy 354.227451 -305.613067) (xy 354.268642 -305.648758) (xy 354.304333 -305.689949)
			(xy 354.333799 -305.735799) (xy 354.356441 -305.785376) (xy 354.371796 -305.837671) (xy 354.379552 -305.891619)
			(xy 354.380038 -305.91887) (xy 354.379569 -305.94624) (xy 354.371755 -306.00042) (xy 354.356267 -306.052924)
			(xy 354.333425 -306.102671) (xy 354.3037 -306.148637) (xy 354.286058 -306.169568) (xy 354.285804 -306.169822)
			(xy 354.280203 -306.176898) (xy 354.273965 -306.193823) (xy 354.273612 -306.202842) (xy 354.273612 -306.269898)
			(xy 354.273967 -306.278915) (xy 354.280216 -306.295832) (xy 354.285804 -306.302918) (xy 354.286058 -306.302918)
			(xy 354.286058 -306.303172) (xy 354.30367 -306.324128) (xy 354.333397 -306.370092) (xy 354.356245 -306.419834)
			(xy 354.371744 -306.472332) (xy 354.379576 -306.526508) (xy 354.379579 -306.581247) (xy 354.371754 -306.635423)
			(xy 354.356261 -306.687924) (xy 354.333419 -306.737669) (xy 354.303697 -306.783636) (xy 354.286058 -306.804568)
			(xy 354.285804 -306.804822) (xy 354.280203 -306.811898) (xy 354.273965 -306.828823) (xy 354.273612 -306.837842)
			(xy 354.273612 -306.904898) (xy 354.273967 -306.913915) (xy 354.280216 -306.930832) (xy 354.285804 -306.937918)
			(xy 354.286058 -306.937918) (xy 354.286058 -306.938172) (xy 354.30367 -306.959128) (xy 354.333397 -307.005092)
			(xy 354.356245 -307.054834) (xy 354.371744 -307.107332) (xy 354.379576 -307.161508) (xy 354.379579 -307.216247)
			(xy 354.371754 -307.270423) (xy 354.356261 -307.322924) (xy 354.333419 -307.372669) (xy 354.303697 -307.418636)
			(xy 354.286058 -307.439568) (xy 354.285804 -307.439822) (xy 354.280203 -307.446898) (xy 354.273965 -307.463823)
			(xy 354.273612 -307.472842) (xy 354.273612 -307.539898) (xy 354.273967 -307.548915) (xy 354.280216 -307.565832)
			(xy 354.285804 -307.572918) (xy 354.286058 -307.572918) (xy 354.286058 -307.573172) (xy 354.303691 -307.594109)
			(xy 354.333405 -307.64008) (xy 354.356243 -307.689826) (xy 354.371735 -307.742326) (xy 354.379564 -307.796501)
			(xy 354.380038 -307.82387) (xy 354.379552 -307.851121) (xy 354.375728 -307.877718) (xy 357.249222 -307.877718)
			(xy 357.249693 -307.850348) (xy 357.257509 -307.796169) (xy 357.272997 -307.743666) (xy 357.295837 -307.693919)
			(xy 357.325561 -307.647952) (xy 357.343202 -307.62702) (xy 357.343456 -307.626766) (xy 357.349028 -307.61967)
			(xy 357.355282 -307.60276) (xy 357.355648 -307.593746) (xy 357.355648 -307.52669) (xy 357.355307 -307.517671)
			(xy 357.349049 -307.500754) (xy 357.343456 -307.49367) (xy 357.343202 -307.49367) (xy 357.343202 -307.493416)
			(xy 357.32558 -307.472468) (xy 357.295856 -307.426503) (xy 357.273011 -307.376759) (xy 357.257515 -307.324259)
			(xy 357.249685 -307.270083) (xy 357.249683 -307.215344) (xy 357.257509 -307.161167) (xy 357.273002 -307.108667)
			(xy 357.295843 -307.058921) (xy 357.325564 -307.012953) (xy 357.343202 -306.99202) (xy 357.343456 -306.991766)
			(xy 357.349028 -306.98467) (xy 357.355282 -306.96776) (xy 357.355648 -306.958746) (xy 357.355648 -306.89169)
			(xy 357.355307 -306.882671) (xy 357.349049 -306.865754) (xy 357.343456 -306.85867) (xy 357.343202 -306.85867)
			(xy 357.343202 -306.858416) (xy 357.32558 -306.837468) (xy 357.295856 -306.791503) (xy 357.273011 -306.741759)
			(xy 357.257515 -306.689259) (xy 357.249685 -306.635083) (xy 357.249683 -306.580344) (xy 357.257509 -306.526167)
			(xy 357.273002 -306.473667) (xy 357.295843 -306.423921) (xy 357.325564 -306.377953) (xy 357.343202 -306.35702)
			(xy 357.343456 -306.356766) (xy 357.349028 -306.34967) (xy 357.355282 -306.33276) (xy 357.355648 -306.323746)
			(xy 357.355648 -306.25669) (xy 357.355307 -306.247671) (xy 357.349049 -306.230754) (xy 357.343456 -306.22367)
			(xy 357.343202 -306.22367) (xy 357.343202 -306.223416) (xy 357.325557 -306.202488) (xy 357.295846 -306.156514)
			(xy 357.273011 -306.106766) (xy 357.257522 -306.054264) (xy 357.249695 -306.000087) (xy 357.249222 -305.972718)
			(xy 357.249708 -305.945467) (xy 357.257464 -305.891519) (xy 357.272819 -305.839224) (xy 357.295461 -305.789647)
			(xy 357.324927 -305.743797) (xy 357.360618 -305.702606) (xy 357.401809 -305.666915) (xy 357.447659 -305.637449)
			(xy 357.497236 -305.614807) (xy 357.549531 -305.599452) (xy 357.603479 -305.591696) (xy 357.657981 -305.591696)
			(xy 357.711929 -305.599452) (xy 357.764224 -305.614807) (xy 357.813801 -305.637449) (xy 357.859651 -305.666915)
			(xy 357.900842 -305.702606) (xy 357.936533 -305.743797) (xy 357.965999 -305.789647) (xy 357.988641 -305.839224)
			(xy 358.003996 -305.891519) (xy 358.011752 -305.945467) (xy 358.012238 -305.972718) (xy 358.011798 -306.000089)
			(xy 358.003976 -306.05427) (xy 357.988482 -306.106774) (xy 357.965634 -306.156521) (xy 357.935903 -306.202486)
			(xy 357.918258 -306.223416) (xy 357.918004 -306.22367) (xy 357.912424 -306.230761) (xy 357.906173 -306.247674)
			(xy 357.905812 -306.25669) (xy 357.905812 -306.323746) (xy 357.906192 -306.332761) (xy 357.912424 -306.349678)
			(xy 357.918004 -306.356766) (xy 357.918258 -306.356766) (xy 357.918258 -306.35702) (xy 357.935917 -306.377938)
			(xy 357.965642 -306.423908) (xy 357.988487 -306.473657) (xy 358.003983 -306.526161) (xy 358.01181 -306.580342)
			(xy 358.011808 -306.635085) (xy 358.003977 -306.689265) (xy 357.988478 -306.741769) (xy 357.965629 -306.791516)
			(xy 357.935901 -306.837484) (xy 357.918258 -306.858416) (xy 357.918004 -306.85867) (xy 357.912424 -306.865761)
			(xy 357.906173 -306.882674) (xy 357.905812 -306.89169) (xy 357.905812 -306.958746) (xy 357.906192 -306.967761)
			(xy 357.912424 -306.984678) (xy 357.918004 -306.991766) (xy 357.918258 -306.991766) (xy 357.918258 -306.99202)
			(xy 357.935917 -307.012938) (xy 357.965642 -307.058908) (xy 357.988487 -307.108657) (xy 358.003983 -307.161161)
			(xy 358.007986 -307.18887) (xy 360.457242 -307.18887) (xy 360.45768 -307.161499) (xy 360.465503 -307.107318)
			(xy 360.480998 -307.054814) (xy 360.503846 -307.005068) (xy 360.533578 -306.959102) (xy 360.551222 -306.938172)
			(xy 360.551476 -306.937918) (xy 360.55707 -306.930837) (xy 360.56331 -306.913916) (xy 360.563668 -306.904898)
			(xy 360.563668 -306.837842) (xy 360.563298 -306.828826) (xy 360.55706 -306.811909) (xy 360.551476 -306.804822)
			(xy 360.551222 -306.804822) (xy 360.551222 -306.804568) (xy 360.533552 -306.783659) (xy 360.503829 -306.737687)
			(xy 360.480986 -306.687937) (xy 360.465492 -306.635431) (xy 360.457666 -306.581249) (xy 360.457669 -306.526505)
			(xy 360.465502 -306.472325) (xy 360.481002 -306.419821) (xy 360.503851 -306.370073) (xy 360.533579 -306.324105)
			(xy 360.551222 -306.303172) (xy 360.551476 -306.302918) (xy 360.55707 -306.295837) (xy 360.56331 -306.278916)
			(xy 360.563668 -306.269898) (xy 360.563668 -306.202842) (xy 360.563298 -306.193826) (xy 360.55706 -306.176909)
			(xy 360.551476 -306.169822) (xy 360.551222 -306.169822) (xy 360.551222 -306.169568) (xy 360.533605 -306.148618)
			(xy 360.503889 -306.102651) (xy 360.481048 -306.052908) (xy 360.465552 -306.000411) (xy 360.457719 -305.946238)
			(xy 360.457242 -305.91887) (xy 360.457728 -305.891619) (xy 360.465484 -305.837671) (xy 360.480839 -305.785376)
			(xy 360.503481 -305.735799) (xy 360.532947 -305.689949) (xy 360.568638 -305.648758) (xy 360.609829 -305.613067)
			(xy 360.655679 -305.583601) (xy 360.705256 -305.560959) (xy 360.757551 -305.545604) (xy 360.811499 -305.537848)
			(xy 360.866001 -305.537848) (xy 360.919949 -305.545604) (xy 360.972244 -305.560959) (xy 361.021821 -305.583601)
			(xy 361.067671 -305.613067) (xy 361.108862 -305.648758) (xy 361.144553 -305.689949) (xy 361.174019 -305.735799)
			(xy 361.196661 -305.785376) (xy 361.212016 -305.837671) (xy 361.219772 -305.891619) (xy 361.220258 -305.91887)
			(xy 361.219785 -305.94624) (xy 361.21197 -306.000419) (xy 361.196483 -306.052923) (xy 361.173643 -306.10267)
			(xy 361.143919 -306.148636) (xy 361.126278 -306.169568) (xy 361.126024 -306.169822) (xy 361.120413 -306.176892)
			(xy 361.114183 -306.193822) (xy 361.113832 -306.202842) (xy 361.113832 -306.269898) (xy 361.114183 -306.278916)
			(xy 361.120434 -306.295833) (xy 361.126024 -306.302918) (xy 361.126278 -306.302918) (xy 361.126278 -306.303172)
			(xy 361.143889 -306.324129) (xy 361.173615 -306.370092) (xy 361.196462 -306.419835) (xy 361.21196 -306.472333)
			(xy 361.219791 -306.526508) (xy 361.219794 -306.581247) (xy 361.21197 -306.635423) (xy 361.196477 -306.687923)
			(xy 361.173637 -306.737668) (xy 361.143916 -306.783635) (xy 361.126278 -306.804568) (xy 361.126024 -306.804822)
			(xy 361.120413 -306.811892) (xy 361.114183 -306.828822) (xy 361.113832 -306.837842) (xy 361.113832 -306.904898)
			(xy 361.114183 -306.913916) (xy 361.120434 -306.930833) (xy 361.126024 -306.937918) (xy 361.126278 -306.937918)
			(xy 361.126278 -306.938172) (xy 361.143914 -306.959107) (xy 361.173627 -307.005078) (xy 361.196464 -307.054825)
			(xy 361.211956 -307.107325) (xy 361.219784 -307.161501) (xy 361.220258 -307.18887) (xy 361.219772 -307.216121)
			(xy 361.212016 -307.270069) (xy 361.196661 -307.322364) (xy 361.174019 -307.371941) (xy 361.144553 -307.417791)
			(xy 361.108862 -307.458982) (xy 361.067671 -307.494673) (xy 361.021821 -307.524139) (xy 360.972244 -307.546781)
			(xy 360.919949 -307.562136) (xy 360.866001 -307.569892) (xy 360.811499 -307.569892) (xy 360.757551 -307.562136)
			(xy 360.705256 -307.546781) (xy 360.655679 -307.524139) (xy 360.609829 -307.494673) (xy 360.568638 -307.458982)
			(xy 360.532947 -307.417791) (xy 360.503481 -307.371941) (xy 360.480839 -307.322364) (xy 360.465484 -307.270069)
			(xy 360.457728 -307.216121) (xy 360.457242 -307.18887) (xy 358.007986 -307.18887) (xy 358.01181 -307.215342)
			(xy 358.011808 -307.270085) (xy 358.003977 -307.324265) (xy 357.988478 -307.376769) (xy 357.965629 -307.426516)
			(xy 357.935901 -307.472484) (xy 357.918258 -307.493416) (xy 357.918004 -307.49367) (xy 357.912424 -307.500761)
			(xy 357.906173 -307.517674) (xy 357.905812 -307.52669) (xy 357.905812 -307.593746) (xy 357.906192 -307.602761)
			(xy 357.912424 -307.619678) (xy 357.918004 -307.626766) (xy 357.918258 -307.626766) (xy 357.918258 -307.62702)
			(xy 357.935867 -307.647977) (xy 357.965584 -307.693942) (xy 357.988427 -307.743683) (xy 358.003925 -307.796179)
			(xy 358.01176 -307.85035) (xy 358.012238 -307.877718) (xy 364.089442 -307.877718) (xy 364.089908 -307.850348)
			(xy 364.097725 -307.796168) (xy 364.113213 -307.743665) (xy 364.136055 -307.693918) (xy 364.16578 -307.647951)
			(xy 364.183422 -307.62702) (xy 364.183676 -307.626766) (xy 364.18925 -307.619671) (xy 364.195502 -307.60276)
			(xy 364.195868 -307.593746) (xy 364.195868 -307.52669) (xy 364.195523 -307.517672) (xy 364.189268 -307.500754)
			(xy 364.183676 -307.49367) (xy 364.183422 -307.49367) (xy 364.183422 -307.493416) (xy 364.165799 -307.472469)
			(xy 364.136074 -307.426503) (xy 364.113228 -307.37676) (xy 364.09773 -307.32426) (xy 364.0899 -307.270083)
			(xy 364.089898 -307.215344) (xy 364.097725 -307.161167) (xy 364.113218 -307.108666) (xy 364.136061 -307.05892)
			(xy 364.165783 -307.012953) (xy 364.183422 -306.99202) (xy 364.183676 -306.991766) (xy 364.18925 -306.984671)
			(xy 364.195502 -306.96776) (xy 364.195868 -306.958746) (xy 364.195868 -306.89169) (xy 364.195523 -306.882672)
			(xy 364.189268 -306.865754) (xy 364.183676 -306.85867) (xy 364.183422 -306.85867) (xy 364.183422 -306.858416)
			(xy 364.165799 -306.837469) (xy 364.136074 -306.791503) (xy 364.113228 -306.74176) (xy 364.09773 -306.68926)
			(xy 364.0899 -306.635083) (xy 364.089898 -306.580344) (xy 364.097725 -306.526167) (xy 364.113218 -306.473666)
			(xy 364.136061 -306.42392) (xy 364.165783 -306.377953) (xy 364.183422 -306.35702) (xy 364.183676 -306.356766)
			(xy 364.18925 -306.349671) (xy 364.195502 -306.33276) (xy 364.195868 -306.323746) (xy 364.195868 -306.25669)
			(xy 364.195523 -306.247672) (xy 364.189268 -306.230754) (xy 364.183676 -306.22367) (xy 364.183422 -306.22367)
			(xy 364.183422 -306.223416) (xy 364.16578 -306.202486) (xy 364.136068 -306.156513) (xy 364.113232 -306.106765)
			(xy 364.097742 -306.054264) (xy 364.089915 -306.000087) (xy 364.089442 -305.972718) (xy 364.089928 -305.945467)
			(xy 364.097684 -305.891519) (xy 364.113039 -305.839224) (xy 364.135681 -305.789647) (xy 364.165147 -305.743797)
			(xy 364.200838 -305.702606) (xy 364.242029 -305.666915) (xy 364.287879 -305.637449) (xy 364.337456 -305.614807)
			(xy 364.389751 -305.599452) (xy 364.443699 -305.591696) (xy 364.498201 -305.591696) (xy 364.552149 -305.599452)
			(xy 364.604444 -305.614807) (xy 364.654021 -305.637449) (xy 364.699871 -305.666915) (xy 364.741062 -305.702606)
			(xy 364.776753 -305.743797) (xy 364.806219 -305.789647) (xy 364.828861 -305.839224) (xy 364.844216 -305.891519)
			(xy 364.851972 -305.945467) (xy 364.852458 -305.972718) (xy 364.852013 -306.000089) (xy 364.844413 -306.052728)
			(xy 374.990866 -306.052728) (xy 374.994937 -305.997106) (xy 375.007063 -305.942669) (xy 375.026986 -305.890578)
			(xy 375.054282 -305.841943) (xy 375.088368 -305.7978) (xy 375.128517 -305.759091) (xy 375.173875 -305.72664)
			(xy 375.223475 -305.701139) (xy 375.276259 -305.683132) (xy 375.331102 -305.673002) (xy 375.386836 -305.670965)
			(xy 375.442273 -305.677065) (xy 375.49623 -305.691171) (xy 375.547559 -305.712983) (xy 375.595165 -305.742037)
			(xy 375.638033 -305.777712) (xy 375.67525 -305.819249) (xy 375.706023 -305.865762) (xy 375.71032 -305.874928)
			(xy 394.819136 -305.874928) (xy 394.823096 -305.825874) (xy 394.834873 -305.77809) (xy 394.854164 -305.732814)
			(xy 394.880467 -305.691218) (xy 394.913102 -305.654381) (xy 394.951223 -305.623256) (xy 394.993844 -305.598649)
			(xy 395.03986 -305.581197) (xy 395.088079 -305.571353) (xy 395.137254 -305.569372) (xy 395.186109 -305.575304)
			(xy 395.23338 -305.588996) (xy 395.277842 -305.610094) (xy 395.318345 -305.63805) (xy 395.353838 -305.672142)
			(xy 395.383403 -305.711486) (xy 395.406274 -305.755063) (xy 395.421858 -305.801744) (xy 395.429753 -305.850321)
			(xy 395.430248 -305.874928) (xy 395.769096 -305.874928) (xy 395.773056 -305.825874) (xy 395.784833 -305.77809)
			(xy 395.804124 -305.732814) (xy 395.830427 -305.691218) (xy 395.863062 -305.654381) (xy 395.901183 -305.623256)
			(xy 395.943804 -305.598649) (xy 395.98982 -305.581197) (xy 396.038039 -305.571353) (xy 396.087214 -305.569372)
			(xy 396.136069 -305.575304) (xy 396.18334 -305.588996) (xy 396.227802 -305.610094) (xy 396.268305 -305.63805)
			(xy 396.303798 -305.672142) (xy 396.333363 -305.711486) (xy 396.356234 -305.755063) (xy 396.371818 -305.801744)
			(xy 396.379713 -305.850321) (xy 396.380208 -305.874928) (xy 396.719056 -305.874928) (xy 396.723016 -305.825874)
			(xy 396.734793 -305.77809) (xy 396.754084 -305.732814) (xy 396.780387 -305.691218) (xy 396.813022 -305.654381)
			(xy 396.851143 -305.623256) (xy 396.893764 -305.598649) (xy 396.93978 -305.581197) (xy 396.987999 -305.571353)
			(xy 397.037174 -305.569372) (xy 397.086029 -305.575304) (xy 397.1333 -305.588996) (xy 397.177762 -305.610094)
			(xy 397.218265 -305.63805) (xy 397.253758 -305.672142) (xy 397.283323 -305.711486) (xy 397.306194 -305.755063)
			(xy 397.321778 -305.801744) (xy 397.329673 -305.850321) (xy 397.330168 -305.874928) (xy 397.329673 -305.899535)
			(xy 397.321778 -305.948112) (xy 397.306194 -305.994793) (xy 397.283323 -306.03837) (xy 397.253758 -306.077714)
			(xy 397.218265 -306.111806) (xy 397.177762 -306.139762) (xy 397.1333 -306.16086) (xy 397.086029 -306.174552)
			(xy 397.037174 -306.180484) (xy 396.987999 -306.178503) (xy 396.93978 -306.168659) (xy 396.893764 -306.151207)
			(xy 396.851143 -306.1266) (xy 396.813022 -306.095475) (xy 396.780387 -306.058638) (xy 396.754084 -306.017042)
			(xy 396.734793 -305.971766) (xy 396.723016 -305.923982) (xy 396.719056 -305.874928) (xy 396.380208 -305.874928)
			(xy 396.379713 -305.899535) (xy 396.371818 -305.948112) (xy 396.356234 -305.994793) (xy 396.333363 -306.03837)
			(xy 396.303798 -306.077714) (xy 396.268305 -306.111806) (xy 396.227802 -306.139762) (xy 396.18334 -306.16086)
			(xy 396.136069 -306.174552) (xy 396.087214 -306.180484) (xy 396.038039 -306.178503) (xy 395.98982 -306.168659)
			(xy 395.943804 -306.151207) (xy 395.901183 -306.1266) (xy 395.863062 -306.095475) (xy 395.830427 -306.058638)
			(xy 395.804124 -306.017042) (xy 395.784833 -305.971766) (xy 395.773056 -305.923982) (xy 395.769096 -305.874928)
			(xy 395.430248 -305.874928) (xy 395.429753 -305.899535) (xy 395.421858 -305.948112) (xy 395.406274 -305.994793)
			(xy 395.383403 -306.03837) (xy 395.353838 -306.077714) (xy 395.318345 -306.111806) (xy 395.277842 -306.139762)
			(xy 395.23338 -306.16086) (xy 395.186109 -306.174552) (xy 395.137254 -306.180484) (xy 395.088079 -306.178503)
			(xy 395.03986 -306.168659) (xy 394.993844 -306.151207) (xy 394.951223 -306.1266) (xy 394.913102 -306.095475)
			(xy 394.880467 -306.058638) (xy 394.854164 -306.017042) (xy 394.834873 -305.971766) (xy 394.823096 -305.923982)
			(xy 394.819136 -305.874928) (xy 375.71032 -305.874928) (xy 375.729695 -305.916259) (xy 375.745763 -305.969666)
			(xy 375.753883 -306.024842) (xy 375.754392 -306.052728) (xy 375.753883 -306.080614) (xy 375.745763 -306.13579)
			(xy 375.729695 -306.189197) (xy 375.706023 -306.239694) (xy 375.67525 -306.286207) (xy 375.638033 -306.327744)
			(xy 375.611095 -306.350162) (xy 383.893834 -306.350162) (xy 383.897794 -306.301108) (xy 383.909571 -306.253324)
			(xy 383.928862 -306.208048) (xy 383.955165 -306.166452) (xy 383.9878 -306.129615) (xy 384.025921 -306.09849)
			(xy 384.068542 -306.073883) (xy 384.114558 -306.056431) (xy 384.162777 -306.046587) (xy 384.211952 -306.044606)
			(xy 384.260807 -306.050538) (xy 384.308078 -306.06423) (xy 384.35254 -306.085328) (xy 384.393043 -306.113284)
			(xy 384.428536 -306.147376) (xy 384.458101 -306.18672) (xy 384.480972 -306.230297) (xy 384.496556 -306.276978)
			(xy 384.504451 -306.325555) (xy 384.504941 -306.349908) (xy 384.844048 -306.349908) (xy 384.848008 -306.300854)
			(xy 384.859785 -306.25307) (xy 384.879076 -306.207794) (xy 384.905379 -306.166198) (xy 384.938014 -306.129361)
			(xy 384.976135 -306.098236) (xy 385.018756 -306.073629) (xy 385.064772 -306.056177) (xy 385.112991 -306.046333)
			(xy 385.162166 -306.044352) (xy 385.211021 -306.050284) (xy 385.258292 -306.063976) (xy 385.302754 -306.085074)
			(xy 385.343257 -306.11303) (xy 385.37875 -306.147122) (xy 385.408315 -306.186466) (xy 385.431186 -306.230043)
			(xy 385.44677 -306.276724) (xy 385.454665 -306.325301) (xy 385.45516 -306.349908) (xy 385.794008 -306.349908)
			(xy 385.797968 -306.300854) (xy 385.809745 -306.25307) (xy 385.829036 -306.207794) (xy 385.855339 -306.166198)
			(xy 385.887974 -306.129361) (xy 385.926095 -306.098236) (xy 385.968716 -306.073629) (xy 386.014732 -306.056177)
			(xy 386.062951 -306.046333) (xy 386.112126 -306.044352) (xy 386.160981 -306.050284) (xy 386.208252 -306.063976)
			(xy 386.252714 -306.085074) (xy 386.293217 -306.11303) (xy 386.32871 -306.147122) (xy 386.358275 -306.186466)
			(xy 386.381146 -306.230043) (xy 386.39673 -306.276724) (xy 386.404625 -306.325301) (xy 386.40512 -306.349908)
			(xy 386.744222 -306.349908) (xy 386.748182 -306.300854) (xy 386.759959 -306.25307) (xy 386.77925 -306.207794)
			(xy 386.805553 -306.166198) (xy 386.838188 -306.129361) (xy 386.876309 -306.098236) (xy 386.91893 -306.073629)
			(xy 386.964946 -306.056177) (xy 387.013165 -306.046333) (xy 387.06234 -306.044352) (xy 387.111195 -306.050284)
			(xy 387.158466 -306.063976) (xy 387.202928 -306.085074) (xy 387.243431 -306.11303) (xy 387.278924 -306.147122)
			(xy 387.308489 -306.186466) (xy 387.33136 -306.230043) (xy 387.346944 -306.276724) (xy 387.354839 -306.325301)
			(xy 387.355334 -306.349908) (xy 387.694182 -306.349908) (xy 387.698142 -306.300854) (xy 387.709919 -306.25307)
			(xy 387.72921 -306.207794) (xy 387.755513 -306.166198) (xy 387.788148 -306.129361) (xy 387.826269 -306.098236)
			(xy 387.86889 -306.073629) (xy 387.914906 -306.056177) (xy 387.963125 -306.046333) (xy 388.0123 -306.044352)
			(xy 388.061155 -306.050284) (xy 388.108426 -306.063976) (xy 388.152888 -306.085074) (xy 388.193391 -306.11303)
			(xy 388.228884 -306.147122) (xy 388.258449 -306.186466) (xy 388.28132 -306.230043) (xy 388.296904 -306.276724)
			(xy 388.304799 -306.325301) (xy 388.305294 -306.349908) (xy 388.644142 -306.349908) (xy 388.648102 -306.300854)
			(xy 388.659879 -306.25307) (xy 388.67917 -306.207794) (xy 388.705473 -306.166198) (xy 388.738108 -306.129361)
			(xy 388.776229 -306.098236) (xy 388.81885 -306.073629) (xy 388.864866 -306.056177) (xy 388.913085 -306.046333)
			(xy 388.96226 -306.044352) (xy 389.011115 -306.050284) (xy 389.058386 -306.063976) (xy 389.102848 -306.085074)
			(xy 389.143351 -306.11303) (xy 389.178844 -306.147122) (xy 389.208409 -306.186466) (xy 389.23128 -306.230043)
			(xy 389.246864 -306.276724) (xy 389.254759 -306.325301) (xy 389.255254 -306.349908) (xy 389.594102 -306.349908)
			(xy 389.598062 -306.300854) (xy 389.609839 -306.25307) (xy 389.62913 -306.207794) (xy 389.655433 -306.166198)
			(xy 389.688068 -306.129361) (xy 389.726189 -306.098236) (xy 389.76881 -306.073629) (xy 389.814826 -306.056177)
			(xy 389.863045 -306.046333) (xy 389.91222 -306.044352) (xy 389.961075 -306.050284) (xy 390.008346 -306.063976)
			(xy 390.052808 -306.085074) (xy 390.093311 -306.11303) (xy 390.128804 -306.147122) (xy 390.158369 -306.186466)
			(xy 390.18124 -306.230043) (xy 390.196824 -306.276724) (xy 390.204719 -306.325301) (xy 390.205214 -306.349908)
			(xy 390.544062 -306.349908) (xy 390.548022 -306.300854) (xy 390.559799 -306.25307) (xy 390.57909 -306.207794)
			(xy 390.605393 -306.166198) (xy 390.638028 -306.129361) (xy 390.676149 -306.098236) (xy 390.71877 -306.073629)
			(xy 390.764786 -306.056177) (xy 390.813005 -306.046333) (xy 390.86218 -306.044352) (xy 390.911035 -306.050284)
			(xy 390.958306 -306.063976) (xy 391.002768 -306.085074) (xy 391.043271 -306.11303) (xy 391.078764 -306.147122)
			(xy 391.108329 -306.186466) (xy 391.1312 -306.230043) (xy 391.146784 -306.276724) (xy 391.154679 -306.325301)
			(xy 391.155174 -306.349908) (xy 391.494022 -306.349908) (xy 391.497982 -306.300854) (xy 391.509759 -306.25307)
			(xy 391.52905 -306.207794) (xy 391.555353 -306.166198) (xy 391.587988 -306.129361) (xy 391.626109 -306.098236)
			(xy 391.66873 -306.073629) (xy 391.714746 -306.056177) (xy 391.762965 -306.046333) (xy 391.81214 -306.044352)
			(xy 391.860995 -306.050284) (xy 391.908266 -306.063976) (xy 391.952728 -306.085074) (xy 391.993231 -306.11303)
			(xy 392.028724 -306.147122) (xy 392.058289 -306.186466) (xy 392.08116 -306.230043) (xy 392.096744 -306.276724)
			(xy 392.104639 -306.325301) (xy 392.105134 -306.349908) (xy 392.443982 -306.349908) (xy 392.447942 -306.300854)
			(xy 392.459719 -306.25307) (xy 392.47901 -306.207794) (xy 392.505313 -306.166198) (xy 392.537948 -306.129361)
			(xy 392.576069 -306.098236) (xy 392.61869 -306.073629) (xy 392.664706 -306.056177) (xy 392.712925 -306.046333)
			(xy 392.7621 -306.044352) (xy 392.810955 -306.050284) (xy 392.858226 -306.063976) (xy 392.902688 -306.085074)
			(xy 392.943191 -306.11303) (xy 392.978684 -306.147122) (xy 393.008249 -306.186466) (xy 393.03112 -306.230043)
			(xy 393.046704 -306.276724) (xy 393.054599 -306.325301) (xy 393.055094 -306.349908) (xy 393.394196 -306.349908)
			(xy 393.398156 -306.300854) (xy 393.409933 -306.25307) (xy 393.429224 -306.207794) (xy 393.455527 -306.166198)
			(xy 393.488162 -306.129361) (xy 393.526283 -306.098236) (xy 393.568904 -306.073629) (xy 393.61492 -306.056177)
			(xy 393.663139 -306.046333) (xy 393.712314 -306.044352) (xy 393.761169 -306.050284) (xy 393.80844 -306.063976)
			(xy 393.852902 -306.085074) (xy 393.893405 -306.11303) (xy 393.928898 -306.147122) (xy 393.958463 -306.186466)
			(xy 393.981334 -306.230043) (xy 393.996918 -306.276724) (xy 394.004813 -306.325301) (xy 394.005308 -306.349908)
			(xy 394.004813 -306.374515) (xy 393.996918 -306.423092) (xy 393.981334 -306.469773) (xy 393.958463 -306.51335)
			(xy 393.928898 -306.552694) (xy 393.893405 -306.586786) (xy 393.852902 -306.614742) (xy 393.80844 -306.63584)
			(xy 393.761169 -306.649532) (xy 393.712314 -306.655464) (xy 393.663139 -306.653483) (xy 393.61492 -306.643639)
			(xy 393.568904 -306.626187) (xy 393.526283 -306.60158) (xy 393.488162 -306.570455) (xy 393.455527 -306.533618)
			(xy 393.429224 -306.492022) (xy 393.409933 -306.446746) (xy 393.398156 -306.398962) (xy 393.394196 -306.349908)
			(xy 393.055094 -306.349908) (xy 393.054599 -306.374515) (xy 393.046704 -306.423092) (xy 393.03112 -306.469773)
			(xy 393.008249 -306.51335) (xy 392.978684 -306.552694) (xy 392.943191 -306.586786) (xy 392.902688 -306.614742)
			(xy 392.858226 -306.63584) (xy 392.810955 -306.649532) (xy 392.7621 -306.655464) (xy 392.712925 -306.653483)
			(xy 392.664706 -306.643639) (xy 392.61869 -306.626187) (xy 392.576069 -306.60158) (xy 392.537948 -306.570455)
			(xy 392.505313 -306.533618) (xy 392.47901 -306.492022) (xy 392.459719 -306.446746) (xy 392.447942 -306.398962)
			(xy 392.443982 -306.349908) (xy 392.105134 -306.349908) (xy 392.104639 -306.374515) (xy 392.096744 -306.423092)
			(xy 392.08116 -306.469773) (xy 392.058289 -306.51335) (xy 392.028724 -306.552694) (xy 391.993231 -306.586786)
			(xy 391.952728 -306.614742) (xy 391.908266 -306.63584) (xy 391.860995 -306.649532) (xy 391.81214 -306.655464)
			(xy 391.762965 -306.653483) (xy 391.714746 -306.643639) (xy 391.66873 -306.626187) (xy 391.626109 -306.60158)
			(xy 391.587988 -306.570455) (xy 391.555353 -306.533618) (xy 391.52905 -306.492022) (xy 391.509759 -306.446746)
			(xy 391.497982 -306.398962) (xy 391.494022 -306.349908) (xy 391.155174 -306.349908) (xy 391.154679 -306.374515)
			(xy 391.146784 -306.423092) (xy 391.1312 -306.469773) (xy 391.108329 -306.51335) (xy 391.078764 -306.552694)
			(xy 391.043271 -306.586786) (xy 391.002768 -306.614742) (xy 390.958306 -306.63584) (xy 390.911035 -306.649532)
			(xy 390.86218 -306.655464) (xy 390.813005 -306.653483) (xy 390.764786 -306.643639) (xy 390.71877 -306.626187)
			(xy 390.676149 -306.60158) (xy 390.638028 -306.570455) (xy 390.605393 -306.533618) (xy 390.57909 -306.492022)
			(xy 390.559799 -306.446746) (xy 390.548022 -306.398962) (xy 390.544062 -306.349908) (xy 390.205214 -306.349908)
			(xy 390.204719 -306.374515) (xy 390.196824 -306.423092) (xy 390.18124 -306.469773) (xy 390.158369 -306.51335)
			(xy 390.128804 -306.552694) (xy 390.093311 -306.586786) (xy 390.052808 -306.614742) (xy 390.008346 -306.63584)
			(xy 389.961075 -306.649532) (xy 389.91222 -306.655464) (xy 389.863045 -306.653483) (xy 389.814826 -306.643639)
			(xy 389.76881 -306.626187) (xy 389.726189 -306.60158) (xy 389.688068 -306.570455) (xy 389.655433 -306.533618)
			(xy 389.62913 -306.492022) (xy 389.609839 -306.446746) (xy 389.598062 -306.398962) (xy 389.594102 -306.349908)
			(xy 389.255254 -306.349908) (xy 389.254759 -306.374515) (xy 389.246864 -306.423092) (xy 389.23128 -306.469773)
			(xy 389.208409 -306.51335) (xy 389.178844 -306.552694) (xy 389.143351 -306.586786) (xy 389.102848 -306.614742)
			(xy 389.058386 -306.63584) (xy 389.011115 -306.649532) (xy 388.96226 -306.655464) (xy 388.913085 -306.653483)
			(xy 388.864866 -306.643639) (xy 388.81885 -306.626187) (xy 388.776229 -306.60158) (xy 388.738108 -306.570455)
			(xy 388.705473 -306.533618) (xy 388.67917 -306.492022) (xy 388.659879 -306.446746) (xy 388.648102 -306.398962)
			(xy 388.644142 -306.349908) (xy 388.305294 -306.349908) (xy 388.304799 -306.374515) (xy 388.296904 -306.423092)
			(xy 388.28132 -306.469773) (xy 388.258449 -306.51335) (xy 388.228884 -306.552694) (xy 388.193391 -306.586786)
			(xy 388.152888 -306.614742) (xy 388.108426 -306.63584) (xy 388.061155 -306.649532) (xy 388.0123 -306.655464)
			(xy 387.963125 -306.653483) (xy 387.914906 -306.643639) (xy 387.86889 -306.626187) (xy 387.826269 -306.60158)
			(xy 387.788148 -306.570455) (xy 387.755513 -306.533618) (xy 387.72921 -306.492022) (xy 387.709919 -306.446746)
			(xy 387.698142 -306.398962) (xy 387.694182 -306.349908) (xy 387.355334 -306.349908) (xy 387.354839 -306.374515)
			(xy 387.346944 -306.423092) (xy 387.33136 -306.469773) (xy 387.308489 -306.51335) (xy 387.278924 -306.552694)
			(xy 387.243431 -306.586786) (xy 387.202928 -306.614742) (xy 387.158466 -306.63584) (xy 387.111195 -306.649532)
			(xy 387.06234 -306.655464) (xy 387.013165 -306.653483) (xy 386.964946 -306.643639) (xy 386.91893 -306.626187)
			(xy 386.876309 -306.60158) (xy 386.838188 -306.570455) (xy 386.805553 -306.533618) (xy 386.77925 -306.492022)
			(xy 386.759959 -306.446746) (xy 386.748182 -306.398962) (xy 386.744222 -306.349908) (xy 386.40512 -306.349908)
			(xy 386.404625 -306.374515) (xy 386.39673 -306.423092) (xy 386.381146 -306.469773) (xy 386.358275 -306.51335)
			(xy 386.32871 -306.552694) (xy 386.293217 -306.586786) (xy 386.252714 -306.614742) (xy 386.208252 -306.63584)
			(xy 386.160981 -306.649532) (xy 386.112126 -306.655464) (xy 386.062951 -306.653483) (xy 386.014732 -306.643639)
			(xy 385.968716 -306.626187) (xy 385.926095 -306.60158) (xy 385.887974 -306.570455) (xy 385.855339 -306.533618)
			(xy 385.829036 -306.492022) (xy 385.809745 -306.446746) (xy 385.797968 -306.398962) (xy 385.794008 -306.349908)
			(xy 385.45516 -306.349908) (xy 385.454665 -306.374515) (xy 385.44677 -306.423092) (xy 385.431186 -306.469773)
			(xy 385.408315 -306.51335) (xy 385.37875 -306.552694) (xy 385.343257 -306.586786) (xy 385.302754 -306.614742)
			(xy 385.258292 -306.63584) (xy 385.211021 -306.649532) (xy 385.162166 -306.655464) (xy 385.112991 -306.653483)
			(xy 385.064772 -306.643639) (xy 385.018756 -306.626187) (xy 384.976135 -306.60158) (xy 384.938014 -306.570455)
			(xy 384.905379 -306.533618) (xy 384.879076 -306.492022) (xy 384.859785 -306.446746) (xy 384.848008 -306.398962)
			(xy 384.844048 -306.349908) (xy 384.504941 -306.349908) (xy 384.504946 -306.350162) (xy 384.504451 -306.374769)
			(xy 384.496556 -306.423346) (xy 384.480972 -306.470027) (xy 384.458101 -306.513604) (xy 384.428536 -306.552948)
			(xy 384.393043 -306.58704) (xy 384.35254 -306.614996) (xy 384.308078 -306.636094) (xy 384.260807 -306.649786)
			(xy 384.211952 -306.655718) (xy 384.162777 -306.653737) (xy 384.114558 -306.643893) (xy 384.068542 -306.626441)
			(xy 384.025921 -306.601834) (xy 383.9878 -306.570709) (xy 383.955165 -306.533872) (xy 383.928862 -306.492276)
			(xy 383.909571 -306.447) (xy 383.897794 -306.399216) (xy 383.893834 -306.350162) (xy 375.611095 -306.350162)
			(xy 375.595165 -306.363419) (xy 375.547559 -306.392473) (xy 375.49623 -306.414285) (xy 375.442273 -306.428391)
			(xy 375.386836 -306.434491) (xy 375.331102 -306.432454) (xy 375.276259 -306.422324) (xy 375.223475 -306.404317)
			(xy 375.173875 -306.378816) (xy 375.128517 -306.346365) (xy 375.088368 -306.307656) (xy 375.054282 -306.263513)
			(xy 375.026986 -306.214878) (xy 375.007063 -306.162787) (xy 374.994937 -306.10835) (xy 374.990866 -306.052728)
			(xy 364.844413 -306.052728) (xy 364.844191 -306.054269) (xy 364.828698 -306.106773) (xy 364.805851 -306.15652)
			(xy 364.776122 -306.202485) (xy 364.758478 -306.223416) (xy 364.758224 -306.22367) (xy 364.752635 -306.230755)
			(xy 364.746392 -306.247673) (xy 364.746032 -306.25669) (xy 364.746032 -306.323746) (xy 364.746408 -306.332761)
			(xy 364.752642 -306.349679) (xy 364.758224 -306.356766) (xy 364.758478 -306.356766) (xy 364.758478 -306.35702)
			(xy 364.776136 -306.377939) (xy 364.80586 -306.423909) (xy 364.828704 -306.473658) (xy 364.844198 -306.526162)
			(xy 364.852025 -306.580342) (xy 364.852023 -306.635085) (xy 364.844193 -306.689265) (xy 364.828694 -306.741768)
			(xy 364.817933 -306.765198) (xy 378.025404 -306.765198) (xy 378.029475 -306.709576) (xy 378.041601 -306.655139)
			(xy 378.061524 -306.603048) (xy 378.08882 -306.554413) (xy 378.122906 -306.51027) (xy 378.163055 -306.471561)
			(xy 378.208413 -306.43911) (xy 378.258013 -306.413609) (xy 378.310797 -306.395602) (xy 378.36564 -306.385472)
			(xy 378.421374 -306.383435) (xy 378.476811 -306.389535) (xy 378.530768 -306.403641) (xy 378.582097 -306.425453)
			(xy 378.629703 -306.454507) (xy 378.672571 -306.490182) (xy 378.709788 -306.531719) (xy 378.740561 -306.578232)
			(xy 378.764233 -306.628729) (xy 378.780301 -306.682136) (xy 378.788421 -306.737312) (xy 378.78893 -306.765198)
			(xy 378.788421 -306.793084) (xy 378.783741 -306.824888) (xy 394.819136 -306.824888) (xy 394.823096 -306.775834)
			(xy 394.834873 -306.72805) (xy 394.854164 -306.682774) (xy 394.880467 -306.641178) (xy 394.913102 -306.604341)
			(xy 394.951223 -306.573216) (xy 394.993844 -306.548609) (xy 395.03986 -306.531157) (xy 395.088079 -306.521313)
			(xy 395.137254 -306.519332) (xy 395.186109 -306.525264) (xy 395.23338 -306.538956) (xy 395.277842 -306.560054)
			(xy 395.318345 -306.58801) (xy 395.353838 -306.622102) (xy 395.383403 -306.661446) (xy 395.406274 -306.705023)
			(xy 395.421858 -306.751704) (xy 395.429753 -306.800281) (xy 395.430248 -306.824888) (xy 395.769096 -306.824888)
			(xy 395.773056 -306.775834) (xy 395.784833 -306.72805) (xy 395.804124 -306.682774) (xy 395.830427 -306.641178)
			(xy 395.863062 -306.604341) (xy 395.901183 -306.573216) (xy 395.943804 -306.548609) (xy 395.98982 -306.531157)
			(xy 396.038039 -306.521313) (xy 396.087214 -306.519332) (xy 396.136069 -306.525264) (xy 396.18334 -306.538956)
			(xy 396.227802 -306.560054) (xy 396.268305 -306.58801) (xy 396.303798 -306.622102) (xy 396.333363 -306.661446)
			(xy 396.356234 -306.705023) (xy 396.371818 -306.751704) (xy 396.379713 -306.800281) (xy 396.380208 -306.824888)
			(xy 396.719056 -306.824888) (xy 396.723016 -306.775834) (xy 396.734793 -306.72805) (xy 396.754084 -306.682774)
			(xy 396.780387 -306.641178) (xy 396.813022 -306.604341) (xy 396.851143 -306.573216) (xy 396.893764 -306.548609)
			(xy 396.93978 -306.531157) (xy 396.987999 -306.521313) (xy 397.037174 -306.519332) (xy 397.086029 -306.525264)
			(xy 397.1333 -306.538956) (xy 397.177762 -306.560054) (xy 397.218265 -306.58801) (xy 397.253758 -306.622102)
			(xy 397.283323 -306.661446) (xy 397.306194 -306.705023) (xy 397.321778 -306.751704) (xy 397.329673 -306.800281)
			(xy 397.330168 -306.824888) (xy 397.329673 -306.849495) (xy 397.321778 -306.898072) (xy 397.306194 -306.944753)
			(xy 397.283323 -306.98833) (xy 397.253758 -307.027674) (xy 397.218265 -307.061766) (xy 397.177762 -307.089722)
			(xy 397.1333 -307.11082) (xy 397.086029 -307.124512) (xy 397.037174 -307.130444) (xy 396.987999 -307.128463)
			(xy 396.93978 -307.118619) (xy 396.893764 -307.101167) (xy 396.851143 -307.07656) (xy 396.813022 -307.045435)
			(xy 396.780387 -307.008598) (xy 396.754084 -306.967002) (xy 396.734793 -306.921726) (xy 396.723016 -306.873942)
			(xy 396.719056 -306.824888) (xy 396.380208 -306.824888) (xy 396.379713 -306.849495) (xy 396.371818 -306.898072)
			(xy 396.356234 -306.944753) (xy 396.333363 -306.98833) (xy 396.303798 -307.027674) (xy 396.268305 -307.061766)
			(xy 396.227802 -307.089722) (xy 396.18334 -307.11082) (xy 396.136069 -307.124512) (xy 396.087214 -307.130444)
			(xy 396.038039 -307.128463) (xy 395.98982 -307.118619) (xy 395.943804 -307.101167) (xy 395.901183 -307.07656)
			(xy 395.863062 -307.045435) (xy 395.830427 -307.008598) (xy 395.804124 -306.967002) (xy 395.784833 -306.921726)
			(xy 395.773056 -306.873942) (xy 395.769096 -306.824888) (xy 395.430248 -306.824888) (xy 395.429753 -306.849495)
			(xy 395.421858 -306.898072) (xy 395.406274 -306.944753) (xy 395.383403 -306.98833) (xy 395.353838 -307.027674)
			(xy 395.318345 -307.061766) (xy 395.277842 -307.089722) (xy 395.23338 -307.11082) (xy 395.186109 -307.124512)
			(xy 395.137254 -307.130444) (xy 395.088079 -307.128463) (xy 395.03986 -307.118619) (xy 394.993844 -307.101167)
			(xy 394.951223 -307.07656) (xy 394.913102 -307.045435) (xy 394.880467 -307.008598) (xy 394.854164 -306.967002)
			(xy 394.834873 -306.921726) (xy 394.823096 -306.873942) (xy 394.819136 -306.824888) (xy 378.783741 -306.824888)
			(xy 378.780301 -306.84826) (xy 378.764233 -306.901667) (xy 378.740561 -306.952164) (xy 378.709788 -306.998677)
			(xy 378.672571 -307.040214) (xy 378.629703 -307.075889) (xy 378.582097 -307.104943) (xy 378.530768 -307.126755)
			(xy 378.476811 -307.140861) (xy 378.421374 -307.146961) (xy 378.36564 -307.144924) (xy 378.310797 -307.134794)
			(xy 378.258013 -307.116787) (xy 378.208413 -307.091286) (xy 378.163055 -307.058835) (xy 378.122906 -307.020126)
			(xy 378.08882 -306.975983) (xy 378.061524 -306.927348) (xy 378.041601 -306.875257) (xy 378.029475 -306.82082)
			(xy 378.025404 -306.765198) (xy 364.817933 -306.765198) (xy 364.805847 -306.791515) (xy 364.77612 -306.837483)
			(xy 364.758478 -306.858416) (xy 364.758224 -306.85867) (xy 364.752635 -306.865755) (xy 364.746392 -306.882673)
			(xy 364.746032 -306.89169) (xy 364.746032 -306.958746) (xy 364.746408 -306.967761) (xy 364.752642 -306.984679)
			(xy 364.758224 -306.991766) (xy 364.758478 -306.991766) (xy 364.758478 -306.99202) (xy 364.776136 -307.012939)
			(xy 364.80586 -307.058909) (xy 364.828704 -307.108658) (xy 364.844198 -307.161162) (xy 364.852025 -307.215342)
			(xy 364.852024 -307.240178) (xy 380.16002 -307.240178) (xy 380.164091 -307.184556) (xy 380.176217 -307.130119)
			(xy 380.19614 -307.078028) (xy 380.223436 -307.029393) (xy 380.257522 -306.98525) (xy 380.297671 -306.946541)
			(xy 380.343029 -306.91409) (xy 380.392629 -306.888589) (xy 380.445413 -306.870582) (xy 380.500256 -306.860452)
			(xy 380.55599 -306.858415) (xy 380.611427 -306.864515) (xy 380.665384 -306.878621) (xy 380.716713 -306.900433)
			(xy 380.764319 -306.929487) (xy 380.807187 -306.965162) (xy 380.844404 -307.006699) (xy 380.875177 -307.053212)
			(xy 380.898849 -307.103709) (xy 380.914917 -307.157116) (xy 380.923037 -307.212292) (xy 380.923546 -307.240178)
			(xy 380.923037 -307.268064) (xy 380.918357 -307.299868) (xy 384.844048 -307.299868) (xy 384.848008 -307.250814)
			(xy 384.859785 -307.20303) (xy 384.879076 -307.157754) (xy 384.905379 -307.116158) (xy 384.938014 -307.079321)
			(xy 384.976135 -307.048196) (xy 385.018756 -307.023589) (xy 385.064772 -307.006137) (xy 385.112991 -306.996293)
			(xy 385.162166 -306.994312) (xy 385.211021 -307.000244) (xy 385.258292 -307.013936) (xy 385.302754 -307.035034)
			(xy 385.343257 -307.06299) (xy 385.37875 -307.097082) (xy 385.408315 -307.136426) (xy 385.431186 -307.180003)
			(xy 385.44677 -307.226684) (xy 385.454665 -307.275261) (xy 385.45516 -307.299868) (xy 385.794008 -307.299868)
			(xy 385.797968 -307.250814) (xy 385.809745 -307.20303) (xy 385.829036 -307.157754) (xy 385.855339 -307.116158)
			(xy 385.887974 -307.079321) (xy 385.926095 -307.048196) (xy 385.968716 -307.023589) (xy 386.014732 -307.006137)
			(xy 386.062951 -306.996293) (xy 386.112126 -306.994312) (xy 386.160981 -307.000244) (xy 386.208252 -307.013936)
			(xy 386.252714 -307.035034) (xy 386.293217 -307.06299) (xy 386.32871 -307.097082) (xy 386.358275 -307.136426)
			(xy 386.381146 -307.180003) (xy 386.39673 -307.226684) (xy 386.404625 -307.275261) (xy 386.40512 -307.299868)
			(xy 386.744222 -307.299868) (xy 386.748182 -307.250814) (xy 386.759959 -307.20303) (xy 386.77925 -307.157754)
			(xy 386.805553 -307.116158) (xy 386.838188 -307.079321) (xy 386.876309 -307.048196) (xy 386.91893 -307.023589)
			(xy 386.964946 -307.006137) (xy 387.013165 -306.996293) (xy 387.06234 -306.994312) (xy 387.111195 -307.000244)
			(xy 387.158466 -307.013936) (xy 387.202928 -307.035034) (xy 387.243431 -307.06299) (xy 387.278924 -307.097082)
			(xy 387.308489 -307.136426) (xy 387.33136 -307.180003) (xy 387.346944 -307.226684) (xy 387.354839 -307.275261)
			(xy 387.355334 -307.299868) (xy 387.694182 -307.299868) (xy 387.698142 -307.250814) (xy 387.709919 -307.20303)
			(xy 387.72921 -307.157754) (xy 387.755513 -307.116158) (xy 387.788148 -307.079321) (xy 387.826269 -307.048196)
			(xy 387.86889 -307.023589) (xy 387.914906 -307.006137) (xy 387.963125 -306.996293) (xy 388.0123 -306.994312)
			(xy 388.061155 -307.000244) (xy 388.108426 -307.013936) (xy 388.152888 -307.035034) (xy 388.193391 -307.06299)
			(xy 388.228884 -307.097082) (xy 388.258449 -307.136426) (xy 388.28132 -307.180003) (xy 388.296904 -307.226684)
			(xy 388.304799 -307.275261) (xy 388.305294 -307.299868) (xy 388.644142 -307.299868) (xy 388.648102 -307.250814)
			(xy 388.659879 -307.20303) (xy 388.67917 -307.157754) (xy 388.705473 -307.116158) (xy 388.738108 -307.079321)
			(xy 388.776229 -307.048196) (xy 388.81885 -307.023589) (xy 388.864866 -307.006137) (xy 388.913085 -306.996293)
			(xy 388.96226 -306.994312) (xy 389.011115 -307.000244) (xy 389.058386 -307.013936) (xy 389.102848 -307.035034)
			(xy 389.143351 -307.06299) (xy 389.178844 -307.097082) (xy 389.208409 -307.136426) (xy 389.23128 -307.180003)
			(xy 389.246864 -307.226684) (xy 389.254759 -307.275261) (xy 389.255254 -307.299868) (xy 389.594102 -307.299868)
			(xy 389.598062 -307.250814) (xy 389.609839 -307.20303) (xy 389.62913 -307.157754) (xy 389.655433 -307.116158)
			(xy 389.688068 -307.079321) (xy 389.726189 -307.048196) (xy 389.76881 -307.023589) (xy 389.814826 -307.006137)
			(xy 389.863045 -306.996293) (xy 389.91222 -306.994312) (xy 389.961075 -307.000244) (xy 390.008346 -307.013936)
			(xy 390.052808 -307.035034) (xy 390.093311 -307.06299) (xy 390.128804 -307.097082) (xy 390.158369 -307.136426)
			(xy 390.18124 -307.180003) (xy 390.196824 -307.226684) (xy 390.204719 -307.275261) (xy 390.205214 -307.299868)
			(xy 390.544062 -307.299868) (xy 390.548022 -307.250814) (xy 390.559799 -307.20303) (xy 390.57909 -307.157754)
			(xy 390.605393 -307.116158) (xy 390.638028 -307.079321) (xy 390.676149 -307.048196) (xy 390.71877 -307.023589)
			(xy 390.764786 -307.006137) (xy 390.813005 -306.996293) (xy 390.86218 -306.994312) (xy 390.911035 -307.000244)
			(xy 390.958306 -307.013936) (xy 391.002768 -307.035034) (xy 391.043271 -307.06299) (xy 391.078764 -307.097082)
			(xy 391.108329 -307.136426) (xy 391.1312 -307.180003) (xy 391.146784 -307.226684) (xy 391.154679 -307.275261)
			(xy 391.155174 -307.299868) (xy 391.494022 -307.299868) (xy 391.497982 -307.250814) (xy 391.509759 -307.20303)
			(xy 391.52905 -307.157754) (xy 391.555353 -307.116158) (xy 391.587988 -307.079321) (xy 391.626109 -307.048196)
			(xy 391.66873 -307.023589) (xy 391.714746 -307.006137) (xy 391.762965 -306.996293) (xy 391.81214 -306.994312)
			(xy 391.860995 -307.000244) (xy 391.908266 -307.013936) (xy 391.952728 -307.035034) (xy 391.993231 -307.06299)
			(xy 392.028724 -307.097082) (xy 392.058289 -307.136426) (xy 392.08116 -307.180003) (xy 392.096744 -307.226684)
			(xy 392.104639 -307.275261) (xy 392.105134 -307.299868) (xy 392.443982 -307.299868) (xy 392.447942 -307.250814)
			(xy 392.459719 -307.20303) (xy 392.47901 -307.157754) (xy 392.505313 -307.116158) (xy 392.537948 -307.079321)
			(xy 392.576069 -307.048196) (xy 392.61869 -307.023589) (xy 392.664706 -307.006137) (xy 392.712925 -306.996293)
			(xy 392.7621 -306.994312) (xy 392.810955 -307.000244) (xy 392.858226 -307.013936) (xy 392.902688 -307.035034)
			(xy 392.943191 -307.06299) (xy 392.978684 -307.097082) (xy 393.008249 -307.136426) (xy 393.03112 -307.180003)
			(xy 393.046704 -307.226684) (xy 393.054599 -307.275261) (xy 393.055094 -307.299868) (xy 393.394196 -307.299868)
			(xy 393.398156 -307.250814) (xy 393.409933 -307.20303) (xy 393.429224 -307.157754) (xy 393.455527 -307.116158)
			(xy 393.488162 -307.079321) (xy 393.526283 -307.048196) (xy 393.568904 -307.023589) (xy 393.61492 -307.006137)
			(xy 393.663139 -306.996293) (xy 393.712314 -306.994312) (xy 393.761169 -307.000244) (xy 393.80844 -307.013936)
			(xy 393.852902 -307.035034) (xy 393.893405 -307.06299) (xy 393.928898 -307.097082) (xy 393.958463 -307.136426)
			(xy 393.981334 -307.180003) (xy 393.996918 -307.226684) (xy 394.004813 -307.275261) (xy 394.005308 -307.299868)
			(xy 394.004813 -307.324475) (xy 393.996918 -307.373052) (xy 393.981334 -307.419733) (xy 393.958463 -307.46331)
			(xy 393.928898 -307.502654) (xy 393.893405 -307.536746) (xy 393.852902 -307.564702) (xy 393.80844 -307.5858)
			(xy 393.761169 -307.599492) (xy 393.712314 -307.605424) (xy 393.663139 -307.603443) (xy 393.61492 -307.593599)
			(xy 393.568904 -307.576147) (xy 393.526283 -307.55154) (xy 393.488162 -307.520415) (xy 393.455527 -307.483578)
			(xy 393.429224 -307.441982) (xy 393.409933 -307.396706) (xy 393.398156 -307.348922) (xy 393.394196 -307.299868)
			(xy 393.055094 -307.299868) (xy 393.054599 -307.324475) (xy 393.046704 -307.373052) (xy 393.03112 -307.419733)
			(xy 393.008249 -307.46331) (xy 392.978684 -307.502654) (xy 392.943191 -307.536746) (xy 392.902688 -307.564702)
			(xy 392.858226 -307.5858) (xy 392.810955 -307.599492) (xy 392.7621 -307.605424) (xy 392.712925 -307.603443)
			(xy 392.664706 -307.593599) (xy 392.61869 -307.576147) (xy 392.576069 -307.55154) (xy 392.537948 -307.520415)
			(xy 392.505313 -307.483578) (xy 392.47901 -307.441982) (xy 392.459719 -307.396706) (xy 392.447942 -307.348922)
			(xy 392.443982 -307.299868) (xy 392.105134 -307.299868) (xy 392.104639 -307.324475) (xy 392.096744 -307.373052)
			(xy 392.08116 -307.419733) (xy 392.058289 -307.46331) (xy 392.028724 -307.502654) (xy 391.993231 -307.536746)
			(xy 391.952728 -307.564702) (xy 391.908266 -307.5858) (xy 391.860995 -307.599492) (xy 391.81214 -307.605424)
			(xy 391.762965 -307.603443) (xy 391.714746 -307.593599) (xy 391.66873 -307.576147) (xy 391.626109 -307.55154)
			(xy 391.587988 -307.520415) (xy 391.555353 -307.483578) (xy 391.52905 -307.441982) (xy 391.509759 -307.396706)
			(xy 391.497982 -307.348922) (xy 391.494022 -307.299868) (xy 391.155174 -307.299868) (xy 391.154679 -307.324475)
			(xy 391.146784 -307.373052) (xy 391.1312 -307.419733) (xy 391.108329 -307.46331) (xy 391.078764 -307.502654)
			(xy 391.043271 -307.536746) (xy 391.002768 -307.564702) (xy 390.958306 -307.5858) (xy 390.911035 -307.599492)
			(xy 390.86218 -307.605424) (xy 390.813005 -307.603443) (xy 390.764786 -307.593599) (xy 390.71877 -307.576147)
			(xy 390.676149 -307.55154) (xy 390.638028 -307.520415) (xy 390.605393 -307.483578) (xy 390.57909 -307.441982)
			(xy 390.559799 -307.396706) (xy 390.548022 -307.348922) (xy 390.544062 -307.299868) (xy 390.205214 -307.299868)
			(xy 390.204719 -307.324475) (xy 390.196824 -307.373052) (xy 390.18124 -307.419733) (xy 390.158369 -307.46331)
			(xy 390.128804 -307.502654) (xy 390.093311 -307.536746) (xy 390.052808 -307.564702) (xy 390.008346 -307.5858)
			(xy 389.961075 -307.599492) (xy 389.91222 -307.605424) (xy 389.863045 -307.603443) (xy 389.814826 -307.593599)
			(xy 389.76881 -307.576147) (xy 389.726189 -307.55154) (xy 389.688068 -307.520415) (xy 389.655433 -307.483578)
			(xy 389.62913 -307.441982) (xy 389.609839 -307.396706) (xy 389.598062 -307.348922) (xy 389.594102 -307.299868)
			(xy 389.255254 -307.299868) (xy 389.254759 -307.324475) (xy 389.246864 -307.373052) (xy 389.23128 -307.419733)
			(xy 389.208409 -307.46331) (xy 389.178844 -307.502654) (xy 389.143351 -307.536746) (xy 389.102848 -307.564702)
			(xy 389.058386 -307.5858) (xy 389.011115 -307.599492) (xy 388.96226 -307.605424) (xy 388.913085 -307.603443)
			(xy 388.864866 -307.593599) (xy 388.81885 -307.576147) (xy 388.776229 -307.55154) (xy 388.738108 -307.520415)
			(xy 388.705473 -307.483578) (xy 388.67917 -307.441982) (xy 388.659879 -307.396706) (xy 388.648102 -307.348922)
			(xy 388.644142 -307.299868) (xy 388.305294 -307.299868) (xy 388.304799 -307.324475) (xy 388.296904 -307.373052)
			(xy 388.28132 -307.419733) (xy 388.258449 -307.46331) (xy 388.228884 -307.502654) (xy 388.193391 -307.536746)
			(xy 388.152888 -307.564702) (xy 388.108426 -307.5858) (xy 388.061155 -307.599492) (xy 388.0123 -307.605424)
			(xy 387.963125 -307.603443) (xy 387.914906 -307.593599) (xy 387.86889 -307.576147) (xy 387.826269 -307.55154)
			(xy 387.788148 -307.520415) (xy 387.755513 -307.483578) (xy 387.72921 -307.441982) (xy 387.709919 -307.396706)
			(xy 387.698142 -307.348922) (xy 387.694182 -307.299868) (xy 387.355334 -307.299868) (xy 387.354839 -307.324475)
			(xy 387.346944 -307.373052) (xy 387.33136 -307.419733) (xy 387.308489 -307.46331) (xy 387.278924 -307.502654)
			(xy 387.243431 -307.536746) (xy 387.202928 -307.564702) (xy 387.158466 -307.5858) (xy 387.111195 -307.599492)
			(xy 387.06234 -307.605424) (xy 387.013165 -307.603443) (xy 386.964946 -307.593599) (xy 386.91893 -307.576147)
			(xy 386.876309 -307.55154) (xy 386.838188 -307.520415) (xy 386.805553 -307.483578) (xy 386.77925 -307.441982)
			(xy 386.759959 -307.396706) (xy 386.748182 -307.348922) (xy 386.744222 -307.299868) (xy 386.40512 -307.299868)
			(xy 386.404625 -307.324475) (xy 386.39673 -307.373052) (xy 386.381146 -307.419733) (xy 386.358275 -307.46331)
			(xy 386.32871 -307.502654) (xy 386.293217 -307.536746) (xy 386.252714 -307.564702) (xy 386.208252 -307.5858)
			(xy 386.160981 -307.599492) (xy 386.112126 -307.605424) (xy 386.062951 -307.603443) (xy 386.014732 -307.593599)
			(xy 385.968716 -307.576147) (xy 385.926095 -307.55154) (xy 385.887974 -307.520415) (xy 385.855339 -307.483578)
			(xy 385.829036 -307.441982) (xy 385.809745 -307.396706) (xy 385.797968 -307.348922) (xy 385.794008 -307.299868)
			(xy 385.45516 -307.299868) (xy 385.454665 -307.324475) (xy 385.44677 -307.373052) (xy 385.431186 -307.419733)
			(xy 385.408315 -307.46331) (xy 385.37875 -307.502654) (xy 385.343257 -307.536746) (xy 385.302754 -307.564702)
			(xy 385.258292 -307.5858) (xy 385.211021 -307.599492) (xy 385.162166 -307.605424) (xy 385.112991 -307.603443)
			(xy 385.064772 -307.593599) (xy 385.018756 -307.576147) (xy 384.976135 -307.55154) (xy 384.938014 -307.520415)
			(xy 384.905379 -307.483578) (xy 384.879076 -307.441982) (xy 384.859785 -307.396706) (xy 384.848008 -307.348922)
			(xy 384.844048 -307.299868) (xy 380.918357 -307.299868) (xy 380.914917 -307.32324) (xy 380.898849 -307.376647)
			(xy 380.875177 -307.427144) (xy 380.844404 -307.473657) (xy 380.807187 -307.515194) (xy 380.764319 -307.550869)
			(xy 380.716713 -307.579923) (xy 380.665384 -307.601735) (xy 380.611427 -307.615841) (xy 380.55599 -307.621941)
			(xy 380.500256 -307.619904) (xy 380.445413 -307.609774) (xy 380.392629 -307.591767) (xy 380.343029 -307.566266)
			(xy 380.297671 -307.533815) (xy 380.257522 -307.495106) (xy 380.223436 -307.450963) (xy 380.19614 -307.402328)
			(xy 380.176217 -307.350237) (xy 380.164091 -307.2958) (xy 380.16002 -307.240178) (xy 364.852024 -307.240178)
			(xy 364.852023 -307.270085) (xy 364.844193 -307.324265) (xy 364.828694 -307.376768) (xy 364.805847 -307.426515)
			(xy 364.77612 -307.472483) (xy 364.758478 -307.493416) (xy 364.758224 -307.49367) (xy 364.752635 -307.500755)
			(xy 364.746392 -307.517673) (xy 364.746032 -307.52669) (xy 364.746032 -307.593746) (xy 364.746408 -307.602761)
			(xy 364.752642 -307.619679) (xy 364.758224 -307.626766) (xy 364.758478 -307.626766) (xy 364.758478 -307.62702)
			(xy 364.77609 -307.647974) (xy 364.805806 -307.693941) (xy 364.828648 -307.743682) (xy 364.837848 -307.774848)
			(xy 394.819136 -307.774848) (xy 394.823096 -307.725794) (xy 394.834873 -307.67801) (xy 394.854164 -307.632734)
			(xy 394.880467 -307.591138) (xy 394.913102 -307.554301) (xy 394.951223 -307.523176) (xy 394.993844 -307.498569)
			(xy 395.03986 -307.481117) (xy 395.088079 -307.471273) (xy 395.137254 -307.469292) (xy 395.186109 -307.475224)
			(xy 395.23338 -307.488916) (xy 395.277842 -307.510014) (xy 395.318345 -307.53797) (xy 395.353838 -307.572062)
			(xy 395.383403 -307.611406) (xy 395.406274 -307.654983) (xy 395.421858 -307.701664) (xy 395.429753 -307.750241)
			(xy 395.430248 -307.774848) (xy 395.769096 -307.774848) (xy 395.773056 -307.725794) (xy 395.784833 -307.67801)
			(xy 395.804124 -307.632734) (xy 395.830427 -307.591138) (xy 395.863062 -307.554301) (xy 395.901183 -307.523176)
			(xy 395.943804 -307.498569) (xy 395.98982 -307.481117) (xy 396.038039 -307.471273) (xy 396.087214 -307.469292)
			(xy 396.136069 -307.475224) (xy 396.18334 -307.488916) (xy 396.227802 -307.510014) (xy 396.268305 -307.53797)
			(xy 396.303798 -307.572062) (xy 396.333363 -307.611406) (xy 396.356234 -307.654983) (xy 396.371818 -307.701664)
			(xy 396.379713 -307.750241) (xy 396.380208 -307.774848) (xy 396.719056 -307.774848) (xy 396.723016 -307.725794)
			(xy 396.734793 -307.67801) (xy 396.754084 -307.632734) (xy 396.780387 -307.591138) (xy 396.813022 -307.554301)
			(xy 396.851143 -307.523176) (xy 396.893764 -307.498569) (xy 396.93978 -307.481117) (xy 396.987999 -307.471273)
			(xy 397.037174 -307.469292) (xy 397.086029 -307.475224) (xy 397.1333 -307.488916) (xy 397.177762 -307.510014)
			(xy 397.218265 -307.53797) (xy 397.253758 -307.572062) (xy 397.283323 -307.611406) (xy 397.306194 -307.654983)
			(xy 397.321778 -307.701664) (xy 397.329673 -307.750241) (xy 397.330168 -307.774848) (xy 397.329673 -307.799455)
			(xy 397.321778 -307.848032) (xy 397.306194 -307.894713) (xy 397.283323 -307.93829) (xy 397.253758 -307.977634)
			(xy 397.218265 -308.011726) (xy 397.177762 -308.039682) (xy 397.1333 -308.06078) (xy 397.086029 -308.074472)
			(xy 397.037174 -308.080404) (xy 396.987999 -308.078423) (xy 396.93978 -308.068579) (xy 396.893764 -308.051127)
			(xy 396.851143 -308.02652) (xy 396.813022 -307.995395) (xy 396.780387 -307.958558) (xy 396.754084 -307.916962)
			(xy 396.734793 -307.871686) (xy 396.723016 -307.823902) (xy 396.719056 -307.774848) (xy 396.380208 -307.774848)
			(xy 396.379713 -307.799455) (xy 396.371818 -307.848032) (xy 396.356234 -307.894713) (xy 396.333363 -307.93829)
			(xy 396.303798 -307.977634) (xy 396.268305 -308.011726) (xy 396.227802 -308.039682) (xy 396.18334 -308.06078)
			(xy 396.136069 -308.074472) (xy 396.087214 -308.080404) (xy 396.038039 -308.078423) (xy 395.98982 -308.068579)
			(xy 395.943804 -308.051127) (xy 395.901183 -308.02652) (xy 395.863062 -307.995395) (xy 395.830427 -307.958558)
			(xy 395.804124 -307.916962) (xy 395.784833 -307.871686) (xy 395.773056 -307.823902) (xy 395.769096 -307.774848)
			(xy 395.430248 -307.774848) (xy 395.429753 -307.799455) (xy 395.421858 -307.848032) (xy 395.406274 -307.894713)
			(xy 395.383403 -307.93829) (xy 395.353838 -307.977634) (xy 395.318345 -308.011726) (xy 395.277842 -308.039682)
			(xy 395.23338 -308.06078) (xy 395.186109 -308.074472) (xy 395.137254 -308.080404) (xy 395.088079 -308.078423)
			(xy 395.03986 -308.068579) (xy 394.993844 -308.051127) (xy 394.951223 -308.02652) (xy 394.913102 -307.995395)
			(xy 394.880467 -307.958558) (xy 394.854164 -307.916962) (xy 394.834873 -307.871686) (xy 394.823096 -307.823902)
			(xy 394.819136 -307.774848) (xy 364.837848 -307.774848) (xy 364.844145 -307.796178) (xy 364.85198 -307.85035)
			(xy 364.852458 -307.877718) (xy 364.851972 -307.904969) (xy 364.844216 -307.958917) (xy 364.828861 -308.011212)
			(xy 364.806219 -308.060789) (xy 364.776753 -308.106639) (xy 364.741062 -308.14783) (xy 364.699871 -308.183521)
			(xy 364.654021 -308.212987) (xy 364.604444 -308.235629) (xy 364.552149 -308.250984) (xy 364.498201 -308.25874)
			(xy 364.443699 -308.25874) (xy 364.389751 -308.250984) (xy 364.337456 -308.235629) (xy 364.287879 -308.212987)
			(xy 364.242029 -308.183521) (xy 364.200838 -308.14783) (xy 364.165147 -308.106639) (xy 364.135681 -308.060789)
			(xy 364.113039 -308.011212) (xy 364.097684 -307.958917) (xy 364.089928 -307.904969) (xy 364.089442 -307.877718)
			(xy 358.012238 -307.877718) (xy 358.011752 -307.904969) (xy 358.003996 -307.958917) (xy 357.988641 -308.011212)
			(xy 357.965999 -308.060789) (xy 357.936533 -308.106639) (xy 357.900842 -308.14783) (xy 357.859651 -308.183521)
			(xy 357.813801 -308.212987) (xy 357.764224 -308.235629) (xy 357.711929 -308.250984) (xy 357.657981 -308.25874)
			(xy 357.603479 -308.25874) (xy 357.549531 -308.250984) (xy 357.497236 -308.235629) (xy 357.447659 -308.212987)
			(xy 357.401809 -308.183521) (xy 357.360618 -308.14783) (xy 357.324927 -308.106639) (xy 357.295461 -308.060789)
			(xy 357.272819 -308.011212) (xy 357.257464 -307.958917) (xy 357.249708 -307.904969) (xy 357.249222 -307.877718)
			(xy 354.375728 -307.877718) (xy 354.371796 -307.905069) (xy 354.356441 -307.957364) (xy 354.333799 -308.006941)
			(xy 354.304333 -308.052791) (xy 354.268642 -308.093982) (xy 354.227451 -308.129673) (xy 354.181601 -308.159139)
			(xy 354.132024 -308.181781) (xy 354.079729 -308.197136) (xy 354.025781 -308.204892) (xy 353.971279 -308.204892)
			(xy 353.917331 -308.197136) (xy 353.865036 -308.181781) (xy 353.815459 -308.159139) (xy 353.769609 -308.129673)
			(xy 353.728418 -308.093982) (xy 353.692727 -308.052791) (xy 353.663261 -308.006941) (xy 353.640619 -307.957364)
			(xy 353.625264 -307.905069) (xy 353.617508 -307.851121) (xy 353.617022 -307.82387) (xy 351.03308 -307.82387)
			(xy 351.03308 -308.450488) (xy 376.378214 -308.450488) (xy 376.382285 -308.394866) (xy 376.394411 -308.340429)
			(xy 376.414334 -308.288338) (xy 376.44163 -308.239703) (xy 376.475716 -308.19556) (xy 376.515865 -308.156851)
			(xy 376.561223 -308.1244) (xy 376.610823 -308.098899) (xy 376.663607 -308.080892) (xy 376.71845 -308.070762)
			(xy 376.774184 -308.068725) (xy 376.829621 -308.074825) (xy 376.883578 -308.088931) (xy 376.934907 -308.110743)
			(xy 376.982513 -308.139797) (xy 377.025381 -308.175472) (xy 377.062598 -308.217009) (xy 377.084479 -308.250082)
			(xy 383.893834 -308.250082) (xy 383.897794 -308.201028) (xy 383.909571 -308.153244) (xy 383.928862 -308.107968)
			(xy 383.955165 -308.066372) (xy 383.9878 -308.029535) (xy 384.025921 -307.99841) (xy 384.068542 -307.973803)
			(xy 384.114558 -307.956351) (xy 384.162777 -307.946507) (xy 384.211952 -307.944526) (xy 384.260807 -307.950458)
			(xy 384.308078 -307.96415) (xy 384.35254 -307.985248) (xy 384.393043 -308.013204) (xy 384.428536 -308.047296)
			(xy 384.458101 -308.08664) (xy 384.480972 -308.130217) (xy 384.496556 -308.176898) (xy 384.504451 -308.225475)
			(xy 384.504941 -308.249828) (xy 384.844048 -308.249828) (xy 384.848008 -308.200774) (xy 384.859785 -308.15299)
			(xy 384.879076 -308.107714) (xy 384.905379 -308.066118) (xy 384.938014 -308.029281) (xy 384.976135 -307.998156)
			(xy 385.018756 -307.973549) (xy 385.064772 -307.956097) (xy 385.112991 -307.946253) (xy 385.162166 -307.944272)
			(xy 385.211021 -307.950204) (xy 385.258292 -307.963896) (xy 385.302754 -307.984994) (xy 385.343257 -308.01295)
			(xy 385.37875 -308.047042) (xy 385.408315 -308.086386) (xy 385.431186 -308.129963) (xy 385.44677 -308.176644)
			(xy 385.454665 -308.225221) (xy 385.45516 -308.249828) (xy 385.794008 -308.249828) (xy 385.797968 -308.200774)
			(xy 385.809745 -308.15299) (xy 385.829036 -308.107714) (xy 385.855339 -308.066118) (xy 385.887974 -308.029281)
			(xy 385.926095 -307.998156) (xy 385.968716 -307.973549) (xy 386.014732 -307.956097) (xy 386.062951 -307.946253)
			(xy 386.112126 -307.944272) (xy 386.160981 -307.950204) (xy 386.208252 -307.963896) (xy 386.252714 -307.984994)
			(xy 386.293217 -308.01295) (xy 386.32871 -308.047042) (xy 386.358275 -308.086386) (xy 386.381146 -308.129963)
			(xy 386.39673 -308.176644) (xy 386.404625 -308.225221) (xy 386.40512 -308.249828) (xy 386.744222 -308.249828)
			(xy 386.748182 -308.200774) (xy 386.759959 -308.15299) (xy 386.77925 -308.107714) (xy 386.805553 -308.066118)
			(xy 386.838188 -308.029281) (xy 386.876309 -307.998156) (xy 386.91893 -307.973549) (xy 386.964946 -307.956097)
			(xy 387.013165 -307.946253) (xy 387.06234 -307.944272) (xy 387.111195 -307.950204) (xy 387.158466 -307.963896)
			(xy 387.202928 -307.984994) (xy 387.243431 -308.01295) (xy 387.278924 -308.047042) (xy 387.308489 -308.086386)
			(xy 387.33136 -308.129963) (xy 387.346944 -308.176644) (xy 387.354839 -308.225221) (xy 387.355334 -308.249828)
			(xy 387.694182 -308.249828) (xy 387.698142 -308.200774) (xy 387.709919 -308.15299) (xy 387.72921 -308.107714)
			(xy 387.755513 -308.066118) (xy 387.788148 -308.029281) (xy 387.826269 -307.998156) (xy 387.86889 -307.973549)
			(xy 387.914906 -307.956097) (xy 387.963125 -307.946253) (xy 388.0123 -307.944272) (xy 388.061155 -307.950204)
			(xy 388.108426 -307.963896) (xy 388.152888 -307.984994) (xy 388.193391 -308.01295) (xy 388.228884 -308.047042)
			(xy 388.258449 -308.086386) (xy 388.28132 -308.129963) (xy 388.296904 -308.176644) (xy 388.304799 -308.225221)
			(xy 388.305294 -308.249828) (xy 388.644142 -308.249828) (xy 388.648102 -308.200774) (xy 388.659879 -308.15299)
			(xy 388.67917 -308.107714) (xy 388.705473 -308.066118) (xy 388.738108 -308.029281) (xy 388.776229 -307.998156)
			(xy 388.81885 -307.973549) (xy 388.864866 -307.956097) (xy 388.913085 -307.946253) (xy 388.96226 -307.944272)
			(xy 389.011115 -307.950204) (xy 389.058386 -307.963896) (xy 389.102848 -307.984994) (xy 389.143351 -308.01295)
			(xy 389.178844 -308.047042) (xy 389.208409 -308.086386) (xy 389.23128 -308.129963) (xy 389.246864 -308.176644)
			(xy 389.254759 -308.225221) (xy 389.255254 -308.249828) (xy 389.594102 -308.249828) (xy 389.598062 -308.200774)
			(xy 389.609839 -308.15299) (xy 389.62913 -308.107714) (xy 389.655433 -308.066118) (xy 389.688068 -308.029281)
			(xy 389.726189 -307.998156) (xy 389.76881 -307.973549) (xy 389.814826 -307.956097) (xy 389.863045 -307.946253)
			(xy 389.91222 -307.944272) (xy 389.961075 -307.950204) (xy 390.008346 -307.963896) (xy 390.052808 -307.984994)
			(xy 390.093311 -308.01295) (xy 390.128804 -308.047042) (xy 390.158369 -308.086386) (xy 390.18124 -308.129963)
			(xy 390.196824 -308.176644) (xy 390.204719 -308.225221) (xy 390.205214 -308.249828) (xy 390.544062 -308.249828)
			(xy 390.548022 -308.200774) (xy 390.559799 -308.15299) (xy 390.57909 -308.107714) (xy 390.605393 -308.066118)
			(xy 390.638028 -308.029281) (xy 390.676149 -307.998156) (xy 390.71877 -307.973549) (xy 390.764786 -307.956097)
			(xy 390.813005 -307.946253) (xy 390.86218 -307.944272) (xy 390.911035 -307.950204) (xy 390.958306 -307.963896)
			(xy 391.002768 -307.984994) (xy 391.043271 -308.01295) (xy 391.078764 -308.047042) (xy 391.108329 -308.086386)
			(xy 391.1312 -308.129963) (xy 391.146784 -308.176644) (xy 391.154679 -308.225221) (xy 391.155174 -308.249828)
			(xy 391.494022 -308.249828) (xy 391.497982 -308.200774) (xy 391.509759 -308.15299) (xy 391.52905 -308.107714)
			(xy 391.555353 -308.066118) (xy 391.587988 -308.029281) (xy 391.626109 -307.998156) (xy 391.66873 -307.973549)
			(xy 391.714746 -307.956097) (xy 391.762965 -307.946253) (xy 391.81214 -307.944272) (xy 391.860995 -307.950204)
			(xy 391.908266 -307.963896) (xy 391.952728 -307.984994) (xy 391.993231 -308.01295) (xy 392.028724 -308.047042)
			(xy 392.058289 -308.086386) (xy 392.08116 -308.129963) (xy 392.096744 -308.176644) (xy 392.104639 -308.225221)
			(xy 392.105134 -308.249828) (xy 392.443982 -308.249828) (xy 392.447942 -308.200774) (xy 392.459719 -308.15299)
			(xy 392.47901 -308.107714) (xy 392.505313 -308.066118) (xy 392.537948 -308.029281) (xy 392.576069 -307.998156)
			(xy 392.61869 -307.973549) (xy 392.664706 -307.956097) (xy 392.712925 -307.946253) (xy 392.7621 -307.944272)
			(xy 392.810955 -307.950204) (xy 392.858226 -307.963896) (xy 392.902688 -307.984994) (xy 392.943191 -308.01295)
			(xy 392.978684 -308.047042) (xy 393.008249 -308.086386) (xy 393.03112 -308.129963) (xy 393.046704 -308.176644)
			(xy 393.054599 -308.225221) (xy 393.055094 -308.249828) (xy 393.394196 -308.249828) (xy 393.398156 -308.200774)
			(xy 393.409933 -308.15299) (xy 393.429224 -308.107714) (xy 393.455527 -308.066118) (xy 393.488162 -308.029281)
			(xy 393.526283 -307.998156) (xy 393.568904 -307.973549) (xy 393.61492 -307.956097) (xy 393.663139 -307.946253)
			(xy 393.712314 -307.944272) (xy 393.761169 -307.950204) (xy 393.80844 -307.963896) (xy 393.852902 -307.984994)
			(xy 393.893405 -308.01295) (xy 393.928898 -308.047042) (xy 393.958463 -308.086386) (xy 393.981334 -308.129963)
			(xy 393.996918 -308.176644) (xy 394.004813 -308.225221) (xy 394.005308 -308.249828) (xy 394.004813 -308.274435)
			(xy 393.996918 -308.323012) (xy 393.981334 -308.369693) (xy 393.958463 -308.41327) (xy 393.928898 -308.452614)
			(xy 393.893405 -308.486706) (xy 393.852902 -308.514662) (xy 393.80844 -308.53576) (xy 393.761169 -308.549452)
			(xy 393.712314 -308.555384) (xy 393.663139 -308.553403) (xy 393.61492 -308.543559) (xy 393.568904 -308.526107)
			(xy 393.526283 -308.5015) (xy 393.488162 -308.470375) (xy 393.455527 -308.433538) (xy 393.429224 -308.391942)
			(xy 393.409933 -308.346666) (xy 393.398156 -308.298882) (xy 393.394196 -308.249828) (xy 393.055094 -308.249828)
			(xy 393.054599 -308.274435) (xy 393.046704 -308.323012) (xy 393.03112 -308.369693) (xy 393.008249 -308.41327)
			(xy 392.978684 -308.452614) (xy 392.943191 -308.486706) (xy 392.902688 -308.514662) (xy 392.858226 -308.53576)
			(xy 392.810955 -308.549452) (xy 392.7621 -308.555384) (xy 392.712925 -308.553403) (xy 392.664706 -308.543559)
			(xy 392.61869 -308.526107) (xy 392.576069 -308.5015) (xy 392.537948 -308.470375) (xy 392.505313 -308.433538)
			(xy 392.47901 -308.391942) (xy 392.459719 -308.346666) (xy 392.447942 -308.298882) (xy 392.443982 -308.249828)
			(xy 392.105134 -308.249828) (xy 392.104639 -308.274435) (xy 392.096744 -308.323012) (xy 392.08116 -308.369693)
			(xy 392.058289 -308.41327) (xy 392.028724 -308.452614) (xy 391.993231 -308.486706) (xy 391.952728 -308.514662)
			(xy 391.908266 -308.53576) (xy 391.860995 -308.549452) (xy 391.81214 -308.555384) (xy 391.762965 -308.553403)
			(xy 391.714746 -308.543559) (xy 391.66873 -308.526107) (xy 391.626109 -308.5015) (xy 391.587988 -308.470375)
			(xy 391.555353 -308.433538) (xy 391.52905 -308.391942) (xy 391.509759 -308.346666) (xy 391.497982 -308.298882)
			(xy 391.494022 -308.249828) (xy 391.155174 -308.249828) (xy 391.154679 -308.274435) (xy 391.146784 -308.323012)
			(xy 391.1312 -308.369693) (xy 391.108329 -308.41327) (xy 391.078764 -308.452614) (xy 391.043271 -308.486706)
			(xy 391.002768 -308.514662) (xy 390.958306 -308.53576) (xy 390.911035 -308.549452) (xy 390.86218 -308.555384)
			(xy 390.813005 -308.553403) (xy 390.764786 -308.543559) (xy 390.71877 -308.526107) (xy 390.676149 -308.5015)
			(xy 390.638028 -308.470375) (xy 390.605393 -308.433538) (xy 390.57909 -308.391942) (xy 390.559799 -308.346666)
			(xy 390.548022 -308.298882) (xy 390.544062 -308.249828) (xy 390.205214 -308.249828) (xy 390.204719 -308.274435)
			(xy 390.196824 -308.323012) (xy 390.18124 -308.369693) (xy 390.158369 -308.41327) (xy 390.128804 -308.452614)
			(xy 390.093311 -308.486706) (xy 390.052808 -308.514662) (xy 390.008346 -308.53576) (xy 389.961075 -308.549452)
			(xy 389.91222 -308.555384) (xy 389.863045 -308.553403) (xy 389.814826 -308.543559) (xy 389.76881 -308.526107)
			(xy 389.726189 -308.5015) (xy 389.688068 -308.470375) (xy 389.655433 -308.433538) (xy 389.62913 -308.391942)
			(xy 389.609839 -308.346666) (xy 389.598062 -308.298882) (xy 389.594102 -308.249828) (xy 389.255254 -308.249828)
			(xy 389.254759 -308.274435) (xy 389.246864 -308.323012) (xy 389.23128 -308.369693) (xy 389.208409 -308.41327)
			(xy 389.178844 -308.452614) (xy 389.143351 -308.486706) (xy 389.102848 -308.514662) (xy 389.058386 -308.53576)
			(xy 389.011115 -308.549452) (xy 388.96226 -308.555384) (xy 388.913085 -308.553403) (xy 388.864866 -308.543559)
			(xy 388.81885 -308.526107) (xy 388.776229 -308.5015) (xy 388.738108 -308.470375) (xy 388.705473 -308.433538)
			(xy 388.67917 -308.391942) (xy 388.659879 -308.346666) (xy 388.648102 -308.298882) (xy 388.644142 -308.249828)
			(xy 388.305294 -308.249828) (xy 388.304799 -308.274435) (xy 388.296904 -308.323012) (xy 388.28132 -308.369693)
			(xy 388.258449 -308.41327) (xy 388.228884 -308.452614) (xy 388.193391 -308.486706) (xy 388.152888 -308.514662)
			(xy 388.108426 -308.53576) (xy 388.061155 -308.549452) (xy 388.0123 -308.555384) (xy 387.963125 -308.553403)
			(xy 387.914906 -308.543559) (xy 387.86889 -308.526107) (xy 387.826269 -308.5015) (xy 387.788148 -308.470375)
			(xy 387.755513 -308.433538) (xy 387.72921 -308.391942) (xy 387.709919 -308.346666) (xy 387.698142 -308.298882)
			(xy 387.694182 -308.249828) (xy 387.355334 -308.249828) (xy 387.354839 -308.274435) (xy 387.346944 -308.323012)
			(xy 387.33136 -308.369693) (xy 387.308489 -308.41327) (xy 387.278924 -308.452614) (xy 387.243431 -308.486706)
			(xy 387.202928 -308.514662) (xy 387.158466 -308.53576) (xy 387.111195 -308.549452) (xy 387.06234 -308.555384)
			(xy 387.013165 -308.553403) (xy 386.964946 -308.543559) (xy 386.91893 -308.526107) (xy 386.876309 -308.5015)
			(xy 386.838188 -308.470375) (xy 386.805553 -308.433538) (xy 386.77925 -308.391942) (xy 386.759959 -308.346666)
			(xy 386.748182 -308.298882) (xy 386.744222 -308.249828) (xy 386.40512 -308.249828) (xy 386.404625 -308.274435)
			(xy 386.39673 -308.323012) (xy 386.381146 -308.369693) (xy 386.358275 -308.41327) (xy 386.32871 -308.452614)
			(xy 386.293217 -308.486706) (xy 386.252714 -308.514662) (xy 386.208252 -308.53576) (xy 386.160981 -308.549452)
			(xy 386.112126 -308.555384) (xy 386.062951 -308.553403) (xy 386.014732 -308.543559) (xy 385.968716 -308.526107)
			(xy 385.926095 -308.5015) (xy 385.887974 -308.470375) (xy 385.855339 -308.433538) (xy 385.829036 -308.391942)
			(xy 385.809745 -308.346666) (xy 385.797968 -308.298882) (xy 385.794008 -308.249828) (xy 385.45516 -308.249828)
			(xy 385.454665 -308.274435) (xy 385.44677 -308.323012) (xy 385.431186 -308.369693) (xy 385.408315 -308.41327)
			(xy 385.37875 -308.452614) (xy 385.343257 -308.486706) (xy 385.302754 -308.514662) (xy 385.258292 -308.53576)
			(xy 385.211021 -308.549452) (xy 385.162166 -308.555384) (xy 385.112991 -308.553403) (xy 385.064772 -308.543559)
			(xy 385.018756 -308.526107) (xy 384.976135 -308.5015) (xy 384.938014 -308.470375) (xy 384.905379 -308.433538)
			(xy 384.879076 -308.391942) (xy 384.859785 -308.346666) (xy 384.848008 -308.298882) (xy 384.844048 -308.249828)
			(xy 384.504941 -308.249828) (xy 384.504946 -308.250082) (xy 384.504451 -308.274689) (xy 384.496556 -308.323266)
			(xy 384.480972 -308.369947) (xy 384.458101 -308.413524) (xy 384.428536 -308.452868) (xy 384.393043 -308.48696)
			(xy 384.35254 -308.514916) (xy 384.308078 -308.536014) (xy 384.260807 -308.549706) (xy 384.211952 -308.555638)
			(xy 384.162777 -308.553657) (xy 384.114558 -308.543813) (xy 384.068542 -308.526361) (xy 384.025921 -308.501754)
			(xy 383.9878 -308.470629) (xy 383.955165 -308.433792) (xy 383.928862 -308.392196) (xy 383.909571 -308.34692)
			(xy 383.897794 -308.299136) (xy 383.893834 -308.250082) (xy 377.084479 -308.250082) (xy 377.093371 -308.263522)
			(xy 377.117043 -308.314019) (xy 377.133111 -308.367426) (xy 377.141231 -308.422602) (xy 377.14174 -308.450488)
			(xy 377.141231 -308.478374) (xy 377.133111 -308.53355) (xy 377.117043 -308.586957) (xy 377.093371 -308.637454)
			(xy 377.078766 -308.65953) (xy 378.705616 -308.65953) (xy 378.709687 -308.603908) (xy 378.721813 -308.549471)
			(xy 378.741736 -308.49738) (xy 378.769032 -308.448745) (xy 378.803118 -308.404602) (xy 378.843267 -308.365893)
			(xy 378.888625 -308.333442) (xy 378.938225 -308.307941) (xy 378.991009 -308.289934) (xy 379.045852 -308.279804)
			(xy 379.101586 -308.277767) (xy 379.157023 -308.283867) (xy 379.21098 -308.297973) (xy 379.262309 -308.319785)
			(xy 379.309915 -308.348839) (xy 379.352783 -308.384514) (xy 379.39 -308.426051) (xy 379.420773 -308.472564)
			(xy 379.444445 -308.523061) (xy 379.460513 -308.576468) (xy 379.468633 -308.631644) (xy 379.469142 -308.65953)
			(xy 379.468633 -308.687416) (xy 379.460513 -308.742592) (xy 379.444445 -308.795999) (xy 379.420773 -308.846496)
			(xy 379.39 -308.893009) (xy 379.352783 -308.934546) (xy 379.309915 -308.970221) (xy 379.262309 -308.999275)
			(xy 379.21098 -309.021087) (xy 379.157023 -309.035193) (xy 379.101586 -309.041293) (xy 379.045852 -309.039256)
			(xy 378.991009 -309.029126) (xy 378.938225 -309.011119) (xy 378.888625 -308.985618) (xy 378.843267 -308.953167)
			(xy 378.803118 -308.914458) (xy 378.769032 -308.870315) (xy 378.741736 -308.82168) (xy 378.721813 -308.769589)
			(xy 378.709687 -308.715152) (xy 378.705616 -308.65953) (xy 377.078766 -308.65953) (xy 377.062598 -308.683967)
			(xy 377.025381 -308.725504) (xy 376.982513 -308.761179) (xy 376.934907 -308.790233) (xy 376.883578 -308.812045)
			(xy 376.829621 -308.826151) (xy 376.774184 -308.832251) (xy 376.71845 -308.830214) (xy 376.663607 -308.820084)
			(xy 376.610823 -308.802077) (xy 376.561223 -308.776576) (xy 376.515865 -308.744125) (xy 376.475716 -308.705416)
			(xy 376.44163 -308.661273) (xy 376.414334 -308.612638) (xy 376.394411 -308.560547) (xy 376.382285 -308.50611)
			(xy 376.378214 -308.450488) (xy 351.03308 -308.450488) (xy 351.03308 -309.414926) (xy 375.299984 -309.414926)
			(xy 375.304055 -309.359304) (xy 375.316181 -309.304867) (xy 375.336104 -309.252776) (xy 375.3634 -309.204141)
			(xy 375.397486 -309.159998) (xy 375.437635 -309.121289) (xy 375.482993 -309.088838) (xy 375.532593 -309.063337)
			(xy 375.585377 -309.04533) (xy 375.64022 -309.0352) (xy 375.695954 -309.033163) (xy 375.751391 -309.039263)
			(xy 375.805348 -309.053369) (xy 375.856677 -309.075181) (xy 375.904283 -309.104235) (xy 375.947151 -309.13991)
			(xy 375.984368 -309.181447) (xy 375.996502 -309.199788) (xy 384.844048 -309.199788) (xy 384.848008 -309.150734)
			(xy 384.859785 -309.10295) (xy 384.879076 -309.057674) (xy 384.905379 -309.016078) (xy 384.938014 -308.979241)
			(xy 384.976135 -308.948116) (xy 385.018756 -308.923509) (xy 385.064772 -308.906057) (xy 385.112991 -308.896213)
			(xy 385.162166 -308.894232) (xy 385.211021 -308.900164) (xy 385.258292 -308.913856) (xy 385.302754 -308.934954)
			(xy 385.343257 -308.96291) (xy 385.37875 -308.997002) (xy 385.408315 -309.036346) (xy 385.431186 -309.079923)
			(xy 385.44677 -309.126604) (xy 385.454665 -309.175181) (xy 385.45516 -309.199788) (xy 385.794008 -309.199788)
			(xy 385.797968 -309.150734) (xy 385.809745 -309.10295) (xy 385.829036 -309.057674) (xy 385.855339 -309.016078)
			(xy 385.887974 -308.979241) (xy 385.926095 -308.948116) (xy 385.968716 -308.923509) (xy 386.014732 -308.906057)
			(xy 386.062951 -308.896213) (xy 386.112126 -308.894232) (xy 386.160981 -308.900164) (xy 386.208252 -308.913856)
			(xy 386.252714 -308.934954) (xy 386.293217 -308.96291) (xy 386.32871 -308.997002) (xy 386.358275 -309.036346)
			(xy 386.381146 -309.079923) (xy 386.39673 -309.126604) (xy 386.404625 -309.175181) (xy 386.40512 -309.199788)
			(xy 386.744222 -309.199788) (xy 386.748182 -309.150734) (xy 386.759959 -309.10295) (xy 386.77925 -309.057674)
			(xy 386.805553 -309.016078) (xy 386.838188 -308.979241) (xy 386.876309 -308.948116) (xy 386.91893 -308.923509)
			(xy 386.964946 -308.906057) (xy 387.013165 -308.896213) (xy 387.06234 -308.894232) (xy 387.111195 -308.900164)
			(xy 387.158466 -308.913856) (xy 387.202928 -308.934954) (xy 387.243431 -308.96291) (xy 387.278924 -308.997002)
			(xy 387.308489 -309.036346) (xy 387.33136 -309.079923) (xy 387.346944 -309.126604) (xy 387.354839 -309.175181)
			(xy 387.355334 -309.199788) (xy 387.694182 -309.199788) (xy 387.698142 -309.150734) (xy 387.709919 -309.10295)
			(xy 387.72921 -309.057674) (xy 387.755513 -309.016078) (xy 387.788148 -308.979241) (xy 387.826269 -308.948116)
			(xy 387.86889 -308.923509) (xy 387.914906 -308.906057) (xy 387.963125 -308.896213) (xy 388.0123 -308.894232)
			(xy 388.061155 -308.900164) (xy 388.108426 -308.913856) (xy 388.152888 -308.934954) (xy 388.193391 -308.96291)
			(xy 388.228884 -308.997002) (xy 388.258449 -309.036346) (xy 388.28132 -309.079923) (xy 388.296904 -309.126604)
			(xy 388.304799 -309.175181) (xy 388.305294 -309.199788) (xy 388.644142 -309.199788) (xy 388.648102 -309.150734)
			(xy 388.659879 -309.10295) (xy 388.67917 -309.057674) (xy 388.705473 -309.016078) (xy 388.738108 -308.979241)
			(xy 388.776229 -308.948116) (xy 388.81885 -308.923509) (xy 388.864866 -308.906057) (xy 388.913085 -308.896213)
			(xy 388.96226 -308.894232) (xy 389.011115 -308.900164) (xy 389.058386 -308.913856) (xy 389.102848 -308.934954)
			(xy 389.143351 -308.96291) (xy 389.178844 -308.997002) (xy 389.208409 -309.036346) (xy 389.23128 -309.079923)
			(xy 389.246864 -309.126604) (xy 389.254759 -309.175181) (xy 389.255254 -309.199788) (xy 389.594102 -309.199788)
			(xy 389.598062 -309.150734) (xy 389.609839 -309.10295) (xy 389.62913 -309.057674) (xy 389.655433 -309.016078)
			(xy 389.688068 -308.979241) (xy 389.726189 -308.948116) (xy 389.76881 -308.923509) (xy 389.814826 -308.906057)
			(xy 389.863045 -308.896213) (xy 389.91222 -308.894232) (xy 389.961075 -308.900164) (xy 390.008346 -308.913856)
			(xy 390.052808 -308.934954) (xy 390.093311 -308.96291) (xy 390.128804 -308.997002) (xy 390.158369 -309.036346)
			(xy 390.18124 -309.079923) (xy 390.196824 -309.126604) (xy 390.204719 -309.175181) (xy 390.205214 -309.199788)
			(xy 390.544062 -309.199788) (xy 390.548022 -309.150734) (xy 390.559799 -309.10295) (xy 390.57909 -309.057674)
			(xy 390.605393 -309.016078) (xy 390.638028 -308.979241) (xy 390.676149 -308.948116) (xy 390.71877 -308.923509)
			(xy 390.764786 -308.906057) (xy 390.813005 -308.896213) (xy 390.86218 -308.894232) (xy 390.911035 -308.900164)
			(xy 390.958306 -308.913856) (xy 391.002768 -308.934954) (xy 391.043271 -308.96291) (xy 391.078764 -308.997002)
			(xy 391.108329 -309.036346) (xy 391.1312 -309.079923) (xy 391.146784 -309.126604) (xy 391.154679 -309.175181)
			(xy 391.155174 -309.199788) (xy 391.494022 -309.199788) (xy 391.497982 -309.150734) (xy 391.509759 -309.10295)
			(xy 391.52905 -309.057674) (xy 391.555353 -309.016078) (xy 391.587988 -308.979241) (xy 391.626109 -308.948116)
			(xy 391.66873 -308.923509) (xy 391.714746 -308.906057) (xy 391.762965 -308.896213) (xy 391.81214 -308.894232)
			(xy 391.860995 -308.900164) (xy 391.908266 -308.913856) (xy 391.952728 -308.934954) (xy 391.993231 -308.96291)
			(xy 392.028724 -308.997002) (xy 392.058289 -309.036346) (xy 392.08116 -309.079923) (xy 392.096744 -309.126604)
			(xy 392.104639 -309.175181) (xy 392.105134 -309.199788) (xy 392.443982 -309.199788) (xy 392.447942 -309.150734)
			(xy 392.459719 -309.10295) (xy 392.47901 -309.057674) (xy 392.505313 -309.016078) (xy 392.537948 -308.979241)
			(xy 392.576069 -308.948116) (xy 392.61869 -308.923509) (xy 392.664706 -308.906057) (xy 392.712925 -308.896213)
			(xy 392.7621 -308.894232) (xy 392.810955 -308.900164) (xy 392.858226 -308.913856) (xy 392.902688 -308.934954)
			(xy 392.943191 -308.96291) (xy 392.978684 -308.997002) (xy 393.008249 -309.036346) (xy 393.03112 -309.079923)
			(xy 393.046704 -309.126604) (xy 393.054599 -309.175181) (xy 393.055094 -309.199788) (xy 393.394196 -309.199788)
			(xy 393.398156 -309.150734) (xy 393.409933 -309.10295) (xy 393.429224 -309.057674) (xy 393.455527 -309.016078)
			(xy 393.488162 -308.979241) (xy 393.526283 -308.948116) (xy 393.568904 -308.923509) (xy 393.61492 -308.906057)
			(xy 393.663139 -308.896213) (xy 393.712314 -308.894232) (xy 393.761169 -308.900164) (xy 393.80844 -308.913856)
			(xy 393.852902 -308.934954) (xy 393.893405 -308.96291) (xy 393.928898 -308.997002) (xy 393.958463 -309.036346)
			(xy 393.981334 -309.079923) (xy 393.996918 -309.126604) (xy 394.004813 -309.175181) (xy 394.005142 -309.191549)
			(xy 394.344268 -309.191549) (xy 394.349631 -309.142197) (xy 394.362906 -309.094362) (xy 394.383746 -309.049305)
			(xy 394.4116 -309.008213) (xy 394.445735 -308.972169) (xy 394.485252 -308.942122) (xy 394.529109 -308.918864)
			(xy 394.576151 -308.903007) (xy 394.625139 -308.894969) (xy 394.64996 -308.89448) (xy 394.664143 -308.894662)
			(xy 394.692383 -308.897331) (xy 394.706348 -308.899814) (xy 394.720306 -308.902031) (xy 394.748443 -308.89944)
			(xy 394.774793 -308.88924) (xy 394.797341 -308.872212) (xy 394.814361 -308.849657) (xy 394.82455 -308.823302)
			(xy 394.827129 -308.795165) (xy 394.824966 -308.781196) (xy 394.822494 -308.767229) (xy 394.819819 -308.73899)
			(xy 394.819632 -308.724808) (xy 394.820069 -308.699987) (xy 394.828099 -308.650999) (xy 394.843948 -308.603955)
			(xy 394.867199 -308.560095) (xy 394.89724 -308.520574) (xy 394.933278 -308.486434) (xy 394.974365 -308.458573)
			(xy 395.019417 -308.437727) (xy 395.067249 -308.424444) (xy 395.1166 -308.419074) (xy 395.166169 -308.421758)
			(xy 395.214651 -308.432426) (xy 395.260768 -308.450798) (xy 395.303306 -308.476388) (xy 395.341144 -308.508522)
			(xy 395.373284 -308.546355) (xy 395.398881 -308.588889) (xy 395.417259 -308.635003) (xy 395.427935 -308.683484)
			(xy 395.43018 -308.724808) (xy 395.769096 -308.724808) (xy 395.773056 -308.675754) (xy 395.784833 -308.62797)
			(xy 395.804124 -308.582694) (xy 395.830427 -308.541098) (xy 395.863062 -308.504261) (xy 395.901183 -308.473136)
			(xy 395.943804 -308.448529) (xy 395.98982 -308.431077) (xy 396.038039 -308.421233) (xy 396.087214 -308.419252)
			(xy 396.136069 -308.425184) (xy 396.18334 -308.438876) (xy 396.227802 -308.459974) (xy 396.268305 -308.48793)
			(xy 396.303798 -308.522022) (xy 396.333363 -308.561366) (xy 396.356234 -308.604943) (xy 396.371818 -308.651624)
			(xy 396.379713 -308.700201) (xy 396.380208 -308.724808) (xy 396.719056 -308.724808) (xy 396.723016 -308.675754)
			(xy 396.734793 -308.62797) (xy 396.754084 -308.582694) (xy 396.780387 -308.541098) (xy 396.813022 -308.504261)
			(xy 396.851143 -308.473136) (xy 396.893764 -308.448529) (xy 396.93978 -308.431077) (xy 396.987999 -308.421233)
			(xy 397.037174 -308.419252) (xy 397.086029 -308.425184) (xy 397.1333 -308.438876) (xy 397.177762 -308.459974)
			(xy 397.218265 -308.48793) (xy 397.253758 -308.522022) (xy 397.283323 -308.561366) (xy 397.306194 -308.604943)
			(xy 397.321778 -308.651624) (xy 397.329673 -308.700201) (xy 397.330168 -308.724808) (xy 397.329673 -308.749415)
			(xy 397.321778 -308.797992) (xy 397.306194 -308.844673) (xy 397.283323 -308.88825) (xy 397.253758 -308.927594)
			(xy 397.218265 -308.961686) (xy 397.177762 -308.989642) (xy 397.1333 -309.01074) (xy 397.086029 -309.024432)
			(xy 397.037174 -309.030364) (xy 396.987999 -309.028383) (xy 396.93978 -309.018539) (xy 396.893764 -309.001087)
			(xy 396.851143 -308.97648) (xy 396.813022 -308.945355) (xy 396.780387 -308.908518) (xy 396.754084 -308.866922)
			(xy 396.734793 -308.821646) (xy 396.723016 -308.773862) (xy 396.719056 -308.724808) (xy 396.380208 -308.724808)
			(xy 396.379713 -308.749415) (xy 396.371818 -308.797992) (xy 396.356234 -308.844673) (xy 396.333363 -308.88825)
			(xy 396.303798 -308.927594) (xy 396.268305 -308.961686) (xy 396.227802 -308.989642) (xy 396.18334 -309.01074)
			(xy 396.136069 -309.024432) (xy 396.087214 -309.030364) (xy 396.038039 -309.028383) (xy 395.98982 -309.018539)
			(xy 395.943804 -309.001087) (xy 395.901183 -308.97648) (xy 395.863062 -308.945355) (xy 395.830427 -308.908518)
			(xy 395.804124 -308.866922) (xy 395.784833 -308.821646) (xy 395.773056 -308.773862) (xy 395.769096 -308.724808)
			(xy 395.43018 -308.724808) (xy 395.430628 -308.733052) (xy 395.425265 -308.782404) (xy 395.41199 -308.830238)
			(xy 395.39115 -308.875294) (xy 395.363296 -308.916385) (xy 395.329162 -308.952428) (xy 395.289646 -308.982475)
			(xy 395.245789 -309.005733) (xy 395.198748 -309.021589) (xy 395.149761 -309.029627) (xy 395.12494 -309.030116)
			(xy 395.110757 -309.029934) (xy 395.082517 -309.027265) (xy 395.068552 -309.024782) (xy 395.054593 -309.02257)
			(xy 395.026457 -309.02516) (xy 395.000108 -309.03536) (xy 394.977561 -309.052388) (xy 394.960541 -309.074941)
			(xy 394.950352 -309.101295) (xy 394.947772 -309.129432) (xy 394.949934 -309.1434) (xy 394.952406 -309.157367)
			(xy 394.955081 -309.185606) (xy 394.955268 -309.199788) (xy 394.954835 -309.224609) (xy 394.946806 -309.273598)
			(xy 394.930957 -309.320643) (xy 394.907706 -309.364504) (xy 394.877666 -309.404026) (xy 394.841627 -309.438167)
			(xy 394.80054 -309.466028) (xy 394.755487 -309.486876) (xy 394.707655 -309.50016) (xy 394.658303 -309.50553)
			(xy 394.608733 -309.502846) (xy 394.56025 -309.492178) (xy 394.514132 -309.473807) (xy 394.471593 -309.448217)
			(xy 394.433755 -309.416082) (xy 394.401613 -309.378249) (xy 394.376016 -309.335715) (xy 394.357637 -309.289599)
			(xy 394.346961 -309.241118) (xy 394.344268 -309.191549) (xy 394.005142 -309.191549) (xy 394.005308 -309.199788)
			(xy 394.004813 -309.224395) (xy 393.996918 -309.272972) (xy 393.981334 -309.319653) (xy 393.958463 -309.36323)
			(xy 393.928898 -309.402574) (xy 393.893405 -309.436666) (xy 393.852902 -309.464622) (xy 393.80844 -309.48572)
			(xy 393.761169 -309.499412) (xy 393.712314 -309.505344) (xy 393.663139 -309.503363) (xy 393.61492 -309.493519)
			(xy 393.568904 -309.476067) (xy 393.526283 -309.45146) (xy 393.488162 -309.420335) (xy 393.455527 -309.383498)
			(xy 393.429224 -309.341902) (xy 393.409933 -309.296626) (xy 393.398156 -309.248842) (xy 393.394196 -309.199788)
			(xy 393.055094 -309.199788) (xy 393.054599 -309.224395) (xy 393.046704 -309.272972) (xy 393.03112 -309.319653)
			(xy 393.008249 -309.36323) (xy 392.978684 -309.402574) (xy 392.943191 -309.436666) (xy 392.902688 -309.464622)
			(xy 392.858226 -309.48572) (xy 392.810955 -309.499412) (xy 392.7621 -309.505344) (xy 392.712925 -309.503363)
			(xy 392.664706 -309.493519) (xy 392.61869 -309.476067) (xy 392.576069 -309.45146) (xy 392.537948 -309.420335)
			(xy 392.505313 -309.383498) (xy 392.47901 -309.341902) (xy 392.459719 -309.296626) (xy 392.447942 -309.248842)
			(xy 392.443982 -309.199788) (xy 392.105134 -309.199788) (xy 392.104639 -309.224395) (xy 392.096744 -309.272972)
			(xy 392.08116 -309.319653) (xy 392.058289 -309.36323) (xy 392.028724 -309.402574) (xy 391.993231 -309.436666)
			(xy 391.952728 -309.464622) (xy 391.908266 -309.48572) (xy 391.860995 -309.499412) (xy 391.81214 -309.505344)
			(xy 391.762965 -309.503363) (xy 391.714746 -309.493519) (xy 391.66873 -309.476067) (xy 391.626109 -309.45146)
			(xy 391.587988 -309.420335) (xy 391.555353 -309.383498) (xy 391.52905 -309.341902) (xy 391.509759 -309.296626)
			(xy 391.497982 -309.248842) (xy 391.494022 -309.199788) (xy 391.155174 -309.199788) (xy 391.154679 -309.224395)
			(xy 391.146784 -309.272972) (xy 391.1312 -309.319653) (xy 391.108329 -309.36323) (xy 391.078764 -309.402574)
			(xy 391.043271 -309.436666) (xy 391.002768 -309.464622) (xy 390.958306 -309.48572) (xy 390.911035 -309.499412)
			(xy 390.86218 -309.505344) (xy 390.813005 -309.503363) (xy 390.764786 -309.493519) (xy 390.71877 -309.476067)
			(xy 390.676149 -309.45146) (xy 390.638028 -309.420335) (xy 390.605393 -309.383498) (xy 390.57909 -309.341902)
			(xy 390.559799 -309.296626) (xy 390.548022 -309.248842) (xy 390.544062 -309.199788) (xy 390.205214 -309.199788)
			(xy 390.204719 -309.224395) (xy 390.196824 -309.272972) (xy 390.18124 -309.319653) (xy 390.158369 -309.36323)
			(xy 390.128804 -309.402574) (xy 390.093311 -309.436666) (xy 390.052808 -309.464622) (xy 390.008346 -309.48572)
			(xy 389.961075 -309.499412) (xy 389.91222 -309.505344) (xy 389.863045 -309.503363) (xy 389.814826 -309.493519)
			(xy 389.76881 -309.476067) (xy 389.726189 -309.45146) (xy 389.688068 -309.420335) (xy 389.655433 -309.383498)
			(xy 389.62913 -309.341902) (xy 389.609839 -309.296626) (xy 389.598062 -309.248842) (xy 389.594102 -309.199788)
			(xy 389.255254 -309.199788) (xy 389.254759 -309.224395) (xy 389.246864 -309.272972) (xy 389.23128 -309.319653)
			(xy 389.208409 -309.36323) (xy 389.178844 -309.402574) (xy 389.143351 -309.436666) (xy 389.102848 -309.464622)
			(xy 389.058386 -309.48572) (xy 389.011115 -309.499412) (xy 388.96226 -309.505344) (xy 388.913085 -309.503363)
			(xy 388.864866 -309.493519) (xy 388.81885 -309.476067) (xy 388.776229 -309.45146) (xy 388.738108 -309.420335)
			(xy 388.705473 -309.383498) (xy 388.67917 -309.341902) (xy 388.659879 -309.296626) (xy 388.648102 -309.248842)
			(xy 388.644142 -309.199788) (xy 388.305294 -309.199788) (xy 388.304799 -309.224395) (xy 388.296904 -309.272972)
			(xy 388.28132 -309.319653) (xy 388.258449 -309.36323) (xy 388.228884 -309.402574) (xy 388.193391 -309.436666)
			(xy 388.152888 -309.464622) (xy 388.108426 -309.48572) (xy 388.061155 -309.499412) (xy 388.0123 -309.505344)
			(xy 387.963125 -309.503363) (xy 387.914906 -309.493519) (xy 387.86889 -309.476067) (xy 387.826269 -309.45146)
			(xy 387.788148 -309.420335) (xy 387.755513 -309.383498) (xy 387.72921 -309.341902) (xy 387.709919 -309.296626)
			(xy 387.698142 -309.248842) (xy 387.694182 -309.199788) (xy 387.355334 -309.199788) (xy 387.354839 -309.224395)
			(xy 387.346944 -309.272972) (xy 387.33136 -309.319653) (xy 387.308489 -309.36323) (xy 387.278924 -309.402574)
			(xy 387.243431 -309.436666) (xy 387.202928 -309.464622) (xy 387.158466 -309.48572) (xy 387.111195 -309.499412)
			(xy 387.06234 -309.505344) (xy 387.013165 -309.503363) (xy 386.964946 -309.493519) (xy 386.91893 -309.476067)
			(xy 386.876309 -309.45146) (xy 386.838188 -309.420335) (xy 386.805553 -309.383498) (xy 386.77925 -309.341902)
			(xy 386.759959 -309.296626) (xy 386.748182 -309.248842) (xy 386.744222 -309.199788) (xy 386.40512 -309.199788)
			(xy 386.404625 -309.224395) (xy 386.39673 -309.272972) (xy 386.381146 -309.319653) (xy 386.358275 -309.36323)
			(xy 386.32871 -309.402574) (xy 386.293217 -309.436666) (xy 386.252714 -309.464622) (xy 386.208252 -309.48572)
			(xy 386.160981 -309.499412) (xy 386.112126 -309.505344) (xy 386.062951 -309.503363) (xy 386.014732 -309.493519)
			(xy 385.968716 -309.476067) (xy 385.926095 -309.45146) (xy 385.887974 -309.420335) (xy 385.855339 -309.383498)
			(xy 385.829036 -309.341902) (xy 385.809745 -309.296626) (xy 385.797968 -309.248842) (xy 385.794008 -309.199788)
			(xy 385.45516 -309.199788) (xy 385.454665 -309.224395) (xy 385.44677 -309.272972) (xy 385.431186 -309.319653)
			(xy 385.408315 -309.36323) (xy 385.37875 -309.402574) (xy 385.343257 -309.436666) (xy 385.302754 -309.464622)
			(xy 385.258292 -309.48572) (xy 385.211021 -309.499412) (xy 385.162166 -309.505344) (xy 385.112991 -309.503363)
			(xy 385.064772 -309.493519) (xy 385.018756 -309.476067) (xy 384.976135 -309.45146) (xy 384.938014 -309.420335)
			(xy 384.905379 -309.383498) (xy 384.879076 -309.341902) (xy 384.859785 -309.296626) (xy 384.848008 -309.248842)
			(xy 384.844048 -309.199788) (xy 375.996502 -309.199788) (xy 376.015141 -309.22796) (xy 376.038813 -309.278457)
			(xy 376.054881 -309.331864) (xy 376.063001 -309.38704) (xy 376.06351 -309.414926) (xy 376.063001 -309.442812)
			(xy 376.054881 -309.497988) (xy 376.038813 -309.551395) (xy 376.015141 -309.601892) (xy 375.984368 -309.648405)
			(xy 375.947151 -309.689942) (xy 375.904283 -309.725617) (xy 375.856677 -309.754671) (xy 375.805348 -309.776483)
			(xy 375.751391 -309.790589) (xy 375.695954 -309.796689) (xy 375.64022 -309.794652) (xy 375.585377 -309.784522)
			(xy 375.532593 -309.766515) (xy 375.482993 -309.741014) (xy 375.437635 -309.708563) (xy 375.397486 -309.669854)
			(xy 375.3634 -309.625711) (xy 375.336104 -309.577076) (xy 375.316181 -309.524985) (xy 375.304055 -309.470548)
			(xy 375.299984 -309.414926) (xy 351.03308 -309.414926) (xy 351.03308 -309.897272) (xy 382.740406 -309.897272)
			(xy 382.744477 -309.84165) (xy 382.756603 -309.787213) (xy 382.776526 -309.735122) (xy 382.803822 -309.686487)
			(xy 382.837908 -309.642344) (xy 382.878057 -309.603635) (xy 382.923415 -309.571184) (xy 382.973015 -309.545683)
			(xy 383.025799 -309.527676) (xy 383.080642 -309.517546) (xy 383.136376 -309.515509) (xy 383.191813 -309.521609)
			(xy 383.24577 -309.535715) (xy 383.297099 -309.557527) (xy 383.344705 -309.586581) (xy 383.387573 -309.622256)
			(xy 383.42479 -309.663793) (xy 383.455563 -309.710306) (xy 383.479235 -309.760803) (xy 383.495303 -309.81421)
			(xy 383.503423 -309.869386) (xy 383.503932 -309.897272) (xy 383.503423 -309.925158) (xy 383.495303 -309.980334)
			(xy 383.479235 -310.033741) (xy 383.455563 -310.084238) (xy 383.42479 -310.130751) (xy 383.407541 -310.150002)
			(xy 383.893834 -310.150002) (xy 383.897794 -310.100948) (xy 383.909571 -310.053164) (xy 383.928862 -310.007888)
			(xy 383.955165 -309.966292) (xy 383.9878 -309.929455) (xy 384.025921 -309.89833) (xy 384.068542 -309.873723)
			(xy 384.114558 -309.856271) (xy 384.162777 -309.846427) (xy 384.211952 -309.844446) (xy 384.260807 -309.850378)
			(xy 384.308078 -309.86407) (xy 384.35254 -309.885168) (xy 384.393043 -309.913124) (xy 384.428536 -309.947216)
			(xy 384.458101 -309.98656) (xy 384.480972 -310.030137) (xy 384.496556 -310.076818) (xy 384.504451 -310.125395)
			(xy 384.504941 -310.149748) (xy 384.844048 -310.149748) (xy 384.848008 -310.100694) (xy 384.859785 -310.05291)
			(xy 384.879076 -310.007634) (xy 384.905379 -309.966038) (xy 384.938014 -309.929201) (xy 384.976135 -309.898076)
			(xy 385.018756 -309.873469) (xy 385.064772 -309.856017) (xy 385.112991 -309.846173) (xy 385.162166 -309.844192)
			(xy 385.211021 -309.850124) (xy 385.258292 -309.863816) (xy 385.302754 -309.884914) (xy 385.343257 -309.91287)
			(xy 385.37875 -309.946962) (xy 385.408315 -309.986306) (xy 385.431186 -310.029883) (xy 385.44677 -310.076564)
			(xy 385.454665 -310.125141) (xy 385.45516 -310.149748) (xy 385.794008 -310.149748) (xy 385.797968 -310.100694)
			(xy 385.809745 -310.05291) (xy 385.829036 -310.007634) (xy 385.855339 -309.966038) (xy 385.887974 -309.929201)
			(xy 385.926095 -309.898076) (xy 385.968716 -309.873469) (xy 386.014732 -309.856017) (xy 386.062951 -309.846173)
			(xy 386.112126 -309.844192) (xy 386.160981 -309.850124) (xy 386.208252 -309.863816) (xy 386.252714 -309.884914)
			(xy 386.293217 -309.91287) (xy 386.32871 -309.946962) (xy 386.358275 -309.986306) (xy 386.381146 -310.029883)
			(xy 386.39673 -310.076564) (xy 386.404625 -310.125141) (xy 386.40512 -310.149748) (xy 386.744222 -310.149748)
			(xy 386.748182 -310.100694) (xy 386.759959 -310.05291) (xy 386.77925 -310.007634) (xy 386.805553 -309.966038)
			(xy 386.838188 -309.929201) (xy 386.876309 -309.898076) (xy 386.91893 -309.873469) (xy 386.964946 -309.856017)
			(xy 387.013165 -309.846173) (xy 387.06234 -309.844192) (xy 387.111195 -309.850124) (xy 387.158466 -309.863816)
			(xy 387.202928 -309.884914) (xy 387.243431 -309.91287) (xy 387.278924 -309.946962) (xy 387.308489 -309.986306)
			(xy 387.33136 -310.029883) (xy 387.346944 -310.076564) (xy 387.354839 -310.125141) (xy 387.355334 -310.149748)
			(xy 387.694182 -310.149748) (xy 387.698142 -310.100694) (xy 387.709919 -310.05291) (xy 387.72921 -310.007634)
			(xy 387.755513 -309.966038) (xy 387.788148 -309.929201) (xy 387.826269 -309.898076) (xy 387.86889 -309.873469)
			(xy 387.914906 -309.856017) (xy 387.963125 -309.846173) (xy 388.0123 -309.844192) (xy 388.061155 -309.850124)
			(xy 388.108426 -309.863816) (xy 388.152888 -309.884914) (xy 388.193391 -309.91287) (xy 388.228884 -309.946962)
			(xy 388.258449 -309.986306) (xy 388.28132 -310.029883) (xy 388.296904 -310.076564) (xy 388.304799 -310.125141)
			(xy 388.305294 -310.149748) (xy 388.644142 -310.149748) (xy 388.648102 -310.100694) (xy 388.659879 -310.05291)
			(xy 388.67917 -310.007634) (xy 388.705473 -309.966038) (xy 388.738108 -309.929201) (xy 388.776229 -309.898076)
			(xy 388.81885 -309.873469) (xy 388.864866 -309.856017) (xy 388.913085 -309.846173) (xy 388.96226 -309.844192)
			(xy 389.011115 -309.850124) (xy 389.058386 -309.863816) (xy 389.102848 -309.884914) (xy 389.143351 -309.91287)
			(xy 389.178844 -309.946962) (xy 389.208409 -309.986306) (xy 389.23128 -310.029883) (xy 389.246864 -310.076564)
			(xy 389.254759 -310.125141) (xy 389.255254 -310.149748) (xy 389.594102 -310.149748) (xy 389.598062 -310.100694)
			(xy 389.609839 -310.05291) (xy 389.62913 -310.007634) (xy 389.655433 -309.966038) (xy 389.688068 -309.929201)
			(xy 389.726189 -309.898076) (xy 389.76881 -309.873469) (xy 389.814826 -309.856017) (xy 389.863045 -309.846173)
			(xy 389.91222 -309.844192) (xy 389.961075 -309.850124) (xy 390.008346 -309.863816) (xy 390.052808 -309.884914)
			(xy 390.093311 -309.91287) (xy 390.128804 -309.946962) (xy 390.158369 -309.986306) (xy 390.18124 -310.029883)
			(xy 390.196824 -310.076564) (xy 390.204719 -310.125141) (xy 390.205214 -310.149748) (xy 390.544062 -310.149748)
			(xy 390.548022 -310.100694) (xy 390.559799 -310.05291) (xy 390.57909 -310.007634) (xy 390.605393 -309.966038)
			(xy 390.638028 -309.929201) (xy 390.676149 -309.898076) (xy 390.71877 -309.873469) (xy 390.764786 -309.856017)
			(xy 390.813005 -309.846173) (xy 390.86218 -309.844192) (xy 390.911035 -309.850124) (xy 390.958306 -309.863816)
			(xy 391.002768 -309.884914) (xy 391.043271 -309.91287) (xy 391.078764 -309.946962) (xy 391.108329 -309.986306)
			(xy 391.1312 -310.029883) (xy 391.146784 -310.076564) (xy 391.154679 -310.125141) (xy 391.155174 -310.149748)
			(xy 391.494022 -310.149748) (xy 391.497982 -310.100694) (xy 391.509759 -310.05291) (xy 391.52905 -310.007634)
			(xy 391.555353 -309.966038) (xy 391.587988 -309.929201) (xy 391.626109 -309.898076) (xy 391.66873 -309.873469)
			(xy 391.714746 -309.856017) (xy 391.762965 -309.846173) (xy 391.81214 -309.844192) (xy 391.860995 -309.850124)
			(xy 391.908266 -309.863816) (xy 391.952728 -309.884914) (xy 391.993231 -309.91287) (xy 392.028724 -309.946962)
			(xy 392.058289 -309.986306) (xy 392.08116 -310.029883) (xy 392.096744 -310.076564) (xy 392.104639 -310.125141)
			(xy 392.105134 -310.149748) (xy 392.443982 -310.149748) (xy 392.447942 -310.100694) (xy 392.459719 -310.05291)
			(xy 392.47901 -310.007634) (xy 392.505313 -309.966038) (xy 392.537948 -309.929201) (xy 392.576069 -309.898076)
			(xy 392.61869 -309.873469) (xy 392.664706 -309.856017) (xy 392.712925 -309.846173) (xy 392.7621 -309.844192)
			(xy 392.810955 -309.850124) (xy 392.858226 -309.863816) (xy 392.902688 -309.884914) (xy 392.943191 -309.91287)
			(xy 392.978684 -309.946962) (xy 393.008249 -309.986306) (xy 393.03112 -310.029883) (xy 393.046704 -310.076564)
			(xy 393.054599 -310.125141) (xy 393.055094 -310.149748) (xy 393.394196 -310.149748) (xy 393.398156 -310.100694)
			(xy 393.409933 -310.05291) (xy 393.429224 -310.007634) (xy 393.455527 -309.966038) (xy 393.488162 -309.929201)
			(xy 393.526283 -309.898076) (xy 393.568904 -309.873469) (xy 393.61492 -309.856017) (xy 393.663139 -309.846173)
			(xy 393.712314 -309.844192) (xy 393.761169 -309.850124) (xy 393.80844 -309.863816) (xy 393.852902 -309.884914)
			(xy 393.893405 -309.91287) (xy 393.928898 -309.946962) (xy 393.958463 -309.986306) (xy 393.981334 -310.029883)
			(xy 393.996918 -310.076564) (xy 394.004813 -310.125141) (xy 394.005308 -310.149748) (xy 394.344156 -310.149748)
			(xy 394.348116 -310.100694) (xy 394.359893 -310.05291) (xy 394.379184 -310.007634) (xy 394.405487 -309.966038)
			(xy 394.438122 -309.929201) (xy 394.476243 -309.898076) (xy 394.518864 -309.873469) (xy 394.56488 -309.856017)
			(xy 394.613099 -309.846173) (xy 394.662274 -309.844192) (xy 394.711129 -309.850124) (xy 394.7584 -309.863816)
			(xy 394.802862 -309.884914) (xy 394.843365 -309.91287) (xy 394.878858 -309.946962) (xy 394.908423 -309.986306)
			(xy 394.931294 -310.029883) (xy 394.946878 -310.076564) (xy 394.954773 -310.125141) (xy 394.955268 -310.149748)
			(xy 395.294116 -310.149748) (xy 395.298076 -310.100694) (xy 395.309853 -310.05291) (xy 395.329144 -310.007634)
			(xy 395.355447 -309.966038) (xy 395.388082 -309.929201) (xy 395.426203 -309.898076) (xy 395.468824 -309.873469)
			(xy 395.51484 -309.856017) (xy 395.563059 -309.846173) (xy 395.612234 -309.844192) (xy 395.661089 -309.850124)
			(xy 395.70836 -309.863816) (xy 395.752822 -309.884914) (xy 395.793325 -309.91287) (xy 395.828818 -309.946962)
			(xy 395.858383 -309.986306) (xy 395.881254 -310.029883) (xy 395.896838 -310.076564) (xy 395.904733 -310.125141)
			(xy 395.905228 -310.149748) (xy 395.904733 -310.174355) (xy 395.896838 -310.222932) (xy 395.881254 -310.269613)
			(xy 395.858383 -310.31319) (xy 395.828818 -310.352534) (xy 395.793325 -310.386626) (xy 395.752822 -310.414582)
			(xy 395.70836 -310.43568) (xy 395.661089 -310.449372) (xy 395.612234 -310.455304) (xy 395.563059 -310.453323)
			(xy 395.51484 -310.443479) (xy 395.468824 -310.426027) (xy 395.426203 -310.40142) (xy 395.388082 -310.370295)
			(xy 395.355447 -310.333458) (xy 395.329144 -310.291862) (xy 395.309853 -310.246586) (xy 395.298076 -310.198802)
			(xy 395.294116 -310.149748) (xy 394.955268 -310.149748) (xy 394.954773 -310.174355) (xy 394.946878 -310.222932)
			(xy 394.931294 -310.269613) (xy 394.908423 -310.31319) (xy 394.878858 -310.352534) (xy 394.843365 -310.386626)
			(xy 394.802862 -310.414582) (xy 394.7584 -310.43568) (xy 394.711129 -310.449372) (xy 394.662274 -310.455304)
			(xy 394.613099 -310.453323) (xy 394.56488 -310.443479) (xy 394.518864 -310.426027) (xy 394.476243 -310.40142)
			(xy 394.438122 -310.370295) (xy 394.405487 -310.333458) (xy 394.379184 -310.291862) (xy 394.359893 -310.246586)
			(xy 394.348116 -310.198802) (xy 394.344156 -310.149748) (xy 394.005308 -310.149748) (xy 394.004813 -310.174355)
			(xy 393.996918 -310.222932) (xy 393.981334 -310.269613) (xy 393.958463 -310.31319) (xy 393.928898 -310.352534)
			(xy 393.893405 -310.386626) (xy 393.852902 -310.414582) (xy 393.80844 -310.43568) (xy 393.761169 -310.449372)
			(xy 393.712314 -310.455304) (xy 393.663139 -310.453323) (xy 393.61492 -310.443479) (xy 393.568904 -310.426027)
			(xy 393.526283 -310.40142) (xy 393.488162 -310.370295) (xy 393.455527 -310.333458) (xy 393.429224 -310.291862)
			(xy 393.409933 -310.246586) (xy 393.398156 -310.198802) (xy 393.394196 -310.149748) (xy 393.055094 -310.149748)
			(xy 393.054599 -310.174355) (xy 393.046704 -310.222932) (xy 393.03112 -310.269613) (xy 393.008249 -310.31319)
			(xy 392.978684 -310.352534) (xy 392.943191 -310.386626) (xy 392.902688 -310.414582) (xy 392.858226 -310.43568)
			(xy 392.810955 -310.449372) (xy 392.7621 -310.455304) (xy 392.712925 -310.453323) (xy 392.664706 -310.443479)
			(xy 392.61869 -310.426027) (xy 392.576069 -310.40142) (xy 392.537948 -310.370295) (xy 392.505313 -310.333458)
			(xy 392.47901 -310.291862) (xy 392.459719 -310.246586) (xy 392.447942 -310.198802) (xy 392.443982 -310.149748)
			(xy 392.105134 -310.149748) (xy 392.104639 -310.174355) (xy 392.096744 -310.222932) (xy 392.08116 -310.269613)
			(xy 392.058289 -310.31319) (xy 392.028724 -310.352534) (xy 391.993231 -310.386626) (xy 391.952728 -310.414582)
			(xy 391.908266 -310.43568) (xy 391.860995 -310.449372) (xy 391.81214 -310.455304) (xy 391.762965 -310.453323)
			(xy 391.714746 -310.443479) (xy 391.66873 -310.426027) (xy 391.626109 -310.40142) (xy 391.587988 -310.370295)
			(xy 391.555353 -310.333458) (xy 391.52905 -310.291862) (xy 391.509759 -310.246586) (xy 391.497982 -310.198802)
			(xy 391.494022 -310.149748) (xy 391.155174 -310.149748) (xy 391.154679 -310.174355) (xy 391.146784 -310.222932)
			(xy 391.1312 -310.269613) (xy 391.108329 -310.31319) (xy 391.078764 -310.352534) (xy 391.043271 -310.386626)
			(xy 391.002768 -310.414582) (xy 390.958306 -310.43568) (xy 390.911035 -310.449372) (xy 390.86218 -310.455304)
			(xy 390.813005 -310.453323) (xy 390.764786 -310.443479) (xy 390.71877 -310.426027) (xy 390.676149 -310.40142)
			(xy 390.638028 -310.370295) (xy 390.605393 -310.333458) (xy 390.57909 -310.291862) (xy 390.559799 -310.246586)
			(xy 390.548022 -310.198802) (xy 390.544062 -310.149748) (xy 390.205214 -310.149748) (xy 390.204719 -310.174355)
			(xy 390.196824 -310.222932) (xy 390.18124 -310.269613) (xy 390.158369 -310.31319) (xy 390.128804 -310.352534)
			(xy 390.093311 -310.386626) (xy 390.052808 -310.414582) (xy 390.008346 -310.43568) (xy 389.961075 -310.449372)
			(xy 389.91222 -310.455304) (xy 389.863045 -310.453323) (xy 389.814826 -310.443479) (xy 389.76881 -310.426027)
			(xy 389.726189 -310.40142) (xy 389.688068 -310.370295) (xy 389.655433 -310.333458) (xy 389.62913 -310.291862)
			(xy 389.609839 -310.246586) (xy 389.598062 -310.198802) (xy 389.594102 -310.149748) (xy 389.255254 -310.149748)
			(xy 389.254759 -310.174355) (xy 389.246864 -310.222932) (xy 389.23128 -310.269613) (xy 389.208409 -310.31319)
			(xy 389.178844 -310.352534) (xy 389.143351 -310.386626) (xy 389.102848 -310.414582) (xy 389.058386 -310.43568)
			(xy 389.011115 -310.449372) (xy 388.96226 -310.455304) (xy 388.913085 -310.453323) (xy 388.864866 -310.443479)
			(xy 388.81885 -310.426027) (xy 388.776229 -310.40142) (xy 388.738108 -310.370295) (xy 388.705473 -310.333458)
			(xy 388.67917 -310.291862) (xy 388.659879 -310.246586) (xy 388.648102 -310.198802) (xy 388.644142 -310.149748)
			(xy 388.305294 -310.149748) (xy 388.304799 -310.174355) (xy 388.296904 -310.222932) (xy 388.28132 -310.269613)
			(xy 388.258449 -310.31319) (xy 388.228884 -310.352534) (xy 388.193391 -310.386626) (xy 388.152888 -310.414582)
			(xy 388.108426 -310.43568) (xy 388.061155 -310.449372) (xy 388.0123 -310.455304) (xy 387.963125 -310.453323)
			(xy 387.914906 -310.443479) (xy 387.86889 -310.426027) (xy 387.826269 -310.40142) (xy 387.788148 -310.370295)
			(xy 387.755513 -310.333458) (xy 387.72921 -310.291862) (xy 387.709919 -310.246586) (xy 387.698142 -310.198802)
			(xy 387.694182 -310.149748) (xy 387.355334 -310.149748) (xy 387.354839 -310.174355) (xy 387.346944 -310.222932)
			(xy 387.33136 -310.269613) (xy 387.308489 -310.31319) (xy 387.278924 -310.352534) (xy 387.243431 -310.386626)
			(xy 387.202928 -310.414582) (xy 387.158466 -310.43568) (xy 387.111195 -310.449372) (xy 387.06234 -310.455304)
			(xy 387.013165 -310.453323) (xy 386.964946 -310.443479) (xy 386.91893 -310.426027) (xy 386.876309 -310.40142)
			(xy 386.838188 -310.370295) (xy 386.805553 -310.333458) (xy 386.77925 -310.291862) (xy 386.759959 -310.246586)
			(xy 386.748182 -310.198802) (xy 386.744222 -310.149748) (xy 386.40512 -310.149748) (xy 386.404625 -310.174355)
			(xy 386.39673 -310.222932) (xy 386.381146 -310.269613) (xy 386.358275 -310.31319) (xy 386.32871 -310.352534)
			(xy 386.293217 -310.386626) (xy 386.252714 -310.414582) (xy 386.208252 -310.43568) (xy 386.160981 -310.449372)
			(xy 386.112126 -310.455304) (xy 386.062951 -310.453323) (xy 386.014732 -310.443479) (xy 385.968716 -310.426027)
			(xy 385.926095 -310.40142) (xy 385.887974 -310.370295) (xy 385.855339 -310.333458) (xy 385.829036 -310.291862)
			(xy 385.809745 -310.246586) (xy 385.797968 -310.198802) (xy 385.794008 -310.149748) (xy 385.45516 -310.149748)
			(xy 385.454665 -310.174355) (xy 385.44677 -310.222932) (xy 385.431186 -310.269613) (xy 385.408315 -310.31319)
			(xy 385.37875 -310.352534) (xy 385.343257 -310.386626) (xy 385.302754 -310.414582) (xy 385.258292 -310.43568)
			(xy 385.211021 -310.449372) (xy 385.162166 -310.455304) (xy 385.112991 -310.453323) (xy 385.064772 -310.443479)
			(xy 385.018756 -310.426027) (xy 384.976135 -310.40142) (xy 384.938014 -310.370295) (xy 384.905379 -310.333458)
			(xy 384.879076 -310.291862) (xy 384.859785 -310.246586) (xy 384.848008 -310.198802) (xy 384.844048 -310.149748)
			(xy 384.504941 -310.149748) (xy 384.504946 -310.150002) (xy 384.504451 -310.174609) (xy 384.496556 -310.223186)
			(xy 384.480972 -310.269867) (xy 384.458101 -310.313444) (xy 384.428536 -310.352788) (xy 384.393043 -310.38688)
			(xy 384.35254 -310.414836) (xy 384.308078 -310.435934) (xy 384.260807 -310.449626) (xy 384.211952 -310.455558)
			(xy 384.162777 -310.453577) (xy 384.114558 -310.443733) (xy 384.068542 -310.426281) (xy 384.025921 -310.401674)
			(xy 383.9878 -310.370549) (xy 383.955165 -310.333712) (xy 383.928862 -310.292116) (xy 383.909571 -310.24684)
			(xy 383.897794 -310.199056) (xy 383.893834 -310.150002) (xy 383.407541 -310.150002) (xy 383.387573 -310.172288)
			(xy 383.344705 -310.207963) (xy 383.297099 -310.237017) (xy 383.24577 -310.258829) (xy 383.191813 -310.272935)
			(xy 383.136376 -310.279035) (xy 383.080642 -310.276998) (xy 383.025799 -310.266868) (xy 382.973015 -310.248861)
			(xy 382.923415 -310.22336) (xy 382.878057 -310.190909) (xy 382.837908 -310.1522) (xy 382.803822 -310.108057)
			(xy 382.776526 -310.059422) (xy 382.756603 -310.007331) (xy 382.744477 -309.952894) (xy 382.740406 -309.897272)
			(xy 351.03308 -309.897272) (xy 351.03308 -310.832246) (xy 376.567952 -310.832246) (xy 376.572023 -310.776624)
			(xy 376.584149 -310.722187) (xy 376.604072 -310.670096) (xy 376.631368 -310.621461) (xy 376.665454 -310.577318)
			(xy 376.705603 -310.538609) (xy 376.750961 -310.506158) (xy 376.800561 -310.480657) (xy 376.853345 -310.46265)
			(xy 376.908188 -310.45252) (xy 376.963922 -310.450483) (xy 377.019359 -310.456583) (xy 377.073316 -310.470689)
			(xy 377.124645 -310.492501) (xy 377.172251 -310.521555) (xy 377.215119 -310.55723) (xy 377.252336 -310.598767)
			(xy 377.283109 -310.64528) (xy 377.306781 -310.695777) (xy 377.322849 -310.749184) (xy 377.330969 -310.80436)
			(xy 377.331478 -310.832246) (xy 377.330969 -310.860132) (xy 377.322849 -310.915308) (xy 377.306781 -310.968715)
			(xy 377.284667 -311.015888) (xy 382.57175 -311.015888) (xy 382.575821 -310.960266) (xy 382.587947 -310.905829)
			(xy 382.60787 -310.853738) (xy 382.635166 -310.805103) (xy 382.669252 -310.76096) (xy 382.709401 -310.722251)
			(xy 382.754759 -310.6898) (xy 382.804359 -310.664299) (xy 382.857143 -310.646292) (xy 382.911986 -310.636162)
			(xy 382.96772 -310.634125) (xy 383.023157 -310.640225) (xy 383.077114 -310.654331) (xy 383.128443 -310.676143)
			(xy 383.176049 -310.705197) (xy 383.218917 -310.740872) (xy 383.256134 -310.782409) (xy 383.286907 -310.828922)
			(xy 383.310579 -310.879419) (xy 383.326647 -310.932826) (xy 383.334767 -310.988002) (xy 383.335276 -311.015888)
			(xy 383.334767 -311.043774) (xy 383.326647 -311.09895) (xy 383.326343 -311.099962) (xy 384.844048 -311.099962)
			(xy 384.848008 -311.050908) (xy 384.859785 -311.003124) (xy 384.879076 -310.957848) (xy 384.905379 -310.916252)
			(xy 384.938014 -310.879415) (xy 384.976135 -310.84829) (xy 385.018756 -310.823683) (xy 385.064772 -310.806231)
			(xy 385.112991 -310.796387) (xy 385.162166 -310.794406) (xy 385.211021 -310.800338) (xy 385.258292 -310.81403)
			(xy 385.302754 -310.835128) (xy 385.343257 -310.863084) (xy 385.37875 -310.897176) (xy 385.408315 -310.93652)
			(xy 385.431186 -310.980097) (xy 385.44677 -311.026778) (xy 385.454665 -311.075355) (xy 385.45516 -311.099962)
			(xy 385.794008 -311.099962) (xy 385.797968 -311.050908) (xy 385.809745 -311.003124) (xy 385.829036 -310.957848)
			(xy 385.855339 -310.916252) (xy 385.887974 -310.879415) (xy 385.926095 -310.84829) (xy 385.968716 -310.823683)
			(xy 386.014732 -310.806231) (xy 386.062951 -310.796387) (xy 386.112126 -310.794406) (xy 386.160981 -310.800338)
			(xy 386.208252 -310.81403) (xy 386.252714 -310.835128) (xy 386.293217 -310.863084) (xy 386.32871 -310.897176)
			(xy 386.358275 -310.93652) (xy 386.381146 -310.980097) (xy 386.39673 -311.026778) (xy 386.404625 -311.075355)
			(xy 386.40512 -311.099962) (xy 386.744222 -311.099962) (xy 386.748182 -311.050908) (xy 386.759959 -311.003124)
			(xy 386.77925 -310.957848) (xy 386.805553 -310.916252) (xy 386.838188 -310.879415) (xy 386.876309 -310.84829)
			(xy 386.91893 -310.823683) (xy 386.964946 -310.806231) (xy 387.013165 -310.796387) (xy 387.06234 -310.794406)
			(xy 387.111195 -310.800338) (xy 387.158466 -310.81403) (xy 387.202928 -310.835128) (xy 387.243431 -310.863084)
			(xy 387.278924 -310.897176) (xy 387.308489 -310.93652) (xy 387.33136 -310.980097) (xy 387.346944 -311.026778)
			(xy 387.354839 -311.075355) (xy 387.355334 -311.099962) (xy 387.694182 -311.099962) (xy 387.698142 -311.050908)
			(xy 387.709919 -311.003124) (xy 387.72921 -310.957848) (xy 387.755513 -310.916252) (xy 387.788148 -310.879415)
			(xy 387.826269 -310.84829) (xy 387.86889 -310.823683) (xy 387.914906 -310.806231) (xy 387.963125 -310.796387)
			(xy 388.0123 -310.794406) (xy 388.061155 -310.800338) (xy 388.108426 -310.81403) (xy 388.152888 -310.835128)
			(xy 388.193391 -310.863084) (xy 388.228884 -310.897176) (xy 388.258449 -310.93652) (xy 388.28132 -310.980097)
			(xy 388.296904 -311.026778) (xy 388.304799 -311.075355) (xy 388.305294 -311.099962) (xy 388.644142 -311.099962)
			(xy 388.648102 -311.050908) (xy 388.659879 -311.003124) (xy 388.67917 -310.957848) (xy 388.705473 -310.916252)
			(xy 388.738108 -310.879415) (xy 388.776229 -310.84829) (xy 388.81885 -310.823683) (xy 388.864866 -310.806231)
			(xy 388.913085 -310.796387) (xy 388.96226 -310.794406) (xy 389.011115 -310.800338) (xy 389.058386 -310.81403)
			(xy 389.102848 -310.835128) (xy 389.143351 -310.863084) (xy 389.178844 -310.897176) (xy 389.208409 -310.93652)
			(xy 389.23128 -310.980097) (xy 389.246864 -311.026778) (xy 389.254759 -311.075355) (xy 389.255254 -311.099962)
			(xy 389.594102 -311.099962) (xy 389.598062 -311.050908) (xy 389.609839 -311.003124) (xy 389.62913 -310.957848)
			(xy 389.655433 -310.916252) (xy 389.688068 -310.879415) (xy 389.726189 -310.84829) (xy 389.76881 -310.823683)
			(xy 389.814826 -310.806231) (xy 389.863045 -310.796387) (xy 389.91222 -310.794406) (xy 389.961075 -310.800338)
			(xy 390.008346 -310.81403) (xy 390.052808 -310.835128) (xy 390.093311 -310.863084) (xy 390.128804 -310.897176)
			(xy 390.158369 -310.93652) (xy 390.18124 -310.980097) (xy 390.196824 -311.026778) (xy 390.204719 -311.075355)
			(xy 390.205214 -311.099962) (xy 390.544062 -311.099962) (xy 390.548022 -311.050908) (xy 390.559799 -311.003124)
			(xy 390.57909 -310.957848) (xy 390.605393 -310.916252) (xy 390.638028 -310.879415) (xy 390.676149 -310.84829)
			(xy 390.71877 -310.823683) (xy 390.764786 -310.806231) (xy 390.813005 -310.796387) (xy 390.86218 -310.794406)
			(xy 390.911035 -310.800338) (xy 390.958306 -310.81403) (xy 391.002768 -310.835128) (xy 391.043271 -310.863084)
			(xy 391.078764 -310.897176) (xy 391.108329 -310.93652) (xy 391.1312 -310.980097) (xy 391.146784 -311.026778)
			(xy 391.154679 -311.075355) (xy 391.155174 -311.099962) (xy 391.494022 -311.099962) (xy 391.497982 -311.050908)
			(xy 391.509759 -311.003124) (xy 391.52905 -310.957848) (xy 391.555353 -310.916252) (xy 391.587988 -310.879415)
			(xy 391.626109 -310.84829) (xy 391.66873 -310.823683) (xy 391.714746 -310.806231) (xy 391.762965 -310.796387)
			(xy 391.81214 -310.794406) (xy 391.860995 -310.800338) (xy 391.908266 -310.81403) (xy 391.952728 -310.835128)
			(xy 391.993231 -310.863084) (xy 392.028724 -310.897176) (xy 392.058289 -310.93652) (xy 392.08116 -310.980097)
			(xy 392.096744 -311.026778) (xy 392.104639 -311.075355) (xy 392.105134 -311.099962) (xy 392.443982 -311.099962)
			(xy 392.447942 -311.050908) (xy 392.459719 -311.003124) (xy 392.47901 -310.957848) (xy 392.505313 -310.916252)
			(xy 392.537948 -310.879415) (xy 392.576069 -310.84829) (xy 392.61869 -310.823683) (xy 392.664706 -310.806231)
			(xy 392.712925 -310.796387) (xy 392.7621 -310.794406) (xy 392.810955 -310.800338) (xy 392.858226 -310.81403)
			(xy 392.902688 -310.835128) (xy 392.943191 -310.863084) (xy 392.978684 -310.897176) (xy 393.008249 -310.93652)
			(xy 393.03112 -310.980097) (xy 393.046704 -311.026778) (xy 393.054599 -311.075355) (xy 393.055094 -311.099962)
			(xy 393.394196 -311.099962) (xy 393.398156 -311.050908) (xy 393.409933 -311.003124) (xy 393.429224 -310.957848)
			(xy 393.455527 -310.916252) (xy 393.488162 -310.879415) (xy 393.526283 -310.84829) (xy 393.568904 -310.823683)
			(xy 393.61492 -310.806231) (xy 393.663139 -310.796387) (xy 393.712314 -310.794406) (xy 393.761169 -310.800338)
			(xy 393.80844 -310.81403) (xy 393.852902 -310.835128) (xy 393.893405 -310.863084) (xy 393.928898 -310.897176)
			(xy 393.958463 -310.93652) (xy 393.981334 -310.980097) (xy 393.996918 -311.026778) (xy 394.004813 -311.075355)
			(xy 394.005308 -311.099962) (xy 394.344156 -311.099962) (xy 394.348116 -311.050908) (xy 394.359893 -311.003124)
			(xy 394.379184 -310.957848) (xy 394.405487 -310.916252) (xy 394.438122 -310.879415) (xy 394.476243 -310.84829)
			(xy 394.518864 -310.823683) (xy 394.56488 -310.806231) (xy 394.613099 -310.796387) (xy 394.662274 -310.794406)
			(xy 394.711129 -310.800338) (xy 394.7584 -310.81403) (xy 394.802862 -310.835128) (xy 394.843365 -310.863084)
			(xy 394.878858 -310.897176) (xy 394.908423 -310.93652) (xy 394.931294 -310.980097) (xy 394.946878 -311.026778)
			(xy 394.954773 -311.075355) (xy 394.955268 -311.099962) (xy 395.294116 -311.099962) (xy 395.298076 -311.050908)
			(xy 395.309853 -311.003124) (xy 395.329144 -310.957848) (xy 395.355447 -310.916252) (xy 395.388082 -310.879415)
			(xy 395.426203 -310.84829) (xy 395.468824 -310.823683) (xy 395.51484 -310.806231) (xy 395.563059 -310.796387)
			(xy 395.612234 -310.794406) (xy 395.661089 -310.800338) (xy 395.70836 -310.81403) (xy 395.752822 -310.835128)
			(xy 395.793325 -310.863084) (xy 395.828818 -310.897176) (xy 395.858383 -310.93652) (xy 395.881254 -310.980097)
			(xy 395.896838 -311.026778) (xy 395.904733 -311.075355) (xy 395.905228 -311.099962) (xy 395.904733 -311.124569)
			(xy 395.896838 -311.173146) (xy 395.881254 -311.219827) (xy 395.858383 -311.263404) (xy 395.828818 -311.302748)
			(xy 395.793325 -311.33684) (xy 395.752822 -311.364796) (xy 395.70836 -311.385894) (xy 395.661089 -311.399586)
			(xy 395.612234 -311.405518) (xy 395.563059 -311.403537) (xy 395.51484 -311.393693) (xy 395.468824 -311.376241)
			(xy 395.426203 -311.351634) (xy 395.388082 -311.320509) (xy 395.355447 -311.283672) (xy 395.329144 -311.242076)
			(xy 395.309853 -311.1968) (xy 395.298076 -311.149016) (xy 395.294116 -311.099962) (xy 394.955268 -311.099962)
			(xy 394.954773 -311.124569) (xy 394.946878 -311.173146) (xy 394.931294 -311.219827) (xy 394.908423 -311.263404)
			(xy 394.878858 -311.302748) (xy 394.843365 -311.33684) (xy 394.802862 -311.364796) (xy 394.7584 -311.385894)
			(xy 394.711129 -311.399586) (xy 394.662274 -311.405518) (xy 394.613099 -311.403537) (xy 394.56488 -311.393693)
			(xy 394.518864 -311.376241) (xy 394.476243 -311.351634) (xy 394.438122 -311.320509) (xy 394.405487 -311.283672)
			(xy 394.379184 -311.242076) (xy 394.359893 -311.1968) (xy 394.348116 -311.149016) (xy 394.344156 -311.099962)
			(xy 394.005308 -311.099962) (xy 394.004813 -311.124569) (xy 393.996918 -311.173146) (xy 393.981334 -311.219827)
			(xy 393.958463 -311.263404) (xy 393.928898 -311.302748) (xy 393.893405 -311.33684) (xy 393.852902 -311.364796)
			(xy 393.80844 -311.385894) (xy 393.761169 -311.399586) (xy 393.712314 -311.405518) (xy 393.663139 -311.403537)
			(xy 393.61492 -311.393693) (xy 393.568904 -311.376241) (xy 393.526283 -311.351634) (xy 393.488162 -311.320509)
			(xy 393.455527 -311.283672) (xy 393.429224 -311.242076) (xy 393.409933 -311.1968) (xy 393.398156 -311.149016)
			(xy 393.394196 -311.099962) (xy 393.055094 -311.099962) (xy 393.054599 -311.124569) (xy 393.046704 -311.173146)
			(xy 393.03112 -311.219827) (xy 393.008249 -311.263404) (xy 392.978684 -311.302748) (xy 392.943191 -311.33684)
			(xy 392.902688 -311.364796) (xy 392.858226 -311.385894) (xy 392.810955 -311.399586) (xy 392.7621 -311.405518)
			(xy 392.712925 -311.403537) (xy 392.664706 -311.393693) (xy 392.61869 -311.376241) (xy 392.576069 -311.351634)
			(xy 392.537948 -311.320509) (xy 392.505313 -311.283672) (xy 392.47901 -311.242076) (xy 392.459719 -311.1968)
			(xy 392.447942 -311.149016) (xy 392.443982 -311.099962) (xy 392.105134 -311.099962) (xy 392.104639 -311.124569)
			(xy 392.096744 -311.173146) (xy 392.08116 -311.219827) (xy 392.058289 -311.263404) (xy 392.028724 -311.302748)
			(xy 391.993231 -311.33684) (xy 391.952728 -311.364796) (xy 391.908266 -311.385894) (xy 391.860995 -311.399586)
			(xy 391.81214 -311.405518) (xy 391.762965 -311.403537) (xy 391.714746 -311.393693) (xy 391.66873 -311.376241)
			(xy 391.626109 -311.351634) (xy 391.587988 -311.320509) (xy 391.555353 -311.283672) (xy 391.52905 -311.242076)
			(xy 391.509759 -311.1968) (xy 391.497982 -311.149016) (xy 391.494022 -311.099962) (xy 391.155174 -311.099962)
			(xy 391.154679 -311.124569) (xy 391.146784 -311.173146) (xy 391.1312 -311.219827) (xy 391.108329 -311.263404)
			(xy 391.078764 -311.302748) (xy 391.043271 -311.33684) (xy 391.002768 -311.364796) (xy 390.958306 -311.385894)
			(xy 390.911035 -311.399586) (xy 390.86218 -311.405518) (xy 390.813005 -311.403537) (xy 390.764786 -311.393693)
			(xy 390.71877 -311.376241) (xy 390.676149 -311.351634) (xy 390.638028 -311.320509) (xy 390.605393 -311.283672)
			(xy 390.57909 -311.242076) (xy 390.559799 -311.1968) (xy 390.548022 -311.149016) (xy 390.544062 -311.099962)
			(xy 390.205214 -311.099962) (xy 390.204719 -311.124569) (xy 390.196824 -311.173146) (xy 390.18124 -311.219827)
			(xy 390.158369 -311.263404) (xy 390.128804 -311.302748) (xy 390.093311 -311.33684) (xy 390.052808 -311.364796)
			(xy 390.008346 -311.385894) (xy 389.961075 -311.399586) (xy 389.91222 -311.405518) (xy 389.863045 -311.403537)
			(xy 389.814826 -311.393693) (xy 389.76881 -311.376241) (xy 389.726189 -311.351634) (xy 389.688068 -311.320509)
			(xy 389.655433 -311.283672) (xy 389.62913 -311.242076) (xy 389.609839 -311.1968) (xy 389.598062 -311.149016)
			(xy 389.594102 -311.099962) (xy 389.255254 -311.099962) (xy 389.254759 -311.124569) (xy 389.246864 -311.173146)
			(xy 389.23128 -311.219827) (xy 389.208409 -311.263404) (xy 389.178844 -311.302748) (xy 389.143351 -311.33684)
			(xy 389.102848 -311.364796) (xy 389.058386 -311.385894) (xy 389.011115 -311.399586) (xy 388.96226 -311.405518)
			(xy 388.913085 -311.403537) (xy 388.864866 -311.393693) (xy 388.81885 -311.376241) (xy 388.776229 -311.351634)
			(xy 388.738108 -311.320509) (xy 388.705473 -311.283672) (xy 388.67917 -311.242076) (xy 388.659879 -311.1968)
			(xy 388.648102 -311.149016) (xy 388.644142 -311.099962) (xy 388.305294 -311.099962) (xy 388.304799 -311.124569)
			(xy 388.296904 -311.173146) (xy 388.28132 -311.219827) (xy 388.258449 -311.263404) (xy 388.228884 -311.302748)
			(xy 388.193391 -311.33684) (xy 388.152888 -311.364796) (xy 388.108426 -311.385894) (xy 388.061155 -311.399586)
			(xy 388.0123 -311.405518) (xy 387.963125 -311.403537) (xy 387.914906 -311.393693) (xy 387.86889 -311.376241)
			(xy 387.826269 -311.351634) (xy 387.788148 -311.320509) (xy 387.755513 -311.283672) (xy 387.72921 -311.242076)
			(xy 387.709919 -311.1968) (xy 387.698142 -311.149016) (xy 387.694182 -311.099962) (xy 387.355334 -311.099962)
			(xy 387.354839 -311.124569) (xy 387.346944 -311.173146) (xy 387.33136 -311.219827) (xy 387.308489 -311.263404)
			(xy 387.278924 -311.302748) (xy 387.243431 -311.33684) (xy 387.202928 -311.364796) (xy 387.158466 -311.385894)
			(xy 387.111195 -311.399586) (xy 387.06234 -311.405518) (xy 387.013165 -311.403537) (xy 386.964946 -311.393693)
			(xy 386.91893 -311.376241) (xy 386.876309 -311.351634) (xy 386.838188 -311.320509) (xy 386.805553 -311.283672)
			(xy 386.77925 -311.242076) (xy 386.759959 -311.1968) (xy 386.748182 -311.149016) (xy 386.744222 -311.099962)
			(xy 386.40512 -311.099962) (xy 386.404625 -311.124569) (xy 386.39673 -311.173146) (xy 386.381146 -311.219827)
			(xy 386.358275 -311.263404) (xy 386.32871 -311.302748) (xy 386.293217 -311.33684) (xy 386.252714 -311.364796)
			(xy 386.208252 -311.385894) (xy 386.160981 -311.399586) (xy 386.112126 -311.405518) (xy 386.062951 -311.403537)
			(xy 386.014732 -311.393693) (xy 385.968716 -311.376241) (xy 385.926095 -311.351634) (xy 385.887974 -311.320509)
			(xy 385.855339 -311.283672) (xy 385.829036 -311.242076) (xy 385.809745 -311.1968) (xy 385.797968 -311.149016)
			(xy 385.794008 -311.099962) (xy 385.45516 -311.099962) (xy 385.454665 -311.124569) (xy 385.44677 -311.173146)
			(xy 385.431186 -311.219827) (xy 385.408315 -311.263404) (xy 385.37875 -311.302748) (xy 385.343257 -311.33684)
			(xy 385.302754 -311.364796) (xy 385.258292 -311.385894) (xy 385.211021 -311.399586) (xy 385.162166 -311.405518)
			(xy 385.112991 -311.403537) (xy 385.064772 -311.393693) (xy 385.018756 -311.376241) (xy 384.976135 -311.351634)
			(xy 384.938014 -311.320509) (xy 384.905379 -311.283672) (xy 384.879076 -311.242076) (xy 384.859785 -311.1968)
			(xy 384.848008 -311.149016) (xy 384.844048 -311.099962) (xy 383.326343 -311.099962) (xy 383.310579 -311.152357)
			(xy 383.286907 -311.202854) (xy 383.256134 -311.249367) (xy 383.218917 -311.290904) (xy 383.176049 -311.326579)
			(xy 383.128443 -311.355633) (xy 383.077114 -311.377445) (xy 383.023157 -311.391551) (xy 382.96772 -311.397651)
			(xy 382.911986 -311.395614) (xy 382.857143 -311.385484) (xy 382.804359 -311.367477) (xy 382.754759 -311.341976)
			(xy 382.709401 -311.309525) (xy 382.669252 -311.270816) (xy 382.635166 -311.226673) (xy 382.60787 -311.178038)
			(xy 382.587947 -311.125947) (xy 382.575821 -311.07151) (xy 382.57175 -311.015888) (xy 377.284667 -311.015888)
			(xy 377.283109 -311.019212) (xy 377.252336 -311.065725) (xy 377.215119 -311.107262) (xy 377.172251 -311.142937)
			(xy 377.124645 -311.171991) (xy 377.073316 -311.193803) (xy 377.019359 -311.207909) (xy 376.963922 -311.214009)
			(xy 376.908188 -311.211972) (xy 376.853345 -311.201842) (xy 376.800561 -311.183835) (xy 376.750961 -311.158334)
			(xy 376.705603 -311.125883) (xy 376.665454 -311.087174) (xy 376.631368 -311.043031) (xy 376.604072 -310.994396)
			(xy 376.584149 -310.942305) (xy 376.572023 -310.887868) (xy 376.567952 -310.832246) (xy 351.03308 -310.832246)
			(xy 351.03308 -311.7342) (xy 380.789432 -311.7342) (xy 380.793503 -311.678578) (xy 380.805629 -311.624141)
			(xy 380.825552 -311.57205) (xy 380.852848 -311.523415) (xy 380.886934 -311.479272) (xy 380.927083 -311.440563)
			(xy 380.972441 -311.408112) (xy 381.022041 -311.382611) (xy 381.074825 -311.364604) (xy 381.129668 -311.354474)
			(xy 381.185402 -311.352437) (xy 381.240839 -311.358537) (xy 381.294796 -311.372643) (xy 381.346125 -311.394455)
			(xy 381.393731 -311.423509) (xy 381.436599 -311.459184) (xy 381.473816 -311.500721) (xy 381.504589 -311.547234)
			(xy 381.528261 -311.597731) (xy 381.544329 -311.651138) (xy 381.552449 -311.706314) (xy 381.552958 -311.7342)
			(xy 381.552449 -311.762086) (xy 381.544329 -311.817262) (xy 381.528261 -311.870669) (xy 381.504589 -311.921166)
			(xy 381.473816 -311.967679) (xy 381.436599 -312.009216) (xy 381.393731 -312.044891) (xy 381.346125 -312.073945)
			(xy 381.294796 -312.095757) (xy 381.240839 -312.109863) (xy 381.185402 -312.115963) (xy 381.129668 -312.113926)
			(xy 381.074825 -312.103796) (xy 381.022041 -312.085789) (xy 380.972441 -312.060288) (xy 380.927083 -312.027837)
			(xy 380.886934 -311.989128) (xy 380.852848 -311.944985) (xy 380.825552 -311.89635) (xy 380.805629 -311.844259)
			(xy 380.793503 -311.789822) (xy 380.789432 -311.7342) (xy 351.03308 -311.7342) (xy 351.03308 -312.523378)
			(xy 380.032004 -312.523378) (xy 380.036075 -312.467756) (xy 380.048201 -312.413319) (xy 380.068124 -312.361228)
			(xy 380.09542 -312.312593) (xy 380.129506 -312.26845) (xy 380.169655 -312.229741) (xy 380.215013 -312.19729)
			(xy 380.264613 -312.171789) (xy 380.317397 -312.153782) (xy 380.37224 -312.143652) (xy 380.427974 -312.141615)
			(xy 380.483411 -312.147715) (xy 380.537368 -312.161821) (xy 380.588697 -312.183633) (xy 380.636303 -312.212687)
			(xy 380.679171 -312.248362) (xy 380.696863 -312.268108) (xy 382.410714 -312.268108) (xy 382.414785 -312.212486)
			(xy 382.426911 -312.158049) (xy 382.446834 -312.105958) (xy 382.47413 -312.057323) (xy 382.508216 -312.01318)
			(xy 382.548365 -311.974471) (xy 382.593723 -311.94202) (xy 382.643323 -311.916519) (xy 382.696107 -311.898512)
			(xy 382.75095 -311.888382) (xy 382.806684 -311.886345) (xy 382.862121 -311.892445) (xy 382.916078 -311.906551)
			(xy 382.967407 -311.928363) (xy 383.015013 -311.957417) (xy 383.057881 -311.993092) (xy 383.095098 -312.034629)
			(xy 383.105048 -312.049668) (xy 383.893834 -312.049668) (xy 383.897794 -312.000614) (xy 383.909571 -311.95283)
			(xy 383.928862 -311.907554) (xy 383.955165 -311.865958) (xy 383.9878 -311.829121) (xy 384.025921 -311.797996)
			(xy 384.068542 -311.773389) (xy 384.114558 -311.755937) (xy 384.162777 -311.746093) (xy 384.211952 -311.744112)
			(xy 384.260807 -311.750044) (xy 384.308078 -311.763736) (xy 384.35254 -311.784834) (xy 384.393043 -311.81279)
			(xy 384.428536 -311.846882) (xy 384.458101 -311.886226) (xy 384.480972 -311.929803) (xy 384.496556 -311.976484)
			(xy 384.504451 -312.025061) (xy 384.504946 -312.049668) (xy 384.504941 -312.049922) (xy 384.844048 -312.049922)
			(xy 384.848008 -312.000868) (xy 384.859785 -311.953084) (xy 384.879076 -311.907808) (xy 384.905379 -311.866212)
			(xy 384.938014 -311.829375) (xy 384.976135 -311.79825) (xy 385.018756 -311.773643) (xy 385.064772 -311.756191)
			(xy 385.112991 -311.746347) (xy 385.162166 -311.744366) (xy 385.211021 -311.750298) (xy 385.258292 -311.76399)
			(xy 385.302754 -311.785088) (xy 385.343257 -311.813044) (xy 385.37875 -311.847136) (xy 385.408315 -311.88648)
			(xy 385.431186 -311.930057) (xy 385.44677 -311.976738) (xy 385.454665 -312.025315) (xy 385.45516 -312.049922)
			(xy 385.794008 -312.049922) (xy 385.797968 -312.000868) (xy 385.809745 -311.953084) (xy 385.829036 -311.907808)
			(xy 385.855339 -311.866212) (xy 385.887974 -311.829375) (xy 385.926095 -311.79825) (xy 385.968716 -311.773643)
			(xy 386.014732 -311.756191) (xy 386.062951 -311.746347) (xy 386.112126 -311.744366) (xy 386.160981 -311.750298)
			(xy 386.208252 -311.76399) (xy 386.252714 -311.785088) (xy 386.293217 -311.813044) (xy 386.32871 -311.847136)
			(xy 386.358275 -311.88648) (xy 386.381146 -311.930057) (xy 386.39673 -311.976738) (xy 386.404625 -312.025315)
			(xy 386.40512 -312.049922) (xy 386.744222 -312.049922) (xy 386.748182 -312.000868) (xy 386.759959 -311.953084)
			(xy 386.77925 -311.907808) (xy 386.805553 -311.866212) (xy 386.838188 -311.829375) (xy 386.876309 -311.79825)
			(xy 386.91893 -311.773643) (xy 386.964946 -311.756191) (xy 387.013165 -311.746347) (xy 387.06234 -311.744366)
			(xy 387.111195 -311.750298) (xy 387.158466 -311.76399) (xy 387.202928 -311.785088) (xy 387.243431 -311.813044)
			(xy 387.278924 -311.847136) (xy 387.308489 -311.88648) (xy 387.33136 -311.930057) (xy 387.346944 -311.976738)
			(xy 387.354839 -312.025315) (xy 387.355334 -312.049922) (xy 387.694182 -312.049922) (xy 387.698142 -312.000868)
			(xy 387.709919 -311.953084) (xy 387.72921 -311.907808) (xy 387.755513 -311.866212) (xy 387.788148 -311.829375)
			(xy 387.826269 -311.79825) (xy 387.86889 -311.773643) (xy 387.914906 -311.756191) (xy 387.963125 -311.746347)
			(xy 388.0123 -311.744366) (xy 388.061155 -311.750298) (xy 388.108426 -311.76399) (xy 388.152888 -311.785088)
			(xy 388.193391 -311.813044) (xy 388.228884 -311.847136) (xy 388.258449 -311.88648) (xy 388.28132 -311.930057)
			(xy 388.296904 -311.976738) (xy 388.304799 -312.025315) (xy 388.305294 -312.049922) (xy 388.644142 -312.049922)
			(xy 388.648102 -312.000868) (xy 388.659879 -311.953084) (xy 388.67917 -311.907808) (xy 388.705473 -311.866212)
			(xy 388.738108 -311.829375) (xy 388.776229 -311.79825) (xy 388.81885 -311.773643) (xy 388.864866 -311.756191)
			(xy 388.913085 -311.746347) (xy 388.96226 -311.744366) (xy 389.011115 -311.750298) (xy 389.058386 -311.76399)
			(xy 389.102848 -311.785088) (xy 389.143351 -311.813044) (xy 389.178844 -311.847136) (xy 389.208409 -311.88648)
			(xy 389.23128 -311.930057) (xy 389.246864 -311.976738) (xy 389.254759 -312.025315) (xy 389.255254 -312.049922)
			(xy 389.594102 -312.049922) (xy 389.598062 -312.000868) (xy 389.609839 -311.953084) (xy 389.62913 -311.907808)
			(xy 389.655433 -311.866212) (xy 389.688068 -311.829375) (xy 389.726189 -311.79825) (xy 389.76881 -311.773643)
			(xy 389.814826 -311.756191) (xy 389.863045 -311.746347) (xy 389.91222 -311.744366) (xy 389.961075 -311.750298)
			(xy 390.008346 -311.76399) (xy 390.052808 -311.785088) (xy 390.093311 -311.813044) (xy 390.128804 -311.847136)
			(xy 390.158369 -311.88648) (xy 390.18124 -311.930057) (xy 390.196824 -311.976738) (xy 390.204719 -312.025315)
			(xy 390.205214 -312.049922) (xy 390.544062 -312.049922) (xy 390.548022 -312.000868) (xy 390.559799 -311.953084)
			(xy 390.57909 -311.907808) (xy 390.605393 -311.866212) (xy 390.638028 -311.829375) (xy 390.676149 -311.79825)
			(xy 390.71877 -311.773643) (xy 390.764786 -311.756191) (xy 390.813005 -311.746347) (xy 390.86218 -311.744366)
			(xy 390.911035 -311.750298) (xy 390.958306 -311.76399) (xy 391.002768 -311.785088) (xy 391.043271 -311.813044)
			(xy 391.078764 -311.847136) (xy 391.108329 -311.88648) (xy 391.1312 -311.930057) (xy 391.146784 -311.976738)
			(xy 391.154679 -312.025315) (xy 391.155174 -312.049922) (xy 391.494022 -312.049922) (xy 391.497982 -312.000868)
			(xy 391.509759 -311.953084) (xy 391.52905 -311.907808) (xy 391.555353 -311.866212) (xy 391.587988 -311.829375)
			(xy 391.626109 -311.79825) (xy 391.66873 -311.773643) (xy 391.714746 -311.756191) (xy 391.762965 -311.746347)
			(xy 391.81214 -311.744366) (xy 391.860995 -311.750298) (xy 391.908266 -311.76399) (xy 391.952728 -311.785088)
			(xy 391.993231 -311.813044) (xy 392.028724 -311.847136) (xy 392.058289 -311.88648) (xy 392.08116 -311.930057)
			(xy 392.096744 -311.976738) (xy 392.104639 -312.025315) (xy 392.105134 -312.049922) (xy 392.443982 -312.049922)
			(xy 392.447942 -312.000868) (xy 392.459719 -311.953084) (xy 392.47901 -311.907808) (xy 392.505313 -311.866212)
			(xy 392.537948 -311.829375) (xy 392.576069 -311.79825) (xy 392.61869 -311.773643) (xy 392.664706 -311.756191)
			(xy 392.712925 -311.746347) (xy 392.7621 -311.744366) (xy 392.810955 -311.750298) (xy 392.858226 -311.76399)
			(xy 392.902688 -311.785088) (xy 392.943191 -311.813044) (xy 392.978684 -311.847136) (xy 393.008249 -311.88648)
			(xy 393.03112 -311.930057) (xy 393.046704 -311.976738) (xy 393.054599 -312.025315) (xy 393.055094 -312.049922)
			(xy 393.394196 -312.049922) (xy 393.398156 -312.000868) (xy 393.409933 -311.953084) (xy 393.429224 -311.907808)
			(xy 393.455527 -311.866212) (xy 393.488162 -311.829375) (xy 393.526283 -311.79825) (xy 393.568904 -311.773643)
			(xy 393.61492 -311.756191) (xy 393.663139 -311.746347) (xy 393.712314 -311.744366) (xy 393.761169 -311.750298)
			(xy 393.80844 -311.76399) (xy 393.852902 -311.785088) (xy 393.893405 -311.813044) (xy 393.928898 -311.847136)
			(xy 393.958463 -311.88648) (xy 393.981334 -311.930057) (xy 393.996918 -311.976738) (xy 394.004813 -312.025315)
			(xy 394.005308 -312.049922) (xy 394.344156 -312.049922) (xy 394.348116 -312.000868) (xy 394.359893 -311.953084)
			(xy 394.379184 -311.907808) (xy 394.405487 -311.866212) (xy 394.438122 -311.829375) (xy 394.476243 -311.79825)
			(xy 394.518864 -311.773643) (xy 394.56488 -311.756191) (xy 394.613099 -311.746347) (xy 394.662274 -311.744366)
			(xy 394.711129 -311.750298) (xy 394.7584 -311.76399) (xy 394.802862 -311.785088) (xy 394.843365 -311.813044)
			(xy 394.878858 -311.847136) (xy 394.908423 -311.88648) (xy 394.931294 -311.930057) (xy 394.946878 -311.976738)
			(xy 394.954773 -312.025315) (xy 394.955268 -312.049922) (xy 395.294116 -312.049922) (xy 395.298076 -312.000868)
			(xy 395.309853 -311.953084) (xy 395.329144 -311.907808) (xy 395.355447 -311.866212) (xy 395.388082 -311.829375)
			(xy 395.426203 -311.79825) (xy 395.468824 -311.773643) (xy 395.51484 -311.756191) (xy 395.563059 -311.746347)
			(xy 395.612234 -311.744366) (xy 395.661089 -311.750298) (xy 395.70836 -311.76399) (xy 395.752822 -311.785088)
			(xy 395.793325 -311.813044) (xy 395.828818 -311.847136) (xy 395.858383 -311.88648) (xy 395.881254 -311.930057)
			(xy 395.896838 -311.976738) (xy 395.904733 -312.025315) (xy 395.905228 -312.049922) (xy 395.904733 -312.074529)
			(xy 395.896838 -312.123106) (xy 395.881254 -312.169787) (xy 395.858383 -312.213364) (xy 395.828818 -312.252708)
			(xy 395.793325 -312.2868) (xy 395.752822 -312.314756) (xy 395.70836 -312.335854) (xy 395.661089 -312.349546)
			(xy 395.612234 -312.355478) (xy 395.563059 -312.353497) (xy 395.51484 -312.343653) (xy 395.468824 -312.326201)
			(xy 395.426203 -312.301594) (xy 395.388082 -312.270469) (xy 395.355447 -312.233632) (xy 395.329144 -312.192036)
			(xy 395.309853 -312.14676) (xy 395.298076 -312.098976) (xy 395.294116 -312.049922) (xy 394.955268 -312.049922)
			(xy 394.954773 -312.074529) (xy 394.946878 -312.123106) (xy 394.931294 -312.169787) (xy 394.908423 -312.213364)
			(xy 394.878858 -312.252708) (xy 394.843365 -312.2868) (xy 394.802862 -312.314756) (xy 394.7584 -312.335854)
			(xy 394.711129 -312.349546) (xy 394.662274 -312.355478) (xy 394.613099 -312.353497) (xy 394.56488 -312.343653)
			(xy 394.518864 -312.326201) (xy 394.476243 -312.301594) (xy 394.438122 -312.270469) (xy 394.405487 -312.233632)
			(xy 394.379184 -312.192036) (xy 394.359893 -312.14676) (xy 394.348116 -312.098976) (xy 394.344156 -312.049922)
			(xy 394.005308 -312.049922) (xy 394.004813 -312.074529) (xy 393.996918 -312.123106) (xy 393.981334 -312.169787)
			(xy 393.958463 -312.213364) (xy 393.928898 -312.252708) (xy 393.893405 -312.2868) (xy 393.852902 -312.314756)
			(xy 393.80844 -312.335854) (xy 393.761169 -312.349546) (xy 393.712314 -312.355478) (xy 393.663139 -312.353497)
			(xy 393.61492 -312.343653) (xy 393.568904 -312.326201) (xy 393.526283 -312.301594) (xy 393.488162 -312.270469)
			(xy 393.455527 -312.233632) (xy 393.429224 -312.192036) (xy 393.409933 -312.14676) (xy 393.398156 -312.098976)
			(xy 393.394196 -312.049922) (xy 393.055094 -312.049922) (xy 393.054599 -312.074529) (xy 393.046704 -312.123106)
			(xy 393.03112 -312.169787) (xy 393.008249 -312.213364) (xy 392.978684 -312.252708) (xy 392.943191 -312.2868)
			(xy 392.902688 -312.314756) (xy 392.858226 -312.335854) (xy 392.810955 -312.349546) (xy 392.7621 -312.355478)
			(xy 392.712925 -312.353497) (xy 392.664706 -312.343653) (xy 392.61869 -312.326201) (xy 392.576069 -312.301594)
			(xy 392.537948 -312.270469) (xy 392.505313 -312.233632) (xy 392.47901 -312.192036) (xy 392.459719 -312.14676)
			(xy 392.447942 -312.098976) (xy 392.443982 -312.049922) (xy 392.105134 -312.049922) (xy 392.104639 -312.074529)
			(xy 392.096744 -312.123106) (xy 392.08116 -312.169787) (xy 392.058289 -312.213364) (xy 392.028724 -312.252708)
			(xy 391.993231 -312.2868) (xy 391.952728 -312.314756) (xy 391.908266 -312.335854) (xy 391.860995 -312.349546)
			(xy 391.81214 -312.355478) (xy 391.762965 -312.353497) (xy 391.714746 -312.343653) (xy 391.66873 -312.326201)
			(xy 391.626109 -312.301594) (xy 391.587988 -312.270469) (xy 391.555353 -312.233632) (xy 391.52905 -312.192036)
			(xy 391.509759 -312.14676) (xy 391.497982 -312.098976) (xy 391.494022 -312.049922) (xy 391.155174 -312.049922)
			(xy 391.154679 -312.074529) (xy 391.146784 -312.123106) (xy 391.1312 -312.169787) (xy 391.108329 -312.213364)
			(xy 391.078764 -312.252708) (xy 391.043271 -312.2868) (xy 391.002768 -312.314756) (xy 390.958306 -312.335854)
			(xy 390.911035 -312.349546) (xy 390.86218 -312.355478) (xy 390.813005 -312.353497) (xy 390.764786 -312.343653)
			(xy 390.71877 -312.326201) (xy 390.676149 -312.301594) (xy 390.638028 -312.270469) (xy 390.605393 -312.233632)
			(xy 390.57909 -312.192036) (xy 390.559799 -312.14676) (xy 390.548022 -312.098976) (xy 390.544062 -312.049922)
			(xy 390.205214 -312.049922) (xy 390.204719 -312.074529) (xy 390.196824 -312.123106) (xy 390.18124 -312.169787)
			(xy 390.158369 -312.213364) (xy 390.128804 -312.252708) (xy 390.093311 -312.2868) (xy 390.052808 -312.314756)
			(xy 390.008346 -312.335854) (xy 389.961075 -312.349546) (xy 389.91222 -312.355478) (xy 389.863045 -312.353497)
			(xy 389.814826 -312.343653) (xy 389.76881 -312.326201) (xy 389.726189 -312.301594) (xy 389.688068 -312.270469)
			(xy 389.655433 -312.233632) (xy 389.62913 -312.192036) (xy 389.609839 -312.14676) (xy 389.598062 -312.098976)
			(xy 389.594102 -312.049922) (xy 389.255254 -312.049922) (xy 389.254759 -312.074529) (xy 389.246864 -312.123106)
			(xy 389.23128 -312.169787) (xy 389.208409 -312.213364) (xy 389.178844 -312.252708) (xy 389.143351 -312.2868)
			(xy 389.102848 -312.314756) (xy 389.058386 -312.335854) (xy 389.011115 -312.349546) (xy 388.96226 -312.355478)
			(xy 388.913085 -312.353497) (xy 388.864866 -312.343653) (xy 388.81885 -312.326201) (xy 388.776229 -312.301594)
			(xy 388.738108 -312.270469) (xy 388.705473 -312.233632) (xy 388.67917 -312.192036) (xy 388.659879 -312.14676)
			(xy 388.648102 -312.098976) (xy 388.644142 -312.049922) (xy 388.305294 -312.049922) (xy 388.304799 -312.074529)
			(xy 388.296904 -312.123106) (xy 388.28132 -312.169787) (xy 388.258449 -312.213364) (xy 388.228884 -312.252708)
			(xy 388.193391 -312.2868) (xy 388.152888 -312.314756) (xy 388.108426 -312.335854) (xy 388.061155 -312.349546)
			(xy 388.0123 -312.355478) (xy 387.963125 -312.353497) (xy 387.914906 -312.343653) (xy 387.86889 -312.326201)
			(xy 387.826269 -312.301594) (xy 387.788148 -312.270469) (xy 387.755513 -312.233632) (xy 387.72921 -312.192036)
			(xy 387.709919 -312.14676) (xy 387.698142 -312.098976) (xy 387.694182 -312.049922) (xy 387.355334 -312.049922)
			(xy 387.354839 -312.074529) (xy 387.346944 -312.123106) (xy 387.33136 -312.169787) (xy 387.308489 -312.213364)
			(xy 387.278924 -312.252708) (xy 387.243431 -312.2868) (xy 387.202928 -312.314756) (xy 387.158466 -312.335854)
			(xy 387.111195 -312.349546) (xy 387.06234 -312.355478) (xy 387.013165 -312.353497) (xy 386.964946 -312.343653)
			(xy 386.91893 -312.326201) (xy 386.876309 -312.301594) (xy 386.838188 -312.270469) (xy 386.805553 -312.233632)
			(xy 386.77925 -312.192036) (xy 386.759959 -312.14676) (xy 386.748182 -312.098976) (xy 386.744222 -312.049922)
			(xy 386.40512 -312.049922) (xy 386.404625 -312.074529) (xy 386.39673 -312.123106) (xy 386.381146 -312.169787)
			(xy 386.358275 -312.213364) (xy 386.32871 -312.252708) (xy 386.293217 -312.2868) (xy 386.252714 -312.314756)
			(xy 386.208252 -312.335854) (xy 386.160981 -312.349546) (xy 386.112126 -312.355478) (xy 386.062951 -312.353497)
			(xy 386.014732 -312.343653) (xy 385.968716 -312.326201) (xy 385.926095 -312.301594) (xy 385.887974 -312.270469)
			(xy 385.855339 -312.233632) (xy 385.829036 -312.192036) (xy 385.809745 -312.14676) (xy 385.797968 -312.098976)
			(xy 385.794008 -312.049922) (xy 385.45516 -312.049922) (xy 385.454665 -312.074529) (xy 385.44677 -312.123106)
			(xy 385.431186 -312.169787) (xy 385.408315 -312.213364) (xy 385.37875 -312.252708) (xy 385.343257 -312.2868)
			(xy 385.302754 -312.314756) (xy 385.258292 -312.335854) (xy 385.211021 -312.349546) (xy 385.162166 -312.355478)
			(xy 385.112991 -312.353497) (xy 385.064772 -312.343653) (xy 385.018756 -312.326201) (xy 384.976135 -312.301594)
			(xy 384.938014 -312.270469) (xy 384.905379 -312.233632) (xy 384.879076 -312.192036) (xy 384.859785 -312.14676)
			(xy 384.848008 -312.098976) (xy 384.844048 -312.049922) (xy 384.504941 -312.049922) (xy 384.504451 -312.074275)
			(xy 384.496556 -312.122852) (xy 384.480972 -312.169533) (xy 384.458101 -312.21311) (xy 384.428536 -312.252454)
			(xy 384.393043 -312.286546) (xy 384.35254 -312.314502) (xy 384.308078 -312.3356) (xy 384.260807 -312.349292)
			(xy 384.211952 -312.355224) (xy 384.162777 -312.353243) (xy 384.114558 -312.343399) (xy 384.068542 -312.325947)
			(xy 384.025921 -312.30134) (xy 383.9878 -312.270215) (xy 383.955165 -312.233378) (xy 383.928862 -312.191782)
			(xy 383.909571 -312.146506) (xy 383.897794 -312.098722) (xy 383.893834 -312.049668) (xy 383.105048 -312.049668)
			(xy 383.125871 -312.081142) (xy 383.149543 -312.131639) (xy 383.165611 -312.185046) (xy 383.173731 -312.240222)
			(xy 383.17424 -312.268108) (xy 383.173731 -312.295994) (xy 383.165611 -312.35117) (xy 383.149543 -312.404577)
			(xy 383.125871 -312.455074) (xy 383.095098 -312.501587) (xy 383.057881 -312.543124) (xy 383.015013 -312.578799)
			(xy 382.967407 -312.607853) (xy 382.916078 -312.629665) (xy 382.862121 -312.643771) (xy 382.806684 -312.649871)
			(xy 382.75095 -312.647834) (xy 382.696107 -312.637704) (xy 382.643323 -312.619697) (xy 382.593723 -312.594196)
			(xy 382.548365 -312.561745) (xy 382.508216 -312.523036) (xy 382.47413 -312.478893) (xy 382.446834 -312.430258)
			(xy 382.426911 -312.378167) (xy 382.414785 -312.32373) (xy 382.410714 -312.268108) (xy 380.696863 -312.268108)
			(xy 380.716388 -312.289899) (xy 380.747161 -312.336412) (xy 380.770833 -312.386909) (xy 380.786901 -312.440316)
			(xy 380.795021 -312.495492) (xy 380.79553 -312.523378) (xy 380.795021 -312.551264) (xy 380.786901 -312.60644)
			(xy 380.770833 -312.659847) (xy 380.747161 -312.710344) (xy 380.716388 -312.756857) (xy 380.679171 -312.798394)
			(xy 380.636303 -312.834069) (xy 380.588697 -312.863123) (xy 380.537368 -312.884935) (xy 380.483411 -312.899041)
			(xy 380.427974 -312.905141) (xy 380.37224 -312.903104) (xy 380.317397 -312.892974) (xy 380.264613 -312.874967)
			(xy 380.215013 -312.849466) (xy 380.169655 -312.817015) (xy 380.129506 -312.778306) (xy 380.09542 -312.734163)
			(xy 380.068124 -312.685528) (xy 380.048201 -312.633437) (xy 380.036075 -312.579) (xy 380.032004 -312.523378)
			(xy 351.03308 -312.523378) (xy 351.03308 -312.999882) (xy 384.844048 -312.999882) (xy 384.848008 -312.950828)
			(xy 384.859785 -312.903044) (xy 384.879076 -312.857768) (xy 384.905379 -312.816172) (xy 384.938014 -312.779335)
			(xy 384.976135 -312.74821) (xy 385.018756 -312.723603) (xy 385.064772 -312.706151) (xy 385.112991 -312.696307)
			(xy 385.162166 -312.694326) (xy 385.211021 -312.700258) (xy 385.258292 -312.71395) (xy 385.302754 -312.735048)
			(xy 385.343257 -312.763004) (xy 385.37875 -312.797096) (xy 385.408315 -312.83644) (xy 385.431186 -312.880017)
			(xy 385.44677 -312.926698) (xy 385.454665 -312.975275) (xy 385.45516 -312.999882) (xy 385.794008 -312.999882)
			(xy 385.797968 -312.950828) (xy 385.809745 -312.903044) (xy 385.829036 -312.857768) (xy 385.855339 -312.816172)
			(xy 385.887974 -312.779335) (xy 385.926095 -312.74821) (xy 385.968716 -312.723603) (xy 386.014732 -312.706151)
			(xy 386.062951 -312.696307) (xy 386.112126 -312.694326) (xy 386.160981 -312.700258) (xy 386.208252 -312.71395)
			(xy 386.252714 -312.735048) (xy 386.293217 -312.763004) (xy 386.32871 -312.797096) (xy 386.358275 -312.83644)
			(xy 386.381146 -312.880017) (xy 386.39673 -312.926698) (xy 386.404625 -312.975275) (xy 386.40512 -312.999882)
			(xy 386.744222 -312.999882) (xy 386.748182 -312.950828) (xy 386.759959 -312.903044) (xy 386.77925 -312.857768)
			(xy 386.805553 -312.816172) (xy 386.838188 -312.779335) (xy 386.876309 -312.74821) (xy 386.91893 -312.723603)
			(xy 386.964946 -312.706151) (xy 387.013165 -312.696307) (xy 387.06234 -312.694326) (xy 387.111195 -312.700258)
			(xy 387.158466 -312.71395) (xy 387.202928 -312.735048) (xy 387.243431 -312.763004) (xy 387.278924 -312.797096)
			(xy 387.308489 -312.83644) (xy 387.33136 -312.880017) (xy 387.346944 -312.926698) (xy 387.354839 -312.975275)
			(xy 387.355334 -312.999882) (xy 387.694182 -312.999882) (xy 387.698142 -312.950828) (xy 387.709919 -312.903044)
			(xy 387.72921 -312.857768) (xy 387.755513 -312.816172) (xy 387.788148 -312.779335) (xy 387.826269 -312.74821)
			(xy 387.86889 -312.723603) (xy 387.914906 -312.706151) (xy 387.963125 -312.696307) (xy 388.0123 -312.694326)
			(xy 388.061155 -312.700258) (xy 388.108426 -312.71395) (xy 388.152888 -312.735048) (xy 388.193391 -312.763004)
			(xy 388.228884 -312.797096) (xy 388.258449 -312.83644) (xy 388.28132 -312.880017) (xy 388.296904 -312.926698)
			(xy 388.304799 -312.975275) (xy 388.305294 -312.999882) (xy 388.644142 -312.999882) (xy 388.648102 -312.950828)
			(xy 388.659879 -312.903044) (xy 388.67917 -312.857768) (xy 388.705473 -312.816172) (xy 388.738108 -312.779335)
			(xy 388.776229 -312.74821) (xy 388.81885 -312.723603) (xy 388.864866 -312.706151) (xy 388.913085 -312.696307)
			(xy 388.96226 -312.694326) (xy 389.011115 -312.700258) (xy 389.058386 -312.71395) (xy 389.102848 -312.735048)
			(xy 389.143351 -312.763004) (xy 389.178844 -312.797096) (xy 389.208409 -312.83644) (xy 389.23128 -312.880017)
			(xy 389.246864 -312.926698) (xy 389.254759 -312.975275) (xy 389.255254 -312.999882) (xy 389.594102 -312.999882)
			(xy 389.598062 -312.950828) (xy 389.609839 -312.903044) (xy 389.62913 -312.857768) (xy 389.655433 -312.816172)
			(xy 389.688068 -312.779335) (xy 389.726189 -312.74821) (xy 389.76881 -312.723603) (xy 389.814826 -312.706151)
			(xy 389.863045 -312.696307) (xy 389.91222 -312.694326) (xy 389.961075 -312.700258) (xy 390.008346 -312.71395)
			(xy 390.052808 -312.735048) (xy 390.093311 -312.763004) (xy 390.128804 -312.797096) (xy 390.158369 -312.83644)
			(xy 390.18124 -312.880017) (xy 390.196824 -312.926698) (xy 390.204719 -312.975275) (xy 390.205214 -312.999882)
			(xy 390.544062 -312.999882) (xy 390.548022 -312.950828) (xy 390.559799 -312.903044) (xy 390.57909 -312.857768)
			(xy 390.605393 -312.816172) (xy 390.638028 -312.779335) (xy 390.676149 -312.74821) (xy 390.71877 -312.723603)
			(xy 390.764786 -312.706151) (xy 390.813005 -312.696307) (xy 390.86218 -312.694326) (xy 390.911035 -312.700258)
			(xy 390.958306 -312.71395) (xy 391.002768 -312.735048) (xy 391.043271 -312.763004) (xy 391.078764 -312.797096)
			(xy 391.108329 -312.83644) (xy 391.1312 -312.880017) (xy 391.146784 -312.926698) (xy 391.154679 -312.975275)
			(xy 391.155174 -312.999882) (xy 391.494022 -312.999882) (xy 391.497982 -312.950828) (xy 391.509759 -312.903044)
			(xy 391.52905 -312.857768) (xy 391.555353 -312.816172) (xy 391.587988 -312.779335) (xy 391.626109 -312.74821)
			(xy 391.66873 -312.723603) (xy 391.714746 -312.706151) (xy 391.762965 -312.696307) (xy 391.81214 -312.694326)
			(xy 391.860995 -312.700258) (xy 391.908266 -312.71395) (xy 391.952728 -312.735048) (xy 391.993231 -312.763004)
			(xy 392.028724 -312.797096) (xy 392.058289 -312.83644) (xy 392.08116 -312.880017) (xy 392.096744 -312.926698)
			(xy 392.104639 -312.975275) (xy 392.105134 -312.999882) (xy 392.443982 -312.999882) (xy 392.447942 -312.950828)
			(xy 392.459719 -312.903044) (xy 392.47901 -312.857768) (xy 392.505313 -312.816172) (xy 392.537948 -312.779335)
			(xy 392.576069 -312.74821) (xy 392.61869 -312.723603) (xy 392.664706 -312.706151) (xy 392.712925 -312.696307)
			(xy 392.7621 -312.694326) (xy 392.810955 -312.700258) (xy 392.858226 -312.71395) (xy 392.902688 -312.735048)
			(xy 392.943191 -312.763004) (xy 392.978684 -312.797096) (xy 393.008249 -312.83644) (xy 393.03112 -312.880017)
			(xy 393.046704 -312.926698) (xy 393.054599 -312.975275) (xy 393.055094 -312.999882) (xy 393.394196 -312.999882)
			(xy 393.398156 -312.950828) (xy 393.409933 -312.903044) (xy 393.429224 -312.857768) (xy 393.455527 -312.816172)
			(xy 393.488162 -312.779335) (xy 393.526283 -312.74821) (xy 393.568904 -312.723603) (xy 393.61492 -312.706151)
			(xy 393.663139 -312.696307) (xy 393.712314 -312.694326) (xy 393.761169 -312.700258) (xy 393.80844 -312.71395)
			(xy 393.852902 -312.735048) (xy 393.893405 -312.763004) (xy 393.928898 -312.797096) (xy 393.958463 -312.83644)
			(xy 393.981334 -312.880017) (xy 393.996918 -312.926698) (xy 394.004813 -312.975275) (xy 394.005308 -312.999882)
			(xy 394.344156 -312.999882) (xy 394.348116 -312.950828) (xy 394.359893 -312.903044) (xy 394.379184 -312.857768)
			(xy 394.405487 -312.816172) (xy 394.438122 -312.779335) (xy 394.476243 -312.74821) (xy 394.518864 -312.723603)
			(xy 394.56488 -312.706151) (xy 394.613099 -312.696307) (xy 394.662274 -312.694326) (xy 394.711129 -312.700258)
			(xy 394.7584 -312.71395) (xy 394.802862 -312.735048) (xy 394.843365 -312.763004) (xy 394.878858 -312.797096)
			(xy 394.908423 -312.83644) (xy 394.931294 -312.880017) (xy 394.946878 -312.926698) (xy 394.954773 -312.975275)
			(xy 394.955268 -312.999882) (xy 395.294116 -312.999882) (xy 395.298076 -312.950828) (xy 395.309853 -312.903044)
			(xy 395.329144 -312.857768) (xy 395.355447 -312.816172) (xy 395.388082 -312.779335) (xy 395.426203 -312.74821)
			(xy 395.468824 -312.723603) (xy 395.51484 -312.706151) (xy 395.563059 -312.696307) (xy 395.612234 -312.694326)
			(xy 395.661089 -312.700258) (xy 395.70836 -312.71395) (xy 395.752822 -312.735048) (xy 395.793325 -312.763004)
			(xy 395.828818 -312.797096) (xy 395.858383 -312.83644) (xy 395.881254 -312.880017) (xy 395.896838 -312.926698)
			(xy 395.904733 -312.975275) (xy 395.905228 -312.999882) (xy 395.904733 -313.024489) (xy 395.896838 -313.073066)
			(xy 395.881254 -313.119747) (xy 395.858383 -313.163324) (xy 395.828818 -313.202668) (xy 395.793325 -313.23676)
			(xy 395.752822 -313.264716) (xy 395.70836 -313.285814) (xy 395.661089 -313.299506) (xy 395.612234 -313.305438)
			(xy 395.563059 -313.303457) (xy 395.51484 -313.293613) (xy 395.468824 -313.276161) (xy 395.426203 -313.251554)
			(xy 395.388082 -313.220429) (xy 395.355447 -313.183592) (xy 395.329144 -313.141996) (xy 395.309853 -313.09672)
			(xy 395.298076 -313.048936) (xy 395.294116 -312.999882) (xy 394.955268 -312.999882) (xy 394.954773 -313.024489)
			(xy 394.946878 -313.073066) (xy 394.931294 -313.119747) (xy 394.908423 -313.163324) (xy 394.878858 -313.202668)
			(xy 394.843365 -313.23676) (xy 394.802862 -313.264716) (xy 394.7584 -313.285814) (xy 394.711129 -313.299506)
			(xy 394.662274 -313.305438) (xy 394.613099 -313.303457) (xy 394.56488 -313.293613) (xy 394.518864 -313.276161)
			(xy 394.476243 -313.251554) (xy 394.438122 -313.220429) (xy 394.405487 -313.183592) (xy 394.379184 -313.141996)
			(xy 394.359893 -313.09672) (xy 394.348116 -313.048936) (xy 394.344156 -312.999882) (xy 394.005308 -312.999882)
			(xy 394.004813 -313.024489) (xy 393.996918 -313.073066) (xy 393.981334 -313.119747) (xy 393.958463 -313.163324)
			(xy 393.928898 -313.202668) (xy 393.893405 -313.23676) (xy 393.852902 -313.264716) (xy 393.80844 -313.285814)
			(xy 393.761169 -313.299506) (xy 393.712314 -313.305438) (xy 393.663139 -313.303457) (xy 393.61492 -313.293613)
			(xy 393.568904 -313.276161) (xy 393.526283 -313.251554) (xy 393.488162 -313.220429) (xy 393.455527 -313.183592)
			(xy 393.429224 -313.141996) (xy 393.409933 -313.09672) (xy 393.398156 -313.048936) (xy 393.394196 -312.999882)
			(xy 393.055094 -312.999882) (xy 393.054599 -313.024489) (xy 393.046704 -313.073066) (xy 393.03112 -313.119747)
			(xy 393.008249 -313.163324) (xy 392.978684 -313.202668) (xy 392.943191 -313.23676) (xy 392.902688 -313.264716)
			(xy 392.858226 -313.285814) (xy 392.810955 -313.299506) (xy 392.7621 -313.305438) (xy 392.712925 -313.303457)
			(xy 392.664706 -313.293613) (xy 392.61869 -313.276161) (xy 392.576069 -313.251554) (xy 392.537948 -313.220429)
			(xy 392.505313 -313.183592) (xy 392.47901 -313.141996) (xy 392.459719 -313.09672) (xy 392.447942 -313.048936)
			(xy 392.443982 -312.999882) (xy 392.105134 -312.999882) (xy 392.104639 -313.024489) (xy 392.096744 -313.073066)
			(xy 392.08116 -313.119747) (xy 392.058289 -313.163324) (xy 392.028724 -313.202668) (xy 391.993231 -313.23676)
			(xy 391.952728 -313.264716) (xy 391.908266 -313.285814) (xy 391.860995 -313.299506) (xy 391.81214 -313.305438)
			(xy 391.762965 -313.303457) (xy 391.714746 -313.293613) (xy 391.66873 -313.276161) (xy 391.626109 -313.251554)
			(xy 391.587988 -313.220429) (xy 391.555353 -313.183592) (xy 391.52905 -313.141996) (xy 391.509759 -313.09672)
			(xy 391.497982 -313.048936) (xy 391.494022 -312.999882) (xy 391.155174 -312.999882) (xy 391.154679 -313.024489)
			(xy 391.146784 -313.073066) (xy 391.1312 -313.119747) (xy 391.108329 -313.163324) (xy 391.078764 -313.202668)
			(xy 391.043271 -313.23676) (xy 391.002768 -313.264716) (xy 390.958306 -313.285814) (xy 390.911035 -313.299506)
			(xy 390.86218 -313.305438) (xy 390.813005 -313.303457) (xy 390.764786 -313.293613) (xy 390.71877 -313.276161)
			(xy 390.676149 -313.251554) (xy 390.638028 -313.220429) (xy 390.605393 -313.183592) (xy 390.57909 -313.141996)
			(xy 390.559799 -313.09672) (xy 390.548022 -313.048936) (xy 390.544062 -312.999882) (xy 390.205214 -312.999882)
			(xy 390.204719 -313.024489) (xy 390.196824 -313.073066) (xy 390.18124 -313.119747) (xy 390.158369 -313.163324)
			(xy 390.128804 -313.202668) (xy 390.093311 -313.23676) (xy 390.052808 -313.264716) (xy 390.008346 -313.285814)
			(xy 389.961075 -313.299506) (xy 389.91222 -313.305438) (xy 389.863045 -313.303457) (xy 389.814826 -313.293613)
			(xy 389.76881 -313.276161) (xy 389.726189 -313.251554) (xy 389.688068 -313.220429) (xy 389.655433 -313.183592)
			(xy 389.62913 -313.141996) (xy 389.609839 -313.09672) (xy 389.598062 -313.048936) (xy 389.594102 -312.999882)
			(xy 389.255254 -312.999882) (xy 389.254759 -313.024489) (xy 389.246864 -313.073066) (xy 389.23128 -313.119747)
			(xy 389.208409 -313.163324) (xy 389.178844 -313.202668) (xy 389.143351 -313.23676) (xy 389.102848 -313.264716)
			(xy 389.058386 -313.285814) (xy 389.011115 -313.299506) (xy 388.96226 -313.305438) (xy 388.913085 -313.303457)
			(xy 388.864866 -313.293613) (xy 388.81885 -313.276161) (xy 388.776229 -313.251554) (xy 388.738108 -313.220429)
			(xy 388.705473 -313.183592) (xy 388.67917 -313.141996) (xy 388.659879 -313.09672) (xy 388.648102 -313.048936)
			(xy 388.644142 -312.999882) (xy 388.305294 -312.999882) (xy 388.304799 -313.024489) (xy 388.296904 -313.073066)
			(xy 388.28132 -313.119747) (xy 388.258449 -313.163324) (xy 388.228884 -313.202668) (xy 388.193391 -313.23676)
			(xy 388.152888 -313.264716) (xy 388.108426 -313.285814) (xy 388.061155 -313.299506) (xy 388.0123 -313.305438)
			(xy 387.963125 -313.303457) (xy 387.914906 -313.293613) (xy 387.86889 -313.276161) (xy 387.826269 -313.251554)
			(xy 387.788148 -313.220429) (xy 387.755513 -313.183592) (xy 387.72921 -313.141996) (xy 387.709919 -313.09672)
			(xy 387.698142 -313.048936) (xy 387.694182 -312.999882) (xy 387.355334 -312.999882) (xy 387.354839 -313.024489)
			(xy 387.346944 -313.073066) (xy 387.33136 -313.119747) (xy 387.308489 -313.163324) (xy 387.278924 -313.202668)
			(xy 387.243431 -313.23676) (xy 387.202928 -313.264716) (xy 387.158466 -313.285814) (xy 387.111195 -313.299506)
			(xy 387.06234 -313.305438) (xy 387.013165 -313.303457) (xy 386.964946 -313.293613) (xy 386.91893 -313.276161)
			(xy 386.876309 -313.251554) (xy 386.838188 -313.220429) (xy 386.805553 -313.183592) (xy 386.77925 -313.141996)
			(xy 386.759959 -313.09672) (xy 386.748182 -313.048936) (xy 386.744222 -312.999882) (xy 386.40512 -312.999882)
			(xy 386.404625 -313.024489) (xy 386.39673 -313.073066) (xy 386.381146 -313.119747) (xy 386.358275 -313.163324)
			(xy 386.32871 -313.202668) (xy 386.293217 -313.23676) (xy 386.252714 -313.264716) (xy 386.208252 -313.285814)
			(xy 386.160981 -313.299506) (xy 386.112126 -313.305438) (xy 386.062951 -313.303457) (xy 386.014732 -313.293613)
			(xy 385.968716 -313.276161) (xy 385.926095 -313.251554) (xy 385.887974 -313.220429) (xy 385.855339 -313.183592)
			(xy 385.829036 -313.141996) (xy 385.809745 -313.09672) (xy 385.797968 -313.048936) (xy 385.794008 -312.999882)
			(xy 385.45516 -312.999882) (xy 385.454665 -313.024489) (xy 385.44677 -313.073066) (xy 385.431186 -313.119747)
			(xy 385.408315 -313.163324) (xy 385.37875 -313.202668) (xy 385.343257 -313.23676) (xy 385.302754 -313.264716)
			(xy 385.258292 -313.285814) (xy 385.211021 -313.299506) (xy 385.162166 -313.305438) (xy 385.112991 -313.303457)
			(xy 385.064772 -313.293613) (xy 385.018756 -313.276161) (xy 384.976135 -313.251554) (xy 384.938014 -313.220429)
			(xy 384.905379 -313.183592) (xy 384.879076 -313.141996) (xy 384.859785 -313.09672) (xy 384.848008 -313.048936)
			(xy 384.844048 -312.999882) (xy 351.03308 -312.999882) (xy 351.03308 -313.669934) (xy 382.34696 -313.669934)
			(xy 382.351031 -313.614312) (xy 382.363157 -313.559875) (xy 382.38308 -313.507784) (xy 382.410376 -313.459149)
			(xy 382.444462 -313.415006) (xy 382.484611 -313.376297) (xy 382.529969 -313.343846) (xy 382.579569 -313.318345)
			(xy 382.632353 -313.300338) (xy 382.687196 -313.290208) (xy 382.74293 -313.288171) (xy 382.798367 -313.294271)
			(xy 382.852324 -313.308377) (xy 382.903653 -313.330189) (xy 382.951259 -313.359243) (xy 382.994127 -313.394918)
			(xy 383.031344 -313.436455) (xy 383.062117 -313.482968) (xy 383.085789 -313.533465) (xy 383.101857 -313.586872)
			(xy 383.109977 -313.642048) (xy 383.110486 -313.669934) (xy 383.109977 -313.69782) (xy 383.101857 -313.752996)
			(xy 383.085789 -313.806403) (xy 383.062117 -313.8569) (xy 383.031344 -313.903413) (xy 382.994127 -313.94495)
			(xy 382.988249 -313.949842) (xy 384.844048 -313.949842) (xy 384.848008 -313.900788) (xy 384.859785 -313.853004)
			(xy 384.879076 -313.807728) (xy 384.905379 -313.766132) (xy 384.938014 -313.729295) (xy 384.976135 -313.69817)
			(xy 385.018756 -313.673563) (xy 385.064772 -313.656111) (xy 385.112991 -313.646267) (xy 385.162166 -313.644286)
			(xy 385.211021 -313.650218) (xy 385.258292 -313.66391) (xy 385.302754 -313.685008) (xy 385.343257 -313.712964)
			(xy 385.37875 -313.747056) (xy 385.408315 -313.7864) (xy 385.431186 -313.829977) (xy 385.44677 -313.876658)
			(xy 385.454665 -313.925235) (xy 385.45516 -313.949842) (xy 385.794008 -313.949842) (xy 385.797968 -313.900788)
			(xy 385.809745 -313.853004) (xy 385.829036 -313.807728) (xy 385.855339 -313.766132) (xy 385.887974 -313.729295)
			(xy 385.926095 -313.69817) (xy 385.968716 -313.673563) (xy 386.014732 -313.656111) (xy 386.062951 -313.646267)
			(xy 386.112126 -313.644286) (xy 386.160981 -313.650218) (xy 386.208252 -313.66391) (xy 386.252714 -313.685008)
			(xy 386.293217 -313.712964) (xy 386.32871 -313.747056) (xy 386.358275 -313.7864) (xy 386.381146 -313.829977)
			(xy 386.39673 -313.876658) (xy 386.404625 -313.925235) (xy 386.40512 -313.949842) (xy 386.744222 -313.949842)
			(xy 386.748182 -313.900788) (xy 386.759959 -313.853004) (xy 386.77925 -313.807728) (xy 386.805553 -313.766132)
			(xy 386.838188 -313.729295) (xy 386.876309 -313.69817) (xy 386.91893 -313.673563) (xy 386.964946 -313.656111)
			(xy 387.013165 -313.646267) (xy 387.06234 -313.644286) (xy 387.111195 -313.650218) (xy 387.158466 -313.66391)
			(xy 387.202928 -313.685008) (xy 387.243431 -313.712964) (xy 387.278924 -313.747056) (xy 387.308489 -313.7864)
			(xy 387.33136 -313.829977) (xy 387.346944 -313.876658) (xy 387.354839 -313.925235) (xy 387.355334 -313.949842)
			(xy 387.694182 -313.949842) (xy 387.698142 -313.900788) (xy 387.709919 -313.853004) (xy 387.72921 -313.807728)
			(xy 387.755513 -313.766132) (xy 387.788148 -313.729295) (xy 387.826269 -313.69817) (xy 387.86889 -313.673563)
			(xy 387.914906 -313.656111) (xy 387.963125 -313.646267) (xy 388.0123 -313.644286) (xy 388.061155 -313.650218)
			(xy 388.108426 -313.66391) (xy 388.152888 -313.685008) (xy 388.193391 -313.712964) (xy 388.228884 -313.747056)
			(xy 388.258449 -313.7864) (xy 388.28132 -313.829977) (xy 388.296904 -313.876658) (xy 388.304799 -313.925235)
			(xy 388.305294 -313.949842) (xy 388.644142 -313.949842) (xy 388.648102 -313.900788) (xy 388.659879 -313.853004)
			(xy 388.67917 -313.807728) (xy 388.705473 -313.766132) (xy 388.738108 -313.729295) (xy 388.776229 -313.69817)
			(xy 388.81885 -313.673563) (xy 388.864866 -313.656111) (xy 388.913085 -313.646267) (xy 388.96226 -313.644286)
			(xy 389.011115 -313.650218) (xy 389.058386 -313.66391) (xy 389.102848 -313.685008) (xy 389.143351 -313.712964)
			(xy 389.178844 -313.747056) (xy 389.208409 -313.7864) (xy 389.23128 -313.829977) (xy 389.246864 -313.876658)
			(xy 389.254759 -313.925235) (xy 389.255254 -313.949842) (xy 389.594102 -313.949842) (xy 389.598062 -313.900788)
			(xy 389.609839 -313.853004) (xy 389.62913 -313.807728) (xy 389.655433 -313.766132) (xy 389.688068 -313.729295)
			(xy 389.726189 -313.69817) (xy 389.76881 -313.673563) (xy 389.814826 -313.656111) (xy 389.863045 -313.646267)
			(xy 389.91222 -313.644286) (xy 389.961075 -313.650218) (xy 390.008346 -313.66391) (xy 390.052808 -313.685008)
			(xy 390.093311 -313.712964) (xy 390.128804 -313.747056) (xy 390.158369 -313.7864) (xy 390.18124 -313.829977)
			(xy 390.196824 -313.876658) (xy 390.204719 -313.925235) (xy 390.205214 -313.949842) (xy 390.544062 -313.949842)
			(xy 390.548022 -313.900788) (xy 390.559799 -313.853004) (xy 390.57909 -313.807728) (xy 390.605393 -313.766132)
			(xy 390.638028 -313.729295) (xy 390.676149 -313.69817) (xy 390.71877 -313.673563) (xy 390.764786 -313.656111)
			(xy 390.813005 -313.646267) (xy 390.86218 -313.644286) (xy 390.911035 -313.650218) (xy 390.958306 -313.66391)
			(xy 391.002768 -313.685008) (xy 391.043271 -313.712964) (xy 391.078764 -313.747056) (xy 391.108329 -313.7864)
			(xy 391.1312 -313.829977) (xy 391.146784 -313.876658) (xy 391.154679 -313.925235) (xy 391.155174 -313.949842)
			(xy 391.494022 -313.949842) (xy 391.497982 -313.900788) (xy 391.509759 -313.853004) (xy 391.52905 -313.807728)
			(xy 391.555353 -313.766132) (xy 391.587988 -313.729295) (xy 391.626109 -313.69817) (xy 391.66873 -313.673563)
			(xy 391.714746 -313.656111) (xy 391.762965 -313.646267) (xy 391.81214 -313.644286) (xy 391.860995 -313.650218)
			(xy 391.908266 -313.66391) (xy 391.952728 -313.685008) (xy 391.993231 -313.712964) (xy 392.028724 -313.747056)
			(xy 392.058289 -313.7864) (xy 392.08116 -313.829977) (xy 392.096744 -313.876658) (xy 392.104639 -313.925235)
			(xy 392.105134 -313.949842) (xy 392.443982 -313.949842) (xy 392.447942 -313.900788) (xy 392.459719 -313.853004)
			(xy 392.47901 -313.807728) (xy 392.505313 -313.766132) (xy 392.537948 -313.729295) (xy 392.576069 -313.69817)
			(xy 392.61869 -313.673563) (xy 392.664706 -313.656111) (xy 392.712925 -313.646267) (xy 392.7621 -313.644286)
			(xy 392.810955 -313.650218) (xy 392.858226 -313.66391) (xy 392.902688 -313.685008) (xy 392.943191 -313.712964)
			(xy 392.978684 -313.747056) (xy 393.008249 -313.7864) (xy 393.03112 -313.829977) (xy 393.046704 -313.876658)
			(xy 393.054599 -313.925235) (xy 393.055094 -313.949842) (xy 393.394196 -313.949842) (xy 393.398156 -313.900788)
			(xy 393.409933 -313.853004) (xy 393.429224 -313.807728) (xy 393.455527 -313.766132) (xy 393.488162 -313.729295)
			(xy 393.526283 -313.69817) (xy 393.568904 -313.673563) (xy 393.61492 -313.656111) (xy 393.663139 -313.646267)
			(xy 393.712314 -313.644286) (xy 393.761169 -313.650218) (xy 393.80844 -313.66391) (xy 393.852902 -313.685008)
			(xy 393.893405 -313.712964) (xy 393.928898 -313.747056) (xy 393.958463 -313.7864) (xy 393.981334 -313.829977)
			(xy 393.996918 -313.876658) (xy 394.004813 -313.925235) (xy 394.005308 -313.949842) (xy 394.344156 -313.949842)
			(xy 394.348116 -313.900788) (xy 394.359893 -313.853004) (xy 394.379184 -313.807728) (xy 394.405487 -313.766132)
			(xy 394.438122 -313.729295) (xy 394.476243 -313.69817) (xy 394.518864 -313.673563) (xy 394.56488 -313.656111)
			(xy 394.613099 -313.646267) (xy 394.662274 -313.644286) (xy 394.711129 -313.650218) (xy 394.7584 -313.66391)
			(xy 394.802862 -313.685008) (xy 394.843365 -313.712964) (xy 394.878858 -313.747056) (xy 394.908423 -313.7864)
			(xy 394.931294 -313.829977) (xy 394.946878 -313.876658) (xy 394.954773 -313.925235) (xy 394.955268 -313.949842)
			(xy 395.294116 -313.949842) (xy 395.298076 -313.900788) (xy 395.309853 -313.853004) (xy 395.329144 -313.807728)
			(xy 395.355447 -313.766132) (xy 395.388082 -313.729295) (xy 395.426203 -313.69817) (xy 395.468824 -313.673563)
			(xy 395.51484 -313.656111) (xy 395.563059 -313.646267) (xy 395.612234 -313.644286) (xy 395.661089 -313.650218)
			(xy 395.70836 -313.66391) (xy 395.752822 -313.685008) (xy 395.793325 -313.712964) (xy 395.828818 -313.747056)
			(xy 395.858383 -313.7864) (xy 395.881254 -313.829977) (xy 395.896838 -313.876658) (xy 395.904733 -313.925235)
			(xy 395.905228 -313.949842) (xy 395.904733 -313.974449) (xy 395.896838 -314.023026) (xy 395.881254 -314.069707)
			(xy 395.858383 -314.113284) (xy 395.828818 -314.152628) (xy 395.793325 -314.18672) (xy 395.752822 -314.214676)
			(xy 395.70836 -314.235774) (xy 395.661089 -314.249466) (xy 395.612234 -314.255398) (xy 395.563059 -314.253417)
			(xy 395.51484 -314.243573) (xy 395.468824 -314.226121) (xy 395.426203 -314.201514) (xy 395.388082 -314.170389)
			(xy 395.355447 -314.133552) (xy 395.329144 -314.091956) (xy 395.309853 -314.04668) (xy 395.298076 -313.998896)
			(xy 395.294116 -313.949842) (xy 394.955268 -313.949842) (xy 394.954773 -313.974449) (xy 394.946878 -314.023026)
			(xy 394.931294 -314.069707) (xy 394.908423 -314.113284) (xy 394.878858 -314.152628) (xy 394.843365 -314.18672)
			(xy 394.802862 -314.214676) (xy 394.7584 -314.235774) (xy 394.711129 -314.249466) (xy 394.662274 -314.255398)
			(xy 394.613099 -314.253417) (xy 394.56488 -314.243573) (xy 394.518864 -314.226121) (xy 394.476243 -314.201514)
			(xy 394.438122 -314.170389) (xy 394.405487 -314.133552) (xy 394.379184 -314.091956) (xy 394.359893 -314.04668)
			(xy 394.348116 -313.998896) (xy 394.344156 -313.949842) (xy 394.005308 -313.949842) (xy 394.004813 -313.974449)
			(xy 393.996918 -314.023026) (xy 393.981334 -314.069707) (xy 393.958463 -314.113284) (xy 393.928898 -314.152628)
			(xy 393.893405 -314.18672) (xy 393.852902 -314.214676) (xy 393.80844 -314.235774) (xy 393.761169 -314.249466)
			(xy 393.712314 -314.255398) (xy 393.663139 -314.253417) (xy 393.61492 -314.243573) (xy 393.568904 -314.226121)
			(xy 393.526283 -314.201514) (xy 393.488162 -314.170389) (xy 393.455527 -314.133552) (xy 393.429224 -314.091956)
			(xy 393.409933 -314.04668) (xy 393.398156 -313.998896) (xy 393.394196 -313.949842) (xy 393.055094 -313.949842)
			(xy 393.054599 -313.974449) (xy 393.046704 -314.023026) (xy 393.03112 -314.069707) (xy 393.008249 -314.113284)
			(xy 392.978684 -314.152628) (xy 392.943191 -314.18672) (xy 392.902688 -314.214676) (xy 392.858226 -314.235774)
			(xy 392.810955 -314.249466) (xy 392.7621 -314.255398) (xy 392.712925 -314.253417) (xy 392.664706 -314.243573)
			(xy 392.61869 -314.226121) (xy 392.576069 -314.201514) (xy 392.537948 -314.170389) (xy 392.505313 -314.133552)
			(xy 392.47901 -314.091956) (xy 392.459719 -314.04668) (xy 392.447942 -313.998896) (xy 392.443982 -313.949842)
			(xy 392.105134 -313.949842) (xy 392.104639 -313.974449) (xy 392.096744 -314.023026) (xy 392.08116 -314.069707)
			(xy 392.058289 -314.113284) (xy 392.028724 -314.152628) (xy 391.993231 -314.18672) (xy 391.952728 -314.214676)
			(xy 391.908266 -314.235774) (xy 391.860995 -314.249466) (xy 391.81214 -314.255398) (xy 391.762965 -314.253417)
			(xy 391.714746 -314.243573) (xy 391.66873 -314.226121) (xy 391.626109 -314.201514) (xy 391.587988 -314.170389)
			(xy 391.555353 -314.133552) (xy 391.52905 -314.091956) (xy 391.509759 -314.04668) (xy 391.497982 -313.998896)
			(xy 391.494022 -313.949842) (xy 391.155174 -313.949842) (xy 391.154679 -313.974449) (xy 391.146784 -314.023026)
			(xy 391.1312 -314.069707) (xy 391.108329 -314.113284) (xy 391.078764 -314.152628) (xy 391.043271 -314.18672)
			(xy 391.002768 -314.214676) (xy 390.958306 -314.235774) (xy 390.911035 -314.249466) (xy 390.86218 -314.255398)
			(xy 390.813005 -314.253417) (xy 390.764786 -314.243573) (xy 390.71877 -314.226121) (xy 390.676149 -314.201514)
			(xy 390.638028 -314.170389) (xy 390.605393 -314.133552) (xy 390.57909 -314.091956) (xy 390.559799 -314.04668)
			(xy 390.548022 -313.998896) (xy 390.544062 -313.949842) (xy 390.205214 -313.949842) (xy 390.204719 -313.974449)
			(xy 390.196824 -314.023026) (xy 390.18124 -314.069707) (xy 390.158369 -314.113284) (xy 390.128804 -314.152628)
			(xy 390.093311 -314.18672) (xy 390.052808 -314.214676) (xy 390.008346 -314.235774) (xy 389.961075 -314.249466)
			(xy 389.91222 -314.255398) (xy 389.863045 -314.253417) (xy 389.814826 -314.243573) (xy 389.76881 -314.226121)
			(xy 389.726189 -314.201514) (xy 389.688068 -314.170389) (xy 389.655433 -314.133552) (xy 389.62913 -314.091956)
			(xy 389.609839 -314.04668) (xy 389.598062 -313.998896) (xy 389.594102 -313.949842) (xy 389.255254 -313.949842)
			(xy 389.254759 -313.974449) (xy 389.246864 -314.023026) (xy 389.23128 -314.069707) (xy 389.208409 -314.113284)
			(xy 389.178844 -314.152628) (xy 389.143351 -314.18672) (xy 389.102848 -314.214676) (xy 389.058386 -314.235774)
			(xy 389.011115 -314.249466) (xy 388.96226 -314.255398) (xy 388.913085 -314.253417) (xy 388.864866 -314.243573)
			(xy 388.81885 -314.226121) (xy 388.776229 -314.201514) (xy 388.738108 -314.170389) (xy 388.705473 -314.133552)
			(xy 388.67917 -314.091956) (xy 388.659879 -314.04668) (xy 388.648102 -313.998896) (xy 388.644142 -313.949842)
			(xy 388.305294 -313.949842) (xy 388.304799 -313.974449) (xy 388.296904 -314.023026) (xy 388.28132 -314.069707)
			(xy 388.258449 -314.113284) (xy 388.228884 -314.152628) (xy 388.193391 -314.18672) (xy 388.152888 -314.214676)
			(xy 388.108426 -314.235774) (xy 388.061155 -314.249466) (xy 388.0123 -314.255398) (xy 387.963125 -314.253417)
			(xy 387.914906 -314.243573) (xy 387.86889 -314.226121) (xy 387.826269 -314.201514) (xy 387.788148 -314.170389)
			(xy 387.755513 -314.133552) (xy 387.72921 -314.091956) (xy 387.709919 -314.04668) (xy 387.698142 -313.998896)
			(xy 387.694182 -313.949842) (xy 387.355334 -313.949842) (xy 387.354839 -313.974449) (xy 387.346944 -314.023026)
			(xy 387.33136 -314.069707) (xy 387.308489 -314.113284) (xy 387.278924 -314.152628) (xy 387.243431 -314.18672)
			(xy 387.202928 -314.214676) (xy 387.158466 -314.235774) (xy 387.111195 -314.249466) (xy 387.06234 -314.255398)
			(xy 387.013165 -314.253417) (xy 386.964946 -314.243573) (xy 386.91893 -314.226121) (xy 386.876309 -314.201514)
			(xy 386.838188 -314.170389) (xy 386.805553 -314.133552) (xy 386.77925 -314.091956) (xy 386.759959 -314.04668)
			(xy 386.748182 -313.998896) (xy 386.744222 -313.949842) (xy 386.40512 -313.949842) (xy 386.404625 -313.974449)
			(xy 386.39673 -314.023026) (xy 386.381146 -314.069707) (xy 386.358275 -314.113284) (xy 386.32871 -314.152628)
			(xy 386.293217 -314.18672) (xy 386.252714 -314.214676) (xy 386.208252 -314.235774) (xy 386.160981 -314.249466)
			(xy 386.112126 -314.255398) (xy 386.062951 -314.253417) (xy 386.014732 -314.243573) (xy 385.968716 -314.226121)
			(xy 385.926095 -314.201514) (xy 385.887974 -314.170389) (xy 385.855339 -314.133552) (xy 385.829036 -314.091956)
			(xy 385.809745 -314.04668) (xy 385.797968 -313.998896) (xy 385.794008 -313.949842) (xy 385.45516 -313.949842)
			(xy 385.454665 -313.974449) (xy 385.44677 -314.023026) (xy 385.431186 -314.069707) (xy 385.408315 -314.113284)
			(xy 385.37875 -314.152628) (xy 385.343257 -314.18672) (xy 385.302754 -314.214676) (xy 385.258292 -314.235774)
			(xy 385.211021 -314.249466) (xy 385.162166 -314.255398) (xy 385.112991 -314.253417) (xy 385.064772 -314.243573)
			(xy 385.018756 -314.226121) (xy 384.976135 -314.201514) (xy 384.938014 -314.170389) (xy 384.905379 -314.133552)
			(xy 384.879076 -314.091956) (xy 384.859785 -314.04668) (xy 384.848008 -313.998896) (xy 384.844048 -313.949842)
			(xy 382.988249 -313.949842) (xy 382.951259 -313.980625) (xy 382.903653 -314.009679) (xy 382.852324 -314.031491)
			(xy 382.798367 -314.045597) (xy 382.74293 -314.051697) (xy 382.687196 -314.04966) (xy 382.632353 -314.03953)
			(xy 382.579569 -314.021523) (xy 382.529969 -313.996022) (xy 382.484611 -313.963571) (xy 382.444462 -313.924862)
			(xy 382.410376 -313.880719) (xy 382.38308 -313.832084) (xy 382.363157 -313.779993) (xy 382.351031 -313.725556)
			(xy 382.34696 -313.669934) (xy 351.03308 -313.669934) (xy 351.03308 -314.844684) (xy 351.03308 -314.846208)
			(xy 351.03331 -314.850779) (xy 351.035221 -314.859727) (xy 351.03689 -314.863988) (xy 351.042986 -314.87872)
			(xy 351.044757 -314.883348) (xy 351.046672 -314.89307) (xy 351.046796 -314.898024) (xy 351.046796 -314.899548)
			(xy 383.89358 -314.899548) (xy 383.89754 -314.850494) (xy 383.909317 -314.80271) (xy 383.928608 -314.757434)
			(xy 383.954911 -314.715838) (xy 383.987546 -314.679001) (xy 384.025667 -314.647876) (xy 384.068288 -314.623269)
			(xy 384.114304 -314.605817) (xy 384.162523 -314.595973) (xy 384.211698 -314.593992) (xy 384.260553 -314.599924)
			(xy 384.307824 -314.613616) (xy 384.352286 -314.634714) (xy 384.392789 -314.66267) (xy 384.428282 -314.696762)
			(xy 384.457847 -314.736106) (xy 384.480718 -314.779683) (xy 384.496302 -314.826364) (xy 384.504197 -314.874941)
			(xy 384.504692 -314.899548) (xy 384.504687 -314.899802) (xy 384.844048 -314.899802) (xy 384.848008 -314.850748)
			(xy 384.859785 -314.802964) (xy 384.879076 -314.757688) (xy 384.905379 -314.716092) (xy 384.938014 -314.679255)
			(xy 384.976135 -314.64813) (xy 385.018756 -314.623523) (xy 385.064772 -314.606071) (xy 385.112991 -314.596227)
			(xy 385.162166 -314.594246) (xy 385.211021 -314.600178) (xy 385.258292 -314.61387) (xy 385.302754 -314.634968)
			(xy 385.343257 -314.662924) (xy 385.37875 -314.697016) (xy 385.408315 -314.73636) (xy 385.431186 -314.779937)
			(xy 385.44677 -314.826618) (xy 385.454665 -314.875195) (xy 385.45516 -314.899802) (xy 385.794008 -314.899802)
			(xy 385.797968 -314.850748) (xy 385.809745 -314.802964) (xy 385.829036 -314.757688) (xy 385.855339 -314.716092)
			(xy 385.887974 -314.679255) (xy 385.926095 -314.64813) (xy 385.968716 -314.623523) (xy 386.014732 -314.606071)
			(xy 386.062951 -314.596227) (xy 386.112126 -314.594246) (xy 386.160981 -314.600178) (xy 386.208252 -314.61387)
			(xy 386.252714 -314.634968) (xy 386.293217 -314.662924) (xy 386.32871 -314.697016) (xy 386.358275 -314.73636)
			(xy 386.381146 -314.779937) (xy 386.39673 -314.826618) (xy 386.404625 -314.875195) (xy 386.40512 -314.899802)
			(xy 386.744222 -314.899802) (xy 386.748182 -314.850748) (xy 386.759959 -314.802964) (xy 386.77925 -314.757688)
			(xy 386.805553 -314.716092) (xy 386.838188 -314.679255) (xy 386.876309 -314.64813) (xy 386.91893 -314.623523)
			(xy 386.964946 -314.606071) (xy 387.013165 -314.596227) (xy 387.06234 -314.594246) (xy 387.111195 -314.600178)
			(xy 387.158466 -314.61387) (xy 387.202928 -314.634968) (xy 387.243431 -314.662924) (xy 387.278924 -314.697016)
			(xy 387.308489 -314.73636) (xy 387.33136 -314.779937) (xy 387.346944 -314.826618) (xy 387.354839 -314.875195)
			(xy 387.355334 -314.899802) (xy 387.694182 -314.899802) (xy 387.698142 -314.850748) (xy 387.709919 -314.802964)
			(xy 387.72921 -314.757688) (xy 387.755513 -314.716092) (xy 387.788148 -314.679255) (xy 387.826269 -314.64813)
			(xy 387.86889 -314.623523) (xy 387.914906 -314.606071) (xy 387.963125 -314.596227) (xy 388.0123 -314.594246)
			(xy 388.061155 -314.600178) (xy 388.108426 -314.61387) (xy 388.152888 -314.634968) (xy 388.193391 -314.662924)
			(xy 388.228884 -314.697016) (xy 388.258449 -314.73636) (xy 388.28132 -314.779937) (xy 388.296904 -314.826618)
			(xy 388.304799 -314.875195) (xy 388.305294 -314.899802) (xy 388.644142 -314.899802) (xy 388.648102 -314.850748)
			(xy 388.659879 -314.802964) (xy 388.67917 -314.757688) (xy 388.705473 -314.716092) (xy 388.738108 -314.679255)
			(xy 388.776229 -314.64813) (xy 388.81885 -314.623523) (xy 388.864866 -314.606071) (xy 388.913085 -314.596227)
			(xy 388.96226 -314.594246) (xy 389.011115 -314.600178) (xy 389.058386 -314.61387) (xy 389.102848 -314.634968)
			(xy 389.143351 -314.662924) (xy 389.178844 -314.697016) (xy 389.208409 -314.73636) (xy 389.23128 -314.779937)
			(xy 389.246864 -314.826618) (xy 389.254759 -314.875195) (xy 389.255254 -314.899802) (xy 389.594102 -314.899802)
			(xy 389.598062 -314.850748) (xy 389.609839 -314.802964) (xy 389.62913 -314.757688) (xy 389.655433 -314.716092)
			(xy 389.688068 -314.679255) (xy 389.726189 -314.64813) (xy 389.76881 -314.623523) (xy 389.814826 -314.606071)
			(xy 389.863045 -314.596227) (xy 389.91222 -314.594246) (xy 389.961075 -314.600178) (xy 390.008346 -314.61387)
			(xy 390.052808 -314.634968) (xy 390.093311 -314.662924) (xy 390.128804 -314.697016) (xy 390.158369 -314.73636)
			(xy 390.18124 -314.779937) (xy 390.196824 -314.826618) (xy 390.204719 -314.875195) (xy 390.205214 -314.899802)
			(xy 390.544062 -314.899802) (xy 390.548022 -314.850748) (xy 390.559799 -314.802964) (xy 390.57909 -314.757688)
			(xy 390.605393 -314.716092) (xy 390.638028 -314.679255) (xy 390.676149 -314.64813) (xy 390.71877 -314.623523)
			(xy 390.764786 -314.606071) (xy 390.813005 -314.596227) (xy 390.86218 -314.594246) (xy 390.911035 -314.600178)
			(xy 390.958306 -314.61387) (xy 391.002768 -314.634968) (xy 391.043271 -314.662924) (xy 391.078764 -314.697016)
			(xy 391.108329 -314.73636) (xy 391.1312 -314.779937) (xy 391.146784 -314.826618) (xy 391.154679 -314.875195)
			(xy 391.155174 -314.899802) (xy 391.494022 -314.899802) (xy 391.497982 -314.850748) (xy 391.509759 -314.802964)
			(xy 391.52905 -314.757688) (xy 391.555353 -314.716092) (xy 391.587988 -314.679255) (xy 391.626109 -314.64813)
			(xy 391.66873 -314.623523) (xy 391.714746 -314.606071) (xy 391.762965 -314.596227) (xy 391.81214 -314.594246)
			(xy 391.860995 -314.600178) (xy 391.908266 -314.61387) (xy 391.952728 -314.634968) (xy 391.993231 -314.662924)
			(xy 392.028724 -314.697016) (xy 392.058289 -314.73636) (xy 392.08116 -314.779937) (xy 392.096744 -314.826618)
			(xy 392.104639 -314.875195) (xy 392.105134 -314.899802) (xy 392.443982 -314.899802) (xy 392.447942 -314.850748)
			(xy 392.459719 -314.802964) (xy 392.47901 -314.757688) (xy 392.505313 -314.716092) (xy 392.537948 -314.679255)
			(xy 392.576069 -314.64813) (xy 392.61869 -314.623523) (xy 392.664706 -314.606071) (xy 392.712925 -314.596227)
			(xy 392.7621 -314.594246) (xy 392.810955 -314.600178) (xy 392.858226 -314.61387) (xy 392.902688 -314.634968)
			(xy 392.943191 -314.662924) (xy 392.978684 -314.697016) (xy 393.008249 -314.73636) (xy 393.03112 -314.779937)
			(xy 393.046704 -314.826618) (xy 393.054599 -314.875195) (xy 393.055094 -314.899802) (xy 393.394196 -314.899802)
			(xy 393.398156 -314.850748) (xy 393.409933 -314.802964) (xy 393.429224 -314.757688) (xy 393.455527 -314.716092)
			(xy 393.488162 -314.679255) (xy 393.526283 -314.64813) (xy 393.568904 -314.623523) (xy 393.61492 -314.606071)
			(xy 393.663139 -314.596227) (xy 393.712314 -314.594246) (xy 393.761169 -314.600178) (xy 393.80844 -314.61387)
			(xy 393.852902 -314.634968) (xy 393.893405 -314.662924) (xy 393.928898 -314.697016) (xy 393.958463 -314.73636)
			(xy 393.981334 -314.779937) (xy 393.996918 -314.826618) (xy 394.004813 -314.875195) (xy 394.005308 -314.899802)
			(xy 394.344156 -314.899802) (xy 394.348116 -314.850748) (xy 394.359893 -314.802964) (xy 394.379184 -314.757688)
			(xy 394.405487 -314.716092) (xy 394.438122 -314.679255) (xy 394.476243 -314.64813) (xy 394.518864 -314.623523)
			(xy 394.56488 -314.606071) (xy 394.613099 -314.596227) (xy 394.662274 -314.594246) (xy 394.711129 -314.600178)
			(xy 394.7584 -314.61387) (xy 394.802862 -314.634968) (xy 394.843365 -314.662924) (xy 394.878858 -314.697016)
			(xy 394.908423 -314.73636) (xy 394.931294 -314.779937) (xy 394.946878 -314.826618) (xy 394.954773 -314.875195)
			(xy 394.955268 -314.899802) (xy 395.294116 -314.899802) (xy 395.298076 -314.850748) (xy 395.309853 -314.802964)
			(xy 395.329144 -314.757688) (xy 395.355447 -314.716092) (xy 395.388082 -314.679255) (xy 395.426203 -314.64813)
			(xy 395.468824 -314.623523) (xy 395.51484 -314.606071) (xy 395.563059 -314.596227) (xy 395.612234 -314.594246)
			(xy 395.661089 -314.600178) (xy 395.70836 -314.61387) (xy 395.752822 -314.634968) (xy 395.793325 -314.662924)
			(xy 395.828818 -314.697016) (xy 395.858383 -314.73636) (xy 395.881254 -314.779937) (xy 395.896838 -314.826618)
			(xy 395.904733 -314.875195) (xy 395.905228 -314.899802) (xy 395.904733 -314.924409) (xy 395.896838 -314.972986)
			(xy 395.881254 -315.019667) (xy 395.858383 -315.063244) (xy 395.828818 -315.102588) (xy 395.793325 -315.13668)
			(xy 395.752822 -315.164636) (xy 395.70836 -315.185734) (xy 395.661089 -315.199426) (xy 395.612234 -315.205358)
			(xy 395.563059 -315.203377) (xy 395.51484 -315.193533) (xy 395.468824 -315.176081) (xy 395.426203 -315.151474)
			(xy 395.388082 -315.120349) (xy 395.355447 -315.083512) (xy 395.329144 -315.041916) (xy 395.309853 -314.99664)
			(xy 395.298076 -314.948856) (xy 395.294116 -314.899802) (xy 394.955268 -314.899802) (xy 394.954773 -314.924409)
			(xy 394.946878 -314.972986) (xy 394.931294 -315.019667) (xy 394.908423 -315.063244) (xy 394.878858 -315.102588)
			(xy 394.843365 -315.13668) (xy 394.802862 -315.164636) (xy 394.7584 -315.185734) (xy 394.711129 -315.199426)
			(xy 394.662274 -315.205358) (xy 394.613099 -315.203377) (xy 394.56488 -315.193533) (xy 394.518864 -315.176081)
			(xy 394.476243 -315.151474) (xy 394.438122 -315.120349) (xy 394.405487 -315.083512) (xy 394.379184 -315.041916)
			(xy 394.359893 -314.99664) (xy 394.348116 -314.948856) (xy 394.344156 -314.899802) (xy 394.005308 -314.899802)
			(xy 394.004813 -314.924409) (xy 393.996918 -314.972986) (xy 393.981334 -315.019667) (xy 393.958463 -315.063244)
			(xy 393.928898 -315.102588) (xy 393.893405 -315.13668) (xy 393.852902 -315.164636) (xy 393.80844 -315.185734)
			(xy 393.761169 -315.199426) (xy 393.712314 -315.205358) (xy 393.663139 -315.203377) (xy 393.61492 -315.193533)
			(xy 393.568904 -315.176081) (xy 393.526283 -315.151474) (xy 393.488162 -315.120349) (xy 393.455527 -315.083512)
			(xy 393.429224 -315.041916) (xy 393.409933 -314.99664) (xy 393.398156 -314.948856) (xy 393.394196 -314.899802)
			(xy 393.055094 -314.899802) (xy 393.054599 -314.924409) (xy 393.046704 -314.972986) (xy 393.03112 -315.019667)
			(xy 393.008249 -315.063244) (xy 392.978684 -315.102588) (xy 392.943191 -315.13668) (xy 392.902688 -315.164636)
			(xy 392.858226 -315.185734) (xy 392.810955 -315.199426) (xy 392.7621 -315.205358) (xy 392.712925 -315.203377)
			(xy 392.664706 -315.193533) (xy 392.61869 -315.176081) (xy 392.576069 -315.151474) (xy 392.537948 -315.120349)
			(xy 392.505313 -315.083512) (xy 392.47901 -315.041916) (xy 392.459719 -314.99664) (xy 392.447942 -314.948856)
			(xy 392.443982 -314.899802) (xy 392.105134 -314.899802) (xy 392.104639 -314.924409) (xy 392.096744 -314.972986)
			(xy 392.08116 -315.019667) (xy 392.058289 -315.063244) (xy 392.028724 -315.102588) (xy 391.993231 -315.13668)
			(xy 391.952728 -315.164636) (xy 391.908266 -315.185734) (xy 391.860995 -315.199426) (xy 391.81214 -315.205358)
			(xy 391.762965 -315.203377) (xy 391.714746 -315.193533) (xy 391.66873 -315.176081) (xy 391.626109 -315.151474)
			(xy 391.587988 -315.120349) (xy 391.555353 -315.083512) (xy 391.52905 -315.041916) (xy 391.509759 -314.99664)
			(xy 391.497982 -314.948856) (xy 391.494022 -314.899802) (xy 391.155174 -314.899802) (xy 391.154679 -314.924409)
			(xy 391.146784 -314.972986) (xy 391.1312 -315.019667) (xy 391.108329 -315.063244) (xy 391.078764 -315.102588)
			(xy 391.043271 -315.13668) (xy 391.002768 -315.164636) (xy 390.958306 -315.185734) (xy 390.911035 -315.199426)
			(xy 390.86218 -315.205358) (xy 390.813005 -315.203377) (xy 390.764786 -315.193533) (xy 390.71877 -315.176081)
			(xy 390.676149 -315.151474) (xy 390.638028 -315.120349) (xy 390.605393 -315.083512) (xy 390.57909 -315.041916)
			(xy 390.559799 -314.99664) (xy 390.548022 -314.948856) (xy 390.544062 -314.899802) (xy 390.205214 -314.899802)
			(xy 390.204719 -314.924409) (xy 390.196824 -314.972986) (xy 390.18124 -315.019667) (xy 390.158369 -315.063244)
			(xy 390.128804 -315.102588) (xy 390.093311 -315.13668) (xy 390.052808 -315.164636) (xy 390.008346 -315.185734)
			(xy 389.961075 -315.199426) (xy 389.91222 -315.205358) (xy 389.863045 -315.203377) (xy 389.814826 -315.193533)
			(xy 389.76881 -315.176081) (xy 389.726189 -315.151474) (xy 389.688068 -315.120349) (xy 389.655433 -315.083512)
			(xy 389.62913 -315.041916) (xy 389.609839 -314.99664) (xy 389.598062 -314.948856) (xy 389.594102 -314.899802)
			(xy 389.255254 -314.899802) (xy 389.254759 -314.924409) (xy 389.246864 -314.972986) (xy 389.23128 -315.019667)
			(xy 389.208409 -315.063244) (xy 389.178844 -315.102588) (xy 389.143351 -315.13668) (xy 389.102848 -315.164636)
			(xy 389.058386 -315.185734) (xy 389.011115 -315.199426) (xy 388.96226 -315.205358) (xy 388.913085 -315.203377)
			(xy 388.864866 -315.193533) (xy 388.81885 -315.176081) (xy 388.776229 -315.151474) (xy 388.738108 -315.120349)
			(xy 388.705473 -315.083512) (xy 388.67917 -315.041916) (xy 388.659879 -314.99664) (xy 388.648102 -314.948856)
			(xy 388.644142 -314.899802) (xy 388.305294 -314.899802) (xy 388.304799 -314.924409) (xy 388.296904 -314.972986)
			(xy 388.28132 -315.019667) (xy 388.258449 -315.063244) (xy 388.228884 -315.102588) (xy 388.193391 -315.13668)
			(xy 388.152888 -315.164636) (xy 388.108426 -315.185734) (xy 388.061155 -315.199426) (xy 388.0123 -315.205358)
			(xy 387.963125 -315.203377) (xy 387.914906 -315.193533) (xy 387.86889 -315.176081) (xy 387.826269 -315.151474)
			(xy 387.788148 -315.120349) (xy 387.755513 -315.083512) (xy 387.72921 -315.041916) (xy 387.709919 -314.99664)
			(xy 387.698142 -314.948856) (xy 387.694182 -314.899802) (xy 387.355334 -314.899802) (xy 387.354839 -314.924409)
			(xy 387.346944 -314.972986) (xy 387.33136 -315.019667) (xy 387.308489 -315.063244) (xy 387.278924 -315.102588)
			(xy 387.243431 -315.13668) (xy 387.202928 -315.164636) (xy 387.158466 -315.185734) (xy 387.111195 -315.199426)
			(xy 387.06234 -315.205358) (xy 387.013165 -315.203377) (xy 386.964946 -315.193533) (xy 386.91893 -315.176081)
			(xy 386.876309 -315.151474) (xy 386.838188 -315.120349) (xy 386.805553 -315.083512) (xy 386.77925 -315.041916)
			(xy 386.759959 -314.99664) (xy 386.748182 -314.948856) (xy 386.744222 -314.899802) (xy 386.40512 -314.899802)
			(xy 386.404625 -314.924409) (xy 386.39673 -314.972986) (xy 386.381146 -315.019667) (xy 386.358275 -315.063244)
			(xy 386.32871 -315.102588) (xy 386.293217 -315.13668) (xy 386.252714 -315.164636) (xy 386.208252 -315.185734)
			(xy 386.160981 -315.199426) (xy 386.112126 -315.205358) (xy 386.062951 -315.203377) (xy 386.014732 -315.193533)
			(xy 385.968716 -315.176081) (xy 385.926095 -315.151474) (xy 385.887974 -315.120349) (xy 385.855339 -315.083512)
			(xy 385.829036 -315.041916) (xy 385.809745 -314.99664) (xy 385.797968 -314.948856) (xy 385.794008 -314.899802)
			(xy 385.45516 -314.899802) (xy 385.454665 -314.924409) (xy 385.44677 -314.972986) (xy 385.431186 -315.019667)
			(xy 385.408315 -315.063244) (xy 385.37875 -315.102588) (xy 385.343257 -315.13668) (xy 385.302754 -315.164636)
			(xy 385.258292 -315.185734) (xy 385.211021 -315.199426) (xy 385.162166 -315.205358) (xy 385.112991 -315.203377)
			(xy 385.064772 -315.193533) (xy 385.018756 -315.176081) (xy 384.976135 -315.151474) (xy 384.938014 -315.120349)
			(xy 384.905379 -315.083512) (xy 384.879076 -315.041916) (xy 384.859785 -314.99664) (xy 384.848008 -314.948856)
			(xy 384.844048 -314.899802) (xy 384.504687 -314.899802) (xy 384.504197 -314.924155) (xy 384.496302 -314.972732)
			(xy 384.480718 -315.019413) (xy 384.457847 -315.06299) (xy 384.428282 -315.102334) (xy 384.392789 -315.136426)
			(xy 384.352286 -315.164382) (xy 384.307824 -315.18548) (xy 384.260553 -315.199172) (xy 384.211698 -315.205104)
			(xy 384.162523 -315.203123) (xy 384.114304 -315.193279) (xy 384.068288 -315.175827) (xy 384.025667 -315.15122)
			(xy 383.987546 -315.120095) (xy 383.954911 -315.083258) (xy 383.928608 -315.041662) (xy 383.909317 -314.996386)
			(xy 383.89754 -314.948602) (xy 383.89358 -314.899548) (xy 351.046796 -314.899548) (xy 351.046796 -315.849762)
			(xy 384.844048 -315.849762) (xy 384.848008 -315.800708) (xy 384.859785 -315.752924) (xy 384.879076 -315.707648)
			(xy 384.905379 -315.666052) (xy 384.938014 -315.629215) (xy 384.976135 -315.59809) (xy 385.018756 -315.573483)
			(xy 385.064772 -315.556031) (xy 385.112991 -315.546187) (xy 385.162166 -315.544206) (xy 385.211021 -315.550138)
			(xy 385.258292 -315.56383) (xy 385.302754 -315.584928) (xy 385.343257 -315.612884) (xy 385.37875 -315.646976)
			(xy 385.408315 -315.68632) (xy 385.431186 -315.729897) (xy 385.44677 -315.776578) (xy 385.454665 -315.825155)
			(xy 385.45516 -315.849762) (xy 385.794008 -315.849762) (xy 385.797968 -315.800708) (xy 385.809745 -315.752924)
			(xy 385.829036 -315.707648) (xy 385.855339 -315.666052) (xy 385.887974 -315.629215) (xy 385.926095 -315.59809)
			(xy 385.968716 -315.573483) (xy 386.014732 -315.556031) (xy 386.062951 -315.546187) (xy 386.112126 -315.544206)
			(xy 386.160981 -315.550138) (xy 386.208252 -315.56383) (xy 386.252714 -315.584928) (xy 386.293217 -315.612884)
			(xy 386.32871 -315.646976) (xy 386.358275 -315.68632) (xy 386.381146 -315.729897) (xy 386.39673 -315.776578)
			(xy 386.404625 -315.825155) (xy 386.40512 -315.849762) (xy 386.744222 -315.849762) (xy 386.748182 -315.800708)
			(xy 386.759959 -315.752924) (xy 386.77925 -315.707648) (xy 386.805553 -315.666052) (xy 386.838188 -315.629215)
			(xy 386.876309 -315.59809) (xy 386.91893 -315.573483) (xy 386.964946 -315.556031) (xy 387.013165 -315.546187)
			(xy 387.06234 -315.544206) (xy 387.111195 -315.550138) (xy 387.158466 -315.56383) (xy 387.202928 -315.584928)
			(xy 387.243431 -315.612884) (xy 387.278924 -315.646976) (xy 387.308489 -315.68632) (xy 387.33136 -315.729897)
			(xy 387.346944 -315.776578) (xy 387.354839 -315.825155) (xy 387.355334 -315.849762) (xy 387.694182 -315.849762)
			(xy 387.698142 -315.800708) (xy 387.709919 -315.752924) (xy 387.72921 -315.707648) (xy 387.755513 -315.666052)
			(xy 387.788148 -315.629215) (xy 387.826269 -315.59809) (xy 387.86889 -315.573483) (xy 387.914906 -315.556031)
			(xy 387.963125 -315.546187) (xy 388.0123 -315.544206) (xy 388.061155 -315.550138) (xy 388.108426 -315.56383)
			(xy 388.152888 -315.584928) (xy 388.193391 -315.612884) (xy 388.228884 -315.646976) (xy 388.258449 -315.68632)
			(xy 388.28132 -315.729897) (xy 388.296904 -315.776578) (xy 388.304799 -315.825155) (xy 388.305294 -315.849762)
			(xy 388.644142 -315.849762) (xy 388.648102 -315.800708) (xy 388.659879 -315.752924) (xy 388.67917 -315.707648)
			(xy 388.705473 -315.666052) (xy 388.738108 -315.629215) (xy 388.776229 -315.59809) (xy 388.81885 -315.573483)
			(xy 388.864866 -315.556031) (xy 388.913085 -315.546187) (xy 388.96226 -315.544206) (xy 389.011115 -315.550138)
			(xy 389.058386 -315.56383) (xy 389.102848 -315.584928) (xy 389.143351 -315.612884) (xy 389.178844 -315.646976)
			(xy 389.208409 -315.68632) (xy 389.23128 -315.729897) (xy 389.246864 -315.776578) (xy 389.254759 -315.825155)
			(xy 389.255254 -315.849762) (xy 389.594102 -315.849762) (xy 389.598062 -315.800708) (xy 389.609839 -315.752924)
			(xy 389.62913 -315.707648) (xy 389.655433 -315.666052) (xy 389.688068 -315.629215) (xy 389.726189 -315.59809)
			(xy 389.76881 -315.573483) (xy 389.814826 -315.556031) (xy 389.863045 -315.546187) (xy 389.91222 -315.544206)
			(xy 389.961075 -315.550138) (xy 390.008346 -315.56383) (xy 390.052808 -315.584928) (xy 390.093311 -315.612884)
			(xy 390.128804 -315.646976) (xy 390.158369 -315.68632) (xy 390.18124 -315.729897) (xy 390.196824 -315.776578)
			(xy 390.204719 -315.825155) (xy 390.205214 -315.849762) (xy 390.544062 -315.849762) (xy 390.548022 -315.800708)
			(xy 390.559799 -315.752924) (xy 390.57909 -315.707648) (xy 390.605393 -315.666052) (xy 390.638028 -315.629215)
			(xy 390.676149 -315.59809) (xy 390.71877 -315.573483) (xy 390.764786 -315.556031) (xy 390.813005 -315.546187)
			(xy 390.86218 -315.544206) (xy 390.911035 -315.550138) (xy 390.958306 -315.56383) (xy 391.002768 -315.584928)
			(xy 391.043271 -315.612884) (xy 391.078764 -315.646976) (xy 391.108329 -315.68632) (xy 391.1312 -315.729897)
			(xy 391.146784 -315.776578) (xy 391.154679 -315.825155) (xy 391.155174 -315.849762) (xy 391.494022 -315.849762)
			(xy 391.497982 -315.800708) (xy 391.509759 -315.752924) (xy 391.52905 -315.707648) (xy 391.555353 -315.666052)
			(xy 391.587988 -315.629215) (xy 391.626109 -315.59809) (xy 391.66873 -315.573483) (xy 391.714746 -315.556031)
			(xy 391.762965 -315.546187) (xy 391.81214 -315.544206) (xy 391.860995 -315.550138) (xy 391.908266 -315.56383)
			(xy 391.952728 -315.584928) (xy 391.993231 -315.612884) (xy 392.028724 -315.646976) (xy 392.058289 -315.68632)
			(xy 392.08116 -315.729897) (xy 392.096744 -315.776578) (xy 392.104639 -315.825155) (xy 392.105134 -315.849762)
			(xy 392.443982 -315.849762) (xy 392.447942 -315.800708) (xy 392.459719 -315.752924) (xy 392.47901 -315.707648)
			(xy 392.505313 -315.666052) (xy 392.537948 -315.629215) (xy 392.576069 -315.59809) (xy 392.61869 -315.573483)
			(xy 392.664706 -315.556031) (xy 392.712925 -315.546187) (xy 392.7621 -315.544206) (xy 392.810955 -315.550138)
			(xy 392.858226 -315.56383) (xy 392.902688 -315.584928) (xy 392.943191 -315.612884) (xy 392.978684 -315.646976)
			(xy 393.008249 -315.68632) (xy 393.03112 -315.729897) (xy 393.046704 -315.776578) (xy 393.054599 -315.825155)
			(xy 393.055094 -315.849762) (xy 393.394196 -315.849762) (xy 393.398156 -315.800708) (xy 393.409933 -315.752924)
			(xy 393.429224 -315.707648) (xy 393.455527 -315.666052) (xy 393.488162 -315.629215) (xy 393.526283 -315.59809)
			(xy 393.568904 -315.573483) (xy 393.61492 -315.556031) (xy 393.663139 -315.546187) (xy 393.712314 -315.544206)
			(xy 393.761169 -315.550138) (xy 393.80844 -315.56383) (xy 393.852902 -315.584928) (xy 393.893405 -315.612884)
			(xy 393.928898 -315.646976) (xy 393.958463 -315.68632) (xy 393.981334 -315.729897) (xy 393.996918 -315.776578)
			(xy 394.004813 -315.825155) (xy 394.005308 -315.849762) (xy 394.344156 -315.849762) (xy 394.348116 -315.800708)
			(xy 394.359893 -315.752924) (xy 394.379184 -315.707648) (xy 394.405487 -315.666052) (xy 394.438122 -315.629215)
			(xy 394.476243 -315.59809) (xy 394.518864 -315.573483) (xy 394.56488 -315.556031) (xy 394.613099 -315.546187)
			(xy 394.662274 -315.544206) (xy 394.711129 -315.550138) (xy 394.7584 -315.56383) (xy 394.802862 -315.584928)
			(xy 394.843365 -315.612884) (xy 394.878858 -315.646976) (xy 394.908423 -315.68632) (xy 394.931294 -315.729897)
			(xy 394.946878 -315.776578) (xy 394.954773 -315.825155) (xy 394.955268 -315.849762) (xy 395.294116 -315.849762)
			(xy 395.298076 -315.800708) (xy 395.309853 -315.752924) (xy 395.329144 -315.707648) (xy 395.355447 -315.666052)
			(xy 395.388082 -315.629215) (xy 395.426203 -315.59809) (xy 395.468824 -315.573483) (xy 395.51484 -315.556031)
			(xy 395.563059 -315.546187) (xy 395.612234 -315.544206) (xy 395.661089 -315.550138) (xy 395.70836 -315.56383)
			(xy 395.752822 -315.584928) (xy 395.793325 -315.612884) (xy 395.828818 -315.646976) (xy 395.858383 -315.68632)
			(xy 395.881254 -315.729897) (xy 395.896838 -315.776578) (xy 395.904733 -315.825155) (xy 395.905228 -315.849762)
			(xy 395.904733 -315.874369) (xy 395.896838 -315.922946) (xy 395.881254 -315.969627) (xy 395.858383 -316.013204)
			(xy 395.828818 -316.052548) (xy 395.793325 -316.08664) (xy 395.752822 -316.114596) (xy 395.70836 -316.135694)
			(xy 395.661089 -316.149386) (xy 395.612234 -316.155318) (xy 395.563059 -316.153337) (xy 395.51484 -316.143493)
			(xy 395.468824 -316.126041) (xy 395.426203 -316.101434) (xy 395.388082 -316.070309) (xy 395.355447 -316.033472)
			(xy 395.329144 -315.991876) (xy 395.309853 -315.9466) (xy 395.298076 -315.898816) (xy 395.294116 -315.849762)
			(xy 394.955268 -315.849762) (xy 394.954773 -315.874369) (xy 394.946878 -315.922946) (xy 394.931294 -315.969627)
			(xy 394.908423 -316.013204) (xy 394.878858 -316.052548) (xy 394.843365 -316.08664) (xy 394.802862 -316.114596)
			(xy 394.7584 -316.135694) (xy 394.711129 -316.149386) (xy 394.662274 -316.155318) (xy 394.613099 -316.153337)
			(xy 394.56488 -316.143493) (xy 394.518864 -316.126041) (xy 394.476243 -316.101434) (xy 394.438122 -316.070309)
			(xy 394.405487 -316.033472) (xy 394.379184 -315.991876) (xy 394.359893 -315.9466) (xy 394.348116 -315.898816)
			(xy 394.344156 -315.849762) (xy 394.005308 -315.849762) (xy 394.004813 -315.874369) (xy 393.996918 -315.922946)
			(xy 393.981334 -315.969627) (xy 393.958463 -316.013204) (xy 393.928898 -316.052548) (xy 393.893405 -316.08664)
			(xy 393.852902 -316.114596) (xy 393.80844 -316.135694) (xy 393.761169 -316.149386) (xy 393.712314 -316.155318)
			(xy 393.663139 -316.153337) (xy 393.61492 -316.143493) (xy 393.568904 -316.126041) (xy 393.526283 -316.101434)
			(xy 393.488162 -316.070309) (xy 393.455527 -316.033472) (xy 393.429224 -315.991876) (xy 393.409933 -315.9466)
			(xy 393.398156 -315.898816) (xy 393.394196 -315.849762) (xy 393.055094 -315.849762) (xy 393.054599 -315.874369)
			(xy 393.046704 -315.922946) (xy 393.03112 -315.969627) (xy 393.008249 -316.013204) (xy 392.978684 -316.052548)
			(xy 392.943191 -316.08664) (xy 392.902688 -316.114596) (xy 392.858226 -316.135694) (xy 392.810955 -316.149386)
			(xy 392.7621 -316.155318) (xy 392.712925 -316.153337) (xy 392.664706 -316.143493) (xy 392.61869 -316.126041)
			(xy 392.576069 -316.101434) (xy 392.537948 -316.070309) (xy 392.505313 -316.033472) (xy 392.47901 -315.991876)
			(xy 392.459719 -315.9466) (xy 392.447942 -315.898816) (xy 392.443982 -315.849762) (xy 392.105134 -315.849762)
			(xy 392.104639 -315.874369) (xy 392.096744 -315.922946) (xy 392.08116 -315.969627) (xy 392.058289 -316.013204)
			(xy 392.028724 -316.052548) (xy 391.993231 -316.08664) (xy 391.952728 -316.114596) (xy 391.908266 -316.135694)
			(xy 391.860995 -316.149386) (xy 391.81214 -316.155318) (xy 391.762965 -316.153337) (xy 391.714746 -316.143493)
			(xy 391.66873 -316.126041) (xy 391.626109 -316.101434) (xy 391.587988 -316.070309) (xy 391.555353 -316.033472)
			(xy 391.52905 -315.991876) (xy 391.509759 -315.9466) (xy 391.497982 -315.898816) (xy 391.494022 -315.849762)
			(xy 391.155174 -315.849762) (xy 391.154679 -315.874369) (xy 391.146784 -315.922946) (xy 391.1312 -315.969627)
			(xy 391.108329 -316.013204) (xy 391.078764 -316.052548) (xy 391.043271 -316.08664) (xy 391.002768 -316.114596)
			(xy 390.958306 -316.135694) (xy 390.911035 -316.149386) (xy 390.86218 -316.155318) (xy 390.813005 -316.153337)
			(xy 390.764786 -316.143493) (xy 390.71877 -316.126041) (xy 390.676149 -316.101434) (xy 390.638028 -316.070309)
			(xy 390.605393 -316.033472) (xy 390.57909 -315.991876) (xy 390.559799 -315.9466) (xy 390.548022 -315.898816)
			(xy 390.544062 -315.849762) (xy 390.205214 -315.849762) (xy 390.204719 -315.874369) (xy 390.196824 -315.922946)
			(xy 390.18124 -315.969627) (xy 390.158369 -316.013204) (xy 390.128804 -316.052548) (xy 390.093311 -316.08664)
			(xy 390.052808 -316.114596) (xy 390.008346 -316.135694) (xy 389.961075 -316.149386) (xy 389.91222 -316.155318)
			(xy 389.863045 -316.153337) (xy 389.814826 -316.143493) (xy 389.76881 -316.126041) (xy 389.726189 -316.101434)
			(xy 389.688068 -316.070309) (xy 389.655433 -316.033472) (xy 389.62913 -315.991876) (xy 389.609839 -315.9466)
			(xy 389.598062 -315.898816) (xy 389.594102 -315.849762) (xy 389.255254 -315.849762) (xy 389.254759 -315.874369)
			(xy 389.246864 -315.922946) (xy 389.23128 -315.969627) (xy 389.208409 -316.013204) (xy 389.178844 -316.052548)
			(xy 389.143351 -316.08664) (xy 389.102848 -316.114596) (xy 389.058386 -316.135694) (xy 389.011115 -316.149386)
			(xy 388.96226 -316.155318) (xy 388.913085 -316.153337) (xy 388.864866 -316.143493) (xy 388.81885 -316.126041)
			(xy 388.776229 -316.101434) (xy 388.738108 -316.070309) (xy 388.705473 -316.033472) (xy 388.67917 -315.991876)
			(xy 388.659879 -315.9466) (xy 388.648102 -315.898816) (xy 388.644142 -315.849762) (xy 388.305294 -315.849762)
			(xy 388.304799 -315.874369) (xy 388.296904 -315.922946) (xy 388.28132 -315.969627) (xy 388.258449 -316.013204)
			(xy 388.228884 -316.052548) (xy 388.193391 -316.08664) (xy 388.152888 -316.114596) (xy 388.108426 -316.135694)
			(xy 388.061155 -316.149386) (xy 388.0123 -316.155318) (xy 387.963125 -316.153337) (xy 387.914906 -316.143493)
			(xy 387.86889 -316.126041) (xy 387.826269 -316.101434) (xy 387.788148 -316.070309) (xy 387.755513 -316.033472)
			(xy 387.72921 -315.991876) (xy 387.709919 -315.9466) (xy 387.698142 -315.898816) (xy 387.694182 -315.849762)
			(xy 387.355334 -315.849762) (xy 387.354839 -315.874369) (xy 387.346944 -315.922946) (xy 387.33136 -315.969627)
			(xy 387.308489 -316.013204) (xy 387.278924 -316.052548) (xy 387.243431 -316.08664) (xy 387.202928 -316.114596)
			(xy 387.158466 -316.135694) (xy 387.111195 -316.149386) (xy 387.06234 -316.155318) (xy 387.013165 -316.153337)
			(xy 386.964946 -316.143493) (xy 386.91893 -316.126041) (xy 386.876309 -316.101434) (xy 386.838188 -316.070309)
			(xy 386.805553 -316.033472) (xy 386.77925 -315.991876) (xy 386.759959 -315.9466) (xy 386.748182 -315.898816)
			(xy 386.744222 -315.849762) (xy 386.40512 -315.849762) (xy 386.404625 -315.874369) (xy 386.39673 -315.922946)
			(xy 386.381146 -315.969627) (xy 386.358275 -316.013204) (xy 386.32871 -316.052548) (xy 386.293217 -316.08664)
			(xy 386.252714 -316.114596) (xy 386.208252 -316.135694) (xy 386.160981 -316.149386) (xy 386.112126 -316.155318)
			(xy 386.062951 -316.153337) (xy 386.014732 -316.143493) (xy 385.968716 -316.126041) (xy 385.926095 -316.101434)
			(xy 385.887974 -316.070309) (xy 385.855339 -316.033472) (xy 385.829036 -315.991876) (xy 385.809745 -315.9466)
			(xy 385.797968 -315.898816) (xy 385.794008 -315.849762) (xy 385.45516 -315.849762) (xy 385.454665 -315.874369)
			(xy 385.44677 -315.922946) (xy 385.431186 -315.969627) (xy 385.408315 -316.013204) (xy 385.37875 -316.052548)
			(xy 385.343257 -316.08664) (xy 385.302754 -316.114596) (xy 385.258292 -316.135694) (xy 385.211021 -316.149386)
			(xy 385.162166 -316.155318) (xy 385.112991 -316.153337) (xy 385.064772 -316.143493) (xy 385.018756 -316.126041)
			(xy 384.976135 -316.101434) (xy 384.938014 -316.070309) (xy 384.905379 -316.033472) (xy 384.879076 -315.991876)
			(xy 384.859785 -315.9466) (xy 384.848008 -315.898816) (xy 384.844048 -315.849762) (xy 351.046796 -315.849762)
			(xy 351.046796 -317.108078) (xy 351.047812 -317.11773) (xy 351.049436 -317.124976) (xy 351.056272 -317.138151)
			(xy 351.061274 -317.143638) (xy 351.775014 -317.857378) (xy 351.780511 -317.862369) (xy 351.793677 -317.869219)
			(xy 351.800922 -317.87084) (xy 351.810574 -317.871856) (xy 373.917718 -317.871856)
		)
		(stroke
			(width 0)
			(type solid)
		)
		(fill yes)
		(layer "In7.Cu")
		(net "P0V8_PEX3")
	)
	(gr_poly
		(pts
			(xy 52.468526 -416.221418) (xy 52.469034 -416.221418) (xy 52.476553 -416.219817) (xy 52.490242 -416.212842)
			(xy 52.495958 -416.207702) (xy 52.64658 -416.05708) (xy 52.65157 -416.051582) (xy 52.658418 -416.038416)
			(xy 52.660042 -416.031172) (xy 52.661058 -416.02152) (xy 52.661058 -394.452856) (xy 52.661491 -394.442791)
			(xy 52.669223 -394.424203) (xy 52.676044 -394.416788) (xy 52.87518 -394.217652) (xy 52.88258 -394.210812)
			(xy 52.901179 -394.203099) (xy 52.911248 -394.202666) (xy 66.492882 -394.202666) (xy 66.502944 -394.203106)
			(xy 66.521521 -394.210849) (xy 66.52895 -394.217652) (xy 66.56197 -394.250672) (xy 66.568808 -394.258073)
			(xy 66.576521 -394.276672) (xy 66.576956 -394.28674) (xy 66.576956 -409.490164) (xy 71.424292 -409.490164)
			(xy 71.424865 -409.457435) (xy 71.433719 -409.392577) (xy 71.451207 -409.329497) (xy 71.477013 -409.269338)
			(xy 71.49338 -409.24099) (xy 71.496697 -409.234966) (xy 71.500302 -409.221702) (xy 71.500492 -409.214828)
			(xy 71.500492 -408.465528) (xy 71.50029 -408.458655) (xy 71.496689 -408.445393) (xy 71.49338 -408.439366)
			(xy 71.476999 -408.411025) (xy 71.451201 -408.350863) (xy 71.433716 -408.28778) (xy 71.42486 -408.222922)
			(xy 71.424292 -408.190192) (xy 71.424878 -408.157463) (xy 71.433728 -408.092606) (xy 71.451212 -408.029526)
			(xy 71.477014 -407.969367) (xy 71.49338 -407.941018) (xy 71.496687 -407.934989) (xy 71.500298 -407.921729)
			(xy 71.500492 -407.914856) (xy 71.500492 -407.628852) (xy 71.500946 -407.618741) (xy 71.508698 -407.600063)
			(xy 71.523004 -407.585771) (xy 71.541689 -407.578036) (xy 71.5518 -407.577544) (xy 72.26808 -407.577544)
			(xy 72.278181 -407.5781) (xy 72.296848 -407.585821) (xy 72.311141 -407.600095) (xy 72.318887 -407.618752)
			(xy 72.319388 -407.628852) (xy 72.319388 -407.914856) (xy 72.319599 -407.921728) (xy 72.323194 -407.93499)
			(xy 72.3265 -407.941018) (xy 72.342873 -407.969363) (xy 72.368673 -408.029524) (xy 72.38616 -408.092605)
			(xy 72.395019 -408.157463) (xy 72.395588 -408.190192) (xy 72.395043 -408.222922) (xy 72.386181 -408.287781)
			(xy 72.368685 -408.350861) (xy 72.342871 -408.411019) (xy 72.3265 -408.439366) (xy 72.323197 -408.445397)
			(xy 72.319584 -408.458656) (xy 72.319388 -408.465528) (xy 72.319388 -409.214828) (xy 72.319571 -409.221702)
			(xy 72.323185 -409.234965) (xy 72.3265 -409.24099) (xy 72.342862 -409.269341) (xy 72.368664 -409.3295)
			(xy 72.386155 -409.392579) (xy 72.395017 -409.457435) (xy 72.395588 -409.490164) (xy 72.39503 -409.522894)
			(xy 72.386172 -409.587752) (xy 72.36868 -409.650833) (xy 72.34287 -409.71099) (xy 72.3265 -409.739338)
			(xy 72.323172 -409.745356) (xy 72.319575 -409.758625) (xy 72.319388 -409.7655) (xy 72.319388 -410.051504)
			(xy 72.318987 -410.061628) (xy 72.311235 -410.080334) (xy 72.296914 -410.094649) (xy 72.278204 -410.102392)
			(xy 72.26808 -410.102812) (xy 71.5518 -410.102812) (xy 71.541693 -410.102315) (xy 71.523017 -410.09458)
			(xy 71.508723 -410.080286) (xy 71.500986 -410.061611) (xy 71.500492 -410.051504) (xy 71.500492 -409.7655)
			(xy 71.500301 -409.758627) (xy 71.496692 -409.745364) (xy 71.49338 -409.739338) (xy 71.477028 -409.710982)
			(xy 71.451223 -409.650824) (xy 71.43373 -409.587747) (xy 71.424865 -409.522892) (xy 71.424292 -409.490164)
			(xy 66.576956 -409.490164) (xy 66.576956 -410.622705) (xy 73.624782 -410.622705) (xy 73.624784 -410.557267)
			(xy 73.633569 -410.492422) (xy 73.650979 -410.429343) (xy 73.676697 -410.369171) (xy 73.69302 -410.34081)
			(xy 73.696333 -410.334784) (xy 73.699939 -410.321521) (xy 73.700132 -410.314648) (xy 73.700132 -409.565348)
			(xy 73.699918 -409.558476) (xy 73.696324 -409.545214) (xy 73.69302 -409.539186) (xy 73.676709 -409.510819)
			(xy 73.650991 -409.450649) (xy 73.633582 -409.387571) (xy 73.624798 -409.322728) (xy 73.624797 -409.257292)
			(xy 73.633578 -409.192449) (xy 73.650984 -409.129371) (xy 73.676699 -409.069199) (xy 73.69302 -409.040838)
			(xy 73.696323 -409.034807) (xy 73.699936 -409.021548) (xy 73.700132 -409.014676) (xy 73.700132 -408.728672)
			(xy 73.700499 -408.718512) (xy 73.70831 -408.699753) (xy 73.722724 -408.685429) (xy 73.741532 -408.677736)
			(xy 73.751694 -408.677364) (xy 74.467974 -408.677364) (xy 74.478102 -408.677848) (xy 74.496827 -408.685572)
			(xy 74.511185 -408.69986) (xy 74.519001 -408.718546) (xy 74.519536 -408.728672) (xy 74.519536 -409.014676)
			(xy 74.519733 -409.021549) (xy 74.523337 -409.034812) (xy 74.526648 -409.040838) (xy 74.542981 -409.069194)
			(xy 74.568698 -409.129366) (xy 74.586106 -409.192446) (xy 74.594888 -409.257291) (xy 74.594887 -409.322729)
			(xy 74.586101 -409.387574) (xy 74.568691 -409.450654) (xy 74.542971 -409.510825) (xy 74.536028 -409.522889)
			(xy 75.824912 -409.522889) (xy 75.824916 -409.457449) (xy 75.833705 -409.392603) (xy 75.851119 -409.329523)
			(xy 75.876842 -409.269351) (xy 75.893168 -409.24099) (xy 75.896484 -409.234966) (xy 75.900089 -409.221702)
			(xy 75.90028 -409.214828) (xy 75.90028 -408.465528) (xy 75.90008 -408.458655) (xy 75.896477 -408.445393)
			(xy 75.893168 -408.439366) (xy 75.876838 -408.411009) (xy 75.85112 -408.350837) (xy 75.833711 -408.287757)
			(xy 75.824928 -408.222912) (xy 75.824929 -408.157474) (xy 75.833714 -408.092629) (xy 75.851124 -408.02955)
			(xy 75.876844 -407.969379) (xy 75.893168 -407.941018) (xy 75.896474 -407.934989) (xy 75.900085 -407.921729)
			(xy 75.90028 -407.914856) (xy 75.90028 -407.628852) (xy 75.900682 -407.618697) (xy 75.90849 -407.599948)
			(xy 75.922892 -407.585627) (xy 75.941685 -407.577925) (xy 75.951842 -407.577544) (xy 76.668122 -407.577544)
			(xy 76.678251 -407.578008) (xy 76.696973 -407.585744) (xy 76.711329 -407.600037) (xy 76.719147 -407.618726)
			(xy 76.719684 -407.628852) (xy 76.719684 -407.914856) (xy 76.719895 -407.921728) (xy 76.72349 -407.934991)
			(xy 76.726796 -407.941018) (xy 76.74311 -407.969383) (xy 76.768827 -408.029554) (xy 76.786234 -408.092632)
			(xy 76.795018 -408.157475) (xy 76.795019 -408.222911) (xy 76.786237 -408.287755) (xy 76.768831 -408.350833)
			(xy 76.743117 -408.411004) (xy 76.726796 -408.439366) (xy 76.723493 -408.445396) (xy 76.71988 -408.458656)
			(xy 76.719684 -408.465528) (xy 76.719684 -409.214828) (xy 76.719867 -409.221702) (xy 76.723482 -409.234965)
			(xy 76.726796 -409.24099) (xy 76.743087 -409.269368) (xy 76.768805 -409.329536) (xy 76.786215 -409.392611)
			(xy 76.795002 -409.457452) (xy 76.795006 -409.522886) (xy 76.786228 -409.587728) (xy 76.768826 -409.650806)
			(xy 76.743115 -409.710976) (xy 76.726796 -409.739338) (xy 76.723467 -409.745356) (xy 76.719871 -409.758625)
			(xy 76.719684 -409.7655) (xy 76.719684 -410.051504) (xy 76.719281 -410.06166) (xy 76.711481 -410.080416)
			(xy 76.697079 -410.09474) (xy 76.678281 -410.102436) (xy 76.668122 -410.102812) (xy 75.951842 -410.102812)
			(xy 75.941724 -410.10224) (xy 75.923014 -410.094536) (xy 75.908658 -410.080276) (xy 75.900828 -410.061618)
			(xy 75.90028 -410.051504) (xy 75.90028 -409.7655) (xy 75.90009 -409.758627) (xy 75.896481 -409.745364)
			(xy 75.893168 -409.739338) (xy 75.876814 -409.710994) (xy 75.851098 -409.650819) (xy 75.833692 -409.587737)
			(xy 75.824912 -409.522889) (xy 74.536028 -409.522889) (xy 74.526648 -409.539186) (xy 74.523342 -409.545215)
			(xy 74.51973 -409.558475) (xy 74.519536 -409.565348) (xy 74.519536 -410.314648) (xy 74.519743 -410.32152)
			(xy 74.523341 -410.334783) (xy 74.526648 -410.34081) (xy 74.542957 -410.369179) (xy 74.568677 -410.429348)
			(xy 74.586087 -410.492425) (xy 74.594872 -410.557268) (xy 74.594873 -410.589984) (xy 78.024228 -410.589984)
			(xy 78.024819 -410.557255) (xy 78.033669 -410.492398) (xy 78.051152 -410.429318) (xy 78.076951 -410.369159)
			(xy 78.093316 -410.34081) (xy 78.096628 -410.334784) (xy 78.100235 -410.321521) (xy 78.100428 -410.314648)
			(xy 78.100428 -409.565348) (xy 78.100214 -409.558476) (xy 78.096621 -409.545214) (xy 78.093316 -409.539186)
			(xy 78.076946 -409.510839) (xy 78.051145 -409.450679) (xy 78.033657 -409.387599) (xy 78.024798 -409.322741)
			(xy 78.024228 -409.290012) (xy 78.024787 -409.257282) (xy 78.033646 -409.192424) (xy 78.051139 -409.129344)
			(xy 78.076947 -409.069186) (xy 78.093316 -409.040838) (xy 78.096618 -409.034807) (xy 78.100232 -409.021548)
			(xy 78.100428 -409.014676) (xy 78.100428 -408.728672) (xy 78.100794 -408.718544) (xy 78.108556 -408.699835)
			(xy 78.122888 -408.68552) (xy 78.141608 -408.677781) (xy 78.151736 -408.677364) (xy 78.868016 -408.677364)
			(xy 78.878121 -408.677871) (xy 78.896793 -408.685608) (xy 78.911086 -408.699897) (xy 78.918826 -408.718567)
			(xy 78.919324 -408.728672) (xy 78.919324 -409.014676) (xy 78.919522 -409.021549) (xy 78.923126 -409.034812)
			(xy 78.926436 -409.040838) (xy 78.942811 -409.069182) (xy 78.968612 -409.129343) (xy 78.986099 -409.192424)
			(xy 78.994956 -409.257282) (xy 78.995524 -409.290012) (xy 78.994938 -409.322741) (xy 78.986088 -409.387598)
			(xy 78.968603 -409.450678) (xy 78.951668 -409.490164) (xy 80.224376 -409.490164) (xy 80.224951 -409.457435)
			(xy 80.233805 -409.392577) (xy 80.251293 -409.329497) (xy 80.277097 -409.269339) (xy 80.293464 -409.24099)
			(xy 80.296779 -409.234966) (xy 80.300385 -409.221702) (xy 80.300576 -409.214828) (xy 80.300576 -408.465528)
			(xy 80.300376 -408.458655) (xy 80.296774 -408.445392) (xy 80.293464 -408.439366) (xy 80.277091 -408.411021)
			(xy 80.25129 -408.35086) (xy 80.233802 -408.287779) (xy 80.224944 -408.222921) (xy 80.224376 -408.190192)
			(xy 80.224964 -408.157463) (xy 80.233814 -408.092606) (xy 80.251298 -408.029526) (xy 80.277099 -407.969367)
			(xy 80.293464 -407.941018) (xy 80.296769 -407.934989) (xy 80.300381 -407.921729) (xy 80.300576 -407.914856)
			(xy 80.300576 -407.628852) (xy 80.301045 -407.618743) (xy 80.308794 -407.600069) (xy 80.323095 -407.585776)
			(xy 80.341775 -407.578039) (xy 80.351884 -407.577544) (xy 81.068164 -407.577544) (xy 81.078264 -407.578113)
			(xy 81.09693 -407.585829) (xy 81.111224 -407.600099) (xy 81.11897 -407.618753) (xy 81.119472 -407.628852)
			(xy 81.119472 -407.914856) (xy 81.119684 -407.921728) (xy 81.123279 -407.93499) (xy 81.126584 -407.941018)
			(xy 81.142955 -407.969364) (xy 81.168756 -408.029525) (xy 81.186244 -408.092605) (xy 81.195103 -408.157463)
			(xy 81.195672 -408.190192) (xy 81.195115 -408.222922) (xy 81.186255 -408.28778) (xy 81.168762 -408.35086)
			(xy 81.142953 -408.411018) (xy 81.126584 -408.439366) (xy 81.12328 -408.445396) (xy 81.119668 -408.458656)
			(xy 81.119472 -408.465528) (xy 81.119472 -409.214828) (xy 81.119657 -409.221702) (xy 81.12327 -409.234964)
			(xy 81.126584 -409.24099) (xy 81.142944 -409.269342) (xy 81.168748 -409.329501) (xy 81.186239 -409.392579)
			(xy 81.195101 -409.457435) (xy 81.195672 -409.490164) (xy 81.195103 -409.522893) (xy 81.186246 -409.587751)
			(xy 81.168757 -409.650831) (xy 81.142952 -409.71099) (xy 81.126584 -409.739338) (xy 81.123255 -409.745355)
			(xy 81.119659 -409.758625) (xy 81.119472 -409.7655) (xy 81.119472 -410.051504) (xy 81.119086 -410.06163)
			(xy 81.111332 -410.080339) (xy 81.097006 -410.094654) (xy 81.078291 -410.102394) (xy 81.068164 -410.102812)
			(xy 80.351884 -410.102812) (xy 80.341776 -410.102328) (xy 80.3231 -410.094587) (xy 80.308806 -410.08029)
			(xy 80.30107 -410.061612) (xy 80.300576 -410.051504) (xy 80.300576 -409.7655) (xy 80.300387 -409.758627)
			(xy 80.296777 -409.745364) (xy 80.293464 -409.739338) (xy 80.27712 -409.710977) (xy 80.251311 -409.650822)
			(xy 80.233815 -409.587746) (xy 80.224949 -409.522892) (xy 80.224376 -409.490164) (xy 78.951668 -409.490164)
			(xy 78.942802 -409.510837) (xy 78.926436 -409.539186) (xy 78.923129 -409.545215) (xy 78.919518 -409.558475)
			(xy 78.919324 -409.565348) (xy 78.919324 -410.314648) (xy 78.919533 -410.32152) (xy 78.923129 -410.334783)
			(xy 78.926436 -410.34081) (xy 78.942799 -410.369161) (xy 78.968603 -410.429319) (xy 78.986094 -410.492398)
			(xy 78.994954 -410.557255) (xy 78.995524 -410.589984) (xy 78.99497 -410.622705) (xy 82.424868 -410.622705)
			(xy 82.42487 -410.557268) (xy 82.433655 -410.492423) (xy 82.451064 -410.429343) (xy 82.476782 -410.369172)
			(xy 82.493104 -410.34081) (xy 82.496415 -410.334784) (xy 82.500023 -410.321521) (xy 82.500216 -410.314648)
			(xy 82.500216 -409.565348) (xy 82.500003 -409.558476) (xy 82.496409 -409.545214) (xy 82.493104 -409.539186)
			(xy 82.476793 -409.510819) (xy 82.451076 -409.450649) (xy 82.433668 -409.387571) (xy 82.424884 -409.322728)
			(xy 82.424883 -409.257293) (xy 82.433664 -409.192449) (xy 82.451069 -409.129371) (xy 82.476784 -409.0692)
			(xy 82.493104 -409.040838) (xy 82.496406 -409.034807) (xy 82.500019 -409.021548) (xy 82.500216 -409.014676)
			(xy 82.500216 -408.728672) (xy 82.500599 -408.718514) (xy 82.508407 -408.699758) (xy 82.522815 -408.685435)
			(xy 82.541618 -408.677739) (xy 82.551778 -408.677364) (xy 83.268058 -408.677364) (xy 83.278185 -408.677862)
			(xy 83.29691 -408.68558) (xy 83.311268 -408.699864) (xy 83.319085 -408.718548) (xy 83.31962 -408.728672)
			(xy 83.31962 -409.014676) (xy 83.319819 -409.021549) (xy 83.323422 -409.034812) (xy 83.326732 -409.040838)
			(xy 83.343065 -409.069193) (xy 83.368783 -409.129366) (xy 83.386192 -409.192446) (xy 83.394974 -409.257291)
			(xy 83.394973 -409.322729) (xy 83.386187 -409.387575) (xy 83.368777 -409.450654) (xy 83.351888 -409.490164)
			(xy 84.624164 -409.490164) (xy 84.624741 -409.457435) (xy 84.633594 -409.392577) (xy 84.651081 -409.329497)
			(xy 84.676885 -409.269338) (xy 84.693252 -409.24099) (xy 84.696566 -409.234965) (xy 84.700173 -409.221702)
			(xy 84.700364 -409.214828) (xy 84.700364 -408.465528) (xy 84.700166 -408.458655) (xy 84.696562 -408.445392)
			(xy 84.693252 -408.439366) (xy 84.676878 -408.411021) (xy 84.651077 -408.350861) (xy 84.633589 -408.28778)
			(xy 84.624732 -408.222921) (xy 84.624164 -408.190192) (xy 84.624754 -408.157463) (xy 84.633603 -408.092606)
			(xy 84.651087 -408.029526) (xy 84.676887 -407.969367) (xy 84.693252 -407.941018) (xy 84.696556 -407.934988)
			(xy 84.700169 -407.921729) (xy 84.700364 -407.914856) (xy 84.700364 -407.628852) (xy 84.700845 -407.618745)
			(xy 84.708592 -407.600072) (xy 84.722889 -407.585781) (xy 84.741564 -407.578041) (xy 84.751672 -407.577544)
			(xy 85.467952 -407.577544) (xy 85.478051 -407.578123) (xy 85.496717 -407.585835) (xy 85.511012 -407.600102)
			(xy 85.518758 -407.618754) (xy 85.51926 -407.628852) (xy 85.51926 -407.914856) (xy 85.519474 -407.921728)
			(xy 85.523068 -407.93499) (xy 85.526372 -407.941018) (xy 85.542742 -407.969365) (xy 85.568543 -408.029525)
			(xy 85.586032 -408.092605) (xy 85.594891 -408.157463) (xy 85.59546 -408.190192) (xy 89.023706 -408.190192)
			(xy 89.027697 -408.128025) (xy 89.039606 -408.066878) (xy 89.059235 -408.007757) (xy 89.086264 -407.951631)
			(xy 89.120248 -407.899422) (xy 89.16063 -407.851987) (xy 89.206746 -407.810106) (xy 89.257838 -407.774466)
			(xy 89.313069 -407.745652) (xy 89.371531 -407.724138) (xy 89.432265 -407.710276) (xy 89.494272 -407.704294)
			(xy 89.556535 -407.70629) (xy 89.618032 -407.716233) (xy 89.677753 -407.733957) (xy 89.734716 -407.759174)
			(xy 89.787987 -407.791467) (xy 89.836692 -407.830307) (xy 89.880029 -407.875057) (xy 89.917289 -407.924981)
			(xy 89.947858 -407.97926) (xy 89.971236 -408.037003) (xy 89.987037 -408.097261) (xy 89.995003 -408.159044)
			(xy 89.995502 -408.190192) (xy 89.995003 -408.22134) (xy 89.987037 -408.283123) (xy 89.971236 -408.343381)
			(xy 89.947858 -408.401124) (xy 89.917289 -408.455403) (xy 89.880029 -408.505327) (xy 89.836692 -408.550077)
			(xy 89.787987 -408.588917) (xy 89.734716 -408.62121) (xy 89.677753 -408.646427) (xy 89.618032 -408.664151)
			(xy 89.556535 -408.674094) (xy 89.494272 -408.67609) (xy 89.432265 -408.670108) (xy 89.371531 -408.656246)
			(xy 89.313069 -408.634732) (xy 89.257838 -408.605918) (xy 89.206746 -408.570278) (xy 89.16063 -408.528397)
			(xy 89.120248 -408.480962) (xy 89.086264 -408.428753) (xy 89.059235 -408.372627) (xy 89.039606 -408.313506)
			(xy 89.027697 -408.252359) (xy 89.023706 -408.190192) (xy 85.59546 -408.190192) (xy 85.594905 -408.222922)
			(xy 85.586045 -408.28778) (xy 85.568551 -408.35086) (xy 85.542742 -408.411018) (xy 85.526372 -408.439366)
			(xy 85.523067 -408.445396) (xy 85.519456 -408.458656) (xy 85.51926 -408.465528) (xy 85.51926 -409.214828)
			(xy 85.519446 -409.221702) (xy 85.523059 -409.234964) (xy 85.526372 -409.24099) (xy 85.542731 -409.269343)
			(xy 85.568535 -409.329501) (xy 85.586027 -409.392579) (xy 85.594889 -409.457435) (xy 85.59546 -409.490164)
			(xy 85.594892 -409.522893) (xy 85.586036 -409.587751) (xy 85.568546 -409.650831) (xy 85.54274 -409.71099)
			(xy 85.526372 -409.739338) (xy 85.523042 -409.745355) (xy 85.519446 -409.758625) (xy 85.51926 -409.7655)
			(xy 85.51926 -410.051504) (xy 85.518886 -410.061632) (xy 85.511129 -410.080343) (xy 85.496799 -410.094659)
			(xy 85.47808 -410.102396) (xy 85.467952 -410.102812) (xy 84.751672 -410.102812) (xy 84.741563 -410.102338)
			(xy 84.722886 -410.094594) (xy 84.708593 -410.080293) (xy 84.700857 -410.061613) (xy 84.700364 -410.051504)
			(xy 84.700364 -409.7655) (xy 84.700176 -409.758626) (xy 84.696566 -409.745363) (xy 84.693252 -409.739338)
			(xy 84.676907 -409.710978) (xy 84.651099 -409.650823) (xy 84.633603 -409.587746) (xy 84.624737 -409.522892)
			(xy 84.624164 -409.490164) (xy 83.351888 -409.490164) (xy 83.343056 -409.510825) (xy 83.326732 -409.539186)
			(xy 83.323425 -409.545214) (xy 83.319814 -409.558475) (xy 83.31962 -409.565348) (xy 83.31962 -410.314648)
			(xy 83.319829 -410.32152) (xy 83.323426 -410.334783) (xy 83.326732 -410.34081) (xy 83.343042 -410.369178)
			(xy 83.368762 -410.429348) (xy 83.386173 -410.492425) (xy 83.394958 -410.557268) (xy 83.394959 -410.589984)
			(xy 86.824312 -410.589984) (xy 86.824891 -410.557255) (xy 86.833743 -410.492397) (xy 86.851229 -410.429317)
			(xy 86.877033 -410.369158) (xy 86.8934 -410.34081) (xy 86.896711 -410.334784) (xy 86.900319 -410.321521)
			(xy 86.900512 -410.314648) (xy 86.900512 -409.565348) (xy 86.9003 -409.558476) (xy 86.896705 -409.545214)
			(xy 86.8934 -409.539186) (xy 86.877029 -409.51084) (xy 86.851228 -409.450679) (xy 86.83374 -409.387599)
			(xy 86.824882 -409.322741) (xy 86.824312 -409.290012) (xy 86.824859 -409.257282) (xy 86.83372 -409.192423)
			(xy 86.851216 -409.129343) (xy 86.877029 -409.069185) (xy 86.8934 -409.040838) (xy 86.896701 -409.034807)
			(xy 86.900315 -409.021548) (xy 86.900512 -409.014676) (xy 86.900512 -408.728672) (xy 86.900962 -408.71856)
			(xy 86.908711 -408.699879) (xy 86.923019 -408.685585) (xy 86.941708 -408.677853) (xy 86.95182 -408.677364)
			(xy 87.6681 -408.677364) (xy 87.678204 -408.677884) (xy 87.696876 -408.685615) (xy 87.711169 -408.699901)
			(xy 87.71891 -408.718568) (xy 87.719408 -408.728672) (xy 87.719408 -409.014676) (xy 87.719608 -409.021549)
			(xy 87.723211 -409.034811) (xy 87.72652 -409.040838) (xy 87.742903 -409.069178) (xy 87.7687 -409.129341)
			(xy 87.786185 -409.192423) (xy 87.79504 -409.257282) (xy 87.795608 -409.290012) (xy 87.795024 -409.322741)
			(xy 87.786173 -409.387598) (xy 87.768688 -409.450679) (xy 87.751753 -409.490164) (xy 89.023706 -409.490164)
			(xy 89.027697 -409.427997) (xy 89.039606 -409.36685) (xy 89.059235 -409.307729) (xy 89.086264 -409.251603)
			(xy 89.120248 -409.199394) (xy 89.16063 -409.151959) (xy 89.206746 -409.110078) (xy 89.257838 -409.074438)
			(xy 89.313069 -409.045624) (xy 89.371531 -409.02411) (xy 89.432265 -409.010248) (xy 89.494272 -409.004266)
			(xy 89.556535 -409.006262) (xy 89.618032 -409.016205) (xy 89.677753 -409.033929) (xy 89.734716 -409.059146)
			(xy 89.787987 -409.091439) (xy 89.836692 -409.130279) (xy 89.880029 -409.175029) (xy 89.917289 -409.224953)
			(xy 89.947858 -409.279232) (xy 89.971236 -409.336975) (xy 89.987037 -409.397233) (xy 89.995003 -409.459016)
			(xy 89.995502 -409.490164) (xy 89.995003 -409.521312) (xy 89.987037 -409.583095) (xy 89.971236 -409.643353)
			(xy 89.947858 -409.701096) (xy 89.917289 -409.755375) (xy 89.880029 -409.805299) (xy 89.836692 -409.850049)
			(xy 89.787987 -409.888889) (xy 89.734716 -409.921182) (xy 89.677753 -409.946399) (xy 89.618032 -409.964123)
			(xy 89.556535 -409.974066) (xy 89.494272 -409.976062) (xy 89.432265 -409.97008) (xy 89.371531 -409.956218)
			(xy 89.313069 -409.934704) (xy 89.257838 -409.90589) (xy 89.206746 -409.87025) (xy 89.16063 -409.828369)
			(xy 89.120248 -409.780934) (xy 89.086264 -409.728725) (xy 89.059235 -409.672599) (xy 89.039606 -409.613478)
			(xy 89.027697 -409.552331) (xy 89.023706 -409.490164) (xy 87.751753 -409.490164) (xy 87.742886 -409.510837)
			(xy 87.72652 -409.539186) (xy 87.723212 -409.545214) (xy 87.719602 -409.558475) (xy 87.719408 -409.565348)
			(xy 87.719408 -410.314648) (xy 87.719619 -410.32152) (xy 87.723214 -410.334783) (xy 87.72652 -410.34081)
			(xy 87.742891 -410.369156) (xy 87.768691 -410.429317) (xy 87.786179 -410.492397) (xy 87.795038 -410.557255)
			(xy 87.795608 -410.589984) (xy 87.795057 -410.622705) (xy 91.224954 -410.622705) (xy 91.224956 -410.557268)
			(xy 91.233741 -410.492423) (xy 91.251149 -410.429344) (xy 91.276866 -410.369172) (xy 91.293188 -410.34081)
			(xy 91.296498 -410.334783) (xy 91.300107 -410.321521) (xy 91.3003 -410.314648) (xy 91.3003 -409.565348)
			(xy 91.30009 -409.558476) (xy 91.296494 -409.545213) (xy 91.293188 -409.539186) (xy 91.276878 -409.510819)
			(xy 91.251162 -409.450648) (xy 91.233754 -409.387571) (xy 91.22497 -409.322728) (xy 91.224969 -409.257293)
			(xy 91.23375 -409.192449) (xy 91.251155 -409.129371) (xy 91.276868 -409.0692) (xy 91.293188 -409.040838)
			(xy 91.296488 -409.034806) (xy 91.300103 -409.021548) (xy 91.3003 -409.014676) (xy 91.3003 -408.728672)
			(xy 91.300699 -408.718516) (xy 91.308503 -408.699763) (xy 91.322907 -408.685441) (xy 91.341704 -408.677742)
			(xy 91.351862 -408.677364) (xy 92.068142 -408.677364) (xy 92.078274 -408.677793) (xy 92.097001 -408.685539)
			(xy 92.111357 -408.699843) (xy 92.11917 -408.718542) (xy 92.119704 -408.728672) (xy 92.119704 -409.014676)
			(xy 92.119905 -409.021549) (xy 92.123507 -409.034811) (xy 92.126816 -409.040838) (xy 92.14315 -409.069193)
			(xy 92.168869 -409.129365) (xy 92.186277 -409.192445) (xy 92.195061 -409.257291) (xy 92.195059 -409.322729)
			(xy 92.186273 -409.387575) (xy 92.168862 -409.450654) (xy 92.14314 -409.510825) (xy 92.136197 -409.522888)
			(xy 115.425047 -409.522888) (xy 115.425051 -409.45745) (xy 115.433838 -409.392604) (xy 115.451249 -409.329524)
			(xy 115.476969 -409.269352) (xy 115.493292 -409.24099) (xy 115.49661 -409.234967) (xy 115.500214 -409.221702)
			(xy 115.500404 -409.214828) (xy 115.500404 -408.465528) (xy 115.500201 -408.458656) (xy 115.4966 -408.445393)
			(xy 115.493292 -408.439366) (xy 115.476964 -408.411008) (xy 115.45125 -408.350836) (xy 115.433844 -408.287756)
			(xy 115.425062 -408.222911) (xy 115.425063 -408.157475) (xy 115.433847 -408.09263) (xy 115.451254 -408.029551)
			(xy 115.476971 -407.96938) (xy 115.493292 -407.941018) (xy 115.4966 -407.93499) (xy 115.50021 -407.921729)
			(xy 115.500404 -407.914856) (xy 115.500404 -407.628852) (xy 115.500783 -407.618694) (xy 115.508595 -407.59994)
			(xy 115.523004 -407.585618) (xy 115.541806 -407.577921) (xy 115.551966 -407.577544) (xy 116.268246 -407.577544)
			(xy 116.278376 -407.577989) (xy 116.297099 -407.585733) (xy 116.311454 -407.600031) (xy 116.319271 -407.618724)
			(xy 116.319808 -407.628852) (xy 116.319808 -407.914856) (xy 116.320016 -407.921728) (xy 116.323613 -407.934991)
			(xy 116.32692 -407.941018) (xy 116.343237 -407.969383) (xy 116.368957 -408.029552) (xy 116.386367 -408.092631)
			(xy 116.395153 -408.157475) (xy 116.395154 -408.222911) (xy 116.38637 -408.287756) (xy 116.368962 -408.350835)
			(xy 116.343243 -408.411005) (xy 116.32692 -408.439366) (xy 116.323619 -408.445397) (xy 116.320004 -408.458656)
			(xy 116.319808 -408.465528) (xy 116.319808 -409.214828) (xy 116.319988 -409.221702) (xy 116.323604 -409.234965)
			(xy 116.32692 -409.24099) (xy 116.343213 -409.269368) (xy 116.368936 -409.329535) (xy 116.386349 -409.39261)
			(xy 116.395137 -409.457452) (xy 116.395141 -409.522887) (xy 116.386361 -409.58773) (xy 116.368956 -409.650807)
			(xy 116.343241 -409.710977) (xy 116.32692 -409.739338) (xy 116.323593 -409.745357) (xy 116.319995 -409.758625)
			(xy 116.319808 -409.7655) (xy 116.319808 -410.051504) (xy 116.319382 -410.061657) (xy 116.311586 -410.080408)
			(xy 116.297191 -410.094731) (xy 116.278401 -410.102432) (xy 116.268246 -410.102812) (xy 115.551966 -410.102812)
			(xy 115.541844 -410.102303) (xy 115.523131 -410.094574) (xy 115.508778 -410.080295) (xy 115.500951 -410.061624)
			(xy 115.500404 -410.051504) (xy 115.500404 -409.7655) (xy 115.500212 -409.758627) (xy 115.496604 -409.745364)
			(xy 115.493292 -409.739338) (xy 115.476941 -409.710993) (xy 115.451228 -409.650818) (xy 115.433825 -409.587736)
			(xy 115.425047 -409.522888) (xy 92.136197 -409.522888) (xy 92.126816 -409.539186) (xy 92.123507 -409.545214)
			(xy 92.119898 -409.558475) (xy 92.119704 -409.565348) (xy 92.119704 -410.314648) (xy 92.119915 -410.32152)
			(xy 92.12351 -410.334783) (xy 92.126816 -410.34081) (xy 92.143126 -410.369178) (xy 92.168847 -410.429347)
			(xy 92.186259 -410.492425) (xy 92.195045 -410.557268) (xy 92.195045 -410.589984) (xy 117.624352 -410.589984)
			(xy 117.624939 -410.557255) (xy 117.63379 -410.492398) (xy 117.651274 -410.429318) (xy 117.677075 -410.369159)
			(xy 117.69344 -410.34081) (xy 117.696746 -410.334781) (xy 117.700358 -410.321521) (xy 117.700552 -410.314648)
			(xy 117.700552 -409.565348) (xy 117.700348 -409.558476) (xy 117.696749 -409.545213) (xy 117.69344 -409.539186)
			(xy 117.677073 -409.510838) (xy 117.65127 -409.450678) (xy 117.633781 -409.387598) (xy 117.624922 -409.322741)
			(xy 117.624352 -409.290012) (xy 117.624907 -409.257282) (xy 117.633767 -409.192424) (xy 117.651261 -409.129344)
			(xy 117.67707 -409.069186) (xy 117.69344 -409.040838) (xy 117.696737 -409.034804) (xy 117.700354 -409.021548)
			(xy 117.700552 -409.014676) (xy 117.700552 -408.728672) (xy 117.701061 -408.718567) (xy 117.708799 -408.699898)
			(xy 117.723088 -408.685606) (xy 117.741756 -408.677863) (xy 117.75186 -408.677364) (xy 118.46814 -408.677364)
			(xy 118.478247 -408.677852) (xy 118.496919 -408.685596) (xy 118.511211 -408.699891) (xy 118.518951 -408.718565)
			(xy 118.519448 -408.728672) (xy 118.519448 -409.014676) (xy 118.519643 -409.021549) (xy 118.523249 -409.034812)
			(xy 118.52656 -409.040838) (xy 118.542937 -409.069181) (xy 118.568737 -409.129343) (xy 118.586224 -409.192424)
			(xy 118.59508 -409.257282) (xy 118.595648 -409.290012) (xy 118.595059 -409.322741) (xy 118.586209 -409.387598)
			(xy 118.568726 -409.450678) (xy 118.551791 -409.490164) (xy 119.8245 -409.490164) (xy 119.825072 -409.457435)
			(xy 119.833926 -409.392577) (xy 119.851415 -409.329497) (xy 119.87722 -409.269338) (xy 119.893588 -409.24099)
			(xy 119.896905 -409.234967) (xy 119.90051 -409.221702) (xy 119.9007 -409.214828) (xy 119.9007 -408.465528)
			(xy 119.900497 -408.458656) (xy 119.896896 -408.445393) (xy 119.893588 -408.439366) (xy 119.877208 -408.411025)
			(xy 119.85141 -408.350862) (xy 119.833924 -408.28778) (xy 119.825068 -408.222922) (xy 119.8245 -408.190192)
			(xy 119.825085 -408.157463) (xy 119.833935 -408.092606) (xy 119.85142 -408.029525) (xy 119.877222 -407.969367)
			(xy 119.893588 -407.941018) (xy 119.896895 -407.93499) (xy 119.900506 -407.921729) (xy 119.9007 -407.914856)
			(xy 119.9007 -407.628852) (xy 119.901146 -407.61874) (xy 119.908899 -407.600061) (xy 119.923208 -407.585768)
			(xy 119.941896 -407.578035) (xy 119.952008 -407.577544) (xy 120.668288 -407.577544) (xy 120.678389 -407.578094)
			(xy 120.697056 -407.585817) (xy 120.71135 -407.600093) (xy 120.719095 -407.618752) (xy 120.719596 -407.628852)
			(xy 120.719596 -407.914856) (xy 120.719805 -407.921728) (xy 120.723402 -407.934991) (xy 120.726708 -407.941018)
			(xy 120.743082 -407.969363) (xy 120.768881 -408.029524) (xy 120.786369 -408.092605) (xy 120.795227 -408.157463)
			(xy 120.795796 -408.190192) (xy 120.79525 -408.222922) (xy 120.786388 -408.287781) (xy 120.768893 -408.350861)
			(xy 120.74308 -408.411019) (xy 120.726708 -408.439366) (xy 120.723406 -408.445397) (xy 120.719792 -408.458656)
			(xy 120.719596 -408.465528) (xy 120.719596 -409.214828) (xy 120.719778 -409.221702) (xy 120.723393 -409.234965)
			(xy 120.726708 -409.24099) (xy 120.74307 -409.269341) (xy 120.768873 -409.3295) (xy 120.786363 -409.392579)
			(xy 120.795225 -409.457435) (xy 120.795796 -409.490164) (xy 120.795237 -409.522894) (xy 120.786379 -409.587752)
			(xy 120.768887 -409.650832) (xy 120.743077 -409.71099) (xy 120.726708 -409.739338) (xy 120.72338 -409.745356)
			(xy 120.719783 -409.758625) (xy 120.719596 -409.7655) (xy 120.719596 -410.051504) (xy 120.719187 -410.061627)
			(xy 120.711437 -410.080332) (xy 120.697118 -410.094646) (xy 120.678411 -410.10239) (xy 120.668288 -410.102812)
			(xy 119.952008 -410.102812) (xy 119.941888 -410.102378) (xy 119.923186 -410.094634) (xy 119.908872 -410.080324)
			(xy 119.901125 -410.061624) (xy 119.9007 -410.051504) (xy 119.9007 -409.7655) (xy 119.900508 -409.758627)
			(xy 119.8969 -409.745364) (xy 119.893588 -409.739338) (xy 119.877236 -409.710981) (xy 119.851431 -409.650824)
			(xy 119.833938 -409.587747) (xy 119.825073 -409.522892) (xy 119.8245 -409.490164) (xy 118.551791 -409.490164)
			(xy 118.542925 -409.510837) (xy 118.52656 -409.539186) (xy 118.523255 -409.545215) (xy 118.519642 -409.558475)
			(xy 118.519448 -409.565348) (xy 118.519448 -410.314648) (xy 118.519654 -410.32152) (xy 118.523252 -410.334783)
			(xy 118.52656 -410.34081) (xy 118.542926 -410.369159) (xy 118.568728 -410.429318) (xy 118.586218 -410.492398)
			(xy 118.595078 -410.557255) (xy 118.595648 -410.589984) (xy 118.595091 -410.622705) (xy 122.024989 -410.622705)
			(xy 122.024991 -410.557267) (xy 122.033776 -410.492422) (xy 122.051186 -410.429343) (xy 122.076905 -410.369171)
			(xy 122.093228 -410.34081) (xy 122.096541 -410.334785) (xy 122.100147 -410.321521) (xy 122.10034 -410.314648)
			(xy 122.10034 -409.565348) (xy 122.100125 -409.558477) (xy 122.096532 -409.545214) (xy 122.093228 -409.539186)
			(xy 122.076916 -409.510819) (xy 122.051198 -409.450649) (xy 122.033789 -409.387572) (xy 122.025005 -409.322728)
			(xy 122.025003 -409.257292) (xy 122.033785 -409.192449) (xy 122.051191 -409.12937) (xy 122.076907 -409.069199)
			(xy 122.093228 -409.040838) (xy 122.096531 -409.034808) (xy 122.100144 -409.021548) (xy 122.10034 -409.014676)
			(xy 122.10034 -408.728672) (xy 122.100699 -408.718511) (xy 122.108512 -408.69975) (xy 122.122928 -408.685426)
			(xy 122.141738 -408.677735) (xy 122.151902 -408.677364) (xy 122.868182 -408.677364) (xy 122.878311 -408.677842)
			(xy 122.897036 -408.685568) (xy 122.911394 -408.699858) (xy 122.919209 -408.718546) (xy 122.919744 -408.728672)
			(xy 122.919744 -409.014676) (xy 122.91994 -409.021549) (xy 122.923545 -409.034812) (xy 122.926856 -409.040838)
			(xy 122.943189 -409.069194) (xy 122.968905 -409.129366) (xy 122.986313 -409.192446) (xy 122.995095 -409.257291)
			(xy 122.995094 -409.322729) (xy 122.986309 -409.387574) (xy 122.968899 -409.450653) (xy 122.943179 -409.510825)
			(xy 122.936236 -409.522889) (xy 124.225119 -409.522889) (xy 124.225123 -409.457449) (xy 124.233912 -409.392602)
			(xy 124.251326 -409.329522) (xy 124.27705 -409.269351) (xy 124.293376 -409.24099) (xy 124.296693 -409.234966)
			(xy 124.300298 -409.221702) (xy 124.300488 -409.214828) (xy 124.300488 -408.465528) (xy 124.300287 -408.458655)
			(xy 124.296685 -408.445393) (xy 124.293376 -408.439366) (xy 124.277046 -408.411009) (xy 124.251327 -408.350837)
			(xy 124.233918 -408.287758) (xy 124.225135 -408.222912) (xy 124.225136 -408.157474) (xy 124.233921 -408.092629)
			(xy 124.251331 -408.02955) (xy 124.277052 -407.969379) (xy 124.293376 -407.941018) (xy 124.296683 -407.934989)
			(xy 124.300294 -407.921729) (xy 124.300488 -407.914856) (xy 124.300488 -407.628852) (xy 124.300882 -407.618696)
			(xy 124.308691 -407.599945) (xy 124.323096 -407.585624) (xy 124.341892 -407.577924) (xy 124.35205 -407.577544)
			(xy 125.06833 -407.577544) (xy 125.078459 -407.578002) (xy 125.097182 -407.58574) (xy 125.111537 -407.600035)
			(xy 125.119355 -407.618725) (xy 125.119892 -407.628852) (xy 125.119892 -407.914856) (xy 125.120102 -407.921728)
			(xy 125.123698 -407.934991) (xy 125.127004 -407.941018) (xy 125.143318 -407.969383) (xy 125.169034 -408.029554)
			(xy 125.186441 -408.092632) (xy 125.195225 -408.157475) (xy 125.195226 -408.222911) (xy 125.186444 -408.287755)
			(xy 125.169039 -408.350833) (xy 125.143324 -408.411004) (xy 125.127004 -408.439366) (xy 125.123702 -408.445397)
			(xy 125.120088 -408.458656) (xy 125.119892 -408.465528) (xy 125.119892 -409.214828) (xy 125.120074 -409.221702)
			(xy 125.123689 -409.234965) (xy 125.127004 -409.24099) (xy 125.143294 -409.269369) (xy 125.169013 -409.329536)
			(xy 125.186422 -409.392611) (xy 125.195209 -409.457452) (xy 125.195213 -409.522886) (xy 125.186435 -409.587728)
			(xy 125.169033 -409.650805) (xy 125.143322 -409.710976) (xy 125.127004 -409.739338) (xy 125.123676 -409.745356)
			(xy 125.120079 -409.758625) (xy 125.119892 -409.7655) (xy 125.119892 -410.051504) (xy 125.119481 -410.061659)
			(xy 125.111683 -410.080413) (xy 125.097283 -410.094737) (xy 125.078487 -410.102435) (xy 125.06833 -410.102812)
			(xy 124.35205 -410.102812) (xy 124.341933 -410.102234) (xy 124.323223 -410.094532) (xy 124.308867 -410.080274)
			(xy 124.301036 -410.061618) (xy 124.300488 -410.051504) (xy 124.300488 -409.7655) (xy 124.300297 -409.758627)
			(xy 124.296688 -409.745364) (xy 124.293376 -409.739338) (xy 124.277022 -409.710994) (xy 124.251305 -409.650819)
			(xy 124.233899 -409.587737) (xy 124.225119 -409.522889) (xy 122.936236 -409.522889) (xy 122.926856 -409.539186)
			(xy 122.923551 -409.545215) (xy 122.919938 -409.558475) (xy 122.919744 -409.565348) (xy 122.919744 -410.314648)
			(xy 122.91995 -410.32152) (xy 122.923548 -410.334783) (xy 122.926856 -410.34081) (xy 122.943165 -410.369179)
			(xy 122.968884 -410.429348) (xy 122.986294 -410.492425) (xy 122.995079 -410.557268) (xy 122.99508 -410.589984)
			(xy 126.424436 -410.589984) (xy 126.425025 -410.557255) (xy 126.433876 -410.492398) (xy 126.451359 -410.429318)
			(xy 126.477159 -410.369159) (xy 126.493524 -410.34081) (xy 126.496837 -410.334785) (xy 126.500443 -410.321521)
			(xy 126.500636 -410.314648) (xy 126.500636 -409.565348) (xy 126.500421 -409.558476) (xy 126.496828 -409.545214)
			(xy 126.493524 -409.539186) (xy 126.477155 -409.510839) (xy 126.451354 -409.450679) (xy 126.433865 -409.387598)
			(xy 126.425006 -409.322741) (xy 126.424436 -409.290012) (xy 126.424993 -409.257282) (xy 126.433853 -409.192424)
			(xy 126.451346 -409.129344) (xy 126.477155 -409.069186) (xy 126.493524 -409.040838) (xy 126.496827 -409.034808)
			(xy 126.50044 -409.021548) (xy 126.500636 -409.014676) (xy 126.500636 -408.728672) (xy 126.500994 -408.718543)
			(xy 126.508758 -408.699832) (xy 126.523093 -408.685517) (xy 126.541815 -408.67778) (xy 126.551944 -408.677364)
			(xy 127.268224 -408.677364) (xy 127.27833 -408.677864) (xy 127.297002 -408.685603) (xy 127.311294 -408.699895)
			(xy 127.319035 -408.718566) (xy 127.319532 -408.728672) (xy 127.319532 -409.014676) (xy 127.319729 -409.021549)
			(xy 127.323333 -409.034812) (xy 127.326644 -409.040838) (xy 127.343019 -409.069182) (xy 127.36882 -409.129343)
			(xy 127.386307 -409.192424) (xy 127.395164 -409.257282) (xy 127.395732 -409.290012) (xy 127.395145 -409.322741)
			(xy 127.386295 -409.387598) (xy 127.36881 -409.450678) (xy 127.343009 -409.510837) (xy 127.336052 -409.522889)
			(xy 128.624909 -409.522889) (xy 128.624913 -409.457449) (xy 128.633701 -409.392603) (xy 128.651115 -409.329523)
			(xy 128.676839 -409.269351) (xy 128.693164 -409.24099) (xy 128.696479 -409.234966) (xy 128.700085 -409.221702)
			(xy 128.700276 -409.214828) (xy 128.700276 -408.465528) (xy 128.700076 -408.458655) (xy 128.696474 -408.445392)
			(xy 128.693164 -408.439366) (xy 128.676834 -408.411009) (xy 128.651116 -408.350837) (xy 128.633708 -408.287757)
			(xy 128.624924 -408.222912) (xy 128.624925 -408.157474) (xy 128.63371 -408.092629) (xy 128.65112 -408.02955)
			(xy 128.67684 -407.969379) (xy 128.693164 -407.941018) (xy 128.696469 -407.934989) (xy 128.700081 -407.921729)
			(xy 128.700276 -407.914856) (xy 128.700276 -407.628852) (xy 128.700682 -407.618698) (xy 128.708489 -407.599949)
			(xy 128.72289 -407.585628) (xy 128.741682 -407.577926) (xy 128.751838 -407.577544) (xy 129.468118 -407.577544)
			(xy 129.478246 -407.578012) (xy 129.496969 -407.585746) (xy 129.511325 -407.600038) (xy 129.519143 -407.618726)
			(xy 129.51968 -407.628852) (xy 129.51968 -407.914856) (xy 129.519891 -407.921728) (xy 129.523486 -407.934991)
			(xy 129.526792 -407.941018) (xy 129.543106 -407.969383) (xy 129.568823 -408.029554) (xy 129.586231 -408.092632)
			(xy 129.595015 -408.157475) (xy 129.595015 -408.190192) (xy 133.023872 -408.190192) (xy 133.027863 -408.128025)
			(xy 133.039772 -408.066878) (xy 133.059401 -408.007757) (xy 133.08643 -407.951631) (xy 133.120414 -407.899422)
			(xy 133.160796 -407.851987) (xy 133.206912 -407.810106) (xy 133.258004 -407.774466) (xy 133.313235 -407.745652)
			(xy 133.371697 -407.724138) (xy 133.432431 -407.710276) (xy 133.494438 -407.704294) (xy 133.556701 -407.70629)
			(xy 133.618198 -407.716233) (xy 133.677919 -407.733957) (xy 133.734882 -407.759174) (xy 133.788153 -407.791467)
			(xy 133.836858 -407.830307) (xy 133.880195 -407.875057) (xy 133.917455 -407.924981) (xy 133.948024 -407.97926)
			(xy 133.971402 -408.037003) (xy 133.987203 -408.097261) (xy 133.995169 -408.159044) (xy 133.995668 -408.190192)
			(xy 133.995169 -408.22134) (xy 133.987203 -408.283123) (xy 133.971402 -408.343381) (xy 133.948024 -408.401124)
			(xy 133.917455 -408.455403) (xy 133.880195 -408.505327) (xy 133.836858 -408.550077) (xy 133.788153 -408.588917)
			(xy 133.734882 -408.62121) (xy 133.677919 -408.646427) (xy 133.618198 -408.664151) (xy 133.556701 -408.674094)
			(xy 133.494438 -408.67609) (xy 133.432431 -408.670108) (xy 133.371697 -408.656246) (xy 133.313235 -408.634732)
			(xy 133.258004 -408.605918) (xy 133.206912 -408.570278) (xy 133.160796 -408.528397) (xy 133.120414 -408.480962)
			(xy 133.08643 -408.428753) (xy 133.059401 -408.372627) (xy 133.039772 -408.313506) (xy 133.027863 -408.252359)
			(xy 133.023872 -408.190192) (xy 129.595015 -408.190192) (xy 129.595016 -408.222911) (xy 129.586234 -408.287755)
			(xy 129.568828 -408.350833) (xy 129.543113 -408.411004) (xy 129.526792 -408.439366) (xy 129.523489 -408.445396)
			(xy 129.519876 -408.458656) (xy 129.51968 -408.465528) (xy 129.51968 -409.214828) (xy 129.519864 -409.221702)
			(xy 129.523478 -409.234964) (xy 129.526792 -409.24099) (xy 129.543083 -409.269368) (xy 129.568802 -409.329536)
			(xy 129.586212 -409.392611) (xy 129.594999 -409.457452) (xy 129.595003 -409.522886) (xy 129.586224 -409.587728)
			(xy 129.568822 -409.650806) (xy 129.543111 -409.710976) (xy 129.526792 -409.739338) (xy 129.523463 -409.745356)
			(xy 129.519867 -409.758625) (xy 129.51968 -409.7655) (xy 129.51968 -410.051504) (xy 129.519281 -410.061661)
			(xy 129.511481 -410.080417) (xy 129.497077 -410.094741) (xy 129.478277 -410.102437) (xy 129.468118 -410.102812)
			(xy 128.751838 -410.102812) (xy 128.74172 -410.102244) (xy 128.72301 -410.094538) (xy 128.708654 -410.080277)
			(xy 128.700824 -410.061618) (xy 128.700276 -410.051504) (xy 128.700276 -409.7655) (xy 128.700087 -409.758627)
			(xy 128.696477 -409.745364) (xy 128.693164 -409.739338) (xy 128.67681 -409.710994) (xy 128.651094 -409.650819)
			(xy 128.633689 -409.587737) (xy 128.624909 -409.522889) (xy 127.336052 -409.522889) (xy 127.326644 -409.539186)
			(xy 127.323338 -409.545215) (xy 127.319726 -409.558475) (xy 127.319532 -409.565348) (xy 127.319532 -410.314648)
			(xy 127.31974 -410.32152) (xy 127.323337 -410.334783) (xy 127.326644 -410.34081) (xy 127.343008 -410.36916)
			(xy 127.368812 -410.429319) (xy 127.386302 -410.492398) (xy 127.395162 -410.557255) (xy 127.395732 -410.589984)
			(xy 127.395177 -410.622705) (xy 130.825075 -410.622705) (xy 130.825077 -410.557268) (xy 130.833862 -410.492422)
			(xy 130.851271 -410.429343) (xy 130.87699 -410.369172) (xy 130.893312 -410.34081) (xy 130.896624 -410.334784)
			(xy 130.900231 -410.321521) (xy 130.900424 -410.314648) (xy 130.900424 -409.565348) (xy 130.900211 -409.558476)
			(xy 130.896617 -409.545214) (xy 130.893312 -409.539186) (xy 130.877001 -409.510819) (xy 130.851284 -409.450649)
			(xy 130.833875 -409.387571) (xy 130.825091 -409.322728) (xy 130.82509 -409.257293) (xy 130.833871 -409.192449)
			(xy 130.851277 -409.129371) (xy 130.876991 -409.0692) (xy 130.893312 -409.040838) (xy 130.896614 -409.034807)
			(xy 130.900227 -409.021548) (xy 130.900424 -409.014676) (xy 130.900424 -408.728672) (xy 130.900799 -408.718513)
			(xy 130.908608 -408.699755) (xy 130.92302 -408.685432) (xy 130.941825 -408.677738) (xy 130.951986 -408.677364)
			(xy 131.668266 -408.677364) (xy 131.678393 -408.677855) (xy 131.697118 -408.685576) (xy 131.711477 -408.699862)
			(xy 131.719293 -408.718547) (xy 131.719828 -408.728672) (xy 131.719828 -409.014676) (xy 131.720026 -409.021549)
			(xy 131.72363 -409.034812) (xy 131.72694 -409.040838) (xy 131.743273 -409.069193) (xy 131.768991 -409.129366)
			(xy 131.786399 -409.192446) (xy 131.795181 -409.257291) (xy 131.79518 -409.322729) (xy 131.786394 -409.387575)
			(xy 131.768984 -409.450654) (xy 131.752096 -409.490164) (xy 133.023872 -409.490164) (xy 133.027863 -409.427997)
			(xy 133.039772 -409.36685) (xy 133.059401 -409.307729) (xy 133.08643 -409.251603) (xy 133.120414 -409.199394)
			(xy 133.160796 -409.151959) (xy 133.206912 -409.110078) (xy 133.258004 -409.074438) (xy 133.313235 -409.045624)
			(xy 133.371697 -409.02411) (xy 133.432431 -409.010248) (xy 133.494438 -409.004266) (xy 133.556701 -409.006262)
			(xy 133.618198 -409.016205) (xy 133.677919 -409.033929) (xy 133.734882 -409.059146) (xy 133.788153 -409.091439)
			(xy 133.836858 -409.130279) (xy 133.880195 -409.175029) (xy 133.917455 -409.224953) (xy 133.948024 -409.279232)
			(xy 133.952388 -409.290012) (xy 135.22402 -409.290012) (xy 135.228011 -409.227845) (xy 135.23992 -409.166698)
			(xy 135.259549 -409.107577) (xy 135.286578 -409.051451) (xy 135.320562 -408.999242) (xy 135.360944 -408.951807)
			(xy 135.40706 -408.909926) (xy 135.458152 -408.874286) (xy 135.513383 -408.845472) (xy 135.571845 -408.823958)
			(xy 135.632579 -408.810096) (xy 135.694586 -408.804114) (xy 135.756849 -408.80611) (xy 135.818346 -408.816053)
			(xy 135.878067 -408.833777) (xy 135.93503 -408.858994) (xy 135.988301 -408.891287) (xy 136.037006 -408.930127)
			(xy 136.080343 -408.974877) (xy 136.117603 -409.024801) (xy 136.148172 -409.07908) (xy 136.17155 -409.136823)
			(xy 136.187351 -409.197081) (xy 136.195317 -409.258864) (xy 136.195816 -409.290012) (xy 136.195317 -409.32116)
			(xy 136.187351 -409.382943) (xy 136.17155 -409.443201) (xy 136.148172 -409.500944) (xy 136.117603 -409.555223)
			(xy 136.080343 -409.605147) (xy 136.037006 -409.649897) (xy 135.988301 -409.688737) (xy 135.93503 -409.72103)
			(xy 135.878067 -409.746247) (xy 135.818346 -409.763971) (xy 135.756849 -409.773914) (xy 135.694586 -409.77591)
			(xy 135.632579 -409.769928) (xy 135.571845 -409.756066) (xy 135.513383 -409.734552) (xy 135.458152 -409.705738)
			(xy 135.40706 -409.670098) (xy 135.360944 -409.628217) (xy 135.320562 -409.580782) (xy 135.286578 -409.528573)
			(xy 135.259549 -409.472447) (xy 135.23992 -409.413326) (xy 135.228011 -409.352179) (xy 135.22402 -409.290012)
			(xy 133.952388 -409.290012) (xy 133.971402 -409.336975) (xy 133.987203 -409.397233) (xy 133.995169 -409.459016)
			(xy 133.995668 -409.490164) (xy 133.995169 -409.521312) (xy 133.987203 -409.583095) (xy 133.971402 -409.643353)
			(xy 133.948024 -409.701096) (xy 133.917455 -409.755375) (xy 133.880195 -409.805299) (xy 133.836858 -409.850049)
			(xy 133.788153 -409.888889) (xy 133.734882 -409.921182) (xy 133.677919 -409.946399) (xy 133.618198 -409.964123)
			(xy 133.556701 -409.974066) (xy 133.494438 -409.976062) (xy 133.432431 -409.97008) (xy 133.371697 -409.956218)
			(xy 133.313235 -409.934704) (xy 133.258004 -409.90589) (xy 133.206912 -409.87025) (xy 133.160796 -409.828369)
			(xy 133.120414 -409.780934) (xy 133.08643 -409.728725) (xy 133.059401 -409.672599) (xy 133.039772 -409.613478)
			(xy 133.027863 -409.552331) (xy 133.023872 -409.490164) (xy 131.752096 -409.490164) (xy 131.743264 -409.510825)
			(xy 131.72694 -409.539186) (xy 131.723634 -409.545215) (xy 131.720022 -409.558475) (xy 131.719828 -409.565348)
			(xy 131.719828 -410.314648) (xy 131.720036 -410.32152) (xy 131.723633 -410.334783) (xy 131.72694 -410.34081)
			(xy 131.743249 -410.369179) (xy 131.768969 -410.429348) (xy 131.78638 -410.492425) (xy 131.795165 -410.557268)
			(xy 131.795166 -410.589984) (xy 135.22402 -410.589984) (xy 135.228011 -410.527817) (xy 135.23992 -410.46667)
			(xy 135.259549 -410.407549) (xy 135.286578 -410.351423) (xy 135.320562 -410.299214) (xy 135.360944 -410.251779)
			(xy 135.40706 -410.209898) (xy 135.458152 -410.174258) (xy 135.513383 -410.145444) (xy 135.571845 -410.12393)
			(xy 135.632579 -410.110068) (xy 135.694586 -410.104086) (xy 135.756849 -410.106082) (xy 135.818346 -410.116025)
			(xy 135.878067 -410.133749) (xy 135.93503 -410.158966) (xy 135.988301 -410.191259) (xy 136.037006 -410.230099)
			(xy 136.080343 -410.274849) (xy 136.117603 -410.324773) (xy 136.148172 -410.379052) (xy 136.17155 -410.436795)
			(xy 136.187351 -410.497053) (xy 136.195317 -410.558836) (xy 136.195816 -410.589984) (xy 136.195317 -410.621132)
			(xy 136.187351 -410.682915) (xy 136.17155 -410.743173) (xy 136.148172 -410.800916) (xy 136.117603 -410.855195)
			(xy 136.080343 -410.905119) (xy 136.037006 -410.949869) (xy 135.988301 -410.988709) (xy 135.93503 -411.021002)
			(xy 135.878067 -411.046219) (xy 135.818346 -411.063943) (xy 135.756849 -411.073886) (xy 135.694586 -411.075882)
			(xy 135.632579 -411.0699) (xy 135.571845 -411.056038) (xy 135.513383 -411.034524) (xy 135.458152 -411.00571)
			(xy 135.40706 -410.97007) (xy 135.360944 -410.928189) (xy 135.320562 -410.880754) (xy 135.286578 -410.828545)
			(xy 135.259549 -410.772419) (xy 135.23992 -410.713298) (xy 135.228011 -410.652151) (xy 135.22402 -410.589984)
			(xy 131.795166 -410.589984) (xy 131.795167 -410.622704) (xy 131.786385 -410.687548) (xy 131.768978 -410.750626)
			(xy 131.743262 -410.810797) (xy 131.72694 -410.839158) (xy 131.723643 -410.845192) (xy 131.720026 -410.858448)
			(xy 131.719828 -410.86532) (xy 131.719828 -411.151324) (xy 131.719399 -411.161476) (xy 131.7116 -411.180224)
			(xy 131.697207 -411.194545) (xy 131.67842 -411.202249) (xy 131.668266 -411.202632) (xy 130.951986 -411.202632)
			(xy 130.941855 -411.202184) (xy 130.923128 -411.194446) (xy 130.908772 -411.180148) (xy 130.900958 -411.161453)
			(xy 130.900424 -411.151324) (xy 130.900424 -410.86532) (xy 130.900221 -410.858448) (xy 130.89662 -410.845185)
			(xy 130.893312 -410.839158) (xy 130.876977 -410.810804) (xy 130.851262 -410.750631) (xy 130.833857 -410.687551)
			(xy 130.825075 -410.622705) (xy 127.395177 -410.622705) (xy 127.395177 -410.622714) (xy 127.386318 -410.687572)
			(xy 127.368824 -410.750652) (xy 127.343014 -410.81081) (xy 127.326644 -410.839158) (xy 127.323348 -410.845192)
			(xy 127.31973 -410.858448) (xy 127.319532 -410.86532) (xy 127.319532 -411.151324) (xy 127.319035 -411.16143)
			(xy 127.311296 -411.180103) (xy 127.297003 -411.194396) (xy 127.27833 -411.202135) (xy 127.268224 -411.202632)
			(xy 126.551944 -411.202632) (xy 126.541828 -411.202149) (xy 126.523132 -411.194421) (xy 126.508817 -411.180125)
			(xy 126.501065 -411.161439) (xy 126.500636 -411.151324) (xy 126.500636 -410.86532) (xy 126.500432 -410.858448)
			(xy 126.496831 -410.845185) (xy 126.493524 -410.839158) (xy 126.477144 -410.810817) (xy 126.451345 -410.750654)
			(xy 126.433859 -410.687572) (xy 126.425004 -410.622714) (xy 126.424436 -410.589984) (xy 122.99508 -410.589984)
			(xy 122.995081 -410.622704) (xy 122.986299 -410.687548) (xy 122.968893 -410.750626) (xy 122.943177 -410.810797)
			(xy 122.926856 -410.839158) (xy 122.923561 -410.845192) (xy 122.919942 -410.858448) (xy 122.919744 -410.86532)
			(xy 122.919744 -411.151324) (xy 122.919299 -411.161474) (xy 122.911504 -411.180219) (xy 122.897115 -411.19454)
			(xy 122.878334 -411.202246) (xy 122.868182 -411.202632) (xy 122.151902 -411.202632) (xy 122.141772 -411.202171)
			(xy 122.123046 -411.194439) (xy 122.108688 -411.180144) (xy 122.100874 -411.161452) (xy 122.10034 -411.151324)
			(xy 122.10034 -410.86532) (xy 122.100135 -410.858448) (xy 122.096535 -410.845185) (xy 122.093228 -410.839158)
			(xy 122.076893 -410.810804) (xy 122.051177 -410.750631) (xy 122.033771 -410.687551) (xy 122.024989 -410.622705)
			(xy 118.595091 -410.622705) (xy 118.595091 -410.622714) (xy 118.586232 -410.687572) (xy 118.568739 -410.750652)
			(xy 118.542929 -410.81081) (xy 118.52656 -410.839158) (xy 118.523265 -410.845192) (xy 118.519646 -410.858448)
			(xy 118.519448 -410.86532) (xy 118.519448 -411.151324) (xy 118.518936 -411.161428) (xy 118.511199 -411.180098)
			(xy 118.496911 -411.19439) (xy 118.478244 -411.202133) (xy 118.46814 -411.202632) (xy 117.75186 -411.202632)
			(xy 117.741753 -411.202148) (xy 117.72308 -411.194404) (xy 117.708787 -411.180107) (xy 117.701048 -411.161431)
			(xy 117.700552 -411.151324) (xy 117.700552 -410.86532) (xy 117.700358 -410.858447) (xy 117.696752 -410.845184)
			(xy 117.69344 -410.839158) (xy 117.677062 -410.810816) (xy 117.651262 -410.750654) (xy 117.633776 -410.687572)
			(xy 117.62492 -410.622714) (xy 117.624352 -410.589984) (xy 92.195045 -410.589984) (xy 92.195046 -410.622704)
			(xy 92.186264 -410.687549) (xy 92.168856 -410.750627) (xy 92.143139 -410.810797) (xy 92.126816 -410.839158)
			(xy 92.123517 -410.845191) (xy 92.119901 -410.858448) (xy 92.119704 -410.86532) (xy 92.119704 -411.151324)
			(xy 92.119298 -411.161479) (xy 92.111495 -411.180231) (xy 92.097094 -411.194554) (xy 92.078299 -411.202253)
			(xy 92.068142 -411.202632) (xy 91.351862 -411.202632) (xy 91.341729 -411.202204) (xy 91.323002 -411.194458)
			(xy 91.308646 -411.180154) (xy 91.300833 -411.161455) (xy 91.3003 -411.151324) (xy 91.3003 -410.86532)
			(xy 91.3001 -410.858447) (xy 91.296497 -410.845185) (xy 91.293188 -410.839158) (xy 91.276854 -410.810804)
			(xy 91.25114 -410.75063) (xy 91.233735 -410.68755) (xy 91.224954 -410.622705) (xy 87.795057 -410.622705)
			(xy 87.795057 -410.622714) (xy 87.786196 -410.687573) (xy 87.768702 -410.750653) (xy 87.742891 -410.810811)
			(xy 87.72652 -410.839158) (xy 87.723222 -410.845191) (xy 87.719605 -410.858448) (xy 87.719408 -410.86532)
			(xy 87.719408 -411.151324) (xy 87.718935 -411.161433) (xy 87.711191 -411.180111) (xy 87.69689 -411.194404)
			(xy 87.67821 -411.20214) (xy 87.6681 -411.202632) (xy 86.95182 -411.202632) (xy 86.941716 -411.202099)
			(xy 86.923045 -411.194374) (xy 86.90875 -411.180092) (xy 86.901009 -411.161427) (xy 86.900512 -411.151324)
			(xy 86.900512 -410.86532) (xy 86.900311 -410.858447) (xy 86.896709 -410.845185) (xy 86.8934 -410.839158)
			(xy 86.877018 -410.810818) (xy 86.85122 -410.750655) (xy 86.833735 -410.687573) (xy 86.82488 -410.622714)
			(xy 86.824312 -410.589984) (xy 83.394959 -410.589984) (xy 83.39496 -410.622704) (xy 83.386178 -410.687548)
			(xy 83.368771 -410.750626) (xy 83.343054 -410.810797) (xy 83.326732 -410.839158) (xy 83.323435 -410.845191)
			(xy 83.319818 -410.858448) (xy 83.31962 -410.86532) (xy 83.31962 -411.151324) (xy 83.319199 -411.161477)
			(xy 83.311399 -411.180226) (xy 83.297003 -411.194548) (xy 83.278213 -411.202251) (xy 83.268058 -411.202632)
			(xy 82.551778 -411.202632) (xy 82.541646 -411.202191) (xy 82.522919 -411.194451) (xy 82.508563 -411.18015)
			(xy 82.500749 -411.161454) (xy 82.500216 -411.151324) (xy 82.500216 -410.86532) (xy 82.500015 -410.858447)
			(xy 82.496413 -410.845185) (xy 82.493104 -410.839158) (xy 82.476769 -410.810804) (xy 82.451055 -410.750631)
			(xy 82.433649 -410.68755) (xy 82.424868 -410.622705) (xy 78.99497 -410.622705) (xy 78.99497 -410.622714)
			(xy 78.986111 -410.687573) (xy 78.968617 -410.750653) (xy 78.942806 -410.81081) (xy 78.926436 -410.839158)
			(xy 78.923139 -410.845191) (xy 78.919522 -410.858448) (xy 78.919324 -410.86532) (xy 78.919324 -411.151324)
			(xy 78.918835 -411.161431) (xy 78.911094 -411.180106) (xy 78.896799 -411.194399) (xy 78.878123 -411.202137)
			(xy 78.868016 -411.202632) (xy 78.151736 -411.202632) (xy 78.14162 -411.202155) (xy 78.122923 -411.194425)
			(xy 78.108609 -411.180127) (xy 78.100857 -411.16144) (xy 78.100428 -411.151324) (xy 78.100428 -410.86532)
			(xy 78.100225 -410.858448) (xy 78.096624 -410.845185) (xy 78.093316 -410.839158) (xy 78.076935 -410.810817)
			(xy 78.051137 -410.750655) (xy 78.033651 -410.687573) (xy 78.024796 -410.622714) (xy 78.024228 -410.589984)
			(xy 74.594873 -410.589984) (xy 74.594874 -410.622704) (xy 74.586092 -410.687548) (xy 74.568686 -410.750626)
			(xy 74.54297 -410.810797) (xy 74.526648 -410.839158) (xy 74.523352 -410.845192) (xy 74.519734 -410.858448)
			(xy 74.519536 -410.86532) (xy 74.519536 -411.151324) (xy 74.519099 -411.161475) (xy 74.511302 -411.180221)
			(xy 74.496911 -411.194542) (xy 74.478127 -411.202248) (xy 74.467974 -411.202632) (xy 73.751694 -411.202632)
			(xy 73.741563 -411.202177) (xy 73.722837 -411.194442) (xy 73.70848 -411.180146) (xy 73.700666 -411.161452)
			(xy 73.700132 -411.151324) (xy 73.700132 -410.86532) (xy 73.699928 -410.858448) (xy 73.696328 -410.845185)
			(xy 73.69302 -410.839158) (xy 73.676685 -410.810804) (xy 73.650969 -410.750631) (xy 73.633564 -410.687551)
			(xy 73.624782 -410.622705) (xy 66.576956 -410.622705) (xy 66.576956 -412.090108) (xy 71.423792 -412.090108)
			(xy 71.427783 -412.027941) (xy 71.439692 -411.966794) (xy 71.459321 -411.907673) (xy 71.48635 -411.851547)
			(xy 71.520334 -411.799338) (xy 71.560716 -411.751903) (xy 71.606832 -411.710022) (xy 71.657924 -411.674382)
			(xy 71.713155 -411.645568) (xy 71.771617 -411.624054) (xy 71.832351 -411.610192) (xy 71.894358 -411.60421)
			(xy 71.956621 -411.606206) (xy 72.018118 -411.616149) (xy 72.077839 -411.633873) (xy 72.134802 -411.65909)
			(xy 72.188073 -411.691383) (xy 72.236778 -411.730223) (xy 72.280115 -411.774973) (xy 72.317375 -411.824897)
			(xy 72.347944 -411.879176) (xy 72.371322 -411.936919) (xy 72.387123 -411.997177) (xy 72.395089 -412.05896)
			(xy 72.395588 -412.090108) (xy 75.823834 -412.090108) (xy 75.827825 -412.027941) (xy 75.839734 -411.966794)
			(xy 75.859363 -411.907673) (xy 75.886392 -411.851547) (xy 75.920376 -411.799338) (xy 75.960758 -411.751903)
			(xy 76.006874 -411.710022) (xy 76.057966 -411.674382) (xy 76.113197 -411.645568) (xy 76.171659 -411.624054)
			(xy 76.232393 -411.610192) (xy 76.2944 -411.60421) (xy 76.356663 -411.606206) (xy 76.41816 -411.616149)
			(xy 76.477881 -411.633873) (xy 76.534844 -411.65909) (xy 76.588115 -411.691383) (xy 76.63682 -411.730223)
			(xy 76.680157 -411.774973) (xy 76.717417 -411.824897) (xy 76.747986 -411.879176) (xy 76.771364 -411.936919)
			(xy 76.787165 -411.997177) (xy 76.795131 -412.05896) (xy 76.79563 -412.090108) (xy 80.223876 -412.090108)
			(xy 80.227867 -412.027941) (xy 80.239776 -411.966794) (xy 80.259405 -411.907673) (xy 80.286434 -411.851547)
			(xy 80.320418 -411.799338) (xy 80.3608 -411.751903) (xy 80.406916 -411.710022) (xy 80.458008 -411.674382)
			(xy 80.513239 -411.645568) (xy 80.571701 -411.624054) (xy 80.632435 -411.610192) (xy 80.694442 -411.60421)
			(xy 80.756705 -411.606206) (xy 80.818202 -411.616149) (xy 80.877923 -411.633873) (xy 80.934886 -411.65909)
			(xy 80.988157 -411.691383) (xy 81.036862 -411.730223) (xy 81.080199 -411.774973) (xy 81.117459 -411.824897)
			(xy 81.148028 -411.879176) (xy 81.171406 -411.936919) (xy 81.187207 -411.997177) (xy 81.195173 -412.05896)
			(xy 81.195672 -412.090108) (xy 84.623664 -412.090108) (xy 84.627655 -412.027941) (xy 84.639564 -411.966794)
			(xy 84.659193 -411.907673) (xy 84.686222 -411.851547) (xy 84.720206 -411.799338) (xy 84.760588 -411.751903)
			(xy 84.806704 -411.710022) (xy 84.857796 -411.674382) (xy 84.913027 -411.645568) (xy 84.971489 -411.624054)
			(xy 85.032223 -411.610192) (xy 85.09423 -411.60421) (xy 85.156493 -411.606206) (xy 85.21799 -411.616149)
			(xy 85.277711 -411.633873) (xy 85.334674 -411.65909) (xy 85.387945 -411.691383) (xy 85.43665 -411.730223)
			(xy 85.479987 -411.774973) (xy 85.517247 -411.824897) (xy 85.547816 -411.879176) (xy 85.571194 -411.936919)
			(xy 85.586995 -411.997177) (xy 85.594961 -412.05896) (xy 85.59546 -412.090108) (xy 89.023706 -412.090108)
			(xy 89.027697 -412.027941) (xy 89.039606 -411.966794) (xy 89.059235 -411.907673) (xy 89.086264 -411.851547)
			(xy 89.120248 -411.799338) (xy 89.16063 -411.751903) (xy 89.206746 -411.710022) (xy 89.257838 -411.674382)
			(xy 89.313069 -411.645568) (xy 89.371531 -411.624054) (xy 89.432265 -411.610192) (xy 89.494272 -411.60421)
			(xy 89.556535 -411.606206) (xy 89.618032 -411.616149) (xy 89.677753 -411.633873) (xy 89.734716 -411.65909)
			(xy 89.787987 -411.691383) (xy 89.836692 -411.730223) (xy 89.880029 -411.774973) (xy 89.917289 -411.824897)
			(xy 89.947858 -411.879176) (xy 89.971236 -411.936919) (xy 89.987037 -411.997177) (xy 89.995003 -412.05896)
			(xy 89.995502 -412.090108) (xy 115.423958 -412.090108) (xy 115.427949 -412.027941) (xy 115.439858 -411.966794)
			(xy 115.459487 -411.907673) (xy 115.486516 -411.851547) (xy 115.5205 -411.799338) (xy 115.560882 -411.751903)
			(xy 115.606998 -411.710022) (xy 115.65809 -411.674382) (xy 115.713321 -411.645568) (xy 115.771783 -411.624054)
			(xy 115.832517 -411.610192) (xy 115.894524 -411.60421) (xy 115.956787 -411.606206) (xy 116.018284 -411.616149)
			(xy 116.078005 -411.633873) (xy 116.134968 -411.65909) (xy 116.188239 -411.691383) (xy 116.236944 -411.730223)
			(xy 116.280281 -411.774973) (xy 116.317541 -411.824897) (xy 116.34811 -411.879176) (xy 116.371488 -411.936919)
			(xy 116.387289 -411.997177) (xy 116.395255 -412.05896) (xy 116.395754 -412.090108) (xy 119.824 -412.090108)
			(xy 119.827991 -412.027941) (xy 119.8399 -411.966794) (xy 119.859529 -411.907673) (xy 119.886558 -411.851547)
			(xy 119.920542 -411.799338) (xy 119.960924 -411.751903) (xy 120.00704 -411.710022) (xy 120.058132 -411.674382)
			(xy 120.113363 -411.645568) (xy 120.171825 -411.624054) (xy 120.232559 -411.610192) (xy 120.294566 -411.60421)
			(xy 120.356829 -411.606206) (xy 120.418326 -411.616149) (xy 120.478047 -411.633873) (xy 120.53501 -411.65909)
			(xy 120.588281 -411.691383) (xy 120.636986 -411.730223) (xy 120.680323 -411.774973) (xy 120.717583 -411.824897)
			(xy 120.748152 -411.879176) (xy 120.77153 -411.936919) (xy 120.787331 -411.997177) (xy 120.795297 -412.05896)
			(xy 120.795796 -412.090108) (xy 124.224042 -412.090108) (xy 124.228033 -412.027941) (xy 124.239942 -411.966794)
			(xy 124.259571 -411.907673) (xy 124.2866 -411.851547) (xy 124.320584 -411.799338) (xy 124.360966 -411.751903)
			(xy 124.407082 -411.710022) (xy 124.458174 -411.674382) (xy 124.513405 -411.645568) (xy 124.571867 -411.624054)
			(xy 124.632601 -411.610192) (xy 124.694608 -411.60421) (xy 124.756871 -411.606206) (xy 124.818368 -411.616149)
			(xy 124.878089 -411.633873) (xy 124.935052 -411.65909) (xy 124.988323 -411.691383) (xy 125.037028 -411.730223)
			(xy 125.080365 -411.774973) (xy 125.117625 -411.824897) (xy 125.148194 -411.879176) (xy 125.171572 -411.936919)
			(xy 125.187373 -411.997177) (xy 125.195339 -412.05896) (xy 125.195838 -412.090108) (xy 128.62383 -412.090108)
			(xy 128.627821 -412.027941) (xy 128.63973 -411.966794) (xy 128.659359 -411.907673) (xy 128.686388 -411.851547)
			(xy 128.720372 -411.799338) (xy 128.760754 -411.751903) (xy 128.80687 -411.710022) (xy 128.857962 -411.674382)
			(xy 128.913193 -411.645568) (xy 128.971655 -411.624054) (xy 129.032389 -411.610192) (xy 129.094396 -411.60421)
			(xy 129.156659 -411.606206) (xy 129.218156 -411.616149) (xy 129.277877 -411.633873) (xy 129.33484 -411.65909)
			(xy 129.388111 -411.691383) (xy 129.436816 -411.730223) (xy 129.480153 -411.774973) (xy 129.517413 -411.824897)
			(xy 129.547982 -411.879176) (xy 129.57136 -411.936919) (xy 129.587161 -411.997177) (xy 129.595127 -412.05896)
			(xy 129.595626 -412.090108) (xy 133.023872 -412.090108) (xy 133.027863 -412.027941) (xy 133.039772 -411.966794)
			(xy 133.059401 -411.907673) (xy 133.08643 -411.851547) (xy 133.120414 -411.799338) (xy 133.160796 -411.751903)
			(xy 133.206912 -411.710022) (xy 133.258004 -411.674382) (xy 133.313235 -411.645568) (xy 133.371697 -411.624054)
			(xy 133.432431 -411.610192) (xy 133.494438 -411.60421) (xy 133.556701 -411.606206) (xy 133.618198 -411.616149)
			(xy 133.677919 -411.633873) (xy 133.734882 -411.65909) (xy 133.788153 -411.691383) (xy 133.836858 -411.730223)
			(xy 133.880195 -411.774973) (xy 133.917455 -411.824897) (xy 133.948024 -411.879176) (xy 133.971402 -411.936919)
			(xy 133.987203 -411.997177) (xy 133.995169 -412.05896) (xy 133.995668 -412.090108) (xy 133.995169 -412.121256)
			(xy 133.987203 -412.183039) (xy 133.971402 -412.243297) (xy 133.948024 -412.30104) (xy 133.917455 -412.355319)
			(xy 133.880195 -412.405243) (xy 133.836858 -412.449993) (xy 133.788153 -412.488833) (xy 133.734882 -412.521126)
			(xy 133.677919 -412.546343) (xy 133.618198 -412.564067) (xy 133.556701 -412.57401) (xy 133.494438 -412.576006)
			(xy 133.432431 -412.570024) (xy 133.371697 -412.556162) (xy 133.313235 -412.534648) (xy 133.258004 -412.505834)
			(xy 133.206912 -412.470194) (xy 133.160796 -412.428313) (xy 133.120414 -412.380878) (xy 133.08643 -412.328669)
			(xy 133.059401 -412.272543) (xy 133.039772 -412.213422) (xy 133.027863 -412.152275) (xy 133.023872 -412.090108)
			(xy 129.595626 -412.090108) (xy 129.595127 -412.121256) (xy 129.587161 -412.183039) (xy 129.57136 -412.243297)
			(xy 129.547982 -412.30104) (xy 129.517413 -412.355319) (xy 129.480153 -412.405243) (xy 129.436816 -412.449993)
			(xy 129.388111 -412.488833) (xy 129.33484 -412.521126) (xy 129.277877 -412.546343) (xy 129.218156 -412.564067)
			(xy 129.156659 -412.57401) (xy 129.094396 -412.576006) (xy 129.032389 -412.570024) (xy 128.971655 -412.556162)
			(xy 128.913193 -412.534648) (xy 128.857962 -412.505834) (xy 128.80687 -412.470194) (xy 128.760754 -412.428313)
			(xy 128.720372 -412.380878) (xy 128.686388 -412.328669) (xy 128.659359 -412.272543) (xy 128.63973 -412.213422)
			(xy 128.627821 -412.152275) (xy 128.62383 -412.090108) (xy 125.195838 -412.090108) (xy 125.195339 -412.121256)
			(xy 125.187373 -412.183039) (xy 125.171572 -412.243297) (xy 125.148194 -412.30104) (xy 125.117625 -412.355319)
			(xy 125.080365 -412.405243) (xy 125.037028 -412.449993) (xy 124.988323 -412.488833) (xy 124.935052 -412.521126)
			(xy 124.878089 -412.546343) (xy 124.818368 -412.564067) (xy 124.756871 -412.57401) (xy 124.694608 -412.576006)
			(xy 124.632601 -412.570024) (xy 124.571867 -412.556162) (xy 124.513405 -412.534648) (xy 124.458174 -412.505834)
			(xy 124.407082 -412.470194) (xy 124.360966 -412.428313) (xy 124.320584 -412.380878) (xy 124.2866 -412.328669)
			(xy 124.259571 -412.272543) (xy 124.239942 -412.213422) (xy 124.228033 -412.152275) (xy 124.224042 -412.090108)
			(xy 120.795796 -412.090108) (xy 120.795297 -412.121256) (xy 120.787331 -412.183039) (xy 120.77153 -412.243297)
			(xy 120.748152 -412.30104) (xy 120.717583 -412.355319) (xy 120.680323 -412.405243) (xy 120.636986 -412.449993)
			(xy 120.588281 -412.488833) (xy 120.53501 -412.521126) (xy 120.478047 -412.546343) (xy 120.418326 -412.564067)
			(xy 120.356829 -412.57401) (xy 120.294566 -412.576006) (xy 120.232559 -412.570024) (xy 120.171825 -412.556162)
			(xy 120.113363 -412.534648) (xy 120.058132 -412.505834) (xy 120.00704 -412.470194) (xy 119.960924 -412.428313)
			(xy 119.920542 -412.380878) (xy 119.886558 -412.328669) (xy 119.859529 -412.272543) (xy 119.8399 -412.213422)
			(xy 119.827991 -412.152275) (xy 119.824 -412.090108) (xy 116.395754 -412.090108) (xy 116.395255 -412.121256)
			(xy 116.387289 -412.183039) (xy 116.371488 -412.243297) (xy 116.34811 -412.30104) (xy 116.317541 -412.355319)
			(xy 116.280281 -412.405243) (xy 116.236944 -412.449993) (xy 116.188239 -412.488833) (xy 116.134968 -412.521126)
			(xy 116.078005 -412.546343) (xy 116.018284 -412.564067) (xy 115.956787 -412.57401) (xy 115.894524 -412.576006)
			(xy 115.832517 -412.570024) (xy 115.771783 -412.556162) (xy 115.713321 -412.534648) (xy 115.65809 -412.505834)
			(xy 115.606998 -412.470194) (xy 115.560882 -412.428313) (xy 115.5205 -412.380878) (xy 115.486516 -412.328669)
			(xy 115.459487 -412.272543) (xy 115.439858 -412.213422) (xy 115.427949 -412.152275) (xy 115.423958 -412.090108)
			(xy 89.995502 -412.090108) (xy 89.995003 -412.121256) (xy 89.987037 -412.183039) (xy 89.971236 -412.243297)
			(xy 89.947858 -412.30104) (xy 89.917289 -412.355319) (xy 89.880029 -412.405243) (xy 89.836692 -412.449993)
			(xy 89.787987 -412.488833) (xy 89.734716 -412.521126) (xy 89.677753 -412.546343) (xy 89.618032 -412.564067)
			(xy 89.556535 -412.57401) (xy 89.494272 -412.576006) (xy 89.432265 -412.570024) (xy 89.371531 -412.556162)
			(xy 89.313069 -412.534648) (xy 89.257838 -412.505834) (xy 89.206746 -412.470194) (xy 89.16063 -412.428313)
			(xy 89.120248 -412.380878) (xy 89.086264 -412.328669) (xy 89.059235 -412.272543) (xy 89.039606 -412.213422)
			(xy 89.027697 -412.152275) (xy 89.023706 -412.090108) (xy 85.59546 -412.090108) (xy 85.594961 -412.121256)
			(xy 85.586995 -412.183039) (xy 85.571194 -412.243297) (xy 85.547816 -412.30104) (xy 85.517247 -412.355319)
			(xy 85.479987 -412.405243) (xy 85.43665 -412.449993) (xy 85.387945 -412.488833) (xy 85.334674 -412.521126)
			(xy 85.277711 -412.546343) (xy 85.21799 -412.564067) (xy 85.156493 -412.57401) (xy 85.09423 -412.576006)
			(xy 85.032223 -412.570024) (xy 84.971489 -412.556162) (xy 84.913027 -412.534648) (xy 84.857796 -412.505834)
			(xy 84.806704 -412.470194) (xy 84.760588 -412.428313) (xy 84.720206 -412.380878) (xy 84.686222 -412.328669)
			(xy 84.659193 -412.272543) (xy 84.639564 -412.213422) (xy 84.627655 -412.152275) (xy 84.623664 -412.090108)
			(xy 81.195672 -412.090108) (xy 81.195173 -412.121256) (xy 81.187207 -412.183039) (xy 81.171406 -412.243297)
			(xy 81.148028 -412.30104) (xy 81.117459 -412.355319) (xy 81.080199 -412.405243) (xy 81.036862 -412.449993)
			(xy 80.988157 -412.488833) (xy 80.934886 -412.521126) (xy 80.877923 -412.546343) (xy 80.818202 -412.564067)
			(xy 80.756705 -412.57401) (xy 80.694442 -412.576006) (xy 80.632435 -412.570024) (xy 80.571701 -412.556162)
			(xy 80.513239 -412.534648) (xy 80.458008 -412.505834) (xy 80.406916 -412.470194) (xy 80.3608 -412.428313)
			(xy 80.320418 -412.380878) (xy 80.286434 -412.328669) (xy 80.259405 -412.272543) (xy 80.239776 -412.213422)
			(xy 80.227867 -412.152275) (xy 80.223876 -412.090108) (xy 76.79563 -412.090108) (xy 76.795131 -412.121256)
			(xy 76.787165 -412.183039) (xy 76.771364 -412.243297) (xy 76.747986 -412.30104) (xy 76.717417 -412.355319)
			(xy 76.680157 -412.405243) (xy 76.63682 -412.449993) (xy 76.588115 -412.488833) (xy 76.534844 -412.521126)
			(xy 76.477881 -412.546343) (xy 76.41816 -412.564067) (xy 76.356663 -412.57401) (xy 76.2944 -412.576006)
			(xy 76.232393 -412.570024) (xy 76.171659 -412.556162) (xy 76.113197 -412.534648) (xy 76.057966 -412.505834)
			(xy 76.006874 -412.470194) (xy 75.960758 -412.428313) (xy 75.920376 -412.380878) (xy 75.886392 -412.328669)
			(xy 75.859363 -412.272543) (xy 75.839734 -412.213422) (xy 75.827825 -412.152275) (xy 75.823834 -412.090108)
			(xy 72.395588 -412.090108) (xy 72.395089 -412.121256) (xy 72.387123 -412.183039) (xy 72.371322 -412.243297)
			(xy 72.347944 -412.30104) (xy 72.317375 -412.355319) (xy 72.280115 -412.405243) (xy 72.236778 -412.449993)
			(xy 72.188073 -412.488833) (xy 72.134802 -412.521126) (xy 72.077839 -412.546343) (xy 72.018118 -412.564067)
			(xy 71.956621 -412.57401) (xy 71.894358 -412.576006) (xy 71.832351 -412.570024) (xy 71.771617 -412.556162)
			(xy 71.713155 -412.534648) (xy 71.657924 -412.505834) (xy 71.606832 -412.470194) (xy 71.560716 -412.428313)
			(xy 71.520334 -412.380878) (xy 71.48635 -412.328669) (xy 71.459321 -412.272543) (xy 71.439692 -412.213422)
			(xy 71.427783 -412.152275) (xy 71.423792 -412.090108) (xy 66.576956 -412.090108) (xy 66.576956 -416.13836)
			(xy 66.577972 -416.148012) (xy 66.579596 -416.155258) (xy 66.586434 -416.16843) (xy 66.591434 -416.17392)
			(xy 66.625216 -416.207702) (xy 66.630715 -416.21269) (xy 66.643881 -416.219537) (xy 66.651124 -416.221164)
			(xy 66.660776 -416.22218) (xy 140.973048 -416.22218) (xy 140.982071 -416.221815) (xy 140.999002 -416.215563)
			(xy 141.012729 -416.203846) (xy 141.021562 -416.188108) (xy 141.02334 -416.179254) (xy 141.02334 -394.305282)
			(xy 141.023869 -394.291599) (xy 141.033313 -394.265916) (xy 141.051064 -394.245089) (xy 141.074925 -394.231693)
			(xy 141.088364 -394.229082) (xy 141.09065 -394.228574) (xy 141.095984 -394.22578) (xy 141.098524 -394.224256)
			(xy 141.107414 -394.217144) (xy 141.1859 -394.138658) (xy 141.193296 -394.131805) (xy 141.211894 -394.124062)
			(xy 141.221968 -394.123672) (xy 154.47518 -394.123672) (xy 154.485231 -394.124178) (xy 154.503791 -394.131899)
			(xy 154.511248 -394.138658) (xy 154.517852 -394.145262) (xy 154.521662 -394.154406) (xy 154.523435 -394.159034)
			(xy 154.525353 -394.168755) (xy 154.525472 -394.17371) (xy 154.525472 -394.307314) (xy 154.525765 -394.315187)
			(xy 154.53055 -394.330189) (xy 154.53487 -394.336778) (xy 154.57678 -394.378688) (xy 154.57678 -395.4272)
			(xy 157.53664 -395.4272) (xy 157.540711 -395.371578) (xy 157.552837 -395.317141) (xy 157.57276 -395.26505)
			(xy 157.600056 -395.216415) (xy 157.634142 -395.172272) (xy 157.674291 -395.133563) (xy 157.719649 -395.101112)
			(xy 157.769249 -395.075611) (xy 157.822033 -395.057604) (xy 157.876876 -395.047474) (xy 157.93261 -395.045437)
			(xy 157.988047 -395.051537) (xy 158.042004 -395.065643) (xy 158.093333 -395.087455) (xy 158.140939 -395.116509)
			(xy 158.183807 -395.152184) (xy 158.221024 -395.193721) (xy 158.251797 -395.240234) (xy 158.275469 -395.290731)
			(xy 158.291537 -395.344138) (xy 158.299657 -395.399314) (xy 158.300166 -395.4272) (xy 158.299657 -395.455086)
			(xy 158.291537 -395.510262) (xy 158.275469 -395.563669) (xy 158.251797 -395.614166) (xy 158.221024 -395.660679)
			(xy 158.183807 -395.702216) (xy 158.140939 -395.737891) (xy 158.093333 -395.766945) (xy 158.042004 -395.788757)
			(xy 157.988047 -395.802863) (xy 157.93261 -395.808963) (xy 157.876876 -395.806926) (xy 157.822033 -395.796796)
			(xy 157.769249 -395.778789) (xy 157.719649 -395.753288) (xy 157.674291 -395.720837) (xy 157.634142 -395.682128)
			(xy 157.600056 -395.637985) (xy 157.57276 -395.58935) (xy 157.552837 -395.537259) (xy 157.540711 -395.482822)
			(xy 157.53664 -395.4272) (xy 154.57678 -395.4272) (xy 154.57678 -401.7228) (xy 159.424965 -401.7228)
			(xy 159.424967 -401.657362) (xy 159.433753 -401.592517) (xy 159.451163 -401.529438) (xy 159.476881 -401.469266)
			(xy 159.493204 -401.440904) (xy 159.496518 -401.434879) (xy 159.500124 -401.421615) (xy 159.500316 -401.414742)
			(xy 159.500316 -400.665442) (xy 159.500106 -400.65857) (xy 159.49651 -400.645307) (xy 159.493204 -400.63928)
			(xy 159.476888 -400.610916) (xy 159.451172 -400.550745) (xy 159.433764 -400.487667) (xy 159.424981 -400.422823)
			(xy 159.42498 -400.357387) (xy 159.433762 -400.292543) (xy 159.451168 -400.229465) (xy 159.476883 -400.169294)
			(xy 159.493204 -400.140932) (xy 159.496508 -400.134902) (xy 159.50012 -400.121642) (xy 159.500316 -400.11477)
			(xy 159.500316 -399.828766) (xy 159.500805 -399.818609) (xy 159.508586 -399.799843) (xy 159.522953 -399.78548)
			(xy 159.541721 -399.777703) (xy 159.551878 -399.777204) (xy 160.268158 -399.777204) (xy 160.278323 -399.777697)
			(xy 160.29711 -399.785462) (xy 160.311495 -399.799826) (xy 160.319288 -399.818602) (xy 160.31972 -399.828766)
			(xy 160.31972 -400.11477) (xy 160.319921 -400.121643) (xy 160.323523 -400.134905) (xy 160.326832 -400.140932)
			(xy 160.34316 -400.16929) (xy 160.368879 -400.229462) (xy 160.386287 -400.292541) (xy 160.395071 -400.357386)
			(xy 160.39507 -400.422824) (xy 160.386285 -400.487669) (xy 160.368875 -400.550748) (xy 160.343156 -400.610919)
			(xy 160.326832 -400.63928) (xy 160.323527 -400.645309) (xy 160.319915 -400.658569) (xy 160.31972 -400.665442)
			(xy 160.31972 -401.414742) (xy 160.319932 -401.421614) (xy 160.323526 -401.434877) (xy 160.326832 -401.440904)
			(xy 160.343136 -401.469275) (xy 160.368857 -401.529444) (xy 160.386269 -401.59252) (xy 160.395055 -401.657363)
			(xy 160.395058 -401.722799) (xy 160.386276 -401.787643) (xy 160.36887 -401.850721) (xy 160.343154 -401.910891)
			(xy 160.326832 -401.939252) (xy 160.323501 -401.945269) (xy 160.319906 -401.958539) (xy 160.31972 -401.965414)
			(xy 160.31972 -402.251418) (xy 160.31935 -402.261596) (xy 160.311551 -402.280399) (xy 160.297149 -402.294785)
			(xy 160.278336 -402.302562) (xy 160.268158 -402.30298) (xy 159.551878 -402.30298) (xy 159.541721 -402.302485)
			(xy 159.522955 -402.294707) (xy 159.508591 -402.280342) (xy 159.500814 -402.261575) (xy 159.500316 -402.251418)
			(xy 159.500316 -401.965414) (xy 159.500117 -401.958541) (xy 159.496513 -401.945279) (xy 159.493204 -401.939252)
			(xy 159.476864 -401.910901) (xy 159.45115 -401.850727) (xy 159.433745 -401.787646) (xy 159.424965 -401.7228)
			(xy 154.57678 -401.7228) (xy 154.57678 -402.790152) (xy 161.624264 -402.790152) (xy 161.624835 -402.757423)
			(xy 161.63369 -402.692565) (xy 161.651179 -402.629485) (xy 161.676984 -402.569326) (xy 161.693352 -402.540978)
			(xy 161.696671 -402.534955) (xy 161.700274 -402.52169) (xy 161.700464 -402.514816) (xy 161.700464 -401.765516)
			(xy 161.70027 -401.758643) (xy 161.696664 -401.74538) (xy 161.693352 -401.739354) (xy 161.676973 -401.711012)
			(xy 161.651173 -401.65085) (xy 161.633687 -401.587768) (xy 161.624832 -401.52291) (xy 161.624264 -401.49018)
			(xy 161.624848 -401.457451) (xy 161.633699 -401.392594) (xy 161.651184 -401.329514) (xy 161.676986 -401.269355)
			(xy 161.693352 -401.241006) (xy 161.696661 -401.234978) (xy 161.700271 -401.221717) (xy 161.700464 -401.214844)
			(xy 161.700464 -400.92884) (xy 161.700948 -400.918725) (xy 161.708676 -400.900029) (xy 161.722972 -400.885714)
			(xy 161.741657 -400.877961) (xy 161.751772 -400.877532) (xy 162.468052 -400.877532) (xy 162.478175 -400.877956)
			(xy 162.496884 -400.885694) (xy 162.511201 -400.900009) (xy 162.518942 -400.918717) (xy 162.51936 -400.92884)
			(xy 162.51936 -401.214844) (xy 162.519578 -401.221715) (xy 162.523169 -401.234978) (xy 162.526472 -401.241006)
			(xy 162.542837 -401.269355) (xy 162.56864 -401.329515) (xy 162.58613 -401.392594) (xy 162.59499 -401.457451)
			(xy 162.59556 -401.49018) (xy 162.595 -401.52291) (xy 162.586141 -401.587768) (xy 162.568649 -401.650848)
			(xy 162.551819 -401.690078) (xy 163.824412 -401.690078) (xy 163.824989 -401.657349) (xy 163.833841 -401.592491)
			(xy 163.851328 -401.529411) (xy 163.877133 -401.469252) (xy 163.8935 -401.440904) (xy 163.896813 -401.434879)
			(xy 163.90042 -401.421615) (xy 163.900612 -401.414742) (xy 163.900612 -400.665442) (xy 163.900402 -400.65857)
			(xy 163.896806 -400.645307) (xy 163.8935 -400.63928) (xy 163.877126 -400.610935) (xy 163.851327 -400.550774)
			(xy 163.833839 -400.487693) (xy 163.824981 -400.422835) (xy 163.824412 -400.390106) (xy 163.824957 -400.357376)
			(xy 163.833818 -400.292517) (xy 163.851315 -400.229436) (xy 163.877129 -400.169279) (xy 163.8935 -400.140932)
			(xy 163.896803 -400.134902) (xy 163.900416 -400.121642) (xy 163.900612 -400.11477) (xy 163.900612 -399.828766)
			(xy 163.901098 -399.818641) (xy 163.908832 -399.799924) (xy 163.923117 -399.78557) (xy 163.941797 -399.777747)
			(xy 163.95192 -399.777204) (xy 164.6682 -399.777204) (xy 164.678355 -399.777622) (xy 164.697108 -399.785418)
			(xy 164.711431 -399.799816) (xy 164.71913 -399.818609) (xy 164.719508 -399.828766) (xy 164.719508 -400.11477)
			(xy 164.719711 -400.121642) (xy 164.723312 -400.134905) (xy 164.72662 -400.140932) (xy 164.743 -400.169273)
			(xy 164.768798 -400.229436) (xy 164.786283 -400.292518) (xy 164.79514 -400.357376) (xy 164.795708 -400.390106)
			(xy 164.795121 -400.422835) (xy 164.786272 -400.487692) (xy 164.768787 -400.550772) (xy 164.742986 -400.610931)
			(xy 164.72662 -400.63928) (xy 164.723314 -400.645309) (xy 164.719702 -400.658569) (xy 164.719508 -400.665442)
			(xy 164.719508 -401.414742) (xy 164.719721 -401.421614) (xy 164.723315 -401.434876) (xy 164.72662 -401.440904)
			(xy 164.742989 -401.469251) (xy 164.76879 -401.529412) (xy 164.786278 -401.592492) (xy 164.795138 -401.657349)
			(xy 164.795708 -401.690078) (xy 164.795154 -401.722808) (xy 164.786295 -401.787667) (xy 164.768801 -401.850747)
			(xy 164.74299 -401.910904) (xy 164.72662 -401.939252) (xy 164.723288 -401.945268) (xy 164.719693 -401.958538)
			(xy 164.719508 -401.965414) (xy 164.719508 -402.251418) (xy 164.71899 -402.26154) (xy 164.711265 -402.280253)
			(xy 164.696989 -402.294607) (xy 164.678319 -402.302434) (xy 164.6682 -402.30298) (xy 163.95192 -402.30298)
			(xy 163.941765 -402.302562) (xy 163.923009 -402.294769) (xy 163.908684 -402.280371) (xy 163.900987 -402.261575)
			(xy 163.900612 -402.251418) (xy 163.900612 -401.965414) (xy 163.900413 -401.958541) (xy 163.89681 -401.945279)
			(xy 163.8935 -401.939252) (xy 163.877115 -401.910913) (xy 163.851318 -401.85075) (xy 163.833834 -401.787667)
			(xy 163.824979 -401.722808) (xy 163.824412 -401.690078) (xy 162.551819 -401.690078) (xy 162.542841 -401.711006)
			(xy 162.526472 -401.739354) (xy 162.523172 -401.745386) (xy 162.519557 -401.758644) (xy 162.51936 -401.765516)
			(xy 162.51936 -402.514816) (xy 162.519551 -402.521689) (xy 162.52316 -402.534952) (xy 162.526472 -402.540978)
			(xy 162.542826 -402.569334) (xy 162.568631 -402.629491) (xy 162.586124 -402.692568) (xy 162.594988 -402.757424)
			(xy 162.59556 -402.790152) (xy 162.594987 -402.822879) (xy 166.024881 -402.822879) (xy 166.024887 -402.757439)
			(xy 166.033676 -402.692592) (xy 166.05109 -402.629511) (xy 166.076815 -402.569339) (xy 166.09314 -402.540978)
			(xy 166.096458 -402.534955) (xy 166.100062 -402.52169) (xy 166.100252 -402.514816) (xy 166.100252 -401.765516)
			(xy 166.10006 -401.758643) (xy 166.096452 -401.74538) (xy 166.09314 -401.739354) (xy 166.076801 -401.711002)
			(xy 166.051085 -401.650829) (xy 166.033678 -401.587748) (xy 166.024897 -401.522902) (xy 166.024899 -401.457464)
			(xy 166.033685 -401.392618) (xy 166.051096 -401.329539) (xy 166.076816 -401.269367) (xy 166.09314 -401.241006)
			(xy 166.096448 -401.234978) (xy 166.100059 -401.221717) (xy 166.100252 -401.214844) (xy 166.100252 -400.92884)
			(xy 166.100754 -400.918694) (xy 166.108527 -400.899952) (xy 166.122899 -400.885629) (xy 166.141667 -400.87792)
			(xy 166.151814 -400.877532) (xy 166.868094 -400.877532) (xy 166.878219 -400.878031) (xy 166.896939 -400.885756)
			(xy 166.911295 -400.900038) (xy 166.919116 -400.918717) (xy 166.919656 -400.92884) (xy 166.919656 -401.214844)
			(xy 166.919862 -401.221716) (xy 166.92346 -401.234979) (xy 166.926768 -401.241006) (xy 166.943073 -401.269377)
			(xy 166.968792 -401.329546) (xy 166.986202 -401.392622) (xy 166.994987 -401.457465) (xy 166.994989 -401.5229)
			(xy 166.986209 -401.587744) (xy 166.968803 -401.650822) (xy 166.943089 -401.710993) (xy 166.936294 -401.7228)
			(xy 168.225051 -401.7228) (xy 168.225054 -401.657362) (xy 168.233839 -401.592517) (xy 168.251248 -401.529438)
			(xy 168.276966 -401.469266) (xy 168.293288 -401.440904) (xy 168.2966 -401.434878) (xy 168.300208 -401.421615)
			(xy 168.3004 -401.414742) (xy 168.3004 -400.665442) (xy 168.300192 -400.65857) (xy 168.296595 -400.645307)
			(xy 168.293288 -400.63928) (xy 168.276972 -400.610915) (xy 168.251257 -400.550744) (xy 168.23385 -400.487666)
			(xy 168.225067 -400.422823) (xy 168.225066 -400.357387) (xy 168.233848 -400.292544) (xy 168.251254 -400.229465)
			(xy 168.276968 -400.169294) (xy 168.293288 -400.140932) (xy 168.296591 -400.134901) (xy 168.300204 -400.121642)
			(xy 168.3004 -400.11477) (xy 168.3004 -399.828766) (xy 168.300905 -399.818611) (xy 168.308683 -399.799848)
			(xy 168.323045 -399.785485) (xy 168.341807 -399.777705) (xy 168.351962 -399.777204) (xy 169.068242 -399.777204)
			(xy 169.078398 -399.777698) (xy 169.097162 -399.78548) (xy 169.111524 -399.799845) (xy 169.119303 -399.81861)
			(xy 169.119804 -399.828766) (xy 169.119804 -400.11477) (xy 169.120007 -400.121642) (xy 169.123608 -400.134905)
			(xy 169.126916 -400.140932) (xy 169.143245 -400.16929) (xy 169.168964 -400.229461) (xy 169.186373 -400.292541)
			(xy 169.195157 -400.357386) (xy 169.195156 -400.422824) (xy 169.186371 -400.487669) (xy 169.168961 -400.550748)
			(xy 169.14324 -400.610919) (xy 169.126916 -400.63928) (xy 169.12361 -400.645309) (xy 169.119998 -400.658569)
			(xy 169.119804 -400.665442) (xy 169.119804 -401.414742) (xy 169.120018 -401.421614) (xy 169.123611 -401.434876)
			(xy 169.126916 -401.440904) (xy 169.143221 -401.469275) (xy 169.168943 -401.529443) (xy 169.186355 -401.59252)
			(xy 169.195141 -401.657363) (xy 169.195144 -401.722799) (xy 169.186362 -401.787643) (xy 169.168955 -401.850721)
			(xy 169.143238 -401.910891) (xy 169.126916 -401.939252) (xy 169.123584 -401.945268) (xy 169.119989 -401.958538)
			(xy 169.119804 -401.965414) (xy 169.119804 -402.251418) (xy 169.119283 -402.261572) (xy 169.11151 -402.280333)
			(xy 169.097154 -402.294697) (xy 169.078396 -402.302478) (xy 169.068242 -402.30298) (xy 168.351962 -402.30298)
			(xy 168.341804 -402.302498) (xy 168.323037 -402.294715) (xy 168.308674 -402.280346) (xy 168.300898 -402.261576)
			(xy 168.3004 -402.251418) (xy 168.3004 -401.965414) (xy 168.300203 -401.958541) (xy 168.296598 -401.945278)
			(xy 168.293288 -401.939252) (xy 168.276949 -401.9109) (xy 168.251236 -401.850726) (xy 168.233831 -401.787646)
			(xy 168.225051 -401.7228) (xy 166.936294 -401.7228) (xy 166.926768 -401.739354) (xy 166.923467 -401.745385)
			(xy 166.919853 -401.758644) (xy 166.919656 -401.765516) (xy 166.919656 -402.514816) (xy 166.919835 -402.52169)
			(xy 166.923451 -402.534953) (xy 166.926768 -402.540978) (xy 166.943049 -402.569362) (xy 166.96877 -402.629528)
			(xy 166.986183 -402.692602) (xy 166.994971 -402.757442) (xy 166.994974 -402.790152) (xy 170.424348 -402.790152)
			(xy 170.424922 -402.757423) (xy 170.433776 -402.692565) (xy 170.451264 -402.629485) (xy 170.477069 -402.569326)
			(xy 170.493436 -402.540978) (xy 170.496754 -402.534955) (xy 170.500358 -402.52169) (xy 170.500548 -402.514816)
			(xy 170.500548 -401.765516) (xy 170.500356 -401.758643) (xy 170.496749 -401.74538) (xy 170.493436 -401.739354)
			(xy 170.477056 -401.711013) (xy 170.451256 -401.650851) (xy 170.433771 -401.587769) (xy 170.424915 -401.52291)
			(xy 170.424348 -401.49018) (xy 170.424934 -401.457451) (xy 170.433785 -401.392594) (xy 170.451269 -401.329514)
			(xy 170.47707 -401.269355) (xy 170.493436 -401.241006) (xy 170.496744 -401.234978) (xy 170.500355 -401.221717)
			(xy 170.500548 -401.214844) (xy 170.500548 -400.92884) (xy 170.501117 -400.91874) (xy 170.508832 -400.900073)
			(xy 170.523102 -400.885779) (xy 170.541757 -400.878033) (xy 170.551856 -400.877532) (xy 171.268136 -400.877532)
			(xy 171.278265 -400.877887) (xy 171.296975 -400.885653) (xy 171.311289 -400.899989) (xy 171.319028 -400.918711)
			(xy 171.319444 -400.92884) (xy 171.319444 -401.214844) (xy 171.319652 -401.221716) (xy 171.323249 -401.234979)
			(xy 171.326556 -401.241006) (xy 171.34292 -401.269356) (xy 171.368723 -401.329515) (xy 171.386213 -401.392594)
			(xy 171.395074 -401.457451) (xy 171.395644 -401.49018) (xy 171.395086 -401.52291) (xy 171.386227 -401.587768)
			(xy 171.368734 -401.650848) (xy 171.342925 -401.711006) (xy 171.336115 -401.7228) (xy 172.624827 -401.7228)
			(xy 172.624829 -401.657362) (xy 172.633616 -401.592516) (xy 172.651029 -401.529436) (xy 172.676751 -401.469265)
			(xy 172.693076 -401.440904) (xy 172.696388 -401.434878) (xy 172.699996 -401.421615) (xy 172.700188 -401.414742)
			(xy 172.700188 -400.665442) (xy 172.699981 -400.65857) (xy 172.696383 -400.645307) (xy 172.693076 -400.63928)
			(xy 172.676758 -400.610916) (xy 172.651038 -400.550746) (xy 172.633628 -400.487668) (xy 172.624843 -400.422824)
			(xy 172.624842 -400.357387) (xy 172.633626 -400.292542) (xy 172.651034 -400.229464) (xy 172.676753 -400.169293)
			(xy 172.693076 -400.140932) (xy 172.696378 -400.134901) (xy 172.699992 -400.121642) (xy 172.700188 -400.11477)
			(xy 172.700188 -399.828766) (xy 172.700537 -399.818586) (xy 172.708343 -399.799781) (xy 172.722752 -399.785395)
			(xy 172.741569 -399.777621) (xy 172.75175 -399.777204) (xy 173.46803 -399.777204) (xy 173.478186 -399.777708)
			(xy 173.496949 -399.785486) (xy 173.511312 -399.799848) (xy 173.519091 -399.818611) (xy 173.519592 -399.828766)
			(xy 173.519592 -400.11477) (xy 173.519796 -400.121642) (xy 173.523396 -400.134905) (xy 173.526704 -400.140932)
			(xy 173.54303 -400.169291) (xy 173.568745 -400.229463) (xy 173.586151 -400.292542) (xy 173.594933 -400.357387)
			(xy 173.594932 -400.390106) (xy 177.023784 -400.390106) (xy 177.027775 -400.327939) (xy 177.039684 -400.266792)
			(xy 177.059313 -400.207671) (xy 177.086342 -400.151545) (xy 177.120326 -400.099336) (xy 177.160708 -400.051901)
			(xy 177.206824 -400.01002) (xy 177.257916 -399.97438) (xy 177.313147 -399.945566) (xy 177.371609 -399.924052)
			(xy 177.432343 -399.91019) (xy 177.49435 -399.904208) (xy 177.556613 -399.906204) (xy 177.61811 -399.916147)
			(xy 177.677831 -399.933871) (xy 177.734794 -399.959088) (xy 177.788065 -399.991381) (xy 177.83677 -400.030221)
			(xy 177.880107 -400.074971) (xy 177.917367 -400.124895) (xy 177.947936 -400.179174) (xy 177.971314 -400.236917)
			(xy 177.987115 -400.297175) (xy 177.995081 -400.358958) (xy 177.99558 -400.390106) (xy 177.995081 -400.421254)
			(xy 177.987115 -400.483037) (xy 177.971314 -400.543295) (xy 177.947936 -400.601038) (xy 177.917367 -400.655317)
			(xy 177.880107 -400.705241) (xy 177.83677 -400.749991) (xy 177.788065 -400.788831) (xy 177.734794 -400.821124)
			(xy 177.677831 -400.846341) (xy 177.61811 -400.864065) (xy 177.556613 -400.874008) (xy 177.49435 -400.876004)
			(xy 177.432343 -400.870022) (xy 177.371609 -400.85616) (xy 177.313147 -400.834646) (xy 177.257916 -400.805832)
			(xy 177.206824 -400.770192) (xy 177.160708 -400.728311) (xy 177.120326 -400.680876) (xy 177.086342 -400.628667)
			(xy 177.059313 -400.572541) (xy 177.039684 -400.51342) (xy 177.027775 -400.452273) (xy 177.023784 -400.390106)
			(xy 173.594932 -400.390106) (xy 173.594932 -400.422823) (xy 173.586149 -400.487668) (xy 173.568741 -400.550747)
			(xy 173.543025 -400.610918) (xy 173.526704 -400.63928) (xy 173.523397 -400.645308) (xy 173.519786 -400.658569)
			(xy 173.519592 -400.665442) (xy 173.519592 -401.414742) (xy 173.519807 -401.421614) (xy 173.5234 -401.434876)
			(xy 173.526704 -401.440904) (xy 173.543006 -401.469276) (xy 173.568723 -401.529445) (xy 173.586132 -401.592522)
			(xy 173.594917 -401.657364) (xy 173.59492 -401.722798) (xy 173.58614 -401.787641) (xy 173.568736 -401.850719)
			(xy 173.543023 -401.91089) (xy 173.526704 -401.939252) (xy 173.523371 -401.945268) (xy 173.519777 -401.958538)
			(xy 173.519592 -401.965414) (xy 173.519592 -402.251418) (xy 173.519082 -402.261573) (xy 173.511308 -402.280337)
			(xy 173.496947 -402.294701) (xy 173.478185 -402.30248) (xy 173.46803 -402.30298) (xy 172.75175 -402.30298)
			(xy 172.741584 -402.302496) (xy 172.722794 -402.29473) (xy 172.708408 -402.280363) (xy 172.700618 -402.261584)
			(xy 172.700188 -402.251418) (xy 172.700188 -401.965414) (xy 172.699992 -401.958541) (xy 172.696387 -401.945278)
			(xy 172.693076 -401.939252) (xy 172.676734 -401.910901) (xy 172.651016 -401.850728) (xy 172.633609 -401.787647)
			(xy 172.624827 -401.7228) (xy 171.336115 -401.7228) (xy 171.326556 -401.739354) (xy 171.323262 -401.745389)
			(xy 171.319643 -401.758645) (xy 171.319444 -401.765516) (xy 171.319444 -402.514816) (xy 171.319624 -402.52169)
			(xy 171.32324 -402.534953) (xy 171.326556 -402.540978) (xy 171.342909 -402.569334) (xy 171.368715 -402.629491)
			(xy 171.386208 -402.692568) (xy 171.395072 -402.757424) (xy 171.395644 -402.790152) (xy 171.395073 -402.822879)
			(xy 174.824967 -402.822879) (xy 174.824973 -402.757439) (xy 174.833762 -402.692592) (xy 174.851176 -402.629512)
			(xy 174.876899 -402.569339) (xy 174.893224 -402.540978) (xy 174.896548 -402.534958) (xy 174.900147 -402.521691)
			(xy 174.900336 -402.514816) (xy 174.900336 -401.765516) (xy 174.900133 -401.758644) (xy 174.896532 -401.745381)
			(xy 174.893224 -401.739354) (xy 174.876885 -401.711002) (xy 174.85117 -401.650828) (xy 174.833764 -401.587748)
			(xy 174.824983 -401.522902) (xy 174.824986 -401.457464) (xy 174.833771 -401.392618) (xy 174.851181 -401.329539)
			(xy 174.876901 -401.269367) (xy 174.893224 -401.241006) (xy 174.896538 -401.234981) (xy 174.900144 -401.221718)
			(xy 174.900336 -401.214844) (xy 174.900336 -400.92884) (xy 174.900755 -400.918684) (xy 174.908544 -400.899926)
			(xy 174.922943 -400.8856) (xy 174.94174 -400.877905) (xy 174.951898 -400.877532) (xy 175.668178 -400.877532)
			(xy 175.678302 -400.878044) (xy 175.697022 -400.885763) (xy 175.711378 -400.900042) (xy 175.7192 -400.918718)
			(xy 175.71974 -400.92884) (xy 175.71974 -401.214844) (xy 175.719948 -401.221716) (xy 175.723545 -401.234979)
			(xy 175.726852 -401.241006) (xy 175.743158 -401.269377) (xy 175.768877 -401.329545) (xy 175.786288 -401.392622)
			(xy 175.795073 -401.457465) (xy 175.795076 -401.522901) (xy 175.786294 -401.587744) (xy 175.768889 -401.650822)
			(xy 175.752112 -401.690078) (xy 177.023784 -401.690078) (xy 177.027775 -401.627911) (xy 177.039684 -401.566764)
			(xy 177.059313 -401.507643) (xy 177.086342 -401.451517) (xy 177.120326 -401.399308) (xy 177.160708 -401.351873)
			(xy 177.206824 -401.309992) (xy 177.257916 -401.274352) (xy 177.313147 -401.245538) (xy 177.371609 -401.224024)
			(xy 177.432343 -401.210162) (xy 177.49435 -401.20418) (xy 177.556613 -401.206176) (xy 177.61811 -401.216119)
			(xy 177.677831 -401.233843) (xy 177.734794 -401.25906) (xy 177.788065 -401.291353) (xy 177.83677 -401.330193)
			(xy 177.880107 -401.374943) (xy 177.917367 -401.424867) (xy 177.947936 -401.479146) (xy 177.952403 -401.49018)
			(xy 179.223932 -401.49018) (xy 179.227923 -401.428013) (xy 179.239832 -401.366866) (xy 179.259461 -401.307745)
			(xy 179.28649 -401.251619) (xy 179.320474 -401.19941) (xy 179.360856 -401.151975) (xy 179.406972 -401.110094)
			(xy 179.458064 -401.074454) (xy 179.513295 -401.04564) (xy 179.571757 -401.024126) (xy 179.632491 -401.010264)
			(xy 179.694498 -401.004282) (xy 179.756761 -401.006278) (xy 179.818258 -401.016221) (xy 179.877979 -401.033945)
			(xy 179.934942 -401.059162) (xy 179.988213 -401.091455) (xy 180.036918 -401.130295) (xy 180.080255 -401.175045)
			(xy 180.117515 -401.224969) (xy 180.148084 -401.279248) (xy 180.171462 -401.336991) (xy 180.187263 -401.397249)
			(xy 180.195229 -401.459032) (xy 180.195728 -401.49018) (xy 180.195229 -401.521328) (xy 180.187263 -401.583111)
			(xy 180.171462 -401.643369) (xy 180.165097 -401.65909) (xy 189.391542 -401.65909) (xy 189.395613 -401.603468)
			(xy 189.407739 -401.549031) (xy 189.427662 -401.49694) (xy 189.454958 -401.448305) (xy 189.489044 -401.404162)
			(xy 189.529193 -401.365453) (xy 189.574551 -401.333002) (xy 189.624151 -401.307501) (xy 189.676935 -401.289494)
			(xy 189.731778 -401.279364) (xy 189.787512 -401.277327) (xy 189.842949 -401.283427) (xy 189.896906 -401.297533)
			(xy 189.948235 -401.319345) (xy 189.995841 -401.348399) (xy 190.038709 -401.384074) (xy 190.075926 -401.425611)
			(xy 190.106699 -401.472124) (xy 190.130371 -401.522621) (xy 190.13215 -401.528534) (xy 191.43548 -401.528534)
			(xy 191.439551 -401.472912) (xy 191.451677 -401.418475) (xy 191.4716 -401.366384) (xy 191.498896 -401.317749)
			(xy 191.532982 -401.273606) (xy 191.573131 -401.234897) (xy 191.618489 -401.202446) (xy 191.668089 -401.176945)
			(xy 191.720873 -401.158938) (xy 191.775716 -401.148808) (xy 191.83145 -401.146771) (xy 191.886887 -401.152871)
			(xy 191.940844 -401.166977) (xy 191.992173 -401.188789) (xy 192.039779 -401.217843) (xy 192.082647 -401.253518)
			(xy 192.119864 -401.295055) (xy 192.150637 -401.341568) (xy 192.174309 -401.392065) (xy 192.190377 -401.445472)
			(xy 192.198497 -401.500648) (xy 192.199006 -401.528534) (xy 192.198497 -401.55642) (xy 192.190377 -401.611596)
			(xy 192.174309 -401.665003) (xy 192.150637 -401.7155) (xy 192.119864 -401.762013) (xy 192.082647 -401.80355)
			(xy 192.039779 -401.839225) (xy 191.992173 -401.868279) (xy 191.940844 -401.890091) (xy 191.886887 -401.904197)
			(xy 191.83145 -401.910297) (xy 191.775716 -401.90826) (xy 191.720873 -401.89813) (xy 191.668089 -401.880123)
			(xy 191.618489 -401.854622) (xy 191.573131 -401.822171) (xy 191.532982 -401.783462) (xy 191.498896 -401.739319)
			(xy 191.4716 -401.690684) (xy 191.451677 -401.638593) (xy 191.439551 -401.584156) (xy 191.43548 -401.528534)
			(xy 190.13215 -401.528534) (xy 190.146439 -401.576028) (xy 190.154559 -401.631204) (xy 190.155068 -401.65909)
			(xy 190.154559 -401.686976) (xy 190.146439 -401.742152) (xy 190.130371 -401.795559) (xy 190.106699 -401.846056)
			(xy 190.075926 -401.892569) (xy 190.038709 -401.934106) (xy 189.995841 -401.969781) (xy 189.948235 -401.998835)
			(xy 189.896906 -402.020647) (xy 189.842949 -402.034753) (xy 189.787512 -402.040853) (xy 189.731778 -402.038816)
			(xy 189.676935 -402.028686) (xy 189.624151 -402.010679) (xy 189.574551 -401.985178) (xy 189.529193 -401.952727)
			(xy 189.489044 -401.914018) (xy 189.454958 -401.869875) (xy 189.427662 -401.82124) (xy 189.407739 -401.769149)
			(xy 189.395613 -401.714712) (xy 189.391542 -401.65909) (xy 180.165097 -401.65909) (xy 180.148084 -401.701112)
			(xy 180.117515 -401.755391) (xy 180.080255 -401.805315) (xy 180.036918 -401.850065) (xy 179.988213 -401.888905)
			(xy 179.934942 -401.921198) (xy 179.877979 -401.946415) (xy 179.818258 -401.964139) (xy 179.756761 -401.974082)
			(xy 179.694498 -401.976078) (xy 179.632491 -401.970096) (xy 179.571757 -401.956234) (xy 179.513295 -401.93472)
			(xy 179.458064 -401.905906) (xy 179.406972 -401.870266) (xy 179.360856 -401.828385) (xy 179.320474 -401.78095)
			(xy 179.28649 -401.728741) (xy 179.259461 -401.672615) (xy 179.239832 -401.613494) (xy 179.227923 -401.552347)
			(xy 179.223932 -401.49018) (xy 177.952403 -401.49018) (xy 177.971314 -401.536889) (xy 177.987115 -401.597147)
			(xy 177.995081 -401.65893) (xy 177.99558 -401.690078) (xy 177.995081 -401.721226) (xy 177.987115 -401.783009)
			(xy 177.971314 -401.843267) (xy 177.947936 -401.90101) (xy 177.917367 -401.955289) (xy 177.880107 -402.005213)
			(xy 177.83677 -402.049963) (xy 177.788065 -402.088803) (xy 177.734794 -402.121096) (xy 177.677831 -402.146313)
			(xy 177.61811 -402.164037) (xy 177.556613 -402.17398) (xy 177.49435 -402.175976) (xy 177.432343 -402.169994)
			(xy 177.371609 -402.156132) (xy 177.313147 -402.134618) (xy 177.257916 -402.105804) (xy 177.206824 -402.070164)
			(xy 177.160708 -402.028283) (xy 177.120326 -401.980848) (xy 177.086342 -401.928639) (xy 177.059313 -401.872513)
			(xy 177.039684 -401.813392) (xy 177.027775 -401.752245) (xy 177.023784 -401.690078) (xy 175.752112 -401.690078)
			(xy 175.743173 -401.710993) (xy 175.726852 -401.739354) (xy 175.723558 -401.745389) (xy 175.719939 -401.758645)
			(xy 175.71974 -401.765516) (xy 175.71974 -402.222462) (xy 198.023478 -402.222462) (xy 198.027549 -402.16684)
			(xy 198.039675 -402.112403) (xy 198.059598 -402.060312) (xy 198.086894 -402.011677) (xy 198.12098 -401.967534)
			(xy 198.161129 -401.928825) (xy 198.206487 -401.896374) (xy 198.256087 -401.870873) (xy 198.308871 -401.852866)
			(xy 198.363714 -401.842736) (xy 198.419448 -401.840699) (xy 198.474885 -401.846799) (xy 198.528842 -401.860905)
			(xy 198.580171 -401.882717) (xy 198.627777 -401.911771) (xy 198.670645 -401.947446) (xy 198.707862 -401.988983)
			(xy 198.738635 -402.035496) (xy 198.762307 -402.085993) (xy 198.778375 -402.1394) (xy 198.786495 -402.194576)
			(xy 198.787004 -402.222462) (xy 198.786495 -402.250348) (xy 198.778375 -402.305524) (xy 198.762307 -402.358931)
			(xy 198.738635 -402.409428) (xy 198.707862 -402.455941) (xy 198.670645 -402.497478) (xy 198.627777 -402.533153)
			(xy 198.580171 -402.562207) (xy 198.528842 -402.584019) (xy 198.474885 -402.598125) (xy 198.419448 -402.604225)
			(xy 198.363714 -402.602188) (xy 198.308871 -402.592058) (xy 198.256087 -402.574051) (xy 198.206487 -402.54855)
			(xy 198.161129 -402.516099) (xy 198.12098 -402.47739) (xy 198.086894 -402.433247) (xy 198.059598 -402.384612)
			(xy 198.039675 -402.332521) (xy 198.027549 -402.278084) (xy 198.023478 -402.222462) (xy 175.71974 -402.222462)
			(xy 175.71974 -402.514816) (xy 175.719921 -402.52169) (xy 175.723536 -402.534953) (xy 175.726852 -402.540978)
			(xy 175.743134 -402.569362) (xy 175.768856 -402.629527) (xy 175.786269 -402.692601) (xy 175.795057 -402.757442)
			(xy 175.79506 -402.790152) (xy 179.223932 -402.790152) (xy 179.227923 -402.727985) (xy 179.239832 -402.666838)
			(xy 179.259461 -402.607717) (xy 179.28649 -402.551591) (xy 179.320474 -402.499382) (xy 179.360856 -402.451947)
			(xy 179.406972 -402.410066) (xy 179.458064 -402.374426) (xy 179.513295 -402.345612) (xy 179.571757 -402.324098)
			(xy 179.632491 -402.310236) (xy 179.694498 -402.304254) (xy 179.756761 -402.30625) (xy 179.818258 -402.316193)
			(xy 179.877979 -402.333917) (xy 179.934942 -402.359134) (xy 179.988213 -402.391427) (xy 180.036918 -402.430267)
			(xy 180.080255 -402.475017) (xy 180.117515 -402.524941) (xy 180.148084 -402.57922) (xy 180.171462 -402.636963)
			(xy 180.187263 -402.697221) (xy 180.195229 -402.759004) (xy 180.195728 -402.790152) (xy 180.195229 -402.8213)
			(xy 180.187263 -402.883083) (xy 180.171462 -402.943341) (xy 180.148084 -403.001084) (xy 180.117515 -403.055363)
			(xy 180.080255 -403.105287) (xy 180.036918 -403.150037) (xy 179.988213 -403.188877) (xy 179.934942 -403.22117)
			(xy 179.877979 -403.246387) (xy 179.818258 -403.264111) (xy 179.756761 -403.274054) (xy 179.694498 -403.27605)
			(xy 179.632491 -403.270068) (xy 179.571757 -403.256206) (xy 179.513295 -403.234692) (xy 179.458064 -403.205878)
			(xy 179.406972 -403.170238) (xy 179.360856 -403.128357) (xy 179.320474 -403.080922) (xy 179.28649 -403.028713)
			(xy 179.259461 -402.972587) (xy 179.239832 -402.913466) (xy 179.227923 -402.852319) (xy 179.223932 -402.790152)
			(xy 175.79506 -402.790152) (xy 175.795063 -402.822876) (xy 175.786285 -402.887718) (xy 175.768883 -402.950795)
			(xy 175.743171 -403.010965) (xy 175.726852 -403.039326) (xy 175.723532 -403.045348) (xy 175.719929 -403.058614)
			(xy 175.71974 -403.065488) (xy 175.71974 -403.351492) (xy 175.719273 -403.361641) (xy 175.711487 -403.380385)
			(xy 175.697105 -403.394707) (xy 175.678328 -403.402415) (xy 175.668178 -403.4028) (xy 174.951898 -403.4028)
			(xy 174.941776 -403.402276) (xy 174.923063 -403.394555) (xy 174.908708 -403.380281) (xy 174.900882 -403.361611)
			(xy 174.900336 -403.351492) (xy 174.900336 -403.065488) (xy 174.900144 -403.058615) (xy 174.896535 -403.045352)
			(xy 174.893224 -403.039326) (xy 174.876862 -403.010987) (xy 174.851149 -402.95081) (xy 174.833745 -402.887727)
			(xy 174.824967 -402.822879) (xy 171.395073 -402.822879) (xy 171.395073 -402.822881) (xy 171.386218 -402.887739)
			(xy 171.368729 -402.950819) (xy 171.342924 -403.010978) (xy 171.326556 -403.039326) (xy 171.323236 -403.045348)
			(xy 171.319633 -403.058614) (xy 171.319444 -403.065488) (xy 171.319444 -403.351492) (xy 171.318909 -403.361595)
			(xy 171.311183 -403.380264) (xy 171.296901 -403.394558) (xy 171.278238 -403.402301) (xy 171.268136 -403.4028)
			(xy 170.551856 -403.4028) (xy 170.541744 -403.402351) (xy 170.523065 -403.394599) (xy 170.508772 -403.380291)
			(xy 170.501039 -403.361604) (xy 170.500548 -403.351492) (xy 170.500548 -403.065488) (xy 170.500367 -403.058614)
			(xy 170.496752 -403.045351) (xy 170.493436 -403.039326) (xy 170.477084 -403.010969) (xy 170.451278 -402.950813)
			(xy 170.433785 -402.887735) (xy 170.42492 -402.82288) (xy 170.424348 -402.790152) (xy 166.994974 -402.790152)
			(xy 166.994977 -402.822875) (xy 166.986199 -402.887717) (xy 166.968798 -402.950794) (xy 166.943087 -403.010965)
			(xy 166.926768 -403.039326) (xy 166.923442 -403.045345) (xy 166.919844 -403.058613) (xy 166.919656 -403.065488)
			(xy 166.919656 -403.351492) (xy 166.919173 -403.361639) (xy 166.911391 -403.38038) (xy 166.897014 -403.394702)
			(xy 166.878242 -403.402412) (xy 166.868094 -403.4028) (xy 166.151814 -403.4028) (xy 166.141693 -403.402263)
			(xy 166.12298 -403.394547) (xy 166.108624 -403.380277) (xy 166.100798 -403.36161) (xy 166.100252 -403.351492)
			(xy 166.100252 -403.065488) (xy 166.100071 -403.058614) (xy 166.096456 -403.045351) (xy 166.09314 -403.039326)
			(xy 166.076777 -403.010987) (xy 166.051063 -402.950811) (xy 166.03366 -402.887727) (xy 166.024881 -402.822879)
			(xy 162.594987 -402.822879) (xy 162.594987 -402.822881) (xy 162.586132 -402.887739) (xy 162.568644 -402.950819)
			(xy 162.542839 -403.010978) (xy 162.526472 -403.039326) (xy 162.523146 -403.045345) (xy 162.519548 -403.058613)
			(xy 162.51936 -403.065488) (xy 162.51936 -403.351492) (xy 162.518976 -403.361619) (xy 162.511224 -403.38033)
			(xy 162.496896 -403.394646) (xy 162.478179 -403.402384) (xy 162.468052 -403.4028) (xy 161.751772 -403.4028)
			(xy 161.741661 -403.402338) (xy 161.722983 -403.394591) (xy 161.708689 -403.380287) (xy 161.700955 -403.361603)
			(xy 161.700464 -403.351492) (xy 161.700464 -403.065488) (xy 161.700281 -403.058614) (xy 161.696667 -403.045351)
			(xy 161.693352 -403.039326) (xy 161.677002 -403.010968) (xy 161.651195 -402.950812) (xy 161.633701 -402.887735)
			(xy 161.624836 -402.82288) (xy 161.624264 -402.790152) (xy 154.57678 -402.790152) (xy 154.57678 -405.622713)
			(xy 159.424974 -405.622713) (xy 159.424975 -405.557277) (xy 159.433758 -405.492432) (xy 159.451166 -405.429353)
			(xy 159.476882 -405.369182) (xy 159.493204 -405.34082) (xy 159.496512 -405.334792) (xy 159.500122 -405.321531)
			(xy 159.500316 -405.314658) (xy 159.500316 -404.565358) (xy 159.5001 -404.558487) (xy 159.496508 -404.545224)
			(xy 159.493204 -404.539196) (xy 159.476901 -404.510824) (xy 159.451184 -404.450655) (xy 159.433775 -404.387579)
			(xy 159.42499 -404.322736) (xy 159.424987 -404.257301) (xy 159.433768 -404.192458) (xy 159.451171 -404.129381)
			(xy 159.476884 -404.06921) (xy 159.493204 -404.040848) (xy 159.496538 -404.034833) (xy 159.500131 -404.021562)
			(xy 159.500316 -404.014686) (xy 159.500316 -403.728682) (xy 159.500818 -403.718526) (xy 159.508594 -403.69976)
			(xy 159.522957 -403.685396) (xy 159.541722 -403.677619) (xy 159.551878 -403.67712) (xy 160.268158 -403.67712)
			(xy 160.278325 -403.677598) (xy 160.297115 -403.685366) (xy 160.311501 -403.699735) (xy 160.31929 -403.718516)
			(xy 160.31972 -403.728682) (xy 160.31972 -404.014686) (xy 160.319915 -404.021559) (xy 160.323521 -404.034822)
			(xy 160.326832 -404.040848) (xy 160.343174 -404.069199) (xy 160.368891 -404.129372) (xy 160.386298 -404.192453)
			(xy 160.39508 -404.2573) (xy 160.395078 -404.322738) (xy 160.386291 -404.387584) (xy 160.368879 -404.450664)
			(xy 160.343157 -404.510835) (xy 160.326832 -404.539196) (xy 160.323521 -404.545223) (xy 160.319913 -404.558485)
			(xy 160.31972 -404.565358) (xy 160.31972 -405.314658) (xy 160.319926 -405.32153) (xy 160.323524 -405.334793)
			(xy 160.326832 -405.34082) (xy 160.34315 -405.369184) (xy 160.36887 -405.429354) (xy 160.386279 -405.492432)
			(xy 160.395064 -405.557277) (xy 160.395065 -405.622713) (xy 160.386281 -405.687558) (xy 160.368873 -405.750636)
			(xy 160.343155 -405.810807) (xy 160.326832 -405.839168) (xy 160.323531 -405.8452) (xy 160.319917 -405.858458)
			(xy 160.31972 -405.86533) (xy 160.31972 -406.151334) (xy 160.319363 -406.161513) (xy 160.311559 -406.180317)
			(xy 160.297153 -406.194702) (xy 160.278338 -406.202478) (xy 160.268158 -406.202896) (xy 159.551878 -406.202896)
			(xy 159.541723 -406.202386) (xy 159.52296 -406.19461) (xy 159.508596 -406.18025) (xy 159.500817 -406.161489)
			(xy 159.500316 -406.151334) (xy 159.500316 -405.86533) (xy 159.500111 -405.858458) (xy 159.496511 -405.845195)
			(xy 159.493204 -405.839168) (xy 159.476878 -405.810809) (xy 159.451162 -405.750637) (xy 159.433756 -405.687558)
			(xy 159.424974 -405.622713) (xy 154.57678 -405.622713) (xy 154.57678 -406.690068) (xy 161.624264 -406.690068)
			(xy 161.624842 -406.657339) (xy 161.633695 -406.592481) (xy 161.651182 -406.529401) (xy 161.676985 -406.469243)
			(xy 161.693352 -406.440894) (xy 161.696665 -406.434868) (xy 161.700272 -406.421605) (xy 161.700464 -406.414732)
			(xy 161.700464 -405.665432) (xy 161.700264 -405.658559) (xy 161.696662 -405.645296) (xy 161.693352 -405.63927)
			(xy 161.676979 -405.610925) (xy 161.651178 -405.550764) (xy 161.63369 -405.487683) (xy 161.624833 -405.422825)
			(xy 161.624264 -405.390096) (xy 161.62481 -405.357366) (xy 161.633673 -405.292507) (xy 161.651169 -405.229427)
			(xy 161.676981 -405.169269) (xy 161.693352 -405.140922) (xy 161.696655 -405.134892) (xy 161.700269 -405.121632)
			(xy 161.700464 -405.11476) (xy 161.700464 -404.828756) (xy 161.700948 -404.818649) (xy 161.708694 -404.799977)
			(xy 161.72299 -404.785685) (xy 161.741665 -404.777945) (xy 161.751772 -404.777448) (xy 162.468052 -404.777448)
			(xy 162.478165 -404.777954) (xy 162.496858 -404.785677) (xy 162.511172 -404.799965) (xy 162.518928 -404.818644)
			(xy 162.51936 -404.828756) (xy 162.51936 -405.11476) (xy 162.519572 -405.121632) (xy 162.523167 -405.134894)
			(xy 162.526472 -405.140922) (xy 162.542844 -405.169268) (xy 162.568645 -405.229428) (xy 162.586133 -405.292509)
			(xy 162.594991 -405.357367) (xy 162.59556 -405.390096) (xy 162.595007 -405.422826) (xy 162.586146 -405.487684)
			(xy 162.568652 -405.550764) (xy 162.551821 -405.589994) (xy 163.824412 -405.589994) (xy 163.824996 -405.557265)
			(xy 163.833846 -405.492407) (xy 163.851331 -405.429327) (xy 163.877134 -405.369169) (xy 163.8935 -405.34082)
			(xy 163.896808 -405.334792) (xy 163.900418 -405.321531) (xy 163.900612 -405.314658) (xy 163.900612 -404.565358)
			(xy 163.900396 -404.558487) (xy 163.896804 -404.545224) (xy 163.8935 -404.539196) (xy 163.877133 -404.510848)
			(xy 163.851331 -404.450688) (xy 163.833842 -404.387608) (xy 163.824982 -404.322751) (xy 163.824412 -404.290022)
			(xy 163.824964 -404.257292) (xy 163.833823 -404.192433) (xy 163.851318 -404.129353) (xy 163.877129 -404.069196)
			(xy 163.8935 -404.040848) (xy 163.896833 -404.034832) (xy 163.900427 -404.021562) (xy 163.900612 -404.014686)
			(xy 163.900612 -403.728682) (xy 163.901111 -403.718558) (xy 163.908839 -403.699841) (xy 163.923121 -403.685486)
			(xy 163.941798 -403.677663) (xy 163.95192 -403.67712) (xy 164.6682 -403.67712) (xy 164.678357 -403.677522)
			(xy 164.697113 -403.685321) (xy 164.711437 -403.699724) (xy 164.719133 -403.718523) (xy 164.719508 -403.728682)
			(xy 164.719508 -404.014686) (xy 164.719705 -404.021559) (xy 164.72331 -404.034822) (xy 164.72662 -404.040848)
			(xy 164.743007 -404.069186) (xy 164.768803 -404.12935) (xy 164.786287 -404.192433) (xy 164.795141 -404.257292)
			(xy 164.795708 -404.290022) (xy 164.795129 -404.322751) (xy 164.786277 -404.387609) (xy 164.76879 -404.450689)
			(xy 164.742987 -404.510847) (xy 164.72662 -404.539196) (xy 164.723308 -404.545222) (xy 164.7197 -404.558485)
			(xy 164.719508 -404.565358) (xy 164.719508 -405.314658) (xy 164.719715 -405.32153) (xy 164.723313 -405.334793)
			(xy 164.72662 -405.34082) (xy 164.742995 -405.369164) (xy 164.768794 -405.429325) (xy 164.786281 -405.492407)
			(xy 164.795139 -405.557265) (xy 164.795708 -405.589994) (xy 164.795161 -405.622724) (xy 164.7863 -405.687583)
			(xy 164.768804 -405.750663) (xy 164.742991 -405.810821) (xy 164.72662 -405.839168) (xy 164.723318 -405.845199)
			(xy 164.719704 -405.858458) (xy 164.719508 -405.86533) (xy 164.719508 -406.151334) (xy 164.719003 -406.161457)
			(xy 164.711273 -406.18017) (xy 164.696993 -406.194523) (xy 164.67832 -406.20235) (xy 164.6682 -406.202896)
			(xy 163.95192 -406.202896) (xy 163.941767 -406.202462) (xy 163.923014 -406.194672) (xy 163.90869 -406.180279)
			(xy 163.90099 -406.161489) (xy 163.900612 -406.151334) (xy 163.900612 -405.86533) (xy 163.900407 -405.858458)
			(xy 163.896808 -405.845195) (xy 163.8935 -405.839168) (xy 163.877122 -405.810826) (xy 163.851323 -405.750664)
			(xy 163.833837 -405.687582) (xy 163.82498 -405.622724) (xy 163.824412 -405.589994) (xy 162.551821 -405.589994)
			(xy 162.542842 -405.610922) (xy 162.526472 -405.63927) (xy 162.523166 -405.645299) (xy 162.519555 -405.658559)
			(xy 162.51936 -405.665432) (xy 162.51936 -406.414732) (xy 162.519545 -406.421606) (xy 162.523159 -406.434868)
			(xy 162.526472 -406.440894) (xy 162.542833 -406.469246) (xy 162.568636 -406.529404) (xy 162.586127 -406.592483)
			(xy 162.594989 -406.657339) (xy 162.59556 -406.690068) (xy 162.594994 -406.722792) (xy 166.02489 -406.722792)
			(xy 166.024894 -406.657353) (xy 166.033681 -406.592507) (xy 166.051094 -406.529427) (xy 166.076816 -406.469255)
			(xy 166.09314 -406.440894) (xy 166.096452 -406.434868) (xy 166.10006 -406.421605) (xy 166.100252 -406.414732)
			(xy 166.100252 -405.665432) (xy 166.100054 -405.658559) (xy 166.096451 -405.645296) (xy 166.09314 -405.63927)
			(xy 166.076814 -405.610911) (xy 166.051097 -405.550739) (xy 166.033689 -405.48766) (xy 166.024906 -405.422815)
			(xy 166.024907 -405.357378) (xy 166.033691 -405.292533) (xy 166.051099 -405.229454) (xy 166.076817 -405.169283)
			(xy 166.09314 -405.140922) (xy 166.096442 -405.134891) (xy 166.100057 -405.121632) (xy 166.100252 -405.11476)
			(xy 166.100252 -404.828756) (xy 166.100685 -404.818605) (xy 166.108486 -404.799861) (xy 166.122878 -404.785541)
			(xy 166.141661 -404.777834) (xy 166.151814 -404.777448) (xy 166.868094 -404.777448) (xy 166.878221 -404.777932)
			(xy 166.896944 -404.785659) (xy 166.911301 -404.799946) (xy 166.919119 -404.818631) (xy 166.919656 -404.828756)
			(xy 166.919656 -405.11476) (xy 166.919856 -405.121633) (xy 166.923458 -405.134896) (xy 166.926768 -405.140922)
			(xy 166.943087 -405.169285) (xy 166.968804 -405.229456) (xy 166.986212 -405.292534) (xy 166.994996 -405.357378)
			(xy 166.994997 -405.422815) (xy 166.986214 -405.487659) (xy 166.968806 -405.550738) (xy 166.94309 -405.610909)
			(xy 166.936297 -405.622713) (xy 168.22506 -405.622713) (xy 168.225061 -405.557277) (xy 168.233844 -405.492432)
			(xy 168.251251 -405.429354) (xy 168.276967 -405.369182) (xy 168.293288 -405.34082) (xy 168.296595 -405.334791)
			(xy 168.300206 -405.321531) (xy 168.3004 -405.314658) (xy 168.3004 -404.565358) (xy 168.300186 -404.558486)
			(xy 168.296593 -404.545224) (xy 168.293288 -404.539196) (xy 168.276986 -404.510824) (xy 168.251269 -404.450655)
			(xy 168.233861 -404.387578) (xy 168.225076 -404.322736) (xy 168.225074 -404.257302) (xy 168.233853 -404.192459)
			(xy 168.251257 -404.129381) (xy 168.276969 -404.06921) (xy 168.293288 -404.040848) (xy 168.29662 -404.034832)
			(xy 168.300215 -404.021562) (xy 168.3004 -404.014686) (xy 168.3004 -403.728682) (xy 168.300917 -403.718528)
			(xy 168.308691 -403.699765) (xy 168.323049 -403.685402) (xy 168.341808 -403.677621) (xy 168.351962 -403.67712)
			(xy 169.068242 -403.67712) (xy 169.0784 -403.677599) (xy 169.097167 -403.685383) (xy 169.11153 -403.699753)
			(xy 169.119306 -403.718524) (xy 169.119804 -403.728682) (xy 169.119804 -404.014686) (xy 169.120001 -404.021559)
			(xy 169.123606 -404.034822) (xy 169.126916 -404.040848) (xy 169.143258 -404.069199) (xy 169.168977 -404.129372)
			(xy 169.186384 -404.192453) (xy 169.195166 -404.257299) (xy 169.195164 -404.322738) (xy 169.186377 -404.387584)
			(xy 169.168964 -404.450664) (xy 169.143241 -404.510835) (xy 169.126916 -404.539196) (xy 169.123604 -404.545222)
			(xy 169.119996 -404.558485) (xy 169.119804 -404.565358) (xy 169.119804 -405.314658) (xy 169.120012 -405.32153)
			(xy 169.123609 -405.334793) (xy 169.126916 -405.34082) (xy 169.143235 -405.369184) (xy 169.168955 -405.429354)
			(xy 169.186365 -405.492432) (xy 169.19515 -405.557276) (xy 169.195151 -405.622713) (xy 169.186367 -405.687558)
			(xy 169.168958 -405.750637) (xy 169.143239 -405.810807) (xy 169.126916 -405.839168) (xy 169.123614 -405.845199)
			(xy 169.12 -405.858458) (xy 169.119804 -405.86533) (xy 169.119804 -406.151334) (xy 169.119296 -406.161489)
			(xy 169.111518 -406.180251) (xy 169.097157 -406.194613) (xy 169.078397 -406.202394) (xy 169.068242 -406.202896)
			(xy 168.351962 -406.202896) (xy 168.341806 -406.202399) (xy 168.323042 -406.194618) (xy 168.30868 -406.180254)
			(xy 168.300901 -406.16149) (xy 168.3004 -406.151334) (xy 168.3004 -405.86533) (xy 168.300196 -405.858458)
			(xy 168.296596 -405.845195) (xy 168.293288 -405.839168) (xy 168.276962 -405.810809) (xy 168.251248 -405.750637)
			(xy 168.233842 -405.687558) (xy 168.22506 -405.622713) (xy 166.936297 -405.622713) (xy 166.926768 -405.63927)
			(xy 166.923462 -405.645299) (xy 166.919851 -405.658559) (xy 166.919656 -405.665432) (xy 166.919656 -406.414732)
			(xy 166.919829 -406.421607) (xy 166.923449 -406.43487) (xy 166.926768 -406.440894) (xy 166.943063 -406.46927)
			(xy 166.968783 -406.529438) (xy 166.986194 -406.592514) (xy 166.99498 -406.657355) (xy 166.994982 -406.690068)
			(xy 170.424348 -406.690068) (xy 170.424929 -406.657339) (xy 170.433781 -406.592482) (xy 170.451267 -406.529402)
			(xy 170.47707 -406.469243) (xy 170.493436 -406.440894) (xy 170.496748 -406.434868) (xy 170.500356 -406.421605)
			(xy 170.500548 -406.414732) (xy 170.500548 -405.665432) (xy 170.50035 -405.658559) (xy 170.496747 -405.645296)
			(xy 170.493436 -405.63927) (xy 170.477062 -405.610925) (xy 170.451261 -405.550764) (xy 170.433774 -405.487683)
			(xy 170.424917 -405.422825) (xy 170.424348 -405.390096) (xy 170.424897 -405.357366) (xy 170.433759 -405.292507)
			(xy 170.451254 -405.229427) (xy 170.477066 -405.16927) (xy 170.493436 -405.140922) (xy 170.496738 -405.134891)
			(xy 170.500353 -405.121632) (xy 170.500548 -405.11476) (xy 170.500548 -404.828756) (xy 170.501048 -404.818651)
			(xy 170.50879 -404.799982) (xy 170.523082 -404.78569) (xy 170.541751 -404.777948) (xy 170.551856 -404.777448)
			(xy 171.268136 -404.777448) (xy 171.278241 -404.777954) (xy 171.29691 -404.785694) (xy 171.311201 -404.799984)
			(xy 171.318944 -404.818651) (xy 171.319444 -404.828756) (xy 171.319444 -405.11476) (xy 171.319646 -405.121633)
			(xy 171.323247 -405.134896) (xy 171.326556 -405.140922) (xy 171.342926 -405.169269) (xy 171.368728 -405.229429)
			(xy 171.386216 -405.292509) (xy 171.395075 -405.357367) (xy 171.395644 -405.390096) (xy 171.395093 -405.422826)
			(xy 171.386232 -405.487685) (xy 171.368737 -405.550765) (xy 171.342926 -405.610922) (xy 171.336117 -405.622714)
			(xy 172.624836 -405.622714) (xy 172.624837 -405.557276) (xy 172.633622 -405.492431) (xy 172.651032 -405.429352)
			(xy 172.676752 -405.369181) (xy 172.693076 -405.34082) (xy 172.696382 -405.334791) (xy 172.699994 -405.321531)
			(xy 172.700188 -405.314658) (xy 172.700188 -404.565358) (xy 172.699975 -404.558486) (xy 172.696381 -404.545223)
			(xy 172.693076 -404.539196) (xy 172.676771 -404.510825) (xy 172.65105 -404.450656) (xy 172.633638 -404.38758)
			(xy 172.624852 -404.322737) (xy 172.624849 -404.257301) (xy 172.633631 -404.192457) (xy 172.651037 -404.129379)
			(xy 172.676754 -404.069209) (xy 172.693076 -404.040848) (xy 172.696408 -404.034832) (xy 172.700003 -404.021562)
			(xy 172.700188 -404.014686) (xy 172.700188 -403.728682) (xy 172.70055 -403.718503) (xy 172.708351 -403.699698)
			(xy 172.722756 -403.685313) (xy 172.74157 -403.677537) (xy 172.75175 -403.67712) (xy 173.46803 -403.67712)
			(xy 173.478187 -403.677608) (xy 173.496954 -403.685389) (xy 173.511317 -403.699756) (xy 173.519094 -403.718524)
			(xy 173.519592 -403.728682) (xy 173.519592 -404.014686) (xy 173.51979 -404.021559) (xy 173.523394 -404.034822)
			(xy 173.526704 -404.040848) (xy 173.543044 -404.069199) (xy 173.568757 -404.129373) (xy 173.586162 -404.192454)
			(xy 173.594942 -404.2573) (xy 173.59494 -404.290022) (xy 177.023784 -404.290022) (xy 177.027775 -404.227855)
			(xy 177.039684 -404.166708) (xy 177.059313 -404.107587) (xy 177.086342 -404.051461) (xy 177.120326 -403.999252)
			(xy 177.160708 -403.951817) (xy 177.206824 -403.909936) (xy 177.257916 -403.874296) (xy 177.313147 -403.845482)
			(xy 177.371609 -403.823968) (xy 177.432343 -403.810106) (xy 177.49435 -403.804124) (xy 177.556613 -403.80612)
			(xy 177.61811 -403.816063) (xy 177.677831 -403.833787) (xy 177.734794 -403.859004) (xy 177.788065 -403.891297)
			(xy 177.83677 -403.930137) (xy 177.880107 -403.974887) (xy 177.89237 -403.991318) (xy 190.063626 -403.991318)
			(xy 190.067697 -403.935696) (xy 190.079823 -403.881259) (xy 190.099746 -403.829168) (xy 190.127042 -403.780533)
			(xy 190.161128 -403.73639) (xy 190.201277 -403.697681) (xy 190.246635 -403.66523) (xy 190.296235 -403.639729)
			(xy 190.349019 -403.621722) (xy 190.403862 -403.611592) (xy 190.459596 -403.609555) (xy 190.515033 -403.615655)
			(xy 190.56899 -403.629761) (xy 190.620319 -403.651573) (xy 190.667925 -403.680627) (xy 190.710793 -403.716302)
			(xy 190.74801 -403.757839) (xy 190.778783 -403.804352) (xy 190.802455 -403.854849) (xy 190.818523 -403.908256)
			(xy 190.826643 -403.963432) (xy 190.827152 -403.991318) (xy 190.826643 -404.019204) (xy 190.818523 -404.07438)
			(xy 190.816996 -404.079456) (xy 192.60769 -404.079456) (xy 192.611761 -404.023834) (xy 192.623887 -403.969397)
			(xy 192.64381 -403.917306) (xy 192.671106 -403.868671) (xy 192.705192 -403.824528) (xy 192.745341 -403.785819)
			(xy 192.790699 -403.753368) (xy 192.840299 -403.727867) (xy 192.893083 -403.70986) (xy 192.947926 -403.69973)
			(xy 193.00366 -403.697693) (xy 193.059097 -403.703793) (xy 193.113054 -403.717899) (xy 193.164383 -403.739711)
			(xy 193.211989 -403.768765) (xy 193.254857 -403.80444) (xy 193.292074 -403.845977) (xy 193.322847 -403.89249)
			(xy 193.329763 -403.907244) (xy 193.55765 -403.907244) (xy 193.561721 -403.851622) (xy 193.573847 -403.797185)
			(xy 193.59377 -403.745094) (xy 193.621066 -403.696459) (xy 193.655152 -403.652316) (xy 193.695301 -403.613607)
			(xy 193.740659 -403.581156) (xy 193.790259 -403.555655) (xy 193.843043 -403.537648) (xy 193.897886 -403.527518)
			(xy 193.95362 -403.525481) (xy 194.009057 -403.531581) (xy 194.063014 -403.545687) (xy 194.114343 -403.567499)
			(xy 194.161949 -403.596553) (xy 194.204817 -403.632228) (xy 194.242034 -403.673765) (xy 194.272807 -403.720278)
			(xy 194.296479 -403.770775) (xy 194.312547 -403.824182) (xy 194.320667 -403.879358) (xy 194.321176 -403.907244)
			(xy 194.320667 -403.93513) (xy 194.312547 -403.990306) (xy 194.296479 -404.043713) (xy 194.272807 -404.09421)
			(xy 194.242034 -404.140723) (xy 194.204817 -404.18226) (xy 194.161949 -404.217935) (xy 194.114343 -404.246989)
			(xy 194.063014 -404.268801) (xy 194.009057 -404.282907) (xy 193.95362 -404.289007) (xy 193.897886 -404.28697)
			(xy 193.843043 -404.27684) (xy 193.790259 -404.258833) (xy 193.740659 -404.233332) (xy 193.695301 -404.200881)
			(xy 193.655152 -404.162172) (xy 193.621066 -404.118029) (xy 193.59377 -404.069394) (xy 193.573847 -404.017303)
			(xy 193.561721 -403.962866) (xy 193.55765 -403.907244) (xy 193.329763 -403.907244) (xy 193.346519 -403.942987)
			(xy 193.362587 -403.996394) (xy 193.370707 -404.05157) (xy 193.371216 -404.079456) (xy 193.370707 -404.107342)
			(xy 193.362587 -404.162518) (xy 193.346519 -404.215925) (xy 193.322847 -404.266422) (xy 193.292074 -404.312935)
			(xy 193.254857 -404.354472) (xy 193.211989 -404.390147) (xy 193.164383 -404.419201) (xy 193.113054 -404.441013)
			(xy 193.059097 -404.455119) (xy 193.00366 -404.461219) (xy 192.947926 -404.459182) (xy 192.893083 -404.449052)
			(xy 192.840299 -404.431045) (xy 192.790699 -404.405544) (xy 192.745341 -404.373093) (xy 192.705192 -404.334384)
			(xy 192.671106 -404.290241) (xy 192.64381 -404.241606) (xy 192.623887 -404.189515) (xy 192.611761 -404.135078)
			(xy 192.60769 -404.079456) (xy 190.816996 -404.079456) (xy 190.802455 -404.127787) (xy 190.778783 -404.178284)
			(xy 190.74801 -404.224797) (xy 190.710793 -404.266334) (xy 190.667925 -404.302009) (xy 190.620319 -404.331063)
			(xy 190.56899 -404.352875) (xy 190.515033 -404.366981) (xy 190.459596 -404.373081) (xy 190.403862 -404.371044)
			(xy 190.349019 -404.360914) (xy 190.296235 -404.342907) (xy 190.246635 -404.317406) (xy 190.201277 -404.284955)
			(xy 190.161128 -404.246246) (xy 190.127042 -404.202103) (xy 190.099746 -404.153468) (xy 190.079823 -404.101377)
			(xy 190.067697 -404.04694) (xy 190.063626 -403.991318) (xy 177.89237 -403.991318) (xy 177.917367 -404.024811)
			(xy 177.947936 -404.07909) (xy 177.971314 -404.136833) (xy 177.987115 -404.197091) (xy 177.995081 -404.258874)
			(xy 177.99558 -404.290022) (xy 177.995081 -404.32117) (xy 177.987115 -404.382953) (xy 177.971314 -404.443211)
			(xy 177.947936 -404.500954) (xy 177.917367 -404.555233) (xy 177.880107 -404.605157) (xy 177.83677 -404.649907)
			(xy 177.788065 -404.688747) (xy 177.734794 -404.72104) (xy 177.677831 -404.746257) (xy 177.61811 -404.763981)
			(xy 177.556613 -404.773924) (xy 177.49435 -404.77592) (xy 177.432343 -404.769938) (xy 177.371609 -404.756076)
			(xy 177.313147 -404.734562) (xy 177.257916 -404.705748) (xy 177.206824 -404.670108) (xy 177.160708 -404.628227)
			(xy 177.120326 -404.580792) (xy 177.086342 -404.528583) (xy 177.059313 -404.472457) (xy 177.039684 -404.413336)
			(xy 177.027775 -404.352189) (xy 177.023784 -404.290022) (xy 173.59494 -404.290022) (xy 173.594939 -404.322738)
			(xy 173.586154 -404.387583) (xy 173.568745 -404.450662) (xy 173.543026 -404.510834) (xy 173.526704 -404.539196)
			(xy 173.523391 -404.545221) (xy 173.519784 -404.558485) (xy 173.519592 -404.565358) (xy 173.519592 -405.314658)
			(xy 173.519801 -405.32153) (xy 173.523398 -405.334793) (xy 173.526704 -405.34082) (xy 173.54302 -405.369185)
			(xy 173.568736 -405.429355) (xy 173.586143 -405.492433) (xy 173.594926 -405.557277) (xy 173.594927 -405.622713)
			(xy 173.586145 -405.687557) (xy 173.568739 -405.750635) (xy 173.543024 -405.810806) (xy 173.526704 -405.839168)
			(xy 173.523401 -405.845198) (xy 173.519788 -405.858458) (xy 173.519592 -405.86533) (xy 173.519592 -406.151334)
			(xy 173.519095 -406.16149) (xy 173.511315 -406.180254) (xy 173.496951 -406.194617) (xy 173.478186 -406.202396)
			(xy 173.46803 -406.202896) (xy 172.75175 -406.202896) (xy 172.741586 -406.202396) (xy 172.722799 -406.194634)
			(xy 172.708413 -406.180272) (xy 172.70062 -406.161497) (xy 172.700188 -406.151334) (xy 172.700188 -405.86533)
			(xy 172.699986 -405.858458) (xy 172.696385 -405.845195) (xy 172.693076 -405.839168) (xy 172.676748 -405.81081)
			(xy 172.651028 -405.750638) (xy 172.63362 -405.687559) (xy 172.624836 -405.622714) (xy 171.336117 -405.622714)
			(xy 171.326556 -405.63927) (xy 171.323256 -405.645302) (xy 171.31964 -405.65856) (xy 171.319444 -405.665432)
			(xy 171.319444 -406.414732) (xy 171.319618 -406.421607) (xy 171.323238 -406.43487) (xy 171.326556 -406.440894)
			(xy 171.342915 -406.469247) (xy 171.368719 -406.529405) (xy 171.386211 -406.592483) (xy 171.395073 -406.657339)
			(xy 171.395644 -406.690068) (xy 171.39508 -406.722792) (xy 174.824976 -406.722792) (xy 174.82498 -406.657353)
			(xy 174.833767 -406.592507) (xy 174.851179 -406.529427) (xy 174.8769 -406.469255) (xy 174.893224 -406.440894)
			(xy 174.896543 -406.434871) (xy 174.900145 -406.421606) (xy 174.900336 -406.414732) (xy 174.900336 -405.665432)
			(xy 174.900127 -405.65856) (xy 174.89653 -405.645297) (xy 174.893224 -405.63927) (xy 174.876899 -405.61091)
			(xy 174.851182 -405.550739) (xy 174.833775 -405.48766) (xy 174.824992 -405.422815) (xy 174.824993 -405.357378)
			(xy 174.833777 -405.292534) (xy 174.851185 -405.229455) (xy 174.876902 -405.169283) (xy 174.893224 -405.140922)
			(xy 174.896533 -405.134894) (xy 174.900142 -405.121633) (xy 174.900336 -405.11476) (xy 174.900336 -404.828756)
			(xy 174.900686 -404.818594) (xy 174.908503 -404.799834) (xy 174.922922 -404.785511) (xy 174.941734 -404.77782)
			(xy 174.951898 -404.777448) (xy 175.668178 -404.777448) (xy 175.678304 -404.777945) (xy 175.697027 -404.785667)
			(xy 175.711384 -404.79995) (xy 175.719202 -404.818632) (xy 175.71974 -404.828756) (xy 175.71974 -405.11476)
			(xy 175.719942 -405.121633) (xy 175.723543 -405.134896) (xy 175.726852 -405.140922) (xy 175.743171 -405.169285)
			(xy 175.76889 -405.229456) (xy 175.786298 -405.292534) (xy 175.795082 -405.357378) (xy 175.795083 -405.422815)
			(xy 175.7863 -405.487659) (xy 175.768892 -405.550738) (xy 175.752113 -405.589994) (xy 177.023784 -405.589994)
			(xy 177.027775 -405.527827) (xy 177.039684 -405.46668) (xy 177.059313 -405.407559) (xy 177.086342 -405.351433)
			(xy 177.120326 -405.299224) (xy 177.160708 -405.251789) (xy 177.206824 -405.209908) (xy 177.257916 -405.174268)
			(xy 177.313147 -405.145454) (xy 177.371609 -405.12394) (xy 177.432343 -405.110078) (xy 177.49435 -405.104096)
			(xy 177.556613 -405.106092) (xy 177.61811 -405.116035) (xy 177.677831 -405.133759) (xy 177.734794 -405.158976)
			(xy 177.788065 -405.191269) (xy 177.83677 -405.230109) (xy 177.880107 -405.274859) (xy 177.917367 -405.324783)
			(xy 177.947936 -405.379062) (xy 177.952403 -405.390096) (xy 179.223932 -405.390096) (xy 179.227923 -405.327929)
			(xy 179.239832 -405.266782) (xy 179.259461 -405.207661) (xy 179.28649 -405.151535) (xy 179.320474 -405.099326)
			(xy 179.360856 -405.051891) (xy 179.406972 -405.01001) (xy 179.458064 -404.97437) (xy 179.513295 -404.945556)
			(xy 179.571757 -404.924042) (xy 179.632491 -404.91018) (xy 179.694498 -404.904198) (xy 179.756761 -404.906194)
			(xy 179.818258 -404.916137) (xy 179.877979 -404.933861) (xy 179.934942 -404.959078) (xy 179.988213 -404.991371)
			(xy 180.036918 -405.030211) (xy 180.080255 -405.074961) (xy 180.117515 -405.124885) (xy 180.148084 -405.179164)
			(xy 180.154299 -405.194516) (xy 198.019922 -405.194516) (xy 198.023993 -405.138894) (xy 198.036119 -405.084457)
			(xy 198.056042 -405.032366) (xy 198.083338 -404.983731) (xy 198.117424 -404.939588) (xy 198.157573 -404.900879)
			(xy 198.202931 -404.868428) (xy 198.252531 -404.842927) (xy 198.305315 -404.82492) (xy 198.360158 -404.81479)
			(xy 198.415892 -404.812753) (xy 198.471329 -404.818853) (xy 198.525286 -404.832959) (xy 198.576615 -404.854771)
			(xy 198.624221 -404.883825) (xy 198.667089 -404.9195) (xy 198.704306 -404.961037) (xy 198.735079 -405.00755)
			(xy 198.758751 -405.058047) (xy 198.774819 -405.111454) (xy 198.782939 -405.16663) (xy 198.783448 -405.194516)
			(xy 198.782939 -405.222402) (xy 198.774819 -405.277578) (xy 198.758751 -405.330985) (xy 198.735079 -405.381482)
			(xy 198.704306 -405.427995) (xy 198.667089 -405.469532) (xy 198.624221 -405.505207) (xy 198.576615 -405.534261)
			(xy 198.525286 -405.556073) (xy 198.471329 -405.570179) (xy 198.415892 -405.576279) (xy 198.360158 -405.574242)
			(xy 198.305315 -405.564112) (xy 198.252531 -405.546105) (xy 198.202931 -405.520604) (xy 198.157573 -405.488153)
			(xy 198.117424 -405.449444) (xy 198.083338 -405.405301) (xy 198.056042 -405.356666) (xy 198.036119 -405.304575)
			(xy 198.023993 -405.250138) (xy 198.019922 -405.194516) (xy 180.154299 -405.194516) (xy 180.171462 -405.236907)
			(xy 180.187263 -405.297165) (xy 180.195229 -405.358948) (xy 180.195728 -405.390096) (xy 180.195229 -405.421244)
			(xy 180.187263 -405.483027) (xy 180.171462 -405.543285) (xy 180.148084 -405.601028) (xy 180.117515 -405.655307)
			(xy 180.080255 -405.705231) (xy 180.036918 -405.749981) (xy 179.988213 -405.788821) (xy 179.934942 -405.821114)
			(xy 179.877979 -405.846331) (xy 179.838782 -405.857964) (xy 187.266832 -405.857964) (xy 187.270903 -405.802342)
			(xy 187.283029 -405.747905) (xy 187.302952 -405.695814) (xy 187.330248 -405.647179) (xy 187.364334 -405.603036)
			(xy 187.404483 -405.564327) (xy 187.449841 -405.531876) (xy 187.499441 -405.506375) (xy 187.552225 -405.488368)
			(xy 187.607068 -405.478238) (xy 187.662802 -405.476201) (xy 187.718239 -405.482301) (xy 187.772196 -405.496407)
			(xy 187.823525 -405.518219) (xy 187.871131 -405.547273) (xy 187.913999 -405.582948) (xy 187.951216 -405.624485)
			(xy 187.981989 -405.670998) (xy 188.005661 -405.721495) (xy 188.021729 -405.774902) (xy 188.029849 -405.830078)
			(xy 188.030358 -405.857964) (xy 188.029849 -405.88585) (xy 188.021729 -405.941026) (xy 188.005661 -405.994433)
			(xy 187.981989 -406.04493) (xy 187.951216 -406.091443) (xy 187.913999 -406.13298) (xy 187.871131 -406.168655)
			(xy 187.823525 -406.197709) (xy 187.772196 -406.219521) (xy 187.718239 -406.233627) (xy 187.662802 -406.239727)
			(xy 187.607068 -406.23769) (xy 187.552225 -406.22756) (xy 187.499441 -406.209553) (xy 187.449841 -406.184052)
			(xy 187.404483 -406.151601) (xy 187.364334 -406.112892) (xy 187.330248 -406.068749) (xy 187.302952 -406.020114)
			(xy 187.283029 -405.968023) (xy 187.270903 -405.913586) (xy 187.266832 -405.857964) (xy 179.838782 -405.857964)
			(xy 179.818258 -405.864055) (xy 179.756761 -405.873998) (xy 179.694498 -405.875994) (xy 179.632491 -405.870012)
			(xy 179.571757 -405.85615) (xy 179.513295 -405.834636) (xy 179.458064 -405.805822) (xy 179.406972 -405.770182)
			(xy 179.360856 -405.728301) (xy 179.320474 -405.680866) (xy 179.28649 -405.628657) (xy 179.259461 -405.572531)
			(xy 179.239832 -405.51341) (xy 179.227923 -405.452263) (xy 179.223932 -405.390096) (xy 177.952403 -405.390096)
			(xy 177.971314 -405.436805) (xy 177.987115 -405.497063) (xy 177.995081 -405.558846) (xy 177.99558 -405.589994)
			(xy 177.995081 -405.621142) (xy 177.987115 -405.682925) (xy 177.971314 -405.743183) (xy 177.947936 -405.800926)
			(xy 177.917367 -405.855205) (xy 177.880107 -405.905129) (xy 177.83677 -405.949879) (xy 177.788065 -405.988719)
			(xy 177.734794 -406.021012) (xy 177.677831 -406.046229) (xy 177.61811 -406.063953) (xy 177.556613 -406.073896)
			(xy 177.49435 -406.075892) (xy 177.432343 -406.06991) (xy 177.371609 -406.056048) (xy 177.313147 -406.034534)
			(xy 177.257916 -406.00572) (xy 177.206824 -405.97008) (xy 177.160708 -405.928199) (xy 177.120326 -405.880764)
			(xy 177.086342 -405.828555) (xy 177.059313 -405.772429) (xy 177.039684 -405.713308) (xy 177.027775 -405.652161)
			(xy 177.023784 -405.589994) (xy 175.752113 -405.589994) (xy 175.743174 -405.610909) (xy 175.726852 -405.63927)
			(xy 175.723552 -405.645302) (xy 175.719936 -405.65856) (xy 175.71974 -405.665432) (xy 175.71974 -406.414732)
			(xy 175.719915 -406.421607) (xy 175.723534 -406.434869) (xy 175.726852 -406.440894) (xy 175.743147 -406.46927)
			(xy 175.768868 -406.529438) (xy 175.786279 -406.592513) (xy 175.795067 -406.657355) (xy 175.795068 -406.690068)
			(xy 179.223932 -406.690068) (xy 179.227923 -406.627901) (xy 179.239832 -406.566754) (xy 179.259461 -406.507633)
			(xy 179.28649 -406.451507) (xy 179.320474 -406.399298) (xy 179.360856 -406.351863) (xy 179.406972 -406.309982)
			(xy 179.458064 -406.274342) (xy 179.513295 -406.245528) (xy 179.571757 -406.224014) (xy 179.632491 -406.210152)
			(xy 179.694498 -406.20417) (xy 179.756761 -406.206166) (xy 179.818258 -406.216109) (xy 179.877979 -406.233833)
			(xy 179.934942 -406.25905) (xy 179.988213 -406.291343) (xy 180.036918 -406.330183) (xy 180.080255 -406.374933)
			(xy 180.117515 -406.424857) (xy 180.148084 -406.479136) (xy 180.161087 -406.511252) (xy 198.765666 -406.511252)
			(xy 198.769737 -406.45563) (xy 198.781863 -406.401193) (xy 198.801786 -406.349102) (xy 198.829082 -406.300467)
			(xy 198.863168 -406.256324) (xy 198.903317 -406.217615) (xy 198.948675 -406.185164) (xy 198.998275 -406.159663)
			(xy 199.051059 -406.141656) (xy 199.105902 -406.131526) (xy 199.161636 -406.129489) (xy 199.217073 -406.135589)
			(xy 199.27103 -406.149695) (xy 199.322359 -406.171507) (xy 199.369965 -406.200561) (xy 199.412833 -406.236236)
			(xy 199.45005 -406.277773) (xy 199.480823 -406.324286) (xy 199.504495 -406.374783) (xy 199.520563 -406.42819)
			(xy 199.528683 -406.483366) (xy 199.529192 -406.511252) (xy 199.528683 -406.539138) (xy 199.520563 -406.594314)
			(xy 199.504495 -406.647721) (xy 199.480823 -406.698218) (xy 199.45005 -406.744731) (xy 199.412833 -406.786268)
			(xy 199.369965 -406.821943) (xy 199.322359 -406.850997) (xy 199.27103 -406.872809) (xy 199.217073 -406.886915)
			(xy 199.161636 -406.893015) (xy 199.105902 -406.890978) (xy 199.051059 -406.880848) (xy 198.998275 -406.862841)
			(xy 198.948675 -406.83734) (xy 198.903317 -406.804889) (xy 198.863168 -406.76618) (xy 198.829082 -406.722037)
			(xy 198.801786 -406.673402) (xy 198.781863 -406.621311) (xy 198.769737 -406.566874) (xy 198.765666 -406.511252)
			(xy 180.161087 -406.511252) (xy 180.171462 -406.536879) (xy 180.187263 -406.597137) (xy 180.195229 -406.65892)
			(xy 180.195728 -406.690068) (xy 180.195229 -406.721216) (xy 180.187263 -406.782999) (xy 180.171462 -406.843257)
			(xy 180.148084 -406.901) (xy 180.117515 -406.955279) (xy 180.088348 -406.99436) (xy 187.04255 -406.99436)
			(xy 187.046621 -406.938738) (xy 187.058747 -406.884301) (xy 187.07867 -406.83221) (xy 187.105966 -406.783575)
			(xy 187.140052 -406.739432) (xy 187.180201 -406.700723) (xy 187.225559 -406.668272) (xy 187.275159 -406.642771)
			(xy 187.327943 -406.624764) (xy 187.382786 -406.614634) (xy 187.43852 -406.612597) (xy 187.493957 -406.618697)
			(xy 187.547914 -406.632803) (xy 187.599243 -406.654615) (xy 187.646849 -406.683669) (xy 187.689717 -406.719344)
			(xy 187.726934 -406.760881) (xy 187.757707 -406.807394) (xy 187.781379 -406.857891) (xy 187.797447 -406.911298)
			(xy 187.805567 -406.966474) (xy 187.806076 -406.99436) (xy 187.805567 -407.022246) (xy 187.797447 -407.077422)
			(xy 187.781379 -407.130829) (xy 187.757707 -407.181326) (xy 187.726934 -407.227839) (xy 187.689717 -407.269376)
			(xy 187.646849 -407.305051) (xy 187.599243 -407.334105) (xy 187.547914 -407.355917) (xy 187.493957 -407.370023)
			(xy 187.43852 -407.376123) (xy 187.382786 -407.374086) (xy 187.327943 -407.363956) (xy 187.275159 -407.345949)
			(xy 187.225559 -407.320448) (xy 187.180201 -407.287997) (xy 187.140052 -407.249288) (xy 187.105966 -407.205145)
			(xy 187.07867 -407.15651) (xy 187.058747 -407.104419) (xy 187.046621 -407.049982) (xy 187.04255 -406.99436)
			(xy 180.088348 -406.99436) (xy 180.080255 -407.005203) (xy 180.036918 -407.049953) (xy 179.988213 -407.088793)
			(xy 179.934942 -407.121086) (xy 179.877979 -407.146303) (xy 179.818258 -407.164027) (xy 179.756761 -407.17397)
			(xy 179.694498 -407.175966) (xy 179.632491 -407.169984) (xy 179.571757 -407.156122) (xy 179.513295 -407.134608)
			(xy 179.458064 -407.105794) (xy 179.406972 -407.070154) (xy 179.360856 -407.028273) (xy 179.320474 -406.980838)
			(xy 179.28649 -406.928629) (xy 179.259461 -406.872503) (xy 179.239832 -406.813382) (xy 179.227923 -406.752235)
			(xy 179.223932 -406.690068) (xy 175.795068 -406.690068) (xy 175.79507 -406.72279) (xy 175.78629 -406.787633)
			(xy 175.768886 -406.85071) (xy 175.743172 -406.910881) (xy 175.726852 -406.939242) (xy 175.723526 -406.945261)
			(xy 175.719927 -406.958529) (xy 175.71974 -406.965404) (xy 175.71974 -407.251408) (xy 175.719286 -407.261558)
			(xy 175.711495 -407.280302) (xy 175.697109 -407.294624) (xy 175.678329 -407.302331) (xy 175.668178 -407.302716)
			(xy 174.951898 -407.302716) (xy 174.941766 -407.302274) (xy 174.923036 -407.294537) (xy 174.908679 -407.280237)
			(xy 174.900867 -407.261538) (xy 174.900336 -407.251408) (xy 174.900336 -406.965404) (xy 174.900138 -406.958531)
			(xy 174.896533 -406.945269) (xy 174.893224 -406.939242) (xy 174.876875 -406.910896) (xy 174.851161 -406.850721)
			(xy 174.833756 -406.787639) (xy 174.824976 -406.722792) (xy 171.39508 -406.722792) (xy 171.39508 -406.722798)
			(xy 171.386223 -406.787656) (xy 171.368732 -406.850736) (xy 171.342925 -406.910894) (xy 171.326556 -406.939242)
			(xy 171.323231 -406.945262) (xy 171.319631 -406.958529) (xy 171.319444 -406.965404) (xy 171.319444 -407.251408)
			(xy 171.318922 -407.261512) (xy 171.31119 -407.280182) (xy 171.296905 -407.294475) (xy 171.278239 -407.302217)
			(xy 171.268136 -407.302716) (xy 170.551856 -407.302716) (xy 170.541746 -407.302251) (xy 170.52307 -407.294502)
			(xy 170.508778 -407.280199) (xy 170.501042 -407.261518) (xy 170.500548 -407.251408) (xy 170.500548 -406.965404)
			(xy 170.500361 -406.95853) (xy 170.49675 -406.945267) (xy 170.493436 -406.939242) (xy 170.477091 -406.910882)
			(xy 170.451283 -406.850726) (xy 170.433788 -406.78765) (xy 170.424921 -406.722796) (xy 170.424348 -406.690068)
			(xy 166.994982 -406.690068) (xy 166.994984 -406.72279) (xy 166.986205 -406.787633) (xy 166.968801 -406.85071)
			(xy 166.943088 -406.910881) (xy 166.926768 -406.939242) (xy 166.923436 -406.945258) (xy 166.919842 -406.958529)
			(xy 166.919656 -406.965404) (xy 166.919656 -407.251408) (xy 166.919186 -407.261556) (xy 166.911398 -407.280297)
			(xy 166.897017 -407.294618) (xy 166.878243 -407.302328) (xy 166.868094 -407.302716) (xy 166.151814 -407.302716)
			(xy 166.141683 -407.302261) (xy 166.122954 -407.294529) (xy 166.108595 -407.280233) (xy 166.100783 -407.261537)
			(xy 166.100252 -407.251408) (xy 166.100252 -406.965404) (xy 166.100064 -406.95853) (xy 166.096454 -406.945267)
			(xy 166.09314 -406.939242) (xy 166.076791 -406.910896) (xy 166.051076 -406.850721) (xy 166.03367 -406.787639)
			(xy 166.02489 -406.722792) (xy 162.594994 -406.722792) (xy 162.594994 -406.722797) (xy 162.586137 -406.787655)
			(xy 162.568647 -406.850735) (xy 162.54284 -406.910894) (xy 162.526472 -406.939242) (xy 162.52314 -406.945258)
			(xy 162.519546 -406.958529) (xy 162.51936 -406.965404) (xy 162.51936 -407.251408) (xy 162.518989 -407.261536)
			(xy 162.511231 -407.280247) (xy 162.4969 -407.294563) (xy 162.47818 -407.3023) (xy 162.468052 -407.302716)
			(xy 161.751772 -407.302716) (xy 161.741663 -407.302238) (xy 161.722988 -407.294494) (xy 161.708694 -407.280196)
			(xy 161.700958 -407.261517) (xy 161.700464 -407.251408) (xy 161.700464 -406.965404) (xy 161.700275 -406.95853)
			(xy 161.696665 -406.945268) (xy 161.693352 -406.939242) (xy 161.677008 -406.910881) (xy 161.6512 -406.850726)
			(xy 161.633704 -406.78765) (xy 161.624837 -406.722796) (xy 161.624264 -406.690068) (xy 154.57678 -406.690068)
			(xy 154.57678 -407.4414) (xy 185.755532 -407.4414) (xy 185.759603 -407.385778) (xy 185.771729 -407.331341)
			(xy 185.791652 -407.27925) (xy 185.818948 -407.230615) (xy 185.853034 -407.186472) (xy 185.893183 -407.147763)
			(xy 185.938541 -407.115312) (xy 185.988141 -407.089811) (xy 186.040925 -407.071804) (xy 186.095768 -407.061674)
			(xy 186.151502 -407.059637) (xy 186.206939 -407.065737) (xy 186.260896 -407.079843) (xy 186.312225 -407.101655)
			(xy 186.359831 -407.130709) (xy 186.402699 -407.166384) (xy 186.439916 -407.207921) (xy 186.470689 -407.254434)
			(xy 186.494361 -407.304931) (xy 186.510429 -407.358338) (xy 186.518549 -407.413514) (xy 186.519058 -407.4414)
			(xy 186.518549 -407.469286) (xy 186.510429 -407.524462) (xy 186.494361 -407.577869) (xy 186.470689 -407.628366)
			(xy 186.439916 -407.674879) (xy 186.402699 -407.716416) (xy 186.359831 -407.752091) (xy 186.312225 -407.781145)
			(xy 186.260896 -407.802957) (xy 186.206939 -407.817063) (xy 186.151502 -407.823163) (xy 186.095768 -407.821126)
			(xy 186.040925 -407.810996) (xy 185.988141 -407.792989) (xy 185.938541 -407.767488) (xy 185.893183 -407.735037)
			(xy 185.853034 -407.696328) (xy 185.818948 -407.652185) (xy 185.791652 -407.60355) (xy 185.771729 -407.551459)
			(xy 185.759603 -407.497022) (xy 185.755532 -407.4414) (xy 154.57678 -407.4414) (xy 154.57678 -409.522889)
			(xy 159.424957 -409.522889) (xy 159.424961 -409.45745) (xy 159.433748 -409.392604) (xy 159.45116 -409.329524)
			(xy 159.47688 -409.269352) (xy 159.493204 -409.24099) (xy 159.496523 -409.234967) (xy 159.500126 -409.221702)
			(xy 159.500316 -409.214828) (xy 159.500316 -408.465528) (xy 159.500112 -408.458656) (xy 159.496512 -408.445393)
			(xy 159.493204 -408.439366) (xy 159.476876 -408.411008) (xy 159.451161 -408.350836) (xy 159.433755 -408.287756)
			(xy 159.424973 -408.222912) (xy 159.424974 -408.157475) (xy 159.433758 -408.09263) (xy 159.451165 -408.029551)
			(xy 159.476882 -407.96938) (xy 159.493204 -407.941018) (xy 159.496513 -407.93499) (xy 159.500122 -407.921729)
			(xy 159.500316 -407.914856) (xy 159.500316 -407.628852) (xy 159.500683 -407.618693) (xy 159.508497 -407.599936)
			(xy 159.522911 -407.585614) (xy 159.541716 -407.577919) (xy 159.551878 -407.577544) (xy 160.268158 -407.577544)
			(xy 160.278283 -407.578061) (xy 160.297003 -407.585776) (xy 160.311361 -407.600053) (xy 160.319181 -407.61873)
			(xy 160.31972 -407.628852) (xy 160.31972 -407.914856) (xy 160.319926 -407.921728) (xy 160.323525 -407.934991)
			(xy 160.326832 -407.941018) (xy 160.343148 -407.969383) (xy 160.368868 -408.029553) (xy 160.386278 -408.092631)
			(xy 160.395063 -408.157475) (xy 160.395064 -408.222911) (xy 160.386281 -408.287756) (xy 160.368873 -408.350834)
			(xy 160.343155 -408.411005) (xy 160.326832 -408.439366) (xy 160.323532 -408.445398) (xy 160.319917 -408.458656)
			(xy 160.31972 -408.465528) (xy 160.31972 -409.214828) (xy 160.319899 -409.221702) (xy 160.323516 -409.234965)
			(xy 160.326832 -409.24099) (xy 160.343125 -409.269368) (xy 160.368847 -409.329535) (xy 160.386259 -409.39261)
			(xy 160.395047 -409.457452) (xy 160.395051 -409.522886) (xy 160.386272 -409.587729) (xy 160.368867 -409.650807)
			(xy 160.343153 -409.710977) (xy 160.326832 -409.739338) (xy 160.323506 -409.745357) (xy 160.319907 -409.758625)
			(xy 160.31972 -409.7655) (xy 160.31972 -410.051504) (xy 160.319282 -410.061656) (xy 160.311489 -410.080404)
			(xy 160.297098 -410.094727) (xy 160.278312 -410.10243) (xy 160.268158 -410.102812) (xy 159.551878 -410.102812)
			(xy 159.541756 -410.102293) (xy 159.523044 -410.094568) (xy 159.508691 -410.080292) (xy 159.500863 -410.061623)
			(xy 159.500316 -410.051504) (xy 159.500316 -409.7655) (xy 159.500122 -409.758627) (xy 159.496515 -409.745364)
			(xy 159.493204 -409.739338) (xy 159.476852 -409.710993) (xy 159.451139 -409.650818) (xy 159.433736 -409.587736)
			(xy 159.424957 -409.522889) (xy 154.57678 -409.522889) (xy 154.57678 -410.589984) (xy 161.624264 -410.589984)
			(xy 161.62485 -410.557255) (xy 161.633701 -410.492398) (xy 161.651185 -410.429318) (xy 161.676987 -410.369159)
			(xy 161.693352 -410.34081) (xy 161.696659 -410.334782) (xy 161.70027 -410.321521) (xy 161.700464 -410.314648)
			(xy 161.700464 -409.565348) (xy 161.700258 -409.558476) (xy 161.69666 -409.545213) (xy 161.693352 -409.539186)
			(xy 161.676986 -409.510837) (xy 161.651183 -409.450678) (xy 161.633693 -409.387598) (xy 161.624834 -409.322741)
			(xy 161.624264 -409.290012) (xy 161.624817 -409.257282) (xy 161.633678 -409.192424) (xy 161.651172 -409.129343)
			(xy 161.676982 -409.069186) (xy 161.693352 -409.040838) (xy 161.696649 -409.034805) (xy 161.700267 -409.021548)
			(xy 161.700464 -409.014676) (xy 161.700464 -408.728672) (xy 161.700961 -408.718566) (xy 161.708701 -408.699894)
			(xy 161.722994 -408.685601) (xy 161.741666 -408.677861) (xy 161.751772 -408.677364) (xy 162.468052 -408.677364)
			(xy 162.478167 -408.677854) (xy 162.496863 -408.68558) (xy 162.511177 -408.699874) (xy 162.518931 -408.718558)
			(xy 162.51936 -408.728672) (xy 162.51936 -409.014676) (xy 162.519566 -409.021548) (xy 162.523165 -409.034811)
			(xy 162.526472 -409.040838) (xy 162.54285 -409.06918) (xy 162.568649 -409.129342) (xy 162.586136 -409.192424)
			(xy 162.594992 -409.257282) (xy 162.59556 -409.290012) (xy 162.594969 -409.322741) (xy 162.58612 -409.387598)
			(xy 162.568637 -409.450678) (xy 162.551703 -409.490164) (xy 163.824412 -409.490164) (xy 163.824982 -409.457435)
			(xy 163.833837 -409.392577) (xy 163.851326 -409.329496) (xy 163.877132 -409.269338) (xy 163.8935 -409.24099)
			(xy 163.896818 -409.234967) (xy 163.900422 -409.221702) (xy 163.900612 -409.214828) (xy 163.900612 -408.465528)
			(xy 163.900408 -408.458656) (xy 163.896808 -408.445393) (xy 163.8935 -408.439366) (xy 163.877121 -408.411024)
			(xy 163.851322 -408.350862) (xy 163.833836 -408.28778) (xy 163.82498 -408.222922) (xy 163.824412 -408.190192)
			(xy 163.824995 -408.157463) (xy 163.833845 -408.092605) (xy 163.851331 -408.029525) (xy 163.877134 -407.969367)
			(xy 163.8935 -407.941018) (xy 163.896808 -407.93499) (xy 163.900418 -407.921729) (xy 163.900612 -407.914856)
			(xy 163.900612 -407.628852) (xy 163.901046 -407.618739) (xy 163.908802 -407.600057) (xy 163.923114 -407.585764)
			(xy 163.941806 -407.578033) (xy 163.95192 -407.577544) (xy 164.6682 -407.577544) (xy 164.678302 -407.578084)
			(xy 164.696969 -407.585811) (xy 164.711262 -407.60009) (xy 164.719007 -407.618751) (xy 164.719508 -407.628852)
			(xy 164.719508 -407.914856) (xy 164.719716 -407.921728) (xy 164.723313 -407.934991) (xy 164.72662 -407.941018)
			(xy 164.742995 -407.969362) (xy 164.768794 -408.029524) (xy 164.786281 -408.092605) (xy 164.795139 -408.157463)
			(xy 164.795708 -408.190192) (xy 164.79516 -408.222922) (xy 164.786299 -408.287781) (xy 164.768804 -408.350861)
			(xy 164.742991 -408.411019) (xy 164.72662 -408.439366) (xy 164.723319 -408.445397) (xy 164.719704 -408.458656)
			(xy 164.719508 -408.465528) (xy 164.719508 -409.214828) (xy 164.719688 -409.221702) (xy 164.723304 -409.234965)
			(xy 164.72662 -409.24099) (xy 164.742984 -409.26934) (xy 164.768785 -409.3295) (xy 164.786276 -409.392579)
			(xy 164.795137 -409.457435) (xy 164.795708 -409.490164) (xy 164.795147 -409.522894) (xy 164.78629 -409.587752)
			(xy 164.768798 -409.650832) (xy 164.742989 -409.71099) (xy 164.72662 -409.739338) (xy 164.723293 -409.745357)
			(xy 164.719695 -409.758625) (xy 164.719508 -409.7655) (xy 164.719508 -410.051504) (xy 164.719018 -410.061612)
			(xy 164.711281 -410.080289) (xy 164.696985 -410.094583) (xy 164.678308 -410.102319) (xy 164.6682 -410.102812)
			(xy 163.95192 -410.102812) (xy 163.9418 -410.102368) (xy 163.923099 -410.094629) (xy 163.908785 -410.080321)
			(xy 163.901037 -410.061624) (xy 163.900612 -410.051504) (xy 163.900612 -409.7655) (xy 163.900419 -409.758627)
			(xy 163.896811 -409.745364) (xy 163.8935 -409.739338) (xy 163.87715 -409.71098) (xy 163.851344 -409.650824)
			(xy 163.83385 -409.587747) (xy 163.824985 -409.522892) (xy 163.824412 -409.490164) (xy 162.551703 -409.490164)
			(xy 162.542837 -409.510837) (xy 162.526472 -409.539186) (xy 162.52316 -409.545212) (xy 162.519553 -409.558475)
			(xy 162.51936 -409.565348) (xy 162.51936 -410.314648) (xy 162.519577 -410.321519) (xy 162.523169 -410.334782)
			(xy 162.526472 -410.34081) (xy 162.542839 -410.369159) (xy 162.568641 -410.429318) (xy 162.58613 -410.492398)
			(xy 162.59499 -410.557255) (xy 162.59556 -410.589984) (xy 162.595001 -410.622705) (xy 166.024899 -410.622705)
			(xy 166.024901 -410.557267) (xy 166.033687 -410.492422) (xy 166.051097 -410.429343) (xy 166.076817 -410.369171)
			(xy 166.09314 -410.34081) (xy 166.096446 -410.334781) (xy 166.100058 -410.321521) (xy 166.100252 -410.314648)
			(xy 166.100252 -409.565348) (xy 166.100048 -409.558476) (xy 166.096449 -409.545213) (xy 166.09314 -409.539186)
			(xy 166.076828 -409.510819) (xy 166.051109 -409.450649) (xy 166.0337 -409.387572) (xy 166.024915 -409.322728)
			(xy 166.024914 -409.257292) (xy 166.033696 -409.192448) (xy 166.051102 -409.12937) (xy 166.076819 -409.069199)
			(xy 166.09314 -409.040838) (xy 166.096437 -409.034804) (xy 166.100054 -409.021548) (xy 166.100252 -409.014676)
			(xy 166.100252 -408.728672) (xy 166.100698 -408.718522) (xy 166.108493 -408.699778) (xy 166.122882 -408.685458)
			(xy 166.141662 -408.67775) (xy 166.151814 -408.677364) (xy 166.868094 -408.677364) (xy 166.878223 -408.677832)
			(xy 166.896949 -408.685562) (xy 166.911306 -408.699855) (xy 166.919121 -408.718545) (xy 166.919656 -408.728672)
			(xy 166.919656 -409.014676) (xy 166.91985 -409.021549) (xy 166.923456 -409.034812) (xy 166.926768 -409.040838)
			(xy 166.9431 -409.069194) (xy 166.968816 -409.129366) (xy 166.986223 -409.192446) (xy 166.995005 -409.257292)
			(xy 166.995004 -409.322729) (xy 166.986219 -409.387574) (xy 166.96881 -409.450653) (xy 166.943091 -409.510825)
			(xy 166.936148 -409.522888) (xy 168.225043 -409.522888) (xy 168.225047 -409.45745) (xy 168.233834 -409.392604)
			(xy 168.251245 -409.329524) (xy 168.276965 -409.269352) (xy 168.293288 -409.24099) (xy 168.296605 -409.234967)
			(xy 168.30021 -409.221702) (xy 168.3004 -409.214828) (xy 168.3004 -408.465528) (xy 168.300197 -408.458656)
			(xy 168.296596 -408.445393) (xy 168.293288 -408.439366) (xy 168.276961 -408.411008) (xy 168.251246 -408.350835)
			(xy 168.233841 -408.287756) (xy 168.225059 -408.222911) (xy 168.22506 -408.157475) (xy 168.233844 -408.09263)
			(xy 168.251251 -408.029552) (xy 168.276967 -407.96938) (xy 168.293288 -407.941018) (xy 168.296595 -407.93499)
			(xy 168.300206 -407.921729) (xy 168.3004 -407.914856) (xy 168.3004 -407.628852) (xy 168.300782 -407.618695)
			(xy 168.308594 -407.599941) (xy 168.323002 -407.58562) (xy 168.341802 -407.577922) (xy 168.351962 -407.577544)
			(xy 169.068242 -407.577544) (xy 169.078372 -407.577992) (xy 169.097095 -407.585735) (xy 169.11145 -407.600032)
			(xy 169.119267 -407.618724) (xy 169.119804 -407.628852) (xy 169.119804 -407.914856) (xy 169.120012 -407.921728)
			(xy 169.123609 -407.934991) (xy 169.126916 -407.941018) (xy 169.143233 -407.969383) (xy 169.168953 -408.029552)
			(xy 169.186364 -408.09263) (xy 169.195149 -408.157475) (xy 169.19515 -408.222912) (xy 169.186367 -408.287756)
			(xy 169.168958 -408.350835) (xy 169.143239 -408.411005) (xy 169.126916 -408.439366) (xy 169.123614 -408.445397)
			(xy 169.12 -408.458656) (xy 169.119804 -408.465528) (xy 169.119804 -409.214828) (xy 169.119985 -409.221702)
			(xy 169.1236 -409.234965) (xy 169.126916 -409.24099) (xy 169.143209 -409.269368) (xy 169.168932 -409.329534)
			(xy 169.186345 -409.39261) (xy 169.195133 -409.457452) (xy 169.195137 -409.522887) (xy 169.186357 -409.58773)
			(xy 169.168952 -409.650807) (xy 169.143237 -409.710977) (xy 169.126916 -409.739338) (xy 169.123589 -409.745357)
			(xy 169.119991 -409.758625) (xy 169.119804 -409.7655) (xy 169.119804 -410.051504) (xy 169.119382 -410.061658)
			(xy 169.111586 -410.08041) (xy 169.097189 -410.094733) (xy 169.078398 -410.102433) (xy 169.068242 -410.102812)
			(xy 168.351962 -410.102812) (xy 168.341839 -410.102306) (xy 168.323127 -410.094575) (xy 168.308774 -410.080296)
			(xy 168.300947 -410.061624) (xy 168.3004 -410.051504) (xy 168.3004 -409.7655) (xy 168.300208 -409.758627)
			(xy 168.2966 -409.745364) (xy 168.293288 -409.739338) (xy 168.276937 -409.710993) (xy 168.251225 -409.650817)
			(xy 168.233822 -409.587735) (xy 168.225043 -409.522888) (xy 166.936148 -409.522888) (xy 166.926768 -409.539186)
			(xy 166.923456 -409.545212) (xy 166.919849 -409.558475) (xy 166.919656 -409.565348) (xy 166.919656 -410.314648)
			(xy 166.919861 -410.32152) (xy 166.923459 -410.334783) (xy 166.926768 -410.34081) (xy 166.943076 -410.369179)
			(xy 166.968795 -410.429348) (xy 166.986204 -410.492425) (xy 166.994989 -410.557269) (xy 166.99499 -410.589984)
			(xy 170.424348 -410.589984) (xy 170.424936 -410.557255) (xy 170.433786 -410.492398) (xy 170.45127 -410.429318)
			(xy 170.477071 -410.369159) (xy 170.493436 -410.34081) (xy 170.496742 -410.334781) (xy 170.500354 -410.321521)
			(xy 170.500548 -410.314648) (xy 170.500548 -409.565348) (xy 170.500344 -409.558476) (xy 170.496745 -409.545212)
			(xy 170.493436 -409.539186) (xy 170.477068 -409.510838) (xy 170.451266 -409.450678) (xy 170.433777 -409.387598)
			(xy 170.424918 -409.322741) (xy 170.424348 -409.290012) (xy 170.424904 -409.257282) (xy 170.433764 -409.192424)
			(xy 170.451257 -409.129344) (xy 170.477066 -409.069186) (xy 170.493436 -409.040838) (xy 170.496732 -409.034804)
			(xy 170.50035 -409.021548) (xy 170.500548 -409.014676) (xy 170.500548 -408.728672) (xy 170.501061 -408.718568)
			(xy 170.508798 -408.699899) (xy 170.523086 -408.685607) (xy 170.541752 -408.677864) (xy 170.551856 -408.677364)
			(xy 171.268136 -408.677364) (xy 171.278243 -408.677855) (xy 171.296915 -408.685598) (xy 171.311207 -408.699892)
			(xy 171.318947 -408.718565) (xy 171.319444 -408.728672) (xy 171.319444 -409.014676) (xy 171.31964 -409.021549)
			(xy 171.323245 -409.034812) (xy 171.326556 -409.040838) (xy 171.342932 -409.069181) (xy 171.368733 -409.129343)
			(xy 171.386219 -409.192424) (xy 171.395076 -409.257282) (xy 171.395644 -409.290012) (xy 171.395056 -409.322741)
			(xy 171.386206 -409.387598) (xy 171.368722 -409.450678) (xy 171.342921 -409.510837) (xy 171.335964 -409.522889)
			(xy 172.624819 -409.522889) (xy 172.624823 -409.457449) (xy 172.633612 -409.392602) (xy 172.651026 -409.329522)
			(xy 172.67675 -409.269351) (xy 172.693076 -409.24099) (xy 172.696393 -409.234966) (xy 172.699998 -409.221702)
			(xy 172.700188 -409.214828) (xy 172.700188 -408.465528) (xy 172.699987 -408.458655) (xy 172.696385 -408.445393)
			(xy 172.693076 -408.439366) (xy 172.676746 -408.411009) (xy 172.651027 -408.350837) (xy 172.633618 -408.287758)
			(xy 172.624835 -408.222912) (xy 172.624836 -408.157474) (xy 172.633621 -408.092629) (xy 172.651031 -408.02955)
			(xy 172.676752 -407.969379) (xy 172.693076 -407.941018) (xy 172.696383 -407.934989) (xy 172.699994 -407.921729)
			(xy 172.700188 -407.914856) (xy 172.700188 -407.628852) (xy 172.700582 -407.618696) (xy 172.708391 -407.599945)
			(xy 172.722796 -407.585624) (xy 172.741592 -407.577924) (xy 172.75175 -407.577544) (xy 173.46803 -407.577544)
			(xy 173.478159 -407.578002) (xy 173.496882 -407.58574) (xy 173.511237 -407.600035) (xy 173.519055 -407.618725)
			(xy 173.519592 -407.628852) (xy 173.519592 -407.914856) (xy 173.519802 -407.921728) (xy 173.523398 -407.934991)
			(xy 173.526704 -407.941018) (xy 173.543018 -407.969383) (xy 173.568734 -408.029554) (xy 173.586141 -408.092632)
			(xy 173.594925 -408.157475) (xy 173.594925 -408.190192) (xy 177.023784 -408.190192) (xy 177.027775 -408.128025)
			(xy 177.039684 -408.066878) (xy 177.059313 -408.007757) (xy 177.086342 -407.951631) (xy 177.120326 -407.899422)
			(xy 177.160708 -407.851987) (xy 177.206824 -407.810106) (xy 177.257916 -407.774466) (xy 177.313147 -407.745652)
			(xy 177.371609 -407.724138) (xy 177.432343 -407.710276) (xy 177.49435 -407.704294) (xy 177.556613 -407.70629)
			(xy 177.61811 -407.716233) (xy 177.677831 -407.733957) (xy 177.734794 -407.759174) (xy 177.788065 -407.791467)
			(xy 177.83677 -407.830307) (xy 177.880107 -407.875057) (xy 177.917367 -407.924981) (xy 177.947936 -407.97926)
			(xy 177.971314 -408.037003) (xy 177.987115 -408.097261) (xy 177.995081 -408.159044) (xy 177.99558 -408.190192)
			(xy 177.995081 -408.22134) (xy 177.987115 -408.283123) (xy 177.971314 -408.343381) (xy 177.947936 -408.401124)
			(xy 177.917367 -408.455403) (xy 177.880107 -408.505327) (xy 177.83677 -408.550077) (xy 177.788065 -408.588917)
			(xy 177.782527 -408.592274) (xy 190.042798 -408.592274) (xy 190.046869 -408.536652) (xy 190.058995 -408.482215)
			(xy 190.078918 -408.430124) (xy 190.106214 -408.381489) (xy 190.1403 -408.337346) (xy 190.180449 -408.298637)
			(xy 190.225807 -408.266186) (xy 190.275407 -408.240685) (xy 190.328191 -408.222678) (xy 190.383034 -408.212548)
			(xy 190.438768 -408.210511) (xy 190.494205 -408.216611) (xy 190.548162 -408.230717) (xy 190.599491 -408.252529)
			(xy 190.647097 -408.281583) (xy 190.689965 -408.317258) (xy 190.727182 -408.358795) (xy 190.757955 -408.405308)
			(xy 190.781627 -408.455805) (xy 190.797695 -408.509212) (xy 190.805815 -408.564388) (xy 190.806324 -408.592274)
			(xy 190.805815 -408.62016) (xy 190.797695 -408.675336) (xy 190.781627 -408.728743) (xy 190.757955 -408.77924)
			(xy 190.727182 -408.825753) (xy 190.689965 -408.86729) (xy 190.647097 -408.902965) (xy 190.599491 -408.932019)
			(xy 190.548162 -408.953831) (xy 190.520426 -408.961082) (xy 194.781676 -408.961082) (xy 194.785747 -408.90546)
			(xy 194.797873 -408.851023) (xy 194.817796 -408.798932) (xy 194.845092 -408.750297) (xy 194.879178 -408.706154)
			(xy 194.919327 -408.667445) (xy 194.964685 -408.634994) (xy 195.014285 -408.609493) (xy 195.067069 -408.591486)
			(xy 195.121912 -408.581356) (xy 195.177646 -408.579319) (xy 195.233083 -408.585419) (xy 195.28704 -408.599525)
			(xy 195.338369 -408.621337) (xy 195.385975 -408.650391) (xy 195.42327 -408.681428) (xy 196.990968 -408.681428)
			(xy 196.995039 -408.625806) (xy 197.007165 -408.571369) (xy 197.027088 -408.519278) (xy 197.054384 -408.470643)
			(xy 197.08847 -408.4265) (xy 197.128619 -408.387791) (xy 197.173977 -408.35534) (xy 197.223577 -408.329839)
			(xy 197.276361 -408.311832) (xy 197.331204 -408.301702) (xy 197.386938 -408.299665) (xy 197.442375 -408.305765)
			(xy 197.496332 -408.319871) (xy 197.547661 -408.341683) (xy 197.595267 -408.370737) (xy 197.638135 -408.406412)
			(xy 197.675352 -408.447949) (xy 197.706125 -408.494462) (xy 197.729797 -408.544959) (xy 197.745865 -408.598366)
			(xy 197.753985 -408.653542) (xy 197.754494 -408.681428) (xy 197.753985 -408.709314) (xy 197.745865 -408.76449)
			(xy 197.729797 -408.817897) (xy 197.706125 -408.868394) (xy 197.675352 -408.914907) (xy 197.638135 -408.956444)
			(xy 197.595267 -408.992119) (xy 197.547661 -409.021173) (xy 197.496332 -409.042985) (xy 197.442375 -409.057091)
			(xy 197.386938 -409.063191) (xy 197.331204 -409.061154) (xy 197.276361 -409.051024) (xy 197.223577 -409.033017)
			(xy 197.173977 -409.007516) (xy 197.128619 -408.975065) (xy 197.08847 -408.936356) (xy 197.054384 -408.892213)
			(xy 197.027088 -408.843578) (xy 197.007165 -408.791487) (xy 196.995039 -408.73705) (xy 196.990968 -408.681428)
			(xy 195.42327 -408.681428) (xy 195.428843 -408.686066) (xy 195.46606 -408.727603) (xy 195.496833 -408.774116)
			(xy 195.520505 -408.824613) (xy 195.536573 -408.87802) (xy 195.544693 -408.933196) (xy 195.545202 -408.961082)
			(xy 195.544693 -408.988968) (xy 195.536573 -409.044144) (xy 195.520505 -409.097551) (xy 195.496833 -409.148048)
			(xy 195.46606 -409.194561) (xy 195.428843 -409.236098) (xy 195.385975 -409.271773) (xy 195.338369 -409.300827)
			(xy 195.28704 -409.322639) (xy 195.233083 -409.336745) (xy 195.177646 -409.342845) (xy 195.121912 -409.340808)
			(xy 195.067069 -409.330678) (xy 195.014285 -409.312671) (xy 194.964685 -409.28717) (xy 194.919327 -409.254719)
			(xy 194.879178 -409.21601) (xy 194.845092 -409.171867) (xy 194.817796 -409.123232) (xy 194.797873 -409.071141)
			(xy 194.785747 -409.016704) (xy 194.781676 -408.961082) (xy 190.520426 -408.961082) (xy 190.494205 -408.967937)
			(xy 190.438768 -408.974037) (xy 190.383034 -408.972) (xy 190.328191 -408.96187) (xy 190.275407 -408.943863)
			(xy 190.225807 -408.918362) (xy 190.180449 -408.885911) (xy 190.1403 -408.847202) (xy 190.106214 -408.803059)
			(xy 190.078918 -408.754424) (xy 190.058995 -408.702333) (xy 190.046869 -408.647896) (xy 190.042798 -408.592274)
			(xy 177.782527 -408.592274) (xy 177.734794 -408.62121) (xy 177.677831 -408.646427) (xy 177.61811 -408.664151)
			(xy 177.556613 -408.674094) (xy 177.49435 -408.67609) (xy 177.432343 -408.670108) (xy 177.371609 -408.656246)
			(xy 177.313147 -408.634732) (xy 177.257916 -408.605918) (xy 177.206824 -408.570278) (xy 177.160708 -408.528397)
			(xy 177.120326 -408.480962) (xy 177.086342 -408.428753) (xy 177.059313 -408.372627) (xy 177.039684 -408.313506)
			(xy 177.027775 -408.252359) (xy 177.023784 -408.190192) (xy 173.594925 -408.190192) (xy 173.594926 -408.222911)
			(xy 173.586144 -408.287755) (xy 173.568739 -408.350833) (xy 173.543024 -408.411004) (xy 173.526704 -408.439366)
			(xy 173.523402 -408.445397) (xy 173.519788 -408.458656) (xy 173.519592 -408.465528) (xy 173.519592 -409.214828)
			(xy 173.519774 -409.221702) (xy 173.523389 -409.234965) (xy 173.526704 -409.24099) (xy 173.542994 -409.269369)
			(xy 173.568713 -409.329536) (xy 173.586122 -409.392611) (xy 173.594909 -409.457452) (xy 173.594913 -409.522886)
			(xy 173.586135 -409.587728) (xy 173.568733 -409.650805) (xy 173.543022 -409.710976) (xy 173.526704 -409.739338)
			(xy 173.523376 -409.745356) (xy 173.519779 -409.758625) (xy 173.519592 -409.7655) (xy 173.519592 -410.051504)
			(xy 173.519181 -410.061659) (xy 173.511383 -410.080413) (xy 173.496983 -410.094737) (xy 173.478187 -410.102435)
			(xy 173.46803 -410.102812) (xy 172.75175 -410.102812) (xy 172.741633 -410.102234) (xy 172.722923 -410.094532)
			(xy 172.708567 -410.080274) (xy 172.700736 -410.061618) (xy 172.700188 -410.051504) (xy 172.700188 -409.7655)
			(xy 172.699997 -409.758627) (xy 172.696388 -409.745364) (xy 172.693076 -409.739338) (xy 172.676722 -409.710994)
			(xy 172.651005 -409.650819) (xy 172.633599 -409.587737) (xy 172.624819 -409.522889) (xy 171.335964 -409.522889)
			(xy 171.326556 -409.539186) (xy 171.323251 -409.545215) (xy 171.319638 -409.558475) (xy 171.319444 -409.565348)
			(xy 171.319444 -410.314648) (xy 171.31965 -410.32152) (xy 171.323248 -410.334783) (xy 171.326556 -410.34081)
			(xy 171.342921 -410.369159) (xy 171.368724 -410.429319) (xy 171.386214 -410.492398) (xy 171.395074 -410.557255)
			(xy 171.395644 -410.589984) (xy 171.395088 -410.622705) (xy 174.824985 -410.622705) (xy 174.824987 -410.557267)
			(xy 174.833773 -410.492422) (xy 174.851182 -410.429343) (xy 174.876901 -410.369171) (xy 174.893224 -410.34081)
			(xy 174.896537 -410.334785) (xy 174.900143 -410.321521) (xy 174.900336 -410.314648) (xy 174.900336 -409.565348)
			(xy 174.900121 -409.558476) (xy 174.896528 -409.545214) (xy 174.893224 -409.539186) (xy 174.876912 -409.510819)
			(xy 174.851195 -409.450649) (xy 174.833786 -409.387572) (xy 174.825001 -409.322728) (xy 174.825 -409.257292)
			(xy 174.833782 -409.192449) (xy 174.851188 -409.12937) (xy 174.876903 -409.069199) (xy 174.893224 -409.040838)
			(xy 174.896527 -409.034808) (xy 174.90014 -409.021548) (xy 174.900336 -409.014676) (xy 174.900336 -408.728672)
			(xy 174.900699 -408.718512) (xy 174.908511 -408.699752) (xy 174.922926 -408.685428) (xy 174.941735 -408.677736)
			(xy 174.951898 -408.677364) (xy 175.668178 -408.677364) (xy 175.678306 -408.677845) (xy 175.697032 -408.68557)
			(xy 175.711389 -408.699859) (xy 175.719205 -408.718546) (xy 175.71974 -408.728672) (xy 175.71974 -409.014676)
			(xy 175.719936 -409.021549) (xy 175.723541 -409.034812) (xy 175.726852 -409.040838) (xy 175.743185 -409.069194)
			(xy 175.768902 -409.129366) (xy 175.786309 -409.192446) (xy 175.795092 -409.257291) (xy 175.79509 -409.322729)
			(xy 175.786305 -409.387574) (xy 175.768895 -409.450654) (xy 175.752007 -409.490164) (xy 177.023784 -409.490164)
			(xy 177.027775 -409.427997) (xy 177.039684 -409.36685) (xy 177.059313 -409.307729) (xy 177.086342 -409.251603)
			(xy 177.120326 -409.199394) (xy 177.160708 -409.151959) (xy 177.206824 -409.110078) (xy 177.257916 -409.074438)
			(xy 177.313147 -409.045624) (xy 177.371609 -409.02411) (xy 177.432343 -409.010248) (xy 177.49435 -409.004266)
			(xy 177.556613 -409.006262) (xy 177.61811 -409.016205) (xy 177.677831 -409.033929) (xy 177.734794 -409.059146)
			(xy 177.788065 -409.091439) (xy 177.83677 -409.130279) (xy 177.880107 -409.175029) (xy 177.917367 -409.224953)
			(xy 177.947936 -409.279232) (xy 177.9523 -409.290012) (xy 179.223932 -409.290012) (xy 179.227923 -409.227845)
			(xy 179.239832 -409.166698) (xy 179.259461 -409.107577) (xy 179.28649 -409.051451) (xy 179.320474 -408.999242)
			(xy 179.360856 -408.951807) (xy 179.406972 -408.909926) (xy 179.458064 -408.874286) (xy 179.513295 -408.845472)
			(xy 179.571757 -408.823958) (xy 179.632491 -408.810096) (xy 179.694498 -408.804114) (xy 179.756761 -408.80611)
			(xy 179.818258 -408.816053) (xy 179.877979 -408.833777) (xy 179.934942 -408.858994) (xy 179.988213 -408.891287)
			(xy 180.036918 -408.930127) (xy 180.080255 -408.974877) (xy 180.117515 -409.024801) (xy 180.148084 -409.07908)
			(xy 180.171462 -409.136823) (xy 180.187263 -409.197081) (xy 180.195229 -409.258864) (xy 180.195728 -409.290012)
			(xy 180.195229 -409.32116) (xy 180.187263 -409.382943) (xy 180.177397 -409.420568) (xy 186.579 -409.420568)
			(xy 186.583071 -409.364946) (xy 186.595197 -409.310509) (xy 186.61512 -409.258418) (xy 186.642416 -409.209783)
			(xy 186.676502 -409.16564) (xy 186.716651 -409.126931) (xy 186.762009 -409.09448) (xy 186.811609 -409.068979)
			(xy 186.864393 -409.050972) (xy 186.919236 -409.040842) (xy 186.97497 -409.038805) (xy 187.030407 -409.044905)
			(xy 187.084364 -409.059011) (xy 187.135693 -409.080823) (xy 187.183299 -409.109877) (xy 187.226167 -409.145552)
			(xy 187.263384 -409.187089) (xy 187.294157 -409.233602) (xy 187.317829 -409.284099) (xy 187.333897 -409.337506)
			(xy 187.342017 -409.392682) (xy 187.342526 -409.420568) (xy 187.342017 -409.448454) (xy 187.333897 -409.50363)
			(xy 187.317829 -409.557037) (xy 187.294157 -409.607534) (xy 187.263384 -409.654047) (xy 187.226167 -409.695584)
			(xy 187.183299 -409.731259) (xy 187.135693 -409.760313) (xy 187.084364 -409.782125) (xy 187.030407 -409.796231)
			(xy 186.97497 -409.802331) (xy 186.919236 -409.800294) (xy 186.864393 -409.790164) (xy 186.811609 -409.772157)
			(xy 186.762009 -409.746656) (xy 186.716651 -409.714205) (xy 186.676502 -409.675496) (xy 186.642416 -409.631353)
			(xy 186.61512 -409.582718) (xy 186.595197 -409.530627) (xy 186.583071 -409.47619) (xy 186.579 -409.420568)
			(xy 180.177397 -409.420568) (xy 180.171462 -409.443201) (xy 180.148084 -409.500944) (xy 180.117515 -409.555223)
			(xy 180.080255 -409.605147) (xy 180.036918 -409.649897) (xy 179.988213 -409.688737) (xy 179.934942 -409.72103)
			(xy 179.877979 -409.746247) (xy 179.818258 -409.763971) (xy 179.756761 -409.773914) (xy 179.694498 -409.77591)
			(xy 179.632491 -409.769928) (xy 179.571757 -409.756066) (xy 179.513295 -409.734552) (xy 179.458064 -409.705738)
			(xy 179.406972 -409.670098) (xy 179.360856 -409.628217) (xy 179.320474 -409.580782) (xy 179.28649 -409.528573)
			(xy 179.259461 -409.472447) (xy 179.239832 -409.413326) (xy 179.227923 -409.352179) (xy 179.223932 -409.290012)
			(xy 177.9523 -409.290012) (xy 177.971314 -409.336975) (xy 177.987115 -409.397233) (xy 177.995081 -409.459016)
			(xy 177.99558 -409.490164) (xy 177.995081 -409.521312) (xy 177.987115 -409.583095) (xy 177.971314 -409.643353)
			(xy 177.947936 -409.701096) (xy 177.917367 -409.755375) (xy 177.880107 -409.805299) (xy 177.83677 -409.850049)
			(xy 177.788065 -409.888889) (xy 177.774985 -409.896818) (xy 191.732914 -409.896818) (xy 191.736985 -409.841196)
			(xy 191.749111 -409.786759) (xy 191.769034 -409.734668) (xy 191.79633 -409.686033) (xy 191.830416 -409.64189)
			(xy 191.870565 -409.603181) (xy 191.915923 -409.57073) (xy 191.965523 -409.545229) (xy 192.018307 -409.527222)
			(xy 192.07315 -409.517092) (xy 192.128884 -409.515055) (xy 192.184321 -409.521155) (xy 192.238278 -409.535261)
			(xy 192.289607 -409.557073) (xy 192.337213 -409.586127) (xy 192.380081 -409.621802) (xy 192.417298 -409.663339)
			(xy 192.448071 -409.709852) (xy 192.471743 -409.760349) (xy 192.487811 -409.813756) (xy 192.495931 -409.868932)
			(xy 192.49644 -409.896818) (xy 192.495931 -409.924704) (xy 192.487811 -409.97988) (xy 192.471743 -410.033287)
			(xy 192.448071 -410.083784) (xy 192.417298 -410.130297) (xy 192.380081 -410.171834) (xy 192.337213 -410.207509)
			(xy 192.289607 -410.236563) (xy 192.238278 -410.258375) (xy 192.184321 -410.272481) (xy 192.128884 -410.278581)
			(xy 192.07315 -410.276544) (xy 192.018307 -410.266414) (xy 191.965523 -410.248407) (xy 191.915923 -410.222906)
			(xy 191.870565 -410.190455) (xy 191.830416 -410.151746) (xy 191.79633 -410.107603) (xy 191.769034 -410.058968)
			(xy 191.749111 -410.006877) (xy 191.736985 -409.95244) (xy 191.732914 -409.896818) (xy 177.774985 -409.896818)
			(xy 177.734794 -409.921182) (xy 177.677831 -409.946399) (xy 177.61811 -409.964123) (xy 177.556613 -409.974066)
			(xy 177.49435 -409.976062) (xy 177.432343 -409.97008) (xy 177.371609 -409.956218) (xy 177.313147 -409.934704)
			(xy 177.257916 -409.90589) (xy 177.206824 -409.87025) (xy 177.160708 -409.828369) (xy 177.120326 -409.780934)
			(xy 177.086342 -409.728725) (xy 177.059313 -409.672599) (xy 177.039684 -409.613478) (xy 177.027775 -409.552331)
			(xy 177.023784 -409.490164) (xy 175.752007 -409.490164) (xy 175.743175 -409.510825) (xy 175.726852 -409.539186)
			(xy 175.723546 -409.545215) (xy 175.719934 -409.558475) (xy 175.71974 -409.565348) (xy 175.71974 -410.314648)
			(xy 175.719947 -410.32152) (xy 175.723544 -410.334783) (xy 175.726852 -410.34081) (xy 175.743161 -410.369179)
			(xy 175.76888 -410.429348) (xy 175.78629 -410.492425) (xy 175.795076 -410.557268) (xy 175.795076 -410.589984)
			(xy 179.223932 -410.589984) (xy 179.227923 -410.527817) (xy 179.239832 -410.46667) (xy 179.259461 -410.407549)
			(xy 179.28649 -410.351423) (xy 179.320474 -410.299214) (xy 179.360856 -410.251779) (xy 179.406972 -410.209898)
			(xy 179.458064 -410.174258) (xy 179.513295 -410.145444) (xy 179.571757 -410.12393) (xy 179.632491 -410.110068)
			(xy 179.694498 -410.104086) (xy 179.756761 -410.106082) (xy 179.818258 -410.116025) (xy 179.877979 -410.133749)
			(xy 179.934942 -410.158966) (xy 179.988213 -410.191259) (xy 180.036918 -410.230099) (xy 180.080255 -410.274849)
			(xy 180.117515 -410.324773) (xy 180.148084 -410.379052) (xy 180.171462 -410.436795) (xy 180.187263 -410.497053)
			(xy 180.195229 -410.558836) (xy 180.195728 -410.589984) (xy 180.195229 -410.621132) (xy 180.187263 -410.682915)
			(xy 180.171462 -410.743173) (xy 180.148084 -410.800916) (xy 180.117515 -410.855195) (xy 180.080255 -410.905119)
			(xy 180.036918 -410.949869) (xy 179.988213 -410.988709) (xy 179.934942 -411.021002) (xy 179.896455 -411.03804)
			(xy 185.614054 -411.03804) (xy 185.618125 -410.982418) (xy 185.630251 -410.927981) (xy 185.650174 -410.87589)
			(xy 185.67747 -410.827255) (xy 185.711556 -410.783112) (xy 185.751705 -410.744403) (xy 185.797063 -410.711952)
			(xy 185.846663 -410.686451) (xy 185.899447 -410.668444) (xy 185.95429 -410.658314) (xy 186.010024 -410.656277)
			(xy 186.065461 -410.662377) (xy 186.119418 -410.676483) (xy 186.170747 -410.698295) (xy 186.218353 -410.727349)
			(xy 186.261221 -410.763024) (xy 186.298438 -410.804561) (xy 186.329211 -410.851074) (xy 186.351249 -410.898086)
			(xy 188.828678 -410.898086) (xy 188.832749 -410.842464) (xy 188.844875 -410.788027) (xy 188.864798 -410.735936)
			(xy 188.892094 -410.687301) (xy 188.92618 -410.643158) (xy 188.966329 -410.604449) (xy 189.011687 -410.571998)
			(xy 189.061287 -410.546497) (xy 189.114071 -410.52849) (xy 189.168914 -410.51836) (xy 189.224648 -410.516323)
			(xy 189.280085 -410.522423) (xy 189.334042 -410.536529) (xy 189.385371 -410.558341) (xy 189.432977 -410.587395)
			(xy 189.475845 -410.62307) (xy 189.513062 -410.664607) (xy 189.534439 -410.696918) (xy 195.549264 -410.696918)
			(xy 195.553335 -410.641296) (xy 195.565461 -410.586859) (xy 195.585384 -410.534768) (xy 195.61268 -410.486133)
			(xy 195.646766 -410.44199) (xy 195.686915 -410.403281) (xy 195.732273 -410.37083) (xy 195.781873 -410.345329)
			(xy 195.834657 -410.327322) (xy 195.8895 -410.317192) (xy 195.945234 -410.315155) (xy 196.000671 -410.321255)
			(xy 196.054628 -410.335361) (xy 196.105957 -410.357173) (xy 196.153563 -410.386227) (xy 196.196431 -410.421902)
			(xy 196.233648 -410.463439) (xy 196.264421 -410.509952) (xy 196.288093 -410.560449) (xy 196.304161 -410.613856)
			(xy 196.312281 -410.669032) (xy 196.31279 -410.696918) (xy 196.312281 -410.724804) (xy 196.304161 -410.77998)
			(xy 196.288093 -410.833387) (xy 196.264421 -410.883884) (xy 196.233648 -410.930397) (xy 196.196431 -410.971934)
			(xy 196.153563 -411.007609) (xy 196.105957 -411.036663) (xy 196.054628 -411.058475) (xy 196.000671 -411.072581)
			(xy 195.945234 -411.078681) (xy 195.8895 -411.076644) (xy 195.834657 -411.066514) (xy 195.781873 -411.048507)
			(xy 195.732273 -411.023006) (xy 195.686915 -410.990555) (xy 195.646766 -410.951846) (xy 195.61268 -410.907703)
			(xy 195.585384 -410.859068) (xy 195.565461 -410.806977) (xy 195.553335 -410.75254) (xy 195.549264 -410.696918)
			(xy 189.534439 -410.696918) (xy 189.543835 -410.71112) (xy 189.567507 -410.761617) (xy 189.583575 -410.815024)
			(xy 189.591695 -410.8702) (xy 189.592204 -410.898086) (xy 189.591695 -410.925972) (xy 189.583575 -410.981148)
			(xy 189.567507 -411.034555) (xy 189.543835 -411.085052) (xy 189.513062 -411.131565) (xy 189.475845 -411.173102)
			(xy 189.432977 -411.208777) (xy 189.385371 -411.237831) (xy 189.334042 -411.259643) (xy 189.280085 -411.273749)
			(xy 189.224648 -411.279849) (xy 189.168914 -411.277812) (xy 189.114071 -411.267682) (xy 189.061287 -411.249675)
			(xy 189.011687 -411.224174) (xy 188.966329 -411.191723) (xy 188.92618 -411.153014) (xy 188.892094 -411.108871)
			(xy 188.864798 -411.060236) (xy 188.844875 -411.008145) (xy 188.832749 -410.953708) (xy 188.828678 -410.898086)
			(xy 186.351249 -410.898086) (xy 186.352883 -410.901571) (xy 186.368951 -410.954978) (xy 186.377071 -411.010154)
			(xy 186.37758 -411.03804) (xy 186.377071 -411.065926) (xy 186.368951 -411.121102) (xy 186.352883 -411.174509)
			(xy 186.329211 -411.225006) (xy 186.298438 -411.271519) (xy 186.261221 -411.313056) (xy 186.253817 -411.319218)
			(xy 193.336416 -411.319218) (xy 193.340487 -411.263596) (xy 193.352613 -411.209159) (xy 193.372536 -411.157068)
			(xy 193.399832 -411.108433) (xy 193.433918 -411.06429) (xy 193.474067 -411.025581) (xy 193.519425 -410.99313)
			(xy 193.569025 -410.967629) (xy 193.621809 -410.949622) (xy 193.676652 -410.939492) (xy 193.732386 -410.937455)
			(xy 193.787823 -410.943555) (xy 193.84178 -410.957661) (xy 193.893109 -410.979473) (xy 193.940715 -411.008527)
			(xy 193.983583 -411.044202) (xy 194.0208 -411.085739) (xy 194.051573 -411.132252) (xy 194.075245 -411.182749)
			(xy 194.091313 -411.236156) (xy 194.099433 -411.291332) (xy 194.099942 -411.319218) (xy 194.099812 -411.32633)
			(xy 197.241412 -411.32633) (xy 197.245483 -411.270708) (xy 197.257609 -411.216271) (xy 197.277532 -411.16418)
			(xy 197.304828 -411.115545) (xy 197.338914 -411.071402) (xy 197.379063 -411.032693) (xy 197.424421 -411.000242)
			(xy 197.474021 -410.974741) (xy 197.526805 -410.956734) (xy 197.581648 -410.946604) (xy 197.637382 -410.944567)
			(xy 197.692819 -410.950667) (xy 197.746776 -410.964773) (xy 197.798105 -410.986585) (xy 197.845711 -411.015639)
			(xy 197.888579 -411.051314) (xy 197.925796 -411.092851) (xy 197.956569 -411.139364) (xy 197.980241 -411.189861)
			(xy 197.996309 -411.243268) (xy 198.004429 -411.298444) (xy 198.004938 -411.32633) (xy 198.004429 -411.354216)
			(xy 197.996309 -411.409392) (xy 197.980241 -411.462799) (xy 197.956569 -411.513296) (xy 197.925796 -411.559809)
			(xy 197.888579 -411.601346) (xy 197.845711 -411.637021) (xy 197.798105 -411.666075) (xy 197.746776 -411.687887)
			(xy 197.692819 -411.701993) (xy 197.637382 -411.708093) (xy 197.581648 -411.706056) (xy 197.526805 -411.695926)
			(xy 197.474021 -411.677919) (xy 197.424421 -411.652418) (xy 197.379063 -411.619967) (xy 197.338914 -411.581258)
			(xy 197.304828 -411.537115) (xy 197.277532 -411.48848) (xy 197.257609 -411.436389) (xy 197.245483 -411.381952)
			(xy 197.241412 -411.32633) (xy 194.099812 -411.32633) (xy 194.099433 -411.347104) (xy 194.091313 -411.40228)
			(xy 194.075245 -411.455687) (xy 194.051573 -411.506184) (xy 194.0208 -411.552697) (xy 193.983583 -411.594234)
			(xy 193.940715 -411.629909) (xy 193.893109 -411.658963) (xy 193.84178 -411.680775) (xy 193.787823 -411.694881)
			(xy 193.732386 -411.700981) (xy 193.676652 -411.698944) (xy 193.621809 -411.688814) (xy 193.569025 -411.670807)
			(xy 193.519425 -411.645306) (xy 193.474067 -411.612855) (xy 193.433918 -411.574146) (xy 193.399832 -411.530003)
			(xy 193.372536 -411.481368) (xy 193.352613 -411.429277) (xy 193.340487 -411.37484) (xy 193.336416 -411.319218)
			(xy 186.253817 -411.319218) (xy 186.218353 -411.348731) (xy 186.170747 -411.377785) (xy 186.119418 -411.399597)
			(xy 186.065461 -411.413703) (xy 186.010024 -411.419803) (xy 185.95429 -411.417766) (xy 185.899447 -411.407636)
			(xy 185.846663 -411.389629) (xy 185.797063 -411.364128) (xy 185.751705 -411.331677) (xy 185.711556 -411.292968)
			(xy 185.67747 -411.248825) (xy 185.650174 -411.20019) (xy 185.630251 -411.148099) (xy 185.618125 -411.093662)
			(xy 185.614054 -411.03804) (xy 179.896455 -411.03804) (xy 179.877979 -411.046219) (xy 179.818258 -411.063943)
			(xy 179.756761 -411.073886) (xy 179.694498 -411.075882) (xy 179.632491 -411.0699) (xy 179.571757 -411.056038)
			(xy 179.513295 -411.034524) (xy 179.458064 -411.00571) (xy 179.406972 -410.97007) (xy 179.360856 -410.928189)
			(xy 179.320474 -410.880754) (xy 179.28649 -410.828545) (xy 179.259461 -410.772419) (xy 179.239832 -410.713298)
			(xy 179.227923 -410.652151) (xy 179.223932 -410.589984) (xy 175.795076 -410.589984) (xy 175.795077 -410.622704)
			(xy 175.786296 -410.687548) (xy 175.768889 -410.750626) (xy 175.743173 -410.810797) (xy 175.726852 -410.839158)
			(xy 175.723556 -410.845192) (xy 175.719938 -410.858448) (xy 175.71974 -410.86532) (xy 175.71974 -411.151324)
			(xy 175.719299 -411.161475) (xy 175.711503 -411.18022) (xy 175.697113 -411.194541) (xy 175.678331 -411.202247)
			(xy 175.668178 -411.202632) (xy 174.951898 -411.202632) (xy 174.941768 -411.202174) (xy 174.923041 -411.194441)
			(xy 174.908684 -411.180145) (xy 174.90087 -411.161452) (xy 174.900336 -411.151324) (xy 174.900336 -410.86532)
			(xy 174.900132 -410.858448) (xy 174.896531 -410.845185) (xy 174.893224 -410.839158) (xy 174.876889 -410.810804)
			(xy 174.851173 -410.750631) (xy 174.833767 -410.687551) (xy 174.824985 -410.622705) (xy 171.395088 -410.622705)
			(xy 171.395088 -410.622714) (xy 171.386228 -410.687572) (xy 171.368735 -410.750652) (xy 171.342926 -410.81081)
			(xy 171.326556 -410.839158) (xy 171.323261 -410.845192) (xy 171.319642 -410.858448) (xy 171.319444 -410.86532)
			(xy 171.319444 -411.151324) (xy 171.318936 -411.161429) (xy 171.311198 -411.180099) (xy 171.296909 -411.194392)
			(xy 171.278241 -411.202133) (xy 171.268136 -411.202632) (xy 170.551856 -411.202632) (xy 170.541748 -411.202152)
			(xy 170.523075 -411.194405) (xy 170.508783 -411.180108) (xy 170.501044 -411.161432) (xy 170.500548 -411.151324)
			(xy 170.500548 -410.86532) (xy 170.500355 -410.858447) (xy 170.496748 -410.845184) (xy 170.493436 -410.839158)
			(xy 170.477057 -410.810816) (xy 170.451258 -410.750654) (xy 170.433772 -410.687572) (xy 170.424916 -410.622714)
			(xy 170.424348 -410.589984) (xy 166.99499 -410.589984) (xy 166.994991 -410.622704) (xy 166.98621 -410.687548)
			(xy 166.968804 -410.750626) (xy 166.943089 -410.810797) (xy 166.926768 -410.839158) (xy 166.923466 -410.845189)
			(xy 166.919853 -410.858448) (xy 166.919656 -410.86532) (xy 166.919656 -411.151324) (xy 166.919199 -411.161473)
			(xy 166.911406 -411.180215) (xy 166.897021 -411.194535) (xy 166.878245 -411.202244) (xy 166.868094 -411.202632)
			(xy 166.151814 -411.202632) (xy 166.141685 -411.202161) (xy 166.122959 -411.194433) (xy 166.108601 -411.180141)
			(xy 166.100786 -411.161451) (xy 166.100252 -411.151324) (xy 166.100252 -410.86532) (xy 166.100058 -410.858447)
			(xy 166.096452 -410.845184) (xy 166.09314 -410.839158) (xy 166.076804 -410.810804) (xy 166.051088 -410.750631)
			(xy 166.033681 -410.687551) (xy 166.024899 -410.622705) (xy 162.595001 -410.622705) (xy 162.595001 -410.622714)
			(xy 162.586142 -410.687572) (xy 162.56865 -410.750652) (xy 162.542841 -410.81081) (xy 162.526472 -410.839158)
			(xy 162.52317 -410.845189) (xy 162.519557 -410.858448) (xy 162.51936 -410.86532) (xy 162.51936 -411.151324)
			(xy 162.519003 -411.161453) (xy 162.511239 -411.180165) (xy 162.496904 -411.19448) (xy 162.478182 -411.202217)
			(xy 162.468052 -411.202632) (xy 161.751772 -411.202632) (xy 161.741665 -411.202139) (xy 161.722993 -411.194398)
			(xy 161.7087 -411.180104) (xy 161.700961 -411.161431) (xy 161.700464 -411.151324) (xy 161.700464 -410.86532)
			(xy 161.700269 -410.858447) (xy 161.696663 -410.845184) (xy 161.693352 -410.839158) (xy 161.676975 -410.810815)
			(xy 161.651175 -410.750654) (xy 161.633688 -410.687572) (xy 161.624832 -410.622714) (xy 161.624264 -410.589984)
			(xy 154.57678 -410.589984) (xy 154.57678 -412.090108) (xy 159.42387 -412.090108) (xy 159.427861 -412.027941)
			(xy 159.43977 -411.966794) (xy 159.459399 -411.907673) (xy 159.486428 -411.851547) (xy 159.520412 -411.799338)
			(xy 159.560794 -411.751903) (xy 159.60691 -411.710022) (xy 159.658002 -411.674382) (xy 159.713233 -411.645568)
			(xy 159.771695 -411.624054) (xy 159.832429 -411.610192) (xy 159.894436 -411.60421) (xy 159.956699 -411.606206)
			(xy 160.018196 -411.616149) (xy 160.077917 -411.633873) (xy 160.13488 -411.65909) (xy 160.188151 -411.691383)
			(xy 160.236856 -411.730223) (xy 160.280193 -411.774973) (xy 160.317453 -411.824897) (xy 160.348022 -411.879176)
			(xy 160.3714 -411.936919) (xy 160.387201 -411.997177) (xy 160.395167 -412.05896) (xy 160.395666 -412.090108)
			(xy 163.823912 -412.090108) (xy 163.827903 -412.027941) (xy 163.839812 -411.966794) (xy 163.859441 -411.907673)
			(xy 163.88647 -411.851547) (xy 163.920454 -411.799338) (xy 163.960836 -411.751903) (xy 164.006952 -411.710022)
			(xy 164.058044 -411.674382) (xy 164.113275 -411.645568) (xy 164.171737 -411.624054) (xy 164.232471 -411.610192)
			(xy 164.294478 -411.60421) (xy 164.356741 -411.606206) (xy 164.418238 -411.616149) (xy 164.477959 -411.633873)
			(xy 164.534922 -411.65909) (xy 164.588193 -411.691383) (xy 164.636898 -411.730223) (xy 164.680235 -411.774973)
			(xy 164.717495 -411.824897) (xy 164.748064 -411.879176) (xy 164.771442 -411.936919) (xy 164.787243 -411.997177)
			(xy 164.795209 -412.05896) (xy 164.795708 -412.090108) (xy 168.223954 -412.090108) (xy 168.227945 -412.027941)
			(xy 168.239854 -411.966794) (xy 168.259483 -411.907673) (xy 168.286512 -411.851547) (xy 168.320496 -411.799338)
			(xy 168.360878 -411.751903) (xy 168.406994 -411.710022) (xy 168.458086 -411.674382) (xy 168.513317 -411.645568)
			(xy 168.571779 -411.624054) (xy 168.632513 -411.610192) (xy 168.69452 -411.60421) (xy 168.756783 -411.606206)
			(xy 168.81828 -411.616149) (xy 168.878001 -411.633873) (xy 168.934964 -411.65909) (xy 168.988235 -411.691383)
			(xy 169.03694 -411.730223) (xy 169.080277 -411.774973) (xy 169.117537 -411.824897) (xy 169.148106 -411.879176)
			(xy 169.171484 -411.936919) (xy 169.187285 -411.997177) (xy 169.195251 -412.05896) (xy 169.19575 -412.090108)
			(xy 172.623742 -412.090108) (xy 172.627733 -412.027941) (xy 172.639642 -411.966794) (xy 172.659271 -411.907673)
			(xy 172.6863 -411.851547) (xy 172.720284 -411.799338) (xy 172.760666 -411.751903) (xy 172.806782 -411.710022)
			(xy 172.857874 -411.674382) (xy 172.913105 -411.645568) (xy 172.971567 -411.624054) (xy 173.032301 -411.610192)
			(xy 173.094308 -411.60421) (xy 173.156571 -411.606206) (xy 173.218068 -411.616149) (xy 173.277789 -411.633873)
			(xy 173.334752 -411.65909) (xy 173.388023 -411.691383) (xy 173.436728 -411.730223) (xy 173.480065 -411.774973)
			(xy 173.517325 -411.824897) (xy 173.547894 -411.879176) (xy 173.571272 -411.936919) (xy 173.587073 -411.997177)
			(xy 173.595039 -412.05896) (xy 173.595538 -412.090108) (xy 177.023784 -412.090108) (xy 177.027775 -412.027941)
			(xy 177.039684 -411.966794) (xy 177.059313 -411.907673) (xy 177.086342 -411.851547) (xy 177.120326 -411.799338)
			(xy 177.160708 -411.751903) (xy 177.206824 -411.710022) (xy 177.257916 -411.674382) (xy 177.313147 -411.645568)
			(xy 177.371609 -411.624054) (xy 177.432343 -411.610192) (xy 177.49435 -411.60421) (xy 177.556613 -411.606206)
			(xy 177.61811 -411.616149) (xy 177.677831 -411.633873) (xy 177.734794 -411.65909) (xy 177.788065 -411.691383)
			(xy 177.83677 -411.730223) (xy 177.880107 -411.774973) (xy 177.917367 -411.824897) (xy 177.947936 -411.879176)
			(xy 177.971314 -411.936919) (xy 177.985708 -411.99181) (xy 188.011052 -411.99181) (xy 188.015123 -411.936188)
			(xy 188.027249 -411.881751) (xy 188.047172 -411.82966) (xy 188.074468 -411.781025) (xy 188.108554 -411.736882)
			(xy 188.148703 -411.698173) (xy 188.194061 -411.665722) (xy 188.243661 -411.640221) (xy 188.296445 -411.622214)
			(xy 188.351288 -411.612084) (xy 188.407022 -411.610047) (xy 188.462459 -411.616147) (xy 188.516416 -411.630253)
			(xy 188.567745 -411.652065) (xy 188.615351 -411.681119) (xy 188.658219 -411.716794) (xy 188.695436 -411.758331)
			(xy 188.726209 -411.804844) (xy 188.749881 -411.855341) (xy 188.765949 -411.908748) (xy 188.774069 -411.963924)
			(xy 188.774578 -411.99181) (xy 188.774069 -412.019696) (xy 188.765949 -412.074872) (xy 188.749881 -412.128279)
			(xy 188.726209 -412.178776) (xy 188.695436 -412.225289) (xy 188.658219 -412.266826) (xy 188.615351 -412.302501)
			(xy 188.567745 -412.331555) (xy 188.516416 -412.353367) (xy 188.462459 -412.367473) (xy 188.407022 -412.373573)
			(xy 188.351288 -412.371536) (xy 188.296445 -412.361406) (xy 188.243661 -412.343399) (xy 188.194061 -412.317898)
			(xy 188.148703 -412.285447) (xy 188.108554 -412.246738) (xy 188.074468 -412.202595) (xy 188.047172 -412.15396)
			(xy 188.027249 -412.101869) (xy 188.015123 -412.047432) (xy 188.011052 -411.99181) (xy 177.985708 -411.99181)
			(xy 177.987115 -411.997177) (xy 177.995081 -412.05896) (xy 177.99558 -412.090108) (xy 177.995081 -412.121256)
			(xy 177.987115 -412.183039) (xy 177.971314 -412.243297) (xy 177.947936 -412.30104) (xy 177.917367 -412.355319)
			(xy 177.880107 -412.405243) (xy 177.83677 -412.449993) (xy 177.788065 -412.488833) (xy 177.734794 -412.521126)
			(xy 177.677831 -412.546343) (xy 177.61811 -412.564067) (xy 177.556613 -412.57401) (xy 177.49435 -412.576006)
			(xy 177.432343 -412.570024) (xy 177.371609 -412.556162) (xy 177.313147 -412.534648) (xy 177.257916 -412.505834)
			(xy 177.206824 -412.470194) (xy 177.160708 -412.428313) (xy 177.120326 -412.380878) (xy 177.086342 -412.328669)
			(xy 177.059313 -412.272543) (xy 177.039684 -412.213422) (xy 177.027775 -412.152275) (xy 177.023784 -412.090108)
			(xy 173.595538 -412.090108) (xy 173.595039 -412.121256) (xy 173.587073 -412.183039) (xy 173.571272 -412.243297)
			(xy 173.547894 -412.30104) (xy 173.517325 -412.355319) (xy 173.480065 -412.405243) (xy 173.436728 -412.449993)
			(xy 173.388023 -412.488833) (xy 173.334752 -412.521126) (xy 173.277789 -412.546343) (xy 173.218068 -412.564067)
			(xy 173.156571 -412.57401) (xy 173.094308 -412.576006) (xy 173.032301 -412.570024) (xy 172.971567 -412.556162)
			(xy 172.913105 -412.534648) (xy 172.857874 -412.505834) (xy 172.806782 -412.470194) (xy 172.760666 -412.428313)
			(xy 172.720284 -412.380878) (xy 172.6863 -412.328669) (xy 172.659271 -412.272543) (xy 172.639642 -412.213422)
			(xy 172.627733 -412.152275) (xy 172.623742 -412.090108) (xy 169.19575 -412.090108) (xy 169.195251 -412.121256)
			(xy 169.187285 -412.183039) (xy 169.171484 -412.243297) (xy 169.148106 -412.30104) (xy 169.117537 -412.355319)
			(xy 169.080277 -412.405243) (xy 169.03694 -412.449993) (xy 168.988235 -412.488833) (xy 168.934964 -412.521126)
			(xy 168.878001 -412.546343) (xy 168.81828 -412.564067) (xy 168.756783 -412.57401) (xy 168.69452 -412.576006)
			(xy 168.632513 -412.570024) (xy 168.571779 -412.556162) (xy 168.513317 -412.534648) (xy 168.458086 -412.505834)
			(xy 168.406994 -412.470194) (xy 168.360878 -412.428313) (xy 168.320496 -412.380878) (xy 168.286512 -412.328669)
			(xy 168.259483 -412.272543) (xy 168.239854 -412.213422) (xy 168.227945 -412.152275) (xy 168.223954 -412.090108)
			(xy 164.795708 -412.090108) (xy 164.795209 -412.121256) (xy 164.787243 -412.183039) (xy 164.771442 -412.243297)
			(xy 164.748064 -412.30104) (xy 164.717495 -412.355319) (xy 164.680235 -412.405243) (xy 164.636898 -412.449993)
			(xy 164.588193 -412.488833) (xy 164.534922 -412.521126) (xy 164.477959 -412.546343) (xy 164.418238 -412.564067)
			(xy 164.356741 -412.57401) (xy 164.294478 -412.576006) (xy 164.232471 -412.570024) (xy 164.171737 -412.556162)
			(xy 164.113275 -412.534648) (xy 164.058044 -412.505834) (xy 164.006952 -412.470194) (xy 163.960836 -412.428313)
			(xy 163.920454 -412.380878) (xy 163.88647 -412.328669) (xy 163.859441 -412.272543) (xy 163.839812 -412.213422)
			(xy 163.827903 -412.152275) (xy 163.823912 -412.090108) (xy 160.395666 -412.090108) (xy 160.395167 -412.121256)
			(xy 160.387201 -412.183039) (xy 160.3714 -412.243297) (xy 160.348022 -412.30104) (xy 160.317453 -412.355319)
			(xy 160.280193 -412.405243) (xy 160.236856 -412.449993) (xy 160.188151 -412.488833) (xy 160.13488 -412.521126)
			(xy 160.077917 -412.546343) (xy 160.018196 -412.564067) (xy 159.956699 -412.57401) (xy 159.894436 -412.576006)
			(xy 159.832429 -412.570024) (xy 159.771695 -412.556162) (xy 159.713233 -412.534648) (xy 159.658002 -412.505834)
			(xy 159.60691 -412.470194) (xy 159.560794 -412.428313) (xy 159.520412 -412.380878) (xy 159.486428 -412.328669)
			(xy 159.459399 -412.272543) (xy 159.43977 -412.213422) (xy 159.427861 -412.152275) (xy 159.42387 -412.090108)
			(xy 154.57678 -412.090108) (xy 154.57678 -412.79191) (xy 184.936382 -412.79191) (xy 184.940453 -412.736288)
			(xy 184.952579 -412.681851) (xy 184.972502 -412.62976) (xy 184.999798 -412.581125) (xy 185.033884 -412.536982)
			(xy 185.074033 -412.498273) (xy 185.119391 -412.465822) (xy 185.168991 -412.440321) (xy 185.221775 -412.422314)
			(xy 185.276618 -412.412184) (xy 185.332352 -412.410147) (xy 185.387789 -412.416247) (xy 185.441746 -412.430353)
			(xy 185.493075 -412.452165) (xy 185.540681 -412.481219) (xy 185.583549 -412.516894) (xy 185.620766 -412.558431)
			(xy 185.651539 -412.604944) (xy 185.675211 -412.655441) (xy 185.691279 -412.708848) (xy 185.699399 -412.764024)
			(xy 185.699908 -412.79191) (xy 185.699399 -412.819796) (xy 185.691279 -412.874972) (xy 185.675211 -412.928379)
			(xy 185.651539 -412.978876) (xy 185.620766 -413.025389) (xy 185.583549 -413.066926) (xy 185.540681 -413.102601)
			(xy 185.493075 -413.131655) (xy 185.441746 -413.153467) (xy 185.387789 -413.167573) (xy 185.332352 -413.173673)
			(xy 185.276618 -413.171636) (xy 185.221775 -413.161506) (xy 185.168991 -413.143499) (xy 185.119391 -413.117998)
			(xy 185.074033 -413.085547) (xy 185.033884 -413.046838) (xy 184.999798 -413.002695) (xy 184.972502 -412.95406)
			(xy 184.952579 -412.901969) (xy 184.940453 -412.847532) (xy 184.936382 -412.79191) (xy 154.57678 -412.79191)
			(xy 154.57678 -413.479234) (xy 188.424056 -413.479234) (xy 188.428127 -413.423612) (xy 188.440253 -413.369175)
			(xy 188.460176 -413.317084) (xy 188.487472 -413.268449) (xy 188.521558 -413.224306) (xy 188.561707 -413.185597)
			(xy 188.607065 -413.153146) (xy 188.656665 -413.127645) (xy 188.709449 -413.109638) (xy 188.764292 -413.099508)
			(xy 188.820026 -413.097471) (xy 188.875463 -413.103571) (xy 188.92942 -413.117677) (xy 188.980749 -413.139489)
			(xy 189.028355 -413.168543) (xy 189.071223 -413.204218) (xy 189.10844 -413.245755) (xy 189.139213 -413.292268)
			(xy 189.162885 -413.342765) (xy 189.169325 -413.364172) (xy 197.320914 -413.364172) (xy 197.324985 -413.30855)
			(xy 197.337111 -413.254113) (xy 197.357034 -413.202022) (xy 197.38433 -413.153387) (xy 197.418416 -413.109244)
			(xy 197.458565 -413.070535) (xy 197.503923 -413.038084) (xy 197.553523 -413.012583) (xy 197.606307 -412.994576)
			(xy 197.66115 -412.984446) (xy 197.716884 -412.982409) (xy 197.772321 -412.988509) (xy 197.826278 -413.002615)
			(xy 197.877607 -413.024427) (xy 197.925213 -413.053481) (xy 197.968081 -413.089156) (xy 198.005298 -413.130693)
			(xy 198.036071 -413.177206) (xy 198.059743 -413.227703) (xy 198.075811 -413.28111) (xy 198.083931 -413.336286)
			(xy 198.08444 -413.364172) (xy 198.083931 -413.392058) (xy 198.075811 -413.447234) (xy 198.059743 -413.500641)
			(xy 198.036071 -413.551138) (xy 198.005298 -413.597651) (xy 197.968081 -413.639188) (xy 197.925213 -413.674863)
			(xy 197.877607 -413.703917) (xy 197.826278 -413.725729) (xy 197.772321 -413.739835) (xy 197.716884 -413.745935)
			(xy 197.66115 -413.743898) (xy 197.606307 -413.733768) (xy 197.553523 -413.715761) (xy 197.503923 -413.69026)
			(xy 197.458565 -413.657809) (xy 197.418416 -413.6191) (xy 197.38433 -413.574957) (xy 197.357034 -413.526322)
			(xy 197.337111 -413.474231) (xy 197.324985 -413.419794) (xy 197.320914 -413.364172) (xy 189.169325 -413.364172)
			(xy 189.178953 -413.396172) (xy 189.187073 -413.451348) (xy 189.187582 -413.479234) (xy 189.187073 -413.50712)
			(xy 189.178953 -413.562296) (xy 189.162885 -413.615703) (xy 189.139213 -413.6662) (xy 189.10844 -413.712713)
			(xy 189.071223 -413.75425) (xy 189.028355 -413.789925) (xy 188.980749 -413.818979) (xy 188.92942 -413.840791)
			(xy 188.875463 -413.854897) (xy 188.820026 -413.860997) (xy 188.764292 -413.85896) (xy 188.709449 -413.84883)
			(xy 188.656665 -413.830823) (xy 188.607065 -413.805322) (xy 188.561707 -413.772871) (xy 188.521558 -413.734162)
			(xy 188.487472 -413.690019) (xy 188.460176 -413.641384) (xy 188.440253 -413.589293) (xy 188.428127 -413.534856)
			(xy 188.424056 -413.479234) (xy 154.57678 -413.479234) (xy 154.57678 -415.15919) (xy 187.152532 -415.15919)
			(xy 187.156603 -415.103568) (xy 187.168729 -415.049131) (xy 187.188652 -414.99704) (xy 187.215948 -414.948405)
			(xy 187.250034 -414.904262) (xy 187.290183 -414.865553) (xy 187.335541 -414.833102) (xy 187.385141 -414.807601)
			(xy 187.437925 -414.789594) (xy 187.492768 -414.779464) (xy 187.548502 -414.777427) (xy 187.603939 -414.783527)
			(xy 187.657896 -414.797633) (xy 187.709225 -414.819445) (xy 187.756831 -414.848499) (xy 187.799699 -414.884174)
			(xy 187.836916 -414.925711) (xy 187.867689 -414.972224) (xy 187.891361 -415.022721) (xy 187.907429 -415.076128)
			(xy 187.915549 -415.131304) (xy 187.916058 -415.15919) (xy 187.915549 -415.187076) (xy 187.907429 -415.242252)
			(xy 187.891361 -415.295659) (xy 187.867689 -415.346156) (xy 187.836916 -415.392669) (xy 187.799699 -415.434206)
			(xy 187.756831 -415.469881) (xy 187.709225 -415.498935) (xy 187.657896 -415.520747) (xy 187.603939 -415.534853)
			(xy 187.548502 -415.540953) (xy 187.492768 -415.538916) (xy 187.437925 -415.528786) (xy 187.385141 -415.510779)
			(xy 187.335541 -415.485278) (xy 187.290183 -415.452827) (xy 187.250034 -415.414118) (xy 187.215948 -415.369975)
			(xy 187.188652 -415.32134) (xy 187.168729 -415.269249) (xy 187.156603 -415.214812) (xy 187.152532 -415.15919)
			(xy 154.57678 -415.15919) (xy 154.57678 -416.179508) (xy 154.578571 -416.188304) (xy 154.587381 -416.20393)
			(xy 154.601029 -416.215571) (xy 154.61785 -416.221805) (xy 154.626818 -416.22218) (xy 201.024998 -416.22218)
			(xy 201.03338 -416.221418) (xy 201.040987 -416.219907) (xy 201.054826 -416.212925) (xy 201.060558 -416.207702)
			(xy 201.403204 -415.865056) (xy 201.4106 -415.858204) (xy 201.429199 -415.850462) (xy 201.439272 -415.85007)
			(xy 272.926048 -415.85007) (xy 272.936114 -415.849637) (xy 272.954703 -415.841907) (xy 272.962116 -415.835084)
			(xy 273.521424 -415.275776) (xy 273.528275 -415.26838) (xy 273.536013 -415.249781) (xy 273.53641 -415.239708)
			(xy 273.53641 -403.817582) (xy 273.536837 -403.807513) (xy 273.544557 -403.788915) (xy 273.551396 -403.781514)
			(xy 274.740624 -402.592286) (xy 274.747476 -402.58489) (xy 274.755218 -402.566291) (xy 274.75561 -402.556218)
			(xy 274.75561 -399.413222) (xy 274.755173 -399.403158) (xy 274.74744 -399.384573) (xy 274.740624 -399.377154)
			(xy 274.048982 -398.685512) (xy 274.041583 -398.678667) (xy 274.022985 -398.670937) (xy 274.012914 -398.670526)
			(xy 266.4968 -398.670526) (xy 266.486729 -398.670104) (xy 266.468122 -398.662392) (xy 266.460732 -398.65554)
			(xy 265.274806 -397.469614) (xy 265.270742 -397.46682) (xy 265.186041 -397.409411) (xy 265.020651 -397.288889)
			(xy 264.860076 -397.162024) (xy 264.704558 -397.029008) (xy 264.554332 -396.890042) (xy 264.409628 -396.745336)
			(xy 264.270663 -396.595109) (xy 264.137647 -396.43959) (xy 264.010784 -396.279014) (xy 263.890263 -396.113623)
			(xy 263.832848 -396.028926) (xy 263.830054 -396.024862) (xy 260.191504 -392.386312) (xy 260.184106 -392.379463)
			(xy 260.165508 -392.371726) (xy 260.155436 -392.371326) (xy 254.98552 -392.371326) (xy 254.975457 -392.371764)
			(xy 254.956876 -392.379502) (xy 254.949452 -392.386312) (xy 254.616204 -392.71956) (xy 254.609366 -392.726962)
			(xy 254.601653 -392.74556) (xy 254.601218 -392.755628) (xy 254.601218 -398.518888) (xy 254.600798 -398.52896)
			(xy 254.593088 -398.547569) (xy 254.586232 -398.554956) (xy 253.68504 -399.456148) (xy 253.677641 -399.462991)
			(xy 253.659042 -399.470711) (xy 253.648972 -399.471134) (xy 245.714774 -399.471134) (xy 245.704707 -399.471563)
			(xy 245.686112 -399.479287) (xy 245.678706 -399.48612) (xy 244.936518 -400.228308) (xy 244.929671 -400.235706)
			(xy 244.921937 -400.254304) (xy 244.921532 -400.264376) (xy 244.921532 -401.226274) (xy 244.921028 -401.236325)
			(xy 244.913308 -401.254888) (xy 244.906546 -401.262342) (xy 243.977414 -402.191474) (xy 243.970012 -402.19831)
			(xy 243.951414 -402.206017) (xy 243.941346 -402.20646) (xy 239.48898 -402.20646) (xy 239.478913 -402.206888)
			(xy 239.460319 -402.214615) (xy 239.452912 -402.221446) (xy 238.291878 -403.38248) (xy 238.285036 -403.389879)
			(xy 238.277318 -403.408478) (xy 238.276892 -403.418548) (xy 238.276892 -412.823406) (xy 238.276467 -412.833476)
			(xy 238.268751 -412.852078) (xy 238.261906 -412.859474) (xy 236.70514 -414.41624) (xy 236.697741 -414.423084)
			(xy 236.679142 -414.430806) (xy 236.669072 -414.431226) (xy 207.66532 -414.431226) (xy 207.655269 -414.43072)
			(xy 207.636709 -414.422999) (xy 207.629252 -414.41624) (xy 206.110586 -412.897574) (xy 206.103734 -412.890178)
			(xy 206.095996 -412.871579) (xy 206.0956 -412.861506) (xy 206.0956 -390.349486) (xy 206.095174 -390.339417)
			(xy 206.087456 -390.320816) (xy 206.080614 -390.313418) (xy 203.817982 -388.050786) (xy 203.811129 -388.043391)
			(xy 203.803387 -388.024792) (xy 203.802996 -388.014718) (xy 203.802996 -378.09805) (xy 203.8029 -378.093173)
			(xy 203.80111 -378.083584) (xy 203.79944 -378.079) (xy 203.79563 -378.069856) (xy 202.692 -376.96648)
			(xy 202.674542 -376.948295) (xy 202.644933 -376.907498) (xy 202.622053 -376.862581) (xy 202.606462 -376.814644)
			(xy 202.598541 -376.764862) (xy 202.59802 -376.739658) (xy 202.59802 -376.620024) (xy 202.597584 -376.609959)
			(xy 202.589852 -376.591373) (xy 202.583034 -376.583956) (xy 195.856352 -369.857274) (xy 195.84924 -369.856766)
			(xy 189.411356 -369.856766) (xy 189.40469 -369.856966) (xy 189.391821 -369.860449) (xy 189.385956 -369.863624)
			(xy 189.380622 -369.866672) (xy 189.377066 -369.868196) (xy 189.372614 -369.869867) (xy 189.363278 -369.871664)
			(xy 189.358524 -369.871752) (xy 179.303172 -369.871752) (xy 179.298294 -369.871846) (xy 179.288703 -369.873631)
			(xy 179.284122 -369.875308) (xy 179.274978 -369.879118) (xy 178.68773 -370.466366) (xy 178.685023 -370.469216)
			(xy 178.680426 -370.475593) (xy 178.678586 -370.479066) (xy 178.676006 -370.484494) (xy 178.673188 -370.496173)
			(xy 178.672998 -370.50218) (xy 178.672998 -370.529358) (xy 189.975488 -370.529358) (xy 189.979559 -370.473736)
			(xy 189.991685 -370.419299) (xy 190.011608 -370.367208) (xy 190.038904 -370.318573) (xy 190.07299 -370.27443)
			(xy 190.113139 -370.235721) (xy 190.158497 -370.20327) (xy 190.208097 -370.177769) (xy 190.260881 -370.159762)
			(xy 190.315724 -370.149632) (xy 190.371458 -370.147595) (xy 190.426895 -370.153695) (xy 190.480852 -370.167801)
			(xy 190.532181 -370.189613) (xy 190.579787 -370.218667) (xy 190.622655 -370.254342) (xy 190.659872 -370.295879)
			(xy 190.690645 -370.342392) (xy 190.714317 -370.392889) (xy 190.730385 -370.446296) (xy 190.738505 -370.501472)
			(xy 190.739014 -370.529358) (xy 190.738505 -370.557244) (xy 190.730385 -370.61242) (xy 190.714317 -370.665827)
			(xy 190.690645 -370.716324) (xy 190.659872 -370.762837) (xy 190.622655 -370.804374) (xy 190.579787 -370.840049)
			(xy 190.532181 -370.869103) (xy 190.480852 -370.890915) (xy 190.426895 -370.905021) (xy 190.371458 -370.911121)
			(xy 190.315724 -370.909084) (xy 190.260881 -370.898954) (xy 190.208097 -370.880947) (xy 190.158497 -370.855446)
			(xy 190.113139 -370.822995) (xy 190.07299 -370.784286) (xy 190.038904 -370.740143) (xy 190.011608 -370.691508)
			(xy 189.991685 -370.639417) (xy 189.979559 -370.58498) (xy 189.975488 -370.529358) (xy 178.672998 -370.529358)
			(xy 178.672998 -371.590062) (xy 179.223932 -371.590062) (xy 179.227923 -371.527895) (xy 179.239832 -371.466748)
			(xy 179.259461 -371.407627) (xy 179.28649 -371.351501) (xy 179.320474 -371.299292) (xy 179.360856 -371.251857)
			(xy 179.406972 -371.209976) (xy 179.458064 -371.174336) (xy 179.513295 -371.145522) (xy 179.571757 -371.124008)
			(xy 179.632491 -371.110146) (xy 179.694498 -371.104164) (xy 179.756761 -371.10616) (xy 179.818258 -371.116103)
			(xy 179.877979 -371.133827) (xy 179.934942 -371.159044) (xy 179.988213 -371.191337) (xy 180.036918 -371.230177)
			(xy 180.080255 -371.274927) (xy 180.117515 -371.324851) (xy 180.148084 -371.37913) (xy 180.171462 -371.436873)
			(xy 180.187263 -371.497131) (xy 180.195229 -371.558914) (xy 180.195728 -371.590062) (xy 180.195229 -371.62121)
			(xy 180.187263 -371.682993) (xy 180.171462 -371.743251) (xy 180.148084 -371.800994) (xy 180.117515 -371.855273)
			(xy 180.080255 -371.905197) (xy 180.036918 -371.949947) (xy 179.988213 -371.988787) (xy 179.934942 -372.02108)
			(xy 179.877979 -372.046297) (xy 179.818258 -372.064021) (xy 179.756761 -372.073964) (xy 179.694498 -372.07596)
			(xy 179.632491 -372.069978) (xy 179.571757 -372.056116) (xy 179.513295 -372.034602) (xy 179.458064 -372.005788)
			(xy 179.406972 -371.970148) (xy 179.360856 -371.928267) (xy 179.320474 -371.880832) (xy 179.28649 -371.828623)
			(xy 179.259461 -371.772497) (xy 179.239832 -371.713376) (xy 179.227923 -371.652229) (xy 179.223932 -371.590062)
			(xy 178.672998 -371.590062) (xy 178.672998 -372.890034) (xy 179.223932 -372.890034) (xy 179.227923 -372.827867)
			(xy 179.239832 -372.76672) (xy 179.259461 -372.707599) (xy 179.28649 -372.651473) (xy 179.320474 -372.599264)
			(xy 179.360856 -372.551829) (xy 179.406972 -372.509948) (xy 179.458064 -372.474308) (xy 179.513295 -372.445494)
			(xy 179.571757 -372.42398) (xy 179.632491 -372.410118) (xy 179.694498 -372.404136) (xy 179.756761 -372.406132)
			(xy 179.818258 -372.416075) (xy 179.877979 -372.433799) (xy 179.934942 -372.459016) (xy 179.988213 -372.491309)
			(xy 180.036918 -372.530149) (xy 180.080255 -372.574899) (xy 180.117515 -372.624823) (xy 180.148084 -372.679102)
			(xy 180.171462 -372.736845) (xy 180.187263 -372.797103) (xy 180.195229 -372.858886) (xy 180.195728 -372.890034)
			(xy 180.195229 -372.921182) (xy 180.187263 -372.982965) (xy 180.171462 -373.043223) (xy 180.148084 -373.100966)
			(xy 180.117515 -373.155245) (xy 180.080255 -373.205169) (xy 180.036918 -373.249919) (xy 179.988213 -373.288759)
			(xy 179.934942 -373.321052) (xy 179.877979 -373.346269) (xy 179.818258 -373.363993) (xy 179.756761 -373.373936)
			(xy 179.694498 -373.375932) (xy 179.632491 -373.36995) (xy 179.571757 -373.356088) (xy 179.513295 -373.334574)
			(xy 179.458064 -373.30576) (xy 179.406972 -373.27012) (xy 179.360856 -373.228239) (xy 179.320474 -373.180804)
			(xy 179.28649 -373.128595) (xy 179.259461 -373.072469) (xy 179.239832 -373.013348) (xy 179.227923 -372.952201)
			(xy 179.223932 -372.890034) (xy 178.672998 -372.890034) (xy 178.672998 -375.490232) (xy 179.223932 -375.490232)
			(xy 179.227923 -375.428065) (xy 179.239832 -375.366918) (xy 179.259461 -375.307797) (xy 179.28649 -375.251671)
			(xy 179.320474 -375.199462) (xy 179.360856 -375.152027) (xy 179.406972 -375.110146) (xy 179.458064 -375.074506)
			(xy 179.513295 -375.045692) (xy 179.571757 -375.024178) (xy 179.632491 -375.010316) (xy 179.694498 -375.004334)
			(xy 179.756761 -375.00633) (xy 179.818258 -375.016273) (xy 179.877979 -375.033997) (xy 179.934942 -375.059214)
			(xy 179.988213 -375.091507) (xy 180.036918 -375.130347) (xy 180.080255 -375.175097) (xy 180.117515 -375.225021)
			(xy 180.148084 -375.2793) (xy 180.171462 -375.337043) (xy 180.187263 -375.397301) (xy 180.195229 -375.459084)
			(xy 180.195728 -375.490232) (xy 180.195229 -375.52138) (xy 180.187263 -375.583163) (xy 180.171462 -375.643421)
			(xy 180.148084 -375.701164) (xy 180.117515 -375.755443) (xy 180.080255 -375.805367) (xy 180.036918 -375.850117)
			(xy 179.988213 -375.888957) (xy 179.934942 -375.92125) (xy 179.877979 -375.946467) (xy 179.818258 -375.964191)
			(xy 179.756761 -375.974134) (xy 179.694498 -375.97613) (xy 179.632491 -375.970148) (xy 179.571757 -375.956286)
			(xy 179.513295 -375.934772) (xy 179.458064 -375.905958) (xy 179.406972 -375.870318) (xy 179.360856 -375.828437)
			(xy 179.320474 -375.781002) (xy 179.28649 -375.728793) (xy 179.259461 -375.672667) (xy 179.239832 -375.613546)
			(xy 179.227923 -375.552399) (xy 179.223932 -375.490232) (xy 178.672998 -375.490232) (xy 178.672998 -376.790204)
			(xy 179.223932 -376.790204) (xy 179.227923 -376.728037) (xy 179.239832 -376.66689) (xy 179.259461 -376.607769)
			(xy 179.28649 -376.551643) (xy 179.320474 -376.499434) (xy 179.360856 -376.451999) (xy 179.406972 -376.410118)
			(xy 179.458064 -376.374478) (xy 179.513295 -376.345664) (xy 179.571757 -376.32415) (xy 179.632491 -376.310288)
			(xy 179.694498 -376.304306) (xy 179.756761 -376.306302) (xy 179.818258 -376.316245) (xy 179.877979 -376.333969)
			(xy 179.934942 -376.359186) (xy 179.988213 -376.391479) (xy 180.036918 -376.430319) (xy 180.080255 -376.475069)
			(xy 180.117515 -376.524993) (xy 180.148084 -376.579272) (xy 180.171462 -376.637015) (xy 180.187263 -376.697273)
			(xy 180.195229 -376.759056) (xy 180.195728 -376.790204) (xy 180.195229 -376.821352) (xy 180.187263 -376.883135)
			(xy 180.171462 -376.943393) (xy 180.148084 -377.001136) (xy 180.117515 -377.055415) (xy 180.080255 -377.105339)
			(xy 180.036918 -377.150089) (xy 179.988213 -377.188929) (xy 179.934942 -377.221222) (xy 179.877979 -377.246439)
			(xy 179.818258 -377.264163) (xy 179.756761 -377.274106) (xy 179.694498 -377.276102) (xy 179.632491 -377.27012)
			(xy 179.571757 -377.256258) (xy 179.513295 -377.234744) (xy 179.458064 -377.20593) (xy 179.406972 -377.17029)
			(xy 179.360856 -377.128409) (xy 179.320474 -377.080974) (xy 179.28649 -377.028765) (xy 179.259461 -376.972639)
			(xy 179.239832 -376.913518) (xy 179.227923 -376.852371) (xy 179.223932 -376.790204) (xy 178.672998 -376.790204)
			(xy 178.672998 -378.766811) (xy 193.48983 -378.766811) (xy 193.48983 -378.633249) (xy 193.497894 -378.499931)
			(xy 193.513994 -378.367343) (xy 193.538069 -378.235969) (xy 193.570032 -378.106288) (xy 193.609767 -377.978774)
			(xy 193.657129 -377.853891) (xy 193.711944 -377.732096) (xy 193.774014 -377.613833) (xy 193.84311 -377.499534)
			(xy 193.918982 -377.389614) (xy 194.001352 -377.284477) (xy 194.08992 -377.184504) (xy 194.184362 -377.090062)
			(xy 194.284335 -377.001494) (xy 194.389472 -376.919124) (xy 194.499392 -376.843252) (xy 194.613691 -376.774156)
			(xy 194.731954 -376.712086) (xy 194.853749 -376.657271) (xy 194.978632 -376.609909) (xy 195.106146 -376.570174)
			(xy 195.235827 -376.538211) (xy 195.367201 -376.514136) (xy 195.499789 -376.498036) (xy 195.633107 -376.489972)
			(xy 195.766669 -376.489972) (xy 195.899987 -376.498036) (xy 196.032575 -376.514136) (xy 196.163949 -376.538211)
			(xy 196.29363 -376.570174) (xy 196.421144 -376.609909) (xy 196.546027 -376.657271) (xy 196.667822 -376.712086)
			(xy 196.786085 -376.774156) (xy 196.900384 -376.843252) (xy 197.010304 -376.919124) (xy 197.115441 -377.001494)
			(xy 197.215414 -377.090062) (xy 197.309856 -377.184504) (xy 197.398424 -377.284477) (xy 197.480794 -377.389614)
			(xy 197.556666 -377.499534) (xy 197.625762 -377.613833) (xy 197.687832 -377.732096) (xy 197.742647 -377.853891)
			(xy 197.790009 -377.978774) (xy 197.829744 -378.106288) (xy 197.861707 -378.235969) (xy 197.885782 -378.367343)
			(xy 197.901882 -378.499931) (xy 197.909946 -378.633249) (xy 197.91045 -378.70003) (xy 197.909946 -378.766811)
			(xy 197.901882 -378.900129) (xy 197.885782 -379.032717) (xy 197.861707 -379.164091) (xy 197.829744 -379.293772)
			(xy 197.790009 -379.421286) (xy 197.742647 -379.546169) (xy 197.687832 -379.667964) (xy 197.625762 -379.786227)
			(xy 197.556666 -379.900526) (xy 197.480794 -380.010446) (xy 197.398424 -380.115583) (xy 197.309856 -380.215556)
			(xy 197.215414 -380.309998) (xy 197.115441 -380.398566) (xy 197.010304 -380.480936) (xy 196.900384 -380.556808)
			(xy 196.786085 -380.625904) (xy 196.667822 -380.687974) (xy 196.546027 -380.742789) (xy 196.421144 -380.790151)
			(xy 196.29363 -380.829886) (xy 196.163949 -380.861849) (xy 196.032575 -380.885924) (xy 195.899987 -380.902024)
			(xy 195.766669 -380.910088) (xy 195.633107 -380.910088) (xy 195.499789 -380.902024) (xy 195.367201 -380.885924)
			(xy 195.235827 -380.861849) (xy 195.106146 -380.829886) (xy 194.978632 -380.790151) (xy 194.853749 -380.742789)
			(xy 194.731954 -380.687974) (xy 194.613691 -380.625904) (xy 194.499392 -380.556808) (xy 194.389472 -380.480936)
			(xy 194.284335 -380.398566) (xy 194.184362 -380.309998) (xy 194.08992 -380.215556) (xy 194.001352 -380.115583)
			(xy 193.918982 -380.010446) (xy 193.84311 -379.900526) (xy 193.774014 -379.786227) (xy 193.711944 -379.667964)
			(xy 193.657129 -379.546169) (xy 193.609767 -379.421286) (xy 193.570032 -379.293772) (xy 193.538069 -379.164091)
			(xy 193.513994 -379.032717) (xy 193.497894 -378.900129) (xy 193.48983 -378.766811) (xy 178.672998 -378.766811)
			(xy 178.672998 -379.390148) (xy 179.223932 -379.390148) (xy 179.227923 -379.327981) (xy 179.239832 -379.266834)
			(xy 179.259461 -379.207713) (xy 179.28649 -379.151587) (xy 179.320474 -379.099378) (xy 179.360856 -379.051943)
			(xy 179.406972 -379.010062) (xy 179.458064 -378.974422) (xy 179.513295 -378.945608) (xy 179.571757 -378.924094)
			(xy 179.632491 -378.910232) (xy 179.694498 -378.90425) (xy 179.756761 -378.906246) (xy 179.818258 -378.916189)
			(xy 179.877979 -378.933913) (xy 179.934942 -378.95913) (xy 179.988213 -378.991423) (xy 180.036918 -379.030263)
			(xy 180.080255 -379.075013) (xy 180.117515 -379.124937) (xy 180.148084 -379.179216) (xy 180.171462 -379.236959)
			(xy 180.187263 -379.297217) (xy 180.195229 -379.359) (xy 180.195728 -379.390148) (xy 180.195229 -379.421296)
			(xy 180.187263 -379.483079) (xy 180.171462 -379.543337) (xy 180.148084 -379.60108) (xy 180.117515 -379.655359)
			(xy 180.080255 -379.705283) (xy 180.036918 -379.750033) (xy 179.988213 -379.788873) (xy 179.934942 -379.821166)
			(xy 179.877979 -379.846383) (xy 179.818258 -379.864107) (xy 179.756761 -379.87405) (xy 179.694498 -379.876046)
			(xy 179.632491 -379.870064) (xy 179.571757 -379.856202) (xy 179.513295 -379.834688) (xy 179.458064 -379.805874)
			(xy 179.406972 -379.770234) (xy 179.360856 -379.728353) (xy 179.320474 -379.680918) (xy 179.28649 -379.628709)
			(xy 179.259461 -379.572583) (xy 179.239832 -379.513462) (xy 179.227923 -379.452315) (xy 179.223932 -379.390148)
			(xy 178.672998 -379.390148) (xy 178.672998 -380.69012) (xy 179.223932 -380.69012) (xy 179.227923 -380.627953)
			(xy 179.239832 -380.566806) (xy 179.259461 -380.507685) (xy 179.28649 -380.451559) (xy 179.320474 -380.39935)
			(xy 179.360856 -380.351915) (xy 179.406972 -380.310034) (xy 179.458064 -380.274394) (xy 179.513295 -380.24558)
			(xy 179.571757 -380.224066) (xy 179.632491 -380.210204) (xy 179.694498 -380.204222) (xy 179.756761 -380.206218)
			(xy 179.818258 -380.216161) (xy 179.877979 -380.233885) (xy 179.934942 -380.259102) (xy 179.988213 -380.291395)
			(xy 180.036918 -380.330235) (xy 180.080255 -380.374985) (xy 180.117515 -380.424909) (xy 180.148084 -380.479188)
			(xy 180.171462 -380.536931) (xy 180.187263 -380.597189) (xy 180.195229 -380.658972) (xy 180.195728 -380.69012)
			(xy 180.195229 -380.721268) (xy 180.187263 -380.783051) (xy 180.171462 -380.843309) (xy 180.148084 -380.901052)
			(xy 180.117515 -380.955331) (xy 180.080255 -381.005255) (xy 180.036918 -381.050005) (xy 179.988213 -381.088845)
			(xy 179.934942 -381.121138) (xy 179.877979 -381.146355) (xy 179.818258 -381.164079) (xy 179.756761 -381.174022)
			(xy 179.694498 -381.176018) (xy 179.632491 -381.170036) (xy 179.571757 -381.156174) (xy 179.513295 -381.13466)
			(xy 179.458064 -381.105846) (xy 179.406972 -381.070206) (xy 179.360856 -381.028325) (xy 179.320474 -380.98089)
			(xy 179.28649 -380.928681) (xy 179.259461 -380.872555) (xy 179.239832 -380.813434) (xy 179.227923 -380.752287)
			(xy 179.223932 -380.69012) (xy 178.672998 -380.69012) (xy 178.672998 -383.290064) (xy 179.223932 -383.290064)
			(xy 179.227923 -383.227897) (xy 179.239832 -383.16675) (xy 179.259461 -383.107629) (xy 179.28649 -383.051503)
			(xy 179.320474 -382.999294) (xy 179.360856 -382.951859) (xy 179.406972 -382.909978) (xy 179.458064 -382.874338)
			(xy 179.513295 -382.845524) (xy 179.571757 -382.82401) (xy 179.632491 -382.810148) (xy 179.694498 -382.804166)
			(xy 179.756761 -382.806162) (xy 179.818258 -382.816105) (xy 179.877979 -382.833829) (xy 179.934942 -382.859046)
			(xy 179.988213 -382.891339) (xy 180.036918 -382.930179) (xy 180.080255 -382.974929) (xy 180.117515 -383.024853)
			(xy 180.148084 -383.079132) (xy 180.171462 -383.136875) (xy 180.187263 -383.197133) (xy 180.195229 -383.258916)
			(xy 180.195728 -383.290064) (xy 180.195229 -383.321212) (xy 180.187263 -383.382995) (xy 180.171462 -383.443253)
			(xy 180.148084 -383.500996) (xy 180.117515 -383.555275) (xy 180.080255 -383.605199) (xy 180.036918 -383.649949)
			(xy 179.988213 -383.688789) (xy 179.934942 -383.721082) (xy 179.877979 -383.746299) (xy 179.818258 -383.764023)
			(xy 179.756761 -383.773966) (xy 179.694498 -383.775962) (xy 179.632491 -383.76998) (xy 179.571757 -383.756118)
			(xy 179.513295 -383.734604) (xy 179.458064 -383.70579) (xy 179.406972 -383.67015) (xy 179.360856 -383.628269)
			(xy 179.320474 -383.580834) (xy 179.28649 -383.528625) (xy 179.259461 -383.472499) (xy 179.239832 -383.413378)
			(xy 179.227923 -383.352231) (xy 179.223932 -383.290064) (xy 178.672998 -383.290064) (xy 178.672998 -384.590036)
			(xy 179.223932 -384.590036) (xy 179.227923 -384.527869) (xy 179.239832 -384.466722) (xy 179.259461 -384.407601)
			(xy 179.28649 -384.351475) (xy 179.320474 -384.299266) (xy 179.360856 -384.251831) (xy 179.406972 -384.20995)
			(xy 179.458064 -384.17431) (xy 179.513295 -384.145496) (xy 179.571757 -384.123982) (xy 179.632491 -384.11012)
			(xy 179.694498 -384.104138) (xy 179.756761 -384.106134) (xy 179.818258 -384.116077) (xy 179.877979 -384.133801)
			(xy 179.934942 -384.159018) (xy 179.988213 -384.191311) (xy 180.036918 -384.230151) (xy 180.080255 -384.274901)
			(xy 180.117515 -384.324825) (xy 180.148084 -384.379104) (xy 180.171462 -384.436847) (xy 180.187263 -384.497105)
			(xy 180.195229 -384.558888) (xy 180.195728 -384.590036) (xy 180.195229 -384.621184) (xy 180.187263 -384.682967)
			(xy 180.171462 -384.743225) (xy 180.148084 -384.800968) (xy 180.117515 -384.855247) (xy 180.080255 -384.905171)
			(xy 180.036918 -384.949921) (xy 179.988213 -384.988761) (xy 179.934942 -385.021054) (xy 179.877979 -385.046271)
			(xy 179.818258 -385.063995) (xy 179.756761 -385.073938) (xy 179.694498 -385.075934) (xy 179.632491 -385.069952)
			(xy 179.571757 -385.05609) (xy 179.513295 -385.034576) (xy 179.458064 -385.005762) (xy 179.406972 -384.970122)
			(xy 179.360856 -384.928241) (xy 179.320474 -384.880806) (xy 179.28649 -384.828597) (xy 179.259461 -384.772471)
			(xy 179.239832 -384.71335) (xy 179.227923 -384.652203) (xy 179.223932 -384.590036) (xy 178.672998 -384.590036)
			(xy 178.672998 -387.124702) (xy 187.712602 -387.124702) (xy 187.716673 -387.06908) (xy 187.728799 -387.014643)
			(xy 187.748722 -386.962552) (xy 187.776018 -386.913917) (xy 187.810104 -386.869774) (xy 187.850253 -386.831065)
			(xy 187.895611 -386.798614) (xy 187.945211 -386.773113) (xy 187.997995 -386.755106) (xy 188.052838 -386.744976)
			(xy 188.108572 -386.742939) (xy 188.164009 -386.749039) (xy 188.217966 -386.763145) (xy 188.269295 -386.784957)
			(xy 188.316901 -386.814011) (xy 188.359769 -386.849686) (xy 188.396986 -386.891223) (xy 188.427759 -386.937736)
			(xy 188.451431 -386.988233) (xy 188.467499 -387.04164) (xy 188.475619 -387.096816) (xy 188.476128 -387.124702)
			(xy 188.475619 -387.152588) (xy 188.467499 -387.207764) (xy 188.451431 -387.261171) (xy 188.427759 -387.311668)
			(xy 188.396986 -387.358181) (xy 188.359769 -387.399718) (xy 188.316901 -387.435393) (xy 188.269295 -387.464447)
			(xy 188.217966 -387.486259) (xy 188.164009 -387.500365) (xy 188.108572 -387.506465) (xy 188.052838 -387.504428)
			(xy 187.997995 -387.494298) (xy 187.945211 -387.476291) (xy 187.895611 -387.45079) (xy 187.850253 -387.418339)
			(xy 187.810104 -387.37963) (xy 187.776018 -387.335487) (xy 187.748722 -387.286852) (xy 187.728799 -387.234761)
			(xy 187.716673 -387.180324) (xy 187.712602 -387.124702) (xy 178.672998 -387.124702) (xy 178.672998 -397.59001)
			(xy 179.223932 -397.59001) (xy 179.227923 -397.527843) (xy 179.239832 -397.466696) (xy 179.259461 -397.407575)
			(xy 179.28649 -397.351449) (xy 179.320474 -397.29924) (xy 179.360856 -397.251805) (xy 179.406972 -397.209924)
			(xy 179.458064 -397.174284) (xy 179.513295 -397.14547) (xy 179.571757 -397.123956) (xy 179.632491 -397.110094)
			(xy 179.694498 -397.104112) (xy 179.756761 -397.106108) (xy 179.818258 -397.116051) (xy 179.877979 -397.133775)
			(xy 179.934942 -397.158992) (xy 179.988213 -397.191285) (xy 180.036918 -397.230125) (xy 180.080255 -397.274875)
			(xy 180.117515 -397.324799) (xy 180.148084 -397.379078) (xy 180.171462 -397.436821) (xy 180.187263 -397.497079)
			(xy 180.195229 -397.558862) (xy 180.195728 -397.59001) (xy 180.195229 -397.621158) (xy 180.187263 -397.682941)
			(xy 180.171462 -397.743199) (xy 180.148084 -397.800942) (xy 180.117515 -397.855221) (xy 180.080255 -397.905145)
			(xy 180.036918 -397.949895) (xy 179.988213 -397.988735) (xy 179.934942 -398.021028) (xy 179.877979 -398.046245)
			(xy 179.818258 -398.063969) (xy 179.756761 -398.073912) (xy 179.694498 -398.075908) (xy 179.632491 -398.069926)
			(xy 179.571757 -398.056064) (xy 179.513295 -398.03455) (xy 179.458064 -398.005736) (xy 179.406972 -397.970096)
			(xy 179.360856 -397.928215) (xy 179.320474 -397.88078) (xy 179.28649 -397.828571) (xy 179.259461 -397.772445)
			(xy 179.239832 -397.713324) (xy 179.227923 -397.652177) (xy 179.223932 -397.59001) (xy 178.672998 -397.59001)
			(xy 178.672998 -397.904716) (xy 178.672572 -397.914785) (xy 178.664853 -397.933385) (xy 178.658012 -397.940784)
			(xy 177.72253 -398.876266) (xy 177.715129 -398.883105) (xy 177.697937 -398.890236) (xy 179.223932 -398.890236)
			(xy 179.227923 -398.828069) (xy 179.239832 -398.766922) (xy 179.259461 -398.707801) (xy 179.28649 -398.651675)
			(xy 179.320474 -398.599466) (xy 179.360856 -398.552031) (xy 179.406972 -398.51015) (xy 179.458064 -398.47451)
			(xy 179.513295 -398.445696) (xy 179.571757 -398.424182) (xy 179.632491 -398.41032) (xy 179.694498 -398.404338)
			(xy 179.756761 -398.406334) (xy 179.818258 -398.416277) (xy 179.877979 -398.434001) (xy 179.934942 -398.459218)
			(xy 179.988213 -398.491511) (xy 180.036918 -398.530351) (xy 180.080255 -398.575101) (xy 180.117515 -398.625025)
			(xy 180.148084 -398.679304) (xy 180.171462 -398.737047) (xy 180.187263 -398.797305) (xy 180.195229 -398.859088)
			(xy 180.195728 -398.890236) (xy 180.195229 -398.921384) (xy 180.187263 -398.983167) (xy 180.171462 -399.043425)
			(xy 180.148084 -399.101168) (xy 180.117515 -399.155447) (xy 180.080255 -399.205371) (xy 180.036918 -399.250121)
			(xy 179.988213 -399.288961) (xy 179.934942 -399.321254) (xy 179.877979 -399.346471) (xy 179.818258 -399.364195)
			(xy 179.756761 -399.374138) (xy 179.694498 -399.376134) (xy 179.632491 -399.370152) (xy 179.571757 -399.35629)
			(xy 179.513295 -399.334776) (xy 179.458064 -399.305962) (xy 179.406972 -399.270322) (xy 179.360856 -399.228441)
			(xy 179.320474 -399.181006) (xy 179.28649 -399.128797) (xy 179.259461 -399.072671) (xy 179.239832 -399.01355)
			(xy 179.227923 -398.952403) (xy 179.223932 -398.890236) (xy 177.697937 -398.890236) (xy 177.696531 -398.890819)
			(xy 177.686462 -398.891252) (xy 176.707292 -398.891252) (xy 176.697265 -398.891701) (xy 176.678709 -398.899295)
			(xy 176.671224 -398.905984) (xy 176.491138 -399.08607) (xy 176.459772 -399.116816) (xy 176.392492 -399.173287)
			(xy 176.356772 -399.198846) (xy 176.353216 -399.201386) (xy 176.313084 -399.241518) (xy 176.306404 -399.248929)
			(xy 176.298831 -399.267365) (xy 176.298352 -399.277332) (xy 176.298352 -399.278602) (xy 176.297813 -399.288588)
			(xy 176.290094 -399.307015) (xy 176.283366 -399.314416) (xy 176.104042 -399.49374) (xy 176.10201 -399.49628)
			(xy 176.075025 -399.530794) (xy 176.0159 -399.595454) (xy 175.951319 -399.654666) (xy 175.916844 -399.6817)
			(xy 175.914304 -399.683732) (xy 175.734218 -399.863564) (xy 175.72687 -399.870366) (xy 175.708407 -399.878074)
			(xy 175.698404 -399.87855) (xy 175.443896 -399.87855) (xy 175.440594 -399.879058) (xy 175.408102 -399.88303)
			(xy 175.342771 -399.887221) (xy 175.310038 -399.88744) (xy 175.277305 -399.887226) (xy 175.211974 -399.883033)
			(xy 175.179482 -399.879058) (xy 175.17618 -399.87855) (xy 174.921672 -399.87855) (xy 174.911688 -399.878006)
			(xy 174.893268 -399.87028) (xy 174.885858 -399.863564) (xy 174.85487 -399.832576) (xy 174.850394 -399.82833)
			(xy 174.83987 -399.821899) (xy 174.834042 -399.819876) (xy 174.822612 -399.81632) (xy 174.81042 -399.818352)
			(xy 174.794164 -399.820638) (xy 174.763938 -399.823178) (xy 174.76089 -399.823178) (xy 174.757588 -399.823432)
			(xy 174.745904 -399.823432) (xy 174.718745 -399.822811) (xy 174.665012 -399.814824) (xy 174.612955 -399.799297)
			(xy 174.563627 -399.776544) (xy 174.518025 -399.747023) (xy 174.477071 -399.711333) (xy 174.441593 -399.670195)
			(xy 174.412308 -399.624441) (xy 174.38981 -399.574996) (xy 174.374552 -399.522859) (xy 174.366844 -399.469086)
			(xy 174.366428 -399.441924) (xy 174.366428 -399.4404) (xy 174.366615 -399.425089) (xy 174.369155 -399.394571)
			(xy 174.371508 -399.37944) (xy 174.37354 -399.367248) (xy 174.369984 -399.355818) (xy 174.367973 -399.349983)
			(xy 174.361552 -399.339448) (xy 174.357284 -399.33499) (xy 174.33671 -399.314416) (xy 174.329912 -399.307067)
			(xy 174.322208 -399.288604) (xy 174.321724 -399.278602) (xy 174.321724 -399.024094) (xy 174.321216 -399.020792)
			(xy 174.318647 -399.000544) (xy 174.314962 -398.959892) (xy 174.31385 -398.939512) (xy 174.312834 -398.917668)
			(xy 174.306432 -398.907391) (xy 174.286405 -398.893847) (xy 174.27448 -398.89176) (xy 174.268384 -398.891252)
			(xy 172.30725 -398.891252) (xy 172.297219 -398.891691) (xy 172.278647 -398.89927) (xy 172.271182 -398.905984)
			(xy 172.091096 -399.08607) (xy 172.059785 -399.116743) (xy 171.992631 -399.173087) (xy 171.956984 -399.198592)
			(xy 171.953428 -399.201132) (xy 171.913042 -399.241518) (xy 171.906298 -399.248888) (xy 171.898706 -399.26735)
			(xy 171.89831 -399.277332) (xy 171.89831 -399.278602) (xy 171.897772 -399.288589) (xy 171.890059 -399.307022)
			(xy 171.883324 -399.314416) (xy 171.704 -399.49374) (xy 171.701968 -399.49628) (xy 171.674984 -399.530795)
			(xy 171.615861 -399.595457) (xy 171.551283 -399.654673) (xy 171.516802 -399.6817) (xy 171.514262 -399.683732)
			(xy 171.334176 -399.863564) (xy 171.326831 -399.870375) (xy 171.308368 -399.878104) (xy 171.298362 -399.87855)
			(xy 171.043854 -399.87855) (xy 171.040552 -399.879058) (xy 171.00806 -399.883032) (xy 170.942729 -399.887227)
			(xy 170.909996 -399.88744) (xy 170.877263 -399.887225) (xy 170.811932 -399.883029) (xy 170.77944 -399.879058)
			(xy 170.776138 -399.87855) (xy 170.52163 -399.87855) (xy 170.511641 -399.878017) (xy 170.493206 -399.870305)
			(xy 170.485816 -399.863564) (xy 170.454828 -399.832576) (xy 170.450351 -399.828333) (xy 170.439823 -399.82191)
			(xy 170.434 -399.819876) (xy 170.42257 -399.81632) (xy 170.410378 -399.818352) (xy 170.394122 -399.820638)
			(xy 170.363896 -399.823178) (xy 170.360848 -399.823178) (xy 170.357546 -399.823432) (xy 170.345862 -399.823432)
			(xy 170.318705 -399.822808) (xy 170.264977 -399.814817) (xy 170.212925 -399.799286) (xy 170.163602 -399.77653)
			(xy 170.118005 -399.747008) (xy 170.077056 -399.711319) (xy 170.041582 -399.670182) (xy 170.012302 -399.624429)
			(xy 169.989806 -399.574987) (xy 169.974551 -399.522854) (xy 169.966843 -399.469084) (xy 169.966386 -399.441924)
			(xy 169.966386 -399.4404) (xy 169.966573 -399.425089) (xy 169.969113 -399.394571) (xy 169.971466 -399.37944)
			(xy 169.973498 -399.367248) (xy 169.969942 -399.355818) (xy 169.967929 -399.349984) (xy 169.961504 -399.339453)
			(xy 169.957242 -399.33499) (xy 169.936668 -399.314416) (xy 169.929863 -399.307069) (xy 169.922151 -399.288606)
			(xy 169.921682 -399.278602) (xy 169.921682 -399.024094) (xy 169.921174 -399.020792) (xy 169.918605 -399.000544)
			(xy 169.91492 -398.959892) (xy 169.913808 -398.939512) (xy 169.912792 -398.917668) (xy 169.906387 -398.907397)
			(xy 169.886357 -398.893869) (xy 169.874438 -398.89176) (xy 169.868342 -398.891252) (xy 167.907208 -398.891252)
			(xy 167.89718 -398.891698) (xy 167.87862 -398.899288) (xy 167.87114 -398.905984) (xy 167.691054 -399.08607)
			(xy 167.659742 -399.116742) (xy 167.592587 -399.173083) (xy 167.556942 -399.198592) (xy 167.553386 -399.201132)
			(xy 167.513 -399.241518) (xy 167.506318 -399.248928) (xy 167.498743 -399.267365) (xy 167.498268 -399.277332)
			(xy 167.498268 -399.278602) (xy 167.49773 -399.288589) (xy 167.490012 -399.307017) (xy 167.483282 -399.314416)
			(xy 167.303958 -399.49374) (xy 167.301926 -399.49628) (xy 167.274941 -399.530794) (xy 167.215817 -399.595455)
			(xy 167.151237 -399.654668) (xy 167.11676 -399.6817) (xy 167.11422 -399.683732) (xy 166.934134 -399.863564)
			(xy 166.926787 -399.870368) (xy 166.908324 -399.878082) (xy 166.89832 -399.87855) (xy 166.643812 -399.87855)
			(xy 166.64051 -399.879058) (xy 166.608018 -399.88303) (xy 166.542687 -399.887223) (xy 166.509954 -399.88744)
			(xy 166.477221 -399.887227) (xy 166.411889 -399.883035) (xy 166.379398 -399.879058) (xy 166.376096 -399.87855)
			(xy 166.121588 -399.87855) (xy 166.111603 -399.878009) (xy 166.093178 -399.870287) (xy 166.085774 -399.863564)
			(xy 166.054786 -399.832576) (xy 166.050307 -399.828336) (xy 166.039777 -399.821922) (xy 166.033958 -399.819876)
			(xy 166.022528 -399.81632) (xy 166.010336 -399.818352) (xy 165.99408 -399.820638) (xy 165.963854 -399.823178)
			(xy 165.960806 -399.823178) (xy 165.957504 -399.823432) (xy 165.94582 -399.823432) (xy 165.918661 -399.822812)
			(xy 165.864926 -399.814827) (xy 165.812867 -399.799302) (xy 165.763537 -399.776549) (xy 165.717932 -399.747029)
			(xy 165.676976 -399.711339) (xy 165.641497 -399.6702) (xy 165.612211 -399.624445) (xy 165.589711 -399.574999)
			(xy 165.574453 -399.522861) (xy 165.566744 -399.469086) (xy 165.566344 -399.441924) (xy 165.566344 -399.4404)
			(xy 165.566531 -399.425089) (xy 165.569071 -399.394571) (xy 165.571424 -399.37944) (xy 165.573456 -399.367248)
			(xy 165.5699 -399.355818) (xy 165.56789 -399.349983) (xy 165.56147 -399.339446) (xy 165.5572 -399.33499)
			(xy 165.536626 -399.314416) (xy 165.529826 -399.307067) (xy 165.52212 -399.288604) (xy 165.52164 -399.278602)
			(xy 165.52164 -399.024094) (xy 165.521132 -399.020792) (xy 165.518563 -399.000544) (xy 165.514878 -398.959892)
			(xy 165.513766 -398.939512) (xy 165.51275 -398.917668) (xy 165.506349 -398.907389) (xy 165.486323 -398.893839)
			(xy 165.474396 -398.89176) (xy 165.4683 -398.891252) (xy 163.507166 -398.891252) (xy 163.497133 -398.891688)
			(xy 163.478558 -398.899263) (xy 163.471098 -398.905984) (xy 163.291012 -399.08607) (xy 163.259701 -399.116744)
			(xy 163.192548 -399.173088) (xy 163.1569 -399.198592) (xy 163.153344 -399.201132) (xy 163.112958 -399.241518)
			(xy 163.106281 -399.248931) (xy 163.098712 -399.267366) (xy 163.098226 -399.277332) (xy 163.098226 -399.278602)
			(xy 163.097689 -399.28859) (xy 163.089978 -399.307024) (xy 163.08324 -399.314416) (xy 162.903916 -399.49374)
			(xy 162.901884 -399.49628) (xy 162.8749 -399.530795) (xy 162.815778 -399.595458) (xy 162.7512 -399.654675)
			(xy 162.716718 -399.6817) (xy 162.714178 -399.683732) (xy 162.534092 -399.863564) (xy 162.526748 -399.870377)
			(xy 162.508285 -399.878112) (xy 162.498278 -399.87855) (xy 162.24377 -399.87855) (xy 162.240468 -399.879058)
			(xy 162.207976 -399.883032) (xy 162.142645 -399.887228) (xy 162.109912 -399.88744) (xy 162.077179 -399.887225)
			(xy 162.011848 -399.883031) (xy 161.979356 -399.879058) (xy 161.976054 -399.87855) (xy 161.721546 -399.87855)
			(xy 161.711556 -399.878019) (xy 161.693117 -399.870312) (xy 161.685732 -399.863564) (xy 161.654744 -399.832576)
			(xy 161.650267 -399.828332) (xy 161.639741 -399.821906) (xy 161.633916 -399.819876) (xy 161.622486 -399.81632)
			(xy 161.610294 -399.818352) (xy 161.594038 -399.820638) (xy 161.563812 -399.823178) (xy 161.560764 -399.823178)
			(xy 161.557462 -399.823432) (xy 161.545778 -399.823432) (xy 161.51862 -399.822809) (xy 161.46489 -399.81482)
			(xy 161.412836 -399.79929) (xy 161.363511 -399.776535) (xy 161.317912 -399.747014) (xy 161.276961 -399.711324)
			(xy 161.241486 -399.670187) (xy 161.212204 -399.624434) (xy 161.189708 -399.57499) (xy 161.174451 -399.522856)
			(xy 161.166744 -399.469084) (xy 161.166302 -399.441924) (xy 161.166302 -399.4404) (xy 161.166489 -399.425089)
			(xy 161.169029 -399.394571) (xy 161.171382 -399.37944) (xy 161.173414 -399.367248) (xy 161.169858 -399.355818)
			(xy 161.167846 -399.349984) (xy 161.161423 -399.339451) (xy 161.157158 -399.33499) (xy 161.136584 -399.314416)
			(xy 161.129777 -399.30707) (xy 161.122062 -399.288607) (xy 161.121598 -399.278602) (xy 161.121598 -399.024094)
			(xy 161.12109 -399.020792) (xy 161.118521 -399.000544) (xy 161.114836 -398.959892) (xy 161.113724 -398.939512)
			(xy 161.112708 -398.917668) (xy 161.106304 -398.907395) (xy 161.086275 -398.893861) (xy 161.074354 -398.89176)
			(xy 161.068258 -398.891252) (xy 159.991044 -398.891252) (xy 159.980979 -398.890817) (xy 159.962394 -398.883083)
			(xy 159.954976 -398.876266) (xy 159.871918 -398.793208) (xy 159.863536 -398.786604) (xy 159.846518 -398.785334)
			(xy 159.84601 -398.785334) (xy 159.82933 -398.784234) (xy 159.796049 -398.781058) (xy 159.779462 -398.778984)
			(xy 159.77616 -398.778476) (xy 159.521652 -398.778476) (xy 159.511661 -398.777947) (xy 159.493217 -398.770245)
			(xy 159.485838 -398.76349) (xy 159.454596 -398.732502) (xy 159.45028 -398.728378) (xy 159.440146 -398.722076)
			(xy 159.43453 -398.720056) (xy 159.422592 -398.716246) (xy 159.4104 -398.718278) (xy 159.394894 -398.72073)
			(xy 159.363613 -398.723399) (xy 159.347916 -398.723612) (xy 159.319735 -398.723107) (xy 159.263985 -398.714817)
			(xy 159.210062 -398.698415) (xy 159.159138 -398.674258) (xy 159.112323 -398.642872) (xy 159.091122 -398.624298)
			(xy 159.090614 -398.623536) (xy 159.08782 -398.620996) (xy 159.086804 -398.61998) (xy 159.081978 -398.615408)
			(xy 159.070802 -398.609312) (xy 159.061658 -398.607026) (xy 159.03194 -398.598644) (xy 159.022288 -398.59966)
			(xy 159.011633 -398.60018) (xy 158.99139 -398.59353) (xy 158.975586 -398.57924) (xy 158.966937 -398.559767)
			(xy 158.966408 -398.549114) (xy 158.966408 -398.341088) (xy 158.966571 -398.325586) (xy 158.969118 -398.294687)
			(xy 158.971488 -398.279366) (xy 158.97352 -398.267174) (xy 158.96971 -398.255236) (xy 158.967719 -398.249647)
			(xy 158.961566 -398.239507) (xy 158.957518 -398.23517) (xy 158.93669 -398.214342) (xy 158.92989 -398.206993)
			(xy 158.92218 -398.188531) (xy 158.921704 -398.178528) (xy 158.921704 -397.92402) (xy 158.921196 -397.920718)
			(xy 158.919117 -397.904131) (xy 158.91594 -397.87085) (xy 158.914846 -397.85417) (xy 158.914846 -397.853662)
			(xy 158.913576 -397.836644) (xy 158.906972 -397.828262) (xy 158.751016 -397.672306) (xy 158.744167 -397.664908)
			(xy 158.736428 -397.64631) (xy 158.73603 -397.636238) (xy 158.73603 -395.064488) (xy 158.735937 -395.05961)
			(xy 158.734155 -395.050018) (xy 158.732474 -395.045438) (xy 158.728664 -395.036294) (xy 158.174182 -394.481812)
			(xy 158.166054 -394.475208) (xy 158.158688 -394.470382) (xy 158.154878 -394.46835) (xy 158.153862 -394.467842)
			(xy 158.122458 -394.452343) (xy 158.061694 -394.417513) (xy 158.03245 -394.398246) (xy 157.664658 -394.152374)
			(xy 157.625357 -394.125467) (xy 157.551579 -394.065219) (xy 157.483944 -393.998148) (xy 157.453076 -393.961874)
			(xy 157.447985 -393.956158) (xy 157.435201 -393.947756) (xy 157.42793 -393.945364) (xy 157.378462 -393.93052)
			(xy 157.282638 -393.891978) (xy 157.19131 -393.843739) (xy 157.148022 -393.81557) (xy 156.73578 -393.53998)
			(xy 156.702186 -393.517061) (xy 156.638458 -393.466529) (xy 156.579064 -393.410968) (xy 156.5244 -393.350748)
			(xy 156.499306 -393.318746) (xy 156.493951 -393.312372) (xy 156.480078 -393.303188) (xy 156.472128 -393.300712)
			(xy 156.432789 -393.28973) (xy 156.355895 -393.262179) (xy 156.281509 -393.228435) (xy 156.210132 -393.188722)
			(xy 156.175964 -393.166346) (xy 156.139388 -393.141962) (xy 156.132952 -393.137999) (xy 156.118494 -393.133613)
			(xy 156.11094 -393.133326) (xy 156.085032 -393.140438) (xy 156.06279 -393.153206) (xy 156.015614 -393.173323)
			(xy 155.96617 -393.186948) (xy 155.915349 -393.193836) (xy 155.889706 -393.194286) (xy 155.889452 -393.194286)
			(xy 155.862204 -393.193796) (xy 155.808262 -393.186034) (xy 155.755975 -393.170675) (xy 155.706405 -393.148031)
			(xy 155.660562 -393.118563) (xy 155.61938 -393.082871) (xy 155.583695 -393.041682) (xy 155.554236 -392.995834)
			(xy 155.531601 -392.94626) (xy 155.516251 -392.893969) (xy 155.508499 -392.840026) (xy 155.507944 -392.812778)
			(xy 155.507944 -392.812016) (xy 155.508381 -392.786625) (xy 155.515133 -392.736293) (xy 155.521406 -392.711686)
			(xy 155.522676 -392.707114) (xy 155.523438 -392.698478) (xy 155.523438 -392.69797) (xy 155.5242 -392.688826)
			(xy 155.52166 -392.679936) (xy 155.520284 -392.675576) (xy 155.516189 -392.667402) (xy 155.513532 -392.66368)
			(xy 155.51023 -392.659108) (xy 155.507436 -392.65606) (xy 155.506674 -392.655298) (xy 155.50642 -392.65479)
			(xy 155.50134 -392.649456) (xy 155.490418 -392.637772) (xy 155.47721 -392.623294) (xy 155.476702 -392.622786)
			(xy 155.464479 -392.6087) (xy 155.440978 -392.579736) (xy 155.429712 -392.564874) (xy 155.428696 -392.563858)
			(xy 155.428188 -392.563096) (xy 155.422854 -392.555984) (xy 154.64155 -392.034014) (xy 154.601237 -392.006252)
			(xy 154.525664 -391.944036) (xy 154.490674 -391.909808) (xy 152.736804 -390.155938) (xy 152.702599 -390.120928)
			(xy 152.640485 -390.045277) (xy 152.586086 -389.963902) (xy 152.539926 -389.877586) (xy 152.52065 -389.832596)
			(xy 150.847298 -385.793742) (xy 150.843309 -385.785148) (xy 150.830199 -385.771486) (xy 150.813032 -385.763498)
			(xy 150.80361 -385.7625) (xy 150.6982 -385.755388) (xy 150.672546 -385.769104) (xy 150.665434 -385.78155)
			(xy 150.650675 -385.805919) (xy 150.615062 -385.850387) (xy 150.573233 -385.889064) (xy 150.526117 -385.921091)
			(xy 150.474762 -385.945756) (xy 150.420311 -385.96251) (xy 150.363973 -385.97098) (xy 150.335488 -385.971542)
			(xy 150.308235 -385.971055) (xy 150.254284 -385.963297) (xy 150.201986 -385.947939) (xy 150.152406 -385.925295)
			(xy 150.106553 -385.895826) (xy 150.06536 -385.860131) (xy 150.029667 -385.818938) (xy 150.000199 -385.773084)
			(xy 149.977557 -385.723503) (xy 149.962201 -385.671205) (xy 149.954444 -385.617253) (xy 149.954444 -385.562747)
			(xy 149.962201 -385.508795) (xy 149.977557 -385.456497) (xy 150.000199 -385.406916) (xy 150.029667 -385.361062)
			(xy 150.06536 -385.319869) (xy 150.106553 -385.284174) (xy 150.152406 -385.254705) (xy 150.201986 -385.232061)
			(xy 150.254284 -385.216703) (xy 150.308235 -385.208945) (xy 150.335488 -385.208526) (xy 150.361128 -385.208941)
			(xy 150.411945 -385.215807) (xy 150.461385 -385.229417) (xy 150.508557 -385.249526) (xy 150.55261 -385.275772)
			(xy 150.592752 -385.307681) (xy 150.610824 -385.325874) (xy 150.618353 -385.332968) (xy 150.637406 -385.340972)
			(xy 150.658072 -385.340833) (xy 150.677017 -385.332573) (xy 150.691183 -385.317525) (xy 150.698285 -385.298118)
			(xy 150.6982 -385.287774) (xy 150.696676 -385.231894) (xy 150.696676 -383.688844) (xy 150.69616 -383.678654)
			(xy 150.68814 -383.659912) (xy 150.673493 -383.645732) (xy 150.664164 -383.6416) (xy 150.575264 -383.607564)
			(xy 150.565544 -383.604369) (xy 150.545115 -383.605125) (xy 150.526582 -383.613754) (xy 150.519384 -383.621026)
			(xy 150.501226 -383.640489) (xy 150.460442 -383.674693) (xy 150.415296 -383.70289) (xy 150.366667 -383.724531)
			(xy 150.315499 -383.739195) (xy 150.262788 -383.746598) (xy 150.236174 -383.74701) (xy 150.208924 -383.746522)
			(xy 150.154979 -383.738763) (xy 150.102687 -383.723405) (xy 150.053113 -383.700763) (xy 150.007265 -383.671296)
			(xy 149.966078 -383.635604) (xy 149.930389 -383.594414) (xy 149.900925 -383.548565) (xy 149.878285 -383.498989)
			(xy 149.862932 -383.446696) (xy 149.855176 -383.39275) (xy 149.855176 -383.33825) (xy 149.862932 -383.284304)
			(xy 149.878285 -383.232011) (xy 149.900925 -383.182435) (xy 149.930389 -383.136586) (xy 149.966078 -383.095396)
			(xy 150.007265 -383.059704) (xy 150.053113 -383.030237) (xy 150.102687 -383.007595) (xy 150.154979 -382.992237)
			(xy 150.208924 -382.984478) (xy 150.236174 -382.983994) (xy 150.262784 -382.984462) (xy 150.315486 -382.991871)
			(xy 150.366646 -383.006536) (xy 150.41527 -383.02817) (xy 150.460415 -383.056355) (xy 150.501202 -383.090542)
			(xy 150.519384 -383.109978) (xy 150.52656 -383.117289) (xy 150.545096 -383.125969) (xy 150.565551 -383.126694)
			(xy 150.575264 -383.12344) (xy 150.664164 -383.089404) (xy 150.673539 -383.085328) (xy 150.688254 -383.071162)
			(xy 150.69626 -383.052372) (xy 150.696676 -383.04216) (xy 150.696676 -381.753618) (xy 150.696155 -381.743431)
			(xy 150.68813 -381.724697) (xy 150.673483 -381.710525) (xy 150.664164 -381.706374) (xy 150.560786 -381.666496)
			(xy 150.53056 -381.673608) (xy 150.519892 -381.685292) (xy 150.501738 -381.704576) (xy 150.461022 -381.738446)
			(xy 150.416011 -381.766356) (xy 150.367571 -381.787768) (xy 150.316633 -381.802272) (xy 150.264179 -381.809587)
			(xy 150.237698 -381.810006) (xy 150.210447 -381.80952) (xy 150.1565 -381.801763) (xy 150.104206 -381.786408)
			(xy 150.054629 -381.763767) (xy 150.008779 -381.734301) (xy 149.967589 -381.698609) (xy 149.931898 -381.65742)
			(xy 149.902432 -381.611569) (xy 149.879791 -381.561993) (xy 149.864436 -381.509698) (xy 149.85668 -381.455751)
			(xy 149.85668 -381.401249) (xy 149.864436 -381.347302) (xy 149.879791 -381.295007) (xy 149.902432 -381.245431)
			(xy 149.931898 -381.19958) (xy 149.967589 -381.158391) (xy 150.008779 -381.122699) (xy 150.054629 -381.093233)
			(xy 150.104206 -381.070592) (xy 150.1565 -381.055237) (xy 150.210447 -381.04748) (xy 150.237698 -381.04699)
			(xy 150.264177 -381.047442) (xy 150.316628 -381.054763) (xy 150.367563 -381.069264) (xy 150.416004 -381.090667)
			(xy 150.461021 -381.118561) (xy 150.501751 -381.152411) (xy 150.519892 -381.171704) (xy 150.53056 -381.183388)
			(xy 150.560786 -381.1905) (xy 150.664164 -381.150622) (xy 150.67353 -381.146542) (xy 150.688222 -381.132372)
			(xy 150.6962 -381.113584) (xy 150.696676 -381.103378) (xy 150.696676 -374.651016) (xy 150.696237 -374.640953)
			(xy 150.688498 -374.622373) (xy 150.68169 -374.614948) (xy 149.73808 -373.671338) (xy 149.731235 -373.66394)
			(xy 149.72351 -373.645341) (xy 149.723094 -373.63527) (xy 149.723094 -348.992444) (xy 149.722997 -348.987567)
			(xy 149.721206 -348.977978) (xy 149.719538 -348.973394) (xy 149.715728 -348.96425) (xy 149.09038 -348.338902)
			(xy 149.087527 -348.336198) (xy 149.081147 -348.33161) (xy 149.07768 -348.329758) (xy 149.072254 -348.32717)
			(xy 149.060575 -348.324338) (xy 149.054566 -348.32417) (xy 146.518122 -348.32417) (xy 146.513245 -348.324269)
			(xy 146.503658 -348.326062) (xy 146.499072 -348.327726) (xy 146.489928 -348.331536) (xy 145.99412 -348.827344)
			(xy 145.991417 -348.830197) (xy 145.98683 -348.836578) (xy 145.984976 -348.840044) (xy 145.982394 -348.845471)
			(xy 145.979572 -348.857151) (xy 145.979388 -348.863158) (xy 145.979388 -378.68733) (xy 149.188168 -378.68733)
			(xy 149.192239 -378.631708) (xy 149.204365 -378.577271) (xy 149.224288 -378.52518) (xy 149.251584 -378.476545)
			(xy 149.28567 -378.432402) (xy 149.325819 -378.393693) (xy 149.371177 -378.361242) (xy 149.420777 -378.335741)
			(xy 149.473561 -378.317734) (xy 149.528404 -378.307604) (xy 149.584138 -378.305567) (xy 149.639575 -378.311667)
			(xy 149.693532 -378.325773) (xy 149.744861 -378.347585) (xy 149.792467 -378.376639) (xy 149.835335 -378.412314)
			(xy 149.872552 -378.453851) (xy 149.903325 -378.500364) (xy 149.926997 -378.550861) (xy 149.943065 -378.604268)
			(xy 149.951185 -378.659444) (xy 149.951694 -378.68733) (xy 149.951185 -378.715216) (xy 149.943065 -378.770392)
			(xy 149.926997 -378.823799) (xy 149.903325 -378.874296) (xy 149.872552 -378.920809) (xy 149.835335 -378.962346)
			(xy 149.792467 -378.998021) (xy 149.744861 -379.027075) (xy 149.693532 -379.048887) (xy 149.639575 -379.062993)
			(xy 149.584138 -379.069093) (xy 149.528404 -379.067056) (xy 149.473561 -379.056926) (xy 149.420777 -379.038919)
			(xy 149.371177 -379.013418) (xy 149.325819 -378.980967) (xy 149.28567 -378.942258) (xy 149.251584 -378.898115)
			(xy 149.224288 -378.84948) (xy 149.204365 -378.797389) (xy 149.192239 -378.742952) (xy 149.188168 -378.68733)
			(xy 145.979388 -378.68733) (xy 145.979388 -379.396498) (xy 147.395944 -379.396498) (xy 147.400015 -379.340876)
			(xy 147.412141 -379.286439) (xy 147.432064 -379.234348) (xy 147.45936 -379.185713) (xy 147.493446 -379.14157)
			(xy 147.533595 -379.102861) (xy 147.578953 -379.07041) (xy 147.628553 -379.044909) (xy 147.681337 -379.026902)
			(xy 147.73618 -379.016772) (xy 147.791914 -379.014735) (xy 147.847351 -379.020835) (xy 147.901308 -379.034941)
			(xy 147.952637 -379.056753) (xy 148.000243 -379.085807) (xy 148.043111 -379.121482) (xy 148.080328 -379.163019)
			(xy 148.111101 -379.209532) (xy 148.134773 -379.260029) (xy 148.150841 -379.313436) (xy 148.158961 -379.368612)
			(xy 148.15947 -379.396498) (xy 148.158961 -379.424384) (xy 148.150841 -379.47956) (xy 148.134773 -379.532967)
			(xy 148.111101 -379.583464) (xy 148.080328 -379.629977) (xy 148.043111 -379.671514) (xy 148.000243 -379.707189)
			(xy 147.952637 -379.736243) (xy 147.901308 -379.758055) (xy 147.847351 -379.772161) (xy 147.791914 -379.778261)
			(xy 147.73618 -379.776224) (xy 147.681337 -379.766094) (xy 147.628553 -379.748087) (xy 147.578953 -379.722586)
			(xy 147.533595 -379.690135) (xy 147.493446 -379.651426) (xy 147.45936 -379.607283) (xy 147.432064 -379.558648)
			(xy 147.412141 -379.506557) (xy 147.400015 -379.45212) (xy 147.395944 -379.396498) (xy 145.979388 -379.396498)
			(xy 145.979388 -379.904752) (xy 149.687786 -379.904752) (xy 149.691857 -379.84913) (xy 149.703983 -379.794693)
			(xy 149.723906 -379.742602) (xy 149.751202 -379.693967) (xy 149.785288 -379.649824) (xy 149.825437 -379.611115)
			(xy 149.870795 -379.578664) (xy 149.920395 -379.553163) (xy 149.973179 -379.535156) (xy 150.028022 -379.525026)
			(xy 150.083756 -379.522989) (xy 150.139193 -379.529089) (xy 150.19315 -379.543195) (xy 150.244479 -379.565007)
			(xy 150.292085 -379.594061) (xy 150.334953 -379.629736) (xy 150.37217 -379.671273) (xy 150.402943 -379.717786)
			(xy 150.426615 -379.768283) (xy 150.442683 -379.82169) (xy 150.450803 -379.876866) (xy 150.451312 -379.904752)
			(xy 150.450803 -379.932638) (xy 150.442683 -379.987814) (xy 150.426615 -380.041221) (xy 150.402943 -380.091718)
			(xy 150.37217 -380.138231) (xy 150.334953 -380.179768) (xy 150.292085 -380.215443) (xy 150.244479 -380.244497)
			(xy 150.19315 -380.266309) (xy 150.139193 -380.280415) (xy 150.083756 -380.286515) (xy 150.028022 -380.284478)
			(xy 149.973179 -380.274348) (xy 149.920395 -380.256341) (xy 149.870795 -380.23084) (xy 149.825437 -380.198389)
			(xy 149.785288 -380.15968) (xy 149.751202 -380.115537) (xy 149.723906 -380.066902) (xy 149.703983 -380.014811)
			(xy 149.691857 -379.960374) (xy 149.687786 -379.904752) (xy 145.979388 -379.904752) (xy 145.979388 -380.430532)
			(xy 146.648168 -380.430532) (xy 146.652239 -380.37491) (xy 146.664365 -380.320473) (xy 146.684288 -380.268382)
			(xy 146.711584 -380.219747) (xy 146.74567 -380.175604) (xy 146.785819 -380.136895) (xy 146.831177 -380.104444)
			(xy 146.880777 -380.078943) (xy 146.933561 -380.060936) (xy 146.988404 -380.050806) (xy 147.044138 -380.048769)
			(xy 147.099575 -380.054869) (xy 147.153532 -380.068975) (xy 147.204861 -380.090787) (xy 147.252467 -380.119841)
			(xy 147.295335 -380.155516) (xy 147.332552 -380.197053) (xy 147.363325 -380.243566) (xy 147.386997 -380.294063)
			(xy 147.403065 -380.34747) (xy 147.411185 -380.402646) (xy 147.411694 -380.430532) (xy 147.411185 -380.458418)
			(xy 147.403065 -380.513594) (xy 147.386997 -380.567001) (xy 147.363325 -380.617498) (xy 147.332552 -380.664011)
			(xy 147.295335 -380.705548) (xy 147.252467 -380.741223) (xy 147.204861 -380.770277) (xy 147.153532 -380.792089)
			(xy 147.099575 -380.806195) (xy 147.044138 -380.812295) (xy 146.988404 -380.810258) (xy 146.933561 -380.800128)
			(xy 146.880777 -380.782121) (xy 146.831177 -380.75662) (xy 146.785819 -380.724169) (xy 146.74567 -380.68546)
			(xy 146.711584 -380.641317) (xy 146.684288 -380.592682) (xy 146.664365 -380.540591) (xy 146.652239 -380.486154)
			(xy 146.648168 -380.430532) (xy 145.979388 -380.430532) (xy 145.979388 -380.66472) (xy 145.978961 -380.674788)
			(xy 145.97124 -380.693386) (xy 145.964402 -380.700788) (xy 144.95399 -381.7112) (xy 147.45284 -381.7112)
			(xy 147.456911 -381.655578) (xy 147.469037 -381.601141) (xy 147.48896 -381.54905) (xy 147.516256 -381.500415)
			(xy 147.550342 -381.456272) (xy 147.590491 -381.417563) (xy 147.635849 -381.385112) (xy 147.685449 -381.359611)
			(xy 147.738233 -381.341604) (xy 147.793076 -381.331474) (xy 147.84881 -381.329437) (xy 147.904247 -381.335537)
			(xy 147.958204 -381.349643) (xy 148.009533 -381.371455) (xy 148.057139 -381.400509) (xy 148.100007 -381.436184)
			(xy 148.137224 -381.477721) (xy 148.167997 -381.524234) (xy 148.191669 -381.574731) (xy 148.207737 -381.628138)
			(xy 148.215857 -381.683314) (xy 148.216366 -381.7112) (xy 148.215857 -381.739086) (xy 148.207737 -381.794262)
			(xy 148.191669 -381.847669) (xy 148.167997 -381.898166) (xy 148.137224 -381.944679) (xy 148.100007 -381.986216)
			(xy 148.057139 -382.021891) (xy 148.009533 -382.050945) (xy 147.958204 -382.072757) (xy 147.904247 -382.086863)
			(xy 147.84881 -382.092963) (xy 147.793076 -382.090926) (xy 147.738233 -382.080796) (xy 147.685449 -382.062789)
			(xy 147.635849 -382.037288) (xy 147.590491 -382.004837) (xy 147.550342 -381.966128) (xy 147.516256 -381.921985)
			(xy 147.48896 -381.87335) (xy 147.469037 -381.821259) (xy 147.456911 -381.766822) (xy 147.45284 -381.7112)
			(xy 144.95399 -381.7112) (xy 144.229074 -382.436116) (xy 144.222368 -382.444498) (xy 146.412456 -382.444498)
			(xy 146.416527 -382.388876) (xy 146.428653 -382.334439) (xy 146.448576 -382.282348) (xy 146.475872 -382.233713)
			(xy 146.509958 -382.18957) (xy 146.550107 -382.150861) (xy 146.595465 -382.11841) (xy 146.645065 -382.092909)
			(xy 146.697849 -382.074902) (xy 146.752692 -382.064772) (xy 146.808426 -382.062735) (xy 146.863863 -382.068835)
			(xy 146.91782 -382.082941) (xy 146.969149 -382.104753) (xy 147.016755 -382.133807) (xy 147.059623 -382.169482)
			(xy 147.09684 -382.211019) (xy 147.127613 -382.257532) (xy 147.151285 -382.308029) (xy 147.167353 -382.361436)
			(xy 147.175473 -382.416612) (xy 147.175982 -382.444498) (xy 147.175473 -382.472384) (xy 147.167353 -382.52756)
			(xy 147.151285 -382.580967) (xy 147.127613 -382.631464) (xy 147.09684 -382.677977) (xy 147.059623 -382.719514)
			(xy 147.016755 -382.755189) (xy 146.969149 -382.784243) (xy 146.91782 -382.806055) (xy 146.863863 -382.820161)
			(xy 146.808426 -382.826261) (xy 146.752692 -382.824224) (xy 146.697849 -382.814094) (xy 146.645065 -382.796087)
			(xy 146.595465 -382.770586) (xy 146.550107 -382.738135) (xy 146.509958 -382.699426) (xy 146.475872 -382.655283)
			(xy 146.448576 -382.606648) (xy 146.428653 -382.554557) (xy 146.416527 -382.50012) (xy 146.412456 -382.444498)
			(xy 144.222368 -382.444498) (xy 144.221962 -382.445006) (xy 144.218347 -382.451146) (xy 144.214337 -382.464811)
			(xy 144.214088 -382.47193) (xy 144.208727 -383.460498) (xy 147.395944 -383.460498) (xy 147.400015 -383.404876)
			(xy 147.412141 -383.350439) (xy 147.432064 -383.298348) (xy 147.45936 -383.249713) (xy 147.493446 -383.20557)
			(xy 147.533595 -383.166861) (xy 147.578953 -383.13441) (xy 147.628553 -383.108909) (xy 147.681337 -383.090902)
			(xy 147.73618 -383.080772) (xy 147.791914 -383.078735) (xy 147.847351 -383.084835) (xy 147.901308 -383.098941)
			(xy 147.952637 -383.120753) (xy 148.000243 -383.149807) (xy 148.043111 -383.185482) (xy 148.080328 -383.227019)
			(xy 148.111101 -383.273532) (xy 148.134773 -383.324029) (xy 148.150841 -383.377436) (xy 148.158961 -383.432612)
			(xy 148.15947 -383.460498) (xy 148.158961 -383.488384) (xy 148.150841 -383.54356) (xy 148.134773 -383.596967)
			(xy 148.111101 -383.647464) (xy 148.080328 -383.693977) (xy 148.043111 -383.735514) (xy 148.000243 -383.771189)
			(xy 147.952637 -383.800243) (xy 147.901308 -383.822055) (xy 147.847351 -383.836161) (xy 147.791914 -383.842261)
			(xy 147.73618 -383.840224) (xy 147.681337 -383.830094) (xy 147.628553 -383.812087) (xy 147.578953 -383.786586)
			(xy 147.533595 -383.754135) (xy 147.493446 -383.715426) (xy 147.45936 -383.671283) (xy 147.432064 -383.622648)
			(xy 147.412141 -383.570557) (xy 147.400015 -383.51612) (xy 147.395944 -383.460498) (xy 144.208727 -383.460498)
			(xy 144.206468 -383.877058) (xy 144.202606 -384.591814) (xy 149.09876 -384.591814) (xy 149.102831 -384.536192)
			(xy 149.114957 -384.481755) (xy 149.13488 -384.429664) (xy 149.162176 -384.381029) (xy 149.196262 -384.336886)
			(xy 149.236411 -384.298177) (xy 149.281769 -384.265726) (xy 149.331369 -384.240225) (xy 149.384153 -384.222218)
			(xy 149.438996 -384.212088) (xy 149.49473 -384.210051) (xy 149.550167 -384.216151) (xy 149.604124 -384.230257)
			(xy 149.655453 -384.252069) (xy 149.703059 -384.281123) (xy 149.745927 -384.316798) (xy 149.783144 -384.358335)
			(xy 149.813917 -384.404848) (xy 149.837589 -384.455345) (xy 149.853657 -384.508752) (xy 149.861777 -384.563928)
			(xy 149.862286 -384.591814) (xy 149.861777 -384.6197) (xy 149.853657 -384.674876) (xy 149.837589 -384.728283)
			(xy 149.813917 -384.77878) (xy 149.783144 -384.825293) (xy 149.745927 -384.86683) (xy 149.703059 -384.902505)
			(xy 149.655453 -384.931559) (xy 149.604124 -384.953371) (xy 149.550167 -384.967477) (xy 149.49473 -384.973577)
			(xy 149.438996 -384.97154) (xy 149.384153 -384.96141) (xy 149.331369 -384.943403) (xy 149.281769 -384.917902)
			(xy 149.236411 -384.885451) (xy 149.196262 -384.846742) (xy 149.162176 -384.802599) (xy 149.13488 -384.753964)
			(xy 149.114957 -384.701873) (xy 149.102831 -384.647436) (xy 149.09876 -384.591814) (xy 144.202606 -384.591814)
			(xy 144.202404 -384.629152) (xy 144.196054 -385.784598) (xy 144.195304 -385.830218) (xy 144.186449 -385.921033)
			(xy 144.169265 -386.010647) (xy 144.1439 -386.098296) (xy 144.127728 -386.14096) (xy 144.005722 -386.451348)
			(xy 145.01622 -386.451348) (xy 145.016665 -386.424798) (xy 145.024028 -386.372211) (xy 145.038619 -386.321156)
			(xy 145.060154 -386.272619) (xy 145.088218 -386.227541) (xy 145.122267 -386.186795) (xy 145.161641 -386.151168)
			(xy 145.183352 -386.13588) (xy 145.192242 -386.129784) (xy 145.203418 -386.112258) (xy 145.216118 -386.027676)
			(xy 145.217149 -386.017268) (xy 145.211777 -385.997076) (xy 145.205704 -385.98856) (xy 145.20545 -385.988306)
			(xy 145.189739 -385.967951) (xy 145.16336 -385.923815) (xy 145.143146 -385.876536) (xy 145.129463 -385.826971)
			(xy 145.122558 -385.776017) (xy 145.122138 -385.750308) (xy 145.122624 -385.723057) (xy 145.13038 -385.669109)
			(xy 145.145735 -385.616814) (xy 145.168377 -385.567237) (xy 145.197843 -385.521387) (xy 145.233534 -385.480196)
			(xy 145.274725 -385.444505) (xy 145.320575 -385.415039) (xy 145.370152 -385.392397) (xy 145.422447 -385.377042)
			(xy 145.476395 -385.369286) (xy 145.530897 -385.369286) (xy 145.584845 -385.377042) (xy 145.63714 -385.392397)
			(xy 145.686717 -385.415039) (xy 145.732567 -385.444505) (xy 145.773758 -385.480196) (xy 145.809449 -385.521387)
			(xy 145.838915 -385.567237) (xy 145.861557 -385.616814) (xy 145.876912 -385.669109) (xy 145.884668 -385.723057)
			(xy 145.885154 -385.750308) (xy 145.884687 -385.776857) (xy 145.877329 -385.829443) (xy 145.862743 -385.880499)
			(xy 145.841212 -385.929036) (xy 145.813151 -385.974114) (xy 145.779105 -386.014861) (xy 145.739732 -386.050488)
			(xy 145.718022 -386.065776) (xy 145.709132 -386.071872) (xy 145.697956 -386.089398) (xy 145.685256 -386.17398)
			(xy 145.684235 -386.184389) (xy 145.689598 -386.204581) (xy 145.69567 -386.213096) (xy 145.695924 -386.21335)
			(xy 145.711625 -386.233711) (xy 145.738003 -386.277847) (xy 145.758218 -386.325125) (xy 145.771904 -386.374688)
			(xy 145.778813 -386.425639) (xy 145.779236 -386.451348) (xy 145.77875 -386.478599) (xy 145.770994 -386.532547)
			(xy 145.755639 -386.584842) (xy 145.732997 -386.634419) (xy 145.703531 -386.680269) (xy 145.66784 -386.72146)
			(xy 145.626649 -386.757151) (xy 145.580799 -386.786617) (xy 145.531222 -386.809259) (xy 145.478927 -386.824614)
			(xy 145.424979 -386.83237) (xy 145.370477 -386.83237) (xy 145.316529 -386.824614) (xy 145.264234 -386.809259)
			(xy 145.214657 -386.786617) (xy 145.168807 -386.757151) (xy 145.127616 -386.72146) (xy 145.091925 -386.680269)
			(xy 145.062459 -386.634419) (xy 145.039817 -386.584842) (xy 145.024462 -386.532547) (xy 145.016706 -386.478599)
			(xy 145.01622 -386.451348) (xy 144.005722 -386.451348) (xy 143.395192 -388.004558) (xy 143.394176 -388.007606)
			(xy 143.348762 -388.150354) (xy 143.718278 -388.150354) (xy 143.722349 -388.094732) (xy 143.734475 -388.040295)
			(xy 143.754398 -387.988204) (xy 143.781694 -387.939569) (xy 143.81578 -387.895426) (xy 143.855929 -387.856717)
			(xy 143.901287 -387.824266) (xy 143.950887 -387.798765) (xy 144.003671 -387.780758) (xy 144.058514 -387.770628)
			(xy 144.114248 -387.768591) (xy 144.169685 -387.774691) (xy 144.223642 -387.788797) (xy 144.274971 -387.810609)
			(xy 144.322577 -387.839663) (xy 144.365445 -387.875338) (xy 144.402662 -387.916875) (xy 144.433435 -387.963388)
			(xy 144.457107 -388.013885) (xy 144.473175 -388.067292) (xy 144.481295 -388.122468) (xy 144.481804 -388.150354)
			(xy 144.481748 -388.153402) (xy 146.889468 -388.153402) (xy 146.893539 -388.09778) (xy 146.905665 -388.043343)
			(xy 146.925588 -387.991252) (xy 146.952884 -387.942617) (xy 146.98697 -387.898474) (xy 147.027119 -387.859765)
			(xy 147.072477 -387.827314) (xy 147.122077 -387.801813) (xy 147.174861 -387.783806) (xy 147.229704 -387.773676)
			(xy 147.285438 -387.771639) (xy 147.340875 -387.777739) (xy 147.394832 -387.791845) (xy 147.446161 -387.813657)
			(xy 147.493767 -387.842711) (xy 147.536635 -387.878386) (xy 147.573852 -387.919923) (xy 147.604625 -387.966436)
			(xy 147.628297 -388.016933) (xy 147.644365 -388.07034) (xy 147.652485 -388.125516) (xy 147.652994 -388.153402)
			(xy 147.652485 -388.181288) (xy 147.648141 -388.210806) (xy 148.921468 -388.210806) (xy 148.925539 -388.155184)
			(xy 148.937665 -388.100747) (xy 148.957588 -388.048656) (xy 148.984884 -388.000021) (xy 149.01897 -387.955878)
			(xy 149.059119 -387.917169) (xy 149.104477 -387.884718) (xy 149.154077 -387.859217) (xy 149.206861 -387.84121)
			(xy 149.261704 -387.83108) (xy 149.317438 -387.829043) (xy 149.372875 -387.835143) (xy 149.426832 -387.849249)
			(xy 149.478161 -387.871061) (xy 149.525767 -387.900115) (xy 149.568635 -387.93579) (xy 149.605852 -387.977327)
			(xy 149.636625 -388.02384) (xy 149.660297 -388.074337) (xy 149.676365 -388.127744) (xy 149.684485 -388.18292)
			(xy 149.684994 -388.210806) (xy 149.684485 -388.238692) (xy 149.676365 -388.293868) (xy 149.660297 -388.347275)
			(xy 149.636625 -388.397772) (xy 149.605852 -388.444285) (xy 149.568635 -388.485822) (xy 149.525767 -388.521497)
			(xy 149.478161 -388.550551) (xy 149.426832 -388.572363) (xy 149.372875 -388.586469) (xy 149.317438 -388.592569)
			(xy 149.261704 -388.590532) (xy 149.206861 -388.580402) (xy 149.154077 -388.562395) (xy 149.104477 -388.536894)
			(xy 149.059119 -388.504443) (xy 149.01897 -388.465734) (xy 148.984884 -388.421591) (xy 148.957588 -388.372956)
			(xy 148.937665 -388.320865) (xy 148.925539 -388.266428) (xy 148.921468 -388.210806) (xy 147.648141 -388.210806)
			(xy 147.644365 -388.236464) (xy 147.628297 -388.289871) (xy 147.604625 -388.340368) (xy 147.573852 -388.386881)
			(xy 147.536635 -388.428418) (xy 147.493767 -388.464093) (xy 147.446161 -388.493147) (xy 147.394832 -388.514959)
			(xy 147.340875 -388.529065) (xy 147.285438 -388.535165) (xy 147.229704 -388.533128) (xy 147.174861 -388.522998)
			(xy 147.122077 -388.504991) (xy 147.072477 -388.47949) (xy 147.027119 -388.447039) (xy 146.98697 -388.40833)
			(xy 146.952884 -388.364187) (xy 146.925588 -388.315552) (xy 146.905665 -388.263461) (xy 146.893539 -388.209024)
			(xy 146.889468 -388.153402) (xy 144.481748 -388.153402) (xy 144.481295 -388.17824) (xy 144.473175 -388.233416)
			(xy 144.457107 -388.286823) (xy 144.433435 -388.33732) (xy 144.402662 -388.383833) (xy 144.365445 -388.42537)
			(xy 144.322577 -388.461045) (xy 144.274971 -388.490099) (xy 144.223642 -388.511911) (xy 144.169685 -388.526017)
			(xy 144.114248 -388.532117) (xy 144.058514 -388.53008) (xy 144.003671 -388.51995) (xy 143.950887 -388.501943)
			(xy 143.901287 -388.476442) (xy 143.855929 -388.443991) (xy 143.81578 -388.405282) (xy 143.781694 -388.361139)
			(xy 143.754398 -388.312504) (xy 143.734475 -388.260413) (xy 143.722349 -388.205976) (xy 143.718278 -388.150354)
			(xy 143.348762 -388.150354) (xy 143.200882 -388.615174) (xy 143.193098 -388.639048) (xy 143.175435 -388.68606)
			(xy 143.17013 -388.698486) (xy 144.600166 -388.698486) (xy 144.604237 -388.642864) (xy 144.616363 -388.588427)
			(xy 144.636286 -388.536336) (xy 144.663582 -388.487701) (xy 144.697668 -388.443558) (xy 144.737817 -388.404849)
			(xy 144.783175 -388.372398) (xy 144.832775 -388.346897) (xy 144.885559 -388.32889) (xy 144.940402 -388.31876)
			(xy 144.996136 -388.316723) (xy 145.051573 -388.322823) (xy 145.10553 -388.336929) (xy 145.156859 -388.358741)
			(xy 145.204465 -388.387795) (xy 145.247333 -388.42347) (xy 145.28455 -388.465007) (xy 145.315323 -388.51152)
			(xy 145.338995 -388.562017) (xy 145.355063 -388.615424) (xy 145.363183 -388.6706) (xy 145.363692 -388.698486)
			(xy 145.363183 -388.726372) (xy 145.355063 -388.781548) (xy 145.338995 -388.834955) (xy 145.315323 -388.885452)
			(xy 145.28455 -388.931965) (xy 145.247333 -388.973502) (xy 145.204465 -389.009177) (xy 145.156859 -389.038231)
			(xy 145.10553 -389.060043) (xy 145.051573 -389.074149) (xy 144.996136 -389.080249) (xy 144.940402 -389.078212)
			(xy 144.885559 -389.068082) (xy 144.832775 -389.050075) (xy 144.783175 -389.024574) (xy 144.737817 -388.992123)
			(xy 144.697668 -388.953414) (xy 144.663582 -388.909271) (xy 144.636286 -388.860636) (xy 144.616363 -388.808545)
			(xy 144.604237 -388.754108) (xy 144.600166 -388.698486) (xy 143.17013 -388.698486) (xy 143.165576 -388.709154)
			(xy 142.883723 -389.359648) (xy 145.873468 -389.359648) (xy 145.877539 -389.304026) (xy 145.889665 -389.249589)
			(xy 145.909588 -389.197498) (xy 145.936884 -389.148863) (xy 145.97097 -389.10472) (xy 146.011119 -389.066011)
			(xy 146.056477 -389.03356) (xy 146.106077 -389.008059) (xy 146.158861 -388.990052) (xy 146.213704 -388.979922)
			(xy 146.269438 -388.977885) (xy 146.324875 -388.983985) (xy 146.378832 -388.998091) (xy 146.430161 -389.019903)
			(xy 146.477767 -389.048957) (xy 146.520635 -389.084632) (xy 146.557852 -389.126169) (xy 146.588625 -389.172682)
			(xy 146.612297 -389.223179) (xy 146.628365 -389.276586) (xy 146.636485 -389.331762) (xy 146.636994 -389.359648)
			(xy 146.636485 -389.387534) (xy 146.636365 -389.38835) (xy 147.905468 -389.38835) (xy 147.909539 -389.332728)
			(xy 147.921665 -389.278291) (xy 147.941588 -389.2262) (xy 147.968884 -389.177565) (xy 148.00297 -389.133422)
			(xy 148.043119 -389.094713) (xy 148.088477 -389.062262) (xy 148.138077 -389.036761) (xy 148.190861 -389.018754)
			(xy 148.245704 -389.008624) (xy 148.301438 -389.006587) (xy 148.356875 -389.012687) (xy 148.410832 -389.026793)
			(xy 148.462161 -389.048605) (xy 148.509767 -389.077659) (xy 148.552635 -389.113334) (xy 148.589852 -389.154871)
			(xy 148.594424 -389.161782) (xy 150.953468 -389.161782) (xy 150.957539 -389.10616) (xy 150.969665 -389.051723)
			(xy 150.989588 -388.999632) (xy 151.016884 -388.950997) (xy 151.05097 -388.906854) (xy 151.091119 -388.868145)
			(xy 151.136477 -388.835694) (xy 151.186077 -388.810193) (xy 151.238861 -388.792186) (xy 151.293704 -388.782056)
			(xy 151.349438 -388.780019) (xy 151.404875 -388.786119) (xy 151.458832 -388.800225) (xy 151.510161 -388.822037)
			(xy 151.557767 -388.851091) (xy 151.600635 -388.886766) (xy 151.637852 -388.928303) (xy 151.668625 -388.974816)
			(xy 151.692297 -389.025313) (xy 151.708365 -389.07872) (xy 151.716485 -389.133896) (xy 151.716994 -389.161782)
			(xy 151.716485 -389.189668) (xy 151.708365 -389.244844) (xy 151.692297 -389.298251) (xy 151.668625 -389.348748)
			(xy 151.637852 -389.395261) (xy 151.600635 -389.436798) (xy 151.557767 -389.472473) (xy 151.510161 -389.501527)
			(xy 151.458832 -389.523339) (xy 151.404875 -389.537445) (xy 151.349438 -389.543545) (xy 151.293704 -389.541508)
			(xy 151.238861 -389.531378) (xy 151.186077 -389.513371) (xy 151.136477 -389.48787) (xy 151.091119 -389.455419)
			(xy 151.05097 -389.41671) (xy 151.016884 -389.372567) (xy 150.989588 -389.323932) (xy 150.969665 -389.271841)
			(xy 150.957539 -389.217404) (xy 150.953468 -389.161782) (xy 148.594424 -389.161782) (xy 148.620625 -389.201384)
			(xy 148.644297 -389.251881) (xy 148.660365 -389.305288) (xy 148.668485 -389.360464) (xy 148.668994 -389.38835)
			(xy 148.668485 -389.416236) (xy 148.660365 -389.471412) (xy 148.644297 -389.524819) (xy 148.620625 -389.575316)
			(xy 148.589852 -389.621829) (xy 148.552635 -389.663366) (xy 148.509767 -389.699041) (xy 148.462161 -389.728095)
			(xy 148.410832 -389.749907) (xy 148.356875 -389.764013) (xy 148.301438 -389.770113) (xy 148.245704 -389.768076)
			(xy 148.190861 -389.757946) (xy 148.138077 -389.739939) (xy 148.088477 -389.714438) (xy 148.043119 -389.681987)
			(xy 148.00297 -389.643278) (xy 147.968884 -389.599135) (xy 147.941588 -389.5505) (xy 147.921665 -389.498409)
			(xy 147.909539 -389.443972) (xy 147.905468 -389.38835) (xy 146.636365 -389.38835) (xy 146.628365 -389.44271)
			(xy 146.612297 -389.496117) (xy 146.588625 -389.546614) (xy 146.557852 -389.593127) (xy 146.520635 -389.634664)
			(xy 146.477767 -389.670339) (xy 146.430161 -389.699393) (xy 146.378832 -389.721205) (xy 146.324875 -389.735311)
			(xy 146.269438 -389.741411) (xy 146.213704 -389.739374) (xy 146.158861 -389.729244) (xy 146.106077 -389.711237)
			(xy 146.056477 -389.685736) (xy 146.011119 -389.653285) (xy 145.97097 -389.614576) (xy 145.936884 -389.570433)
			(xy 145.909588 -389.521798) (xy 145.889665 -389.469707) (xy 145.877539 -389.41527) (xy 145.873468 -389.359648)
			(xy 142.883723 -389.359648) (xy 142.655798 -389.885682) (xy 142.65529 -389.887206) (xy 142.6442 -389.9154)
			(xy 143.229582 -389.9154) (xy 143.233653 -389.859778) (xy 143.245779 -389.805341) (xy 143.265702 -389.75325)
			(xy 143.292998 -389.704615) (xy 143.327084 -389.660472) (xy 143.367233 -389.621763) (xy 143.412591 -389.589312)
			(xy 143.462191 -389.563811) (xy 143.514975 -389.545804) (xy 143.569818 -389.535674) (xy 143.625552 -389.533637)
			(xy 143.680989 -389.539737) (xy 143.734946 -389.553843) (xy 143.786275 -389.575655) (xy 143.833881 -389.604709)
			(xy 143.876749 -389.640384) (xy 143.913966 -389.681921) (xy 143.944739 -389.728434) (xy 143.968411 -389.778931)
			(xy 143.984479 -389.832338) (xy 143.992599 -389.887514) (xy 143.993108 -389.9154) (xy 143.992599 -389.943286)
			(xy 143.984479 -389.998462) (xy 143.968411 -390.051869) (xy 143.944739 -390.102366) (xy 143.913966 -390.148879)
			(xy 143.876749 -390.190416) (xy 143.833881 -390.226091) (xy 143.786275 -390.255145) (xy 143.734946 -390.276957)
			(xy 143.680989 -390.291063) (xy 143.625552 -390.297163) (xy 143.569818 -390.295126) (xy 143.514975 -390.284996)
			(xy 143.462191 -390.266989) (xy 143.412591 -390.241488) (xy 143.367233 -390.209037) (xy 143.327084 -390.170328)
			(xy 143.292998 -390.126185) (xy 143.265702 -390.07755) (xy 143.245779 -390.025459) (xy 143.233653 -389.971022)
			(xy 143.229582 -389.9154) (xy 142.6442 -389.9154) (xy 142.442184 -390.428988) (xy 142.426792 -390.467027)
			(xy 142.39055 -390.540656) (xy 142.369794 -390.576054) (xy 142.342298 -390.620542) (xy 142.279303 -390.704033)
			(xy 142.244064 -390.742678) (xy 142.239492 -390.747504) (xy 142.22519 -390.763252) (xy 143.960848 -390.763252)
			(xy 143.964919 -390.70763) (xy 143.977045 -390.653193) (xy 143.996968 -390.601102) (xy 144.024264 -390.552467)
			(xy 144.05835 -390.508324) (xy 144.098499 -390.469615) (xy 144.143857 -390.437164) (xy 144.193457 -390.411663)
			(xy 144.246241 -390.393656) (xy 144.301084 -390.383526) (xy 144.356818 -390.381489) (xy 144.412255 -390.387589)
			(xy 144.466212 -390.401695) (xy 144.517541 -390.423507) (xy 144.565147 -390.452561) (xy 144.608015 -390.488236)
			(xy 144.645232 -390.529773) (xy 144.676005 -390.576286) (xy 144.699677 -390.626783) (xy 144.715745 -390.68019)
			(xy 144.723865 -390.735366) (xy 144.724374 -390.763252) (xy 144.723865 -390.791138) (xy 144.715745 -390.846314)
			(xy 144.699677 -390.899721) (xy 144.676005 -390.950218) (xy 144.645232 -390.996731) (xy 144.608015 -391.038268)
			(xy 144.565147 -391.073943) (xy 144.517541 -391.102997) (xy 144.466212 -391.124809) (xy 144.412255 -391.138915)
			(xy 144.356818 -391.145015) (xy 144.301084 -391.142978) (xy 144.246241 -391.132848) (xy 144.193457 -391.114841)
			(xy 144.143857 -391.08934) (xy 144.098499 -391.056889) (xy 144.05835 -391.01818) (xy 144.024264 -390.974037)
			(xy 143.996968 -390.925402) (xy 143.977045 -390.873311) (xy 143.964919 -390.818874) (xy 143.960848 -390.763252)
			(xy 142.22519 -390.763252) (xy 141.581124 -391.47242) (xy 141.575068 -391.479592) (xy 141.568279 -391.497077)
			(xy 141.567916 -391.506456) (xy 141.567916 -391.518648) (xy 141.568057 -391.52368) (xy 141.568753 -391.52703)
			(xy 142.865854 -391.52703) (xy 142.869925 -391.471408) (xy 142.882051 -391.416971) (xy 142.901974 -391.36488)
			(xy 142.92927 -391.316245) (xy 142.963356 -391.272102) (xy 143.003505 -391.233393) (xy 143.048863 -391.200942)
			(xy 143.098463 -391.175441) (xy 143.151247 -391.157434) (xy 143.20609 -391.147304) (xy 143.261824 -391.145267)
			(xy 143.317261 -391.151367) (xy 143.371218 -391.165473) (xy 143.422547 -391.187285) (xy 143.470153 -391.216339)
			(xy 143.513021 -391.252014) (xy 143.550238 -391.293551) (xy 143.581011 -391.340064) (xy 143.604683 -391.390561)
			(xy 143.620751 -391.443968) (xy 143.628871 -391.499144) (xy 143.629055 -391.50925) (xy 145.03476 -391.50925)
			(xy 145.038831 -391.453628) (xy 145.050957 -391.399191) (xy 145.07088 -391.3471) (xy 145.098176 -391.298465)
			(xy 145.132262 -391.254322) (xy 145.172411 -391.215613) (xy 145.217769 -391.183162) (xy 145.267369 -391.157661)
			(xy 145.320153 -391.139654) (xy 145.374996 -391.129524) (xy 145.43073 -391.127487) (xy 145.486167 -391.133587)
			(xy 145.540124 -391.147693) (xy 145.591453 -391.169505) (xy 145.639059 -391.198559) (xy 145.681927 -391.234234)
			(xy 145.719144 -391.275771) (xy 145.749917 -391.322284) (xy 145.773589 -391.372781) (xy 145.789657 -391.426188)
			(xy 145.797777 -391.481364) (xy 145.798286 -391.50925) (xy 145.797777 -391.537136) (xy 145.793209 -391.568178)
			(xy 147.905468 -391.568178) (xy 147.909539 -391.512556) (xy 147.921665 -391.458119) (xy 147.941588 -391.406028)
			(xy 147.968884 -391.357393) (xy 148.00297 -391.31325) (xy 148.043119 -391.274541) (xy 148.088477 -391.24209)
			(xy 148.138077 -391.216589) (xy 148.190861 -391.198582) (xy 148.245704 -391.188452) (xy 148.301438 -391.186415)
			(xy 148.356875 -391.192515) (xy 148.410832 -391.206621) (xy 148.462161 -391.228433) (xy 148.509767 -391.257487)
			(xy 148.552635 -391.293162) (xy 148.589852 -391.334699) (xy 148.620625 -391.381212) (xy 148.644297 -391.431709)
			(xy 148.660365 -391.485116) (xy 148.668485 -391.540292) (xy 148.668994 -391.568178) (xy 148.668485 -391.596064)
			(xy 148.660365 -391.65124) (xy 148.644297 -391.704647) (xy 148.620625 -391.755144) (xy 148.609885 -391.771378)
			(xy 149.937468 -391.771378) (xy 149.941539 -391.715756) (xy 149.953665 -391.661319) (xy 149.973588 -391.609228)
			(xy 150.000884 -391.560593) (xy 150.03497 -391.51645) (xy 150.075119 -391.477741) (xy 150.120477 -391.44529)
			(xy 150.170077 -391.419789) (xy 150.222861 -391.401782) (xy 150.277704 -391.391652) (xy 150.333438 -391.389615)
			(xy 150.388875 -391.395715) (xy 150.442832 -391.409821) (xy 150.494161 -391.431633) (xy 150.541767 -391.460687)
			(xy 150.584635 -391.496362) (xy 150.621852 -391.537899) (xy 150.652625 -391.584412) (xy 150.676297 -391.634909)
			(xy 150.692365 -391.688316) (xy 150.700485 -391.743492) (xy 150.700994 -391.771378) (xy 150.700485 -391.799264)
			(xy 150.692365 -391.85444) (xy 150.676297 -391.907847) (xy 150.652625 -391.958344) (xy 150.621852 -392.004857)
			(xy 150.584635 -392.046394) (xy 150.541767 -392.082069) (xy 150.494161 -392.111123) (xy 150.442832 -392.132935)
			(xy 150.388875 -392.147041) (xy 150.333438 -392.153141) (xy 150.277704 -392.151104) (xy 150.222861 -392.140974)
			(xy 150.170077 -392.122967) (xy 150.120477 -392.097466) (xy 150.075119 -392.065015) (xy 150.03497 -392.026306)
			(xy 150.000884 -391.982163) (xy 149.973588 -391.933528) (xy 149.953665 -391.881437) (xy 149.941539 -391.827)
			(xy 149.937468 -391.771378) (xy 148.609885 -391.771378) (xy 148.589852 -391.801657) (xy 148.552635 -391.843194)
			(xy 148.509767 -391.878869) (xy 148.462161 -391.907923) (xy 148.410832 -391.929735) (xy 148.356875 -391.943841)
			(xy 148.301438 -391.949941) (xy 148.245704 -391.947904) (xy 148.190861 -391.937774) (xy 148.138077 -391.919767)
			(xy 148.088477 -391.894266) (xy 148.043119 -391.861815) (xy 148.00297 -391.823106) (xy 147.968884 -391.778963)
			(xy 147.941588 -391.730328) (xy 147.921665 -391.678237) (xy 147.909539 -391.6238) (xy 147.905468 -391.568178)
			(xy 145.793209 -391.568178) (xy 145.789657 -391.592312) (xy 145.773589 -391.645719) (xy 145.749917 -391.696216)
			(xy 145.719144 -391.742729) (xy 145.681927 -391.784266) (xy 145.639059 -391.819941) (xy 145.591453 -391.848995)
			(xy 145.540124 -391.870807) (xy 145.486167 -391.884913) (xy 145.43073 -391.891013) (xy 145.374996 -391.888976)
			(xy 145.320153 -391.878846) (xy 145.267369 -391.860839) (xy 145.217769 -391.835338) (xy 145.172411 -391.802887)
			(xy 145.132262 -391.764178) (xy 145.098176 -391.720035) (xy 145.07088 -391.6714) (xy 145.050957 -391.619309)
			(xy 145.038831 -391.564872) (xy 145.03476 -391.50925) (xy 143.629055 -391.50925) (xy 143.62938 -391.52703)
			(xy 143.628871 -391.554916) (xy 143.620751 -391.610092) (xy 143.604683 -391.663499) (xy 143.581011 -391.713996)
			(xy 143.550238 -391.760509) (xy 143.513021 -391.802046) (xy 143.470153 -391.837721) (xy 143.422547 -391.866775)
			(xy 143.371218 -391.888587) (xy 143.317261 -391.902693) (xy 143.261824 -391.908793) (xy 143.20609 -391.906756)
			(xy 143.151247 -391.896626) (xy 143.098463 -391.878619) (xy 143.048863 -391.853118) (xy 143.003505 -391.820667)
			(xy 142.963356 -391.781958) (xy 142.92927 -391.737815) (xy 142.901974 -391.68918) (xy 142.882051 -391.637089)
			(xy 142.869925 -391.582652) (xy 142.865854 -391.52703) (xy 141.568753 -391.52703) (xy 141.570105 -391.533534)
			(xy 141.57198 -391.538206) (xy 141.596364 -391.596626) (xy 141.59865 -391.60323) (xy 141.601444 -391.615422)
			(xy 141.609572 -391.62482) (xy 141.613769 -391.629366) (xy 141.623918 -391.636434) (xy 141.629638 -391.63879)
			(xy 141.629892 -391.63879) (xy 141.64691 -391.645394) (xy 141.654784 -391.645902) (xy 141.683226 -391.648533)
			(xy 141.738915 -391.661228) (xy 141.792089 -391.682085) (xy 141.841559 -391.710636) (xy 141.886219 -391.746245)
			(xy 141.925071 -391.788114) (xy 141.957246 -391.835307) (xy 141.982024 -391.886771) (xy 141.998853 -391.941353)
			(xy 142.007355 -391.997835) (xy 142.007844 -392.026394) (xy 142.007359 -392.053646) (xy 141.999603 -392.107597)
			(xy 141.984249 -392.159894) (xy 141.975386 -392.179302) (xy 146.321016 -392.179302) (xy 146.325087 -392.12368)
			(xy 146.337213 -392.069243) (xy 146.357136 -392.017152) (xy 146.384432 -391.968517) (xy 146.418518 -391.924374)
			(xy 146.458667 -391.885665) (xy 146.504025 -391.853214) (xy 146.553625 -391.827713) (xy 146.606409 -391.809706)
			(xy 146.661252 -391.799576) (xy 146.716986 -391.797539) (xy 146.772423 -391.803639) (xy 146.82638 -391.817745)
			(xy 146.877709 -391.839557) (xy 146.925315 -391.868611) (xy 146.968183 -391.904286) (xy 147.0054 -391.945823)
			(xy 147.036173 -391.992336) (xy 147.059845 -392.042833) (xy 147.075913 -392.09624) (xy 147.084033 -392.151416)
			(xy 147.084542 -392.179302) (xy 147.084033 -392.207188) (xy 147.075913 -392.262364) (xy 147.059845 -392.315771)
			(xy 147.036173 -392.366268) (xy 147.0054 -392.412781) (xy 146.968183 -392.454318) (xy 146.925315 -392.489993)
			(xy 146.877709 -392.519047) (xy 146.82638 -392.540859) (xy 146.772423 -392.554965) (xy 146.716986 -392.561065)
			(xy 146.661252 -392.559028) (xy 146.606409 -392.548898) (xy 146.553625 -392.530891) (xy 146.504025 -392.50539)
			(xy 146.458667 -392.472939) (xy 146.418518 -392.43423) (xy 146.384432 -392.390087) (xy 146.357136 -392.341452)
			(xy 146.337213 -392.289361) (xy 146.325087 -392.234924) (xy 146.321016 -392.179302) (xy 141.975386 -392.179302)
			(xy 141.961608 -392.209475) (xy 141.932143 -392.255328) (xy 141.896452 -392.296522) (xy 141.855262 -392.332218)
			(xy 141.809411 -392.361688) (xy 141.759834 -392.384334) (xy 141.707538 -392.399694) (xy 141.653588 -392.407456)
			(xy 141.626336 -392.407902) (xy 141.599224 -392.407422) (xy 141.545545 -392.399741) (xy 141.493494 -392.384543)
			(xy 141.444116 -392.362133) (xy 141.398406 -392.332962) (xy 141.357283 -392.297617) (xy 141.321575 -392.256809)
			(xy 141.291999 -392.21136) (xy 141.269151 -392.162183) (xy 141.253491 -392.110269) (xy 141.248892 -392.083544)
			(xy 141.246937 -392.073832) (xy 141.236787 -392.056841) (xy 141.220987 -392.044923) (xy 141.211554 -392.041888)
			(xy 141.204442 -392.04011) (xy 141.203172 -392.039348) (xy 141.126464 -392.016742) (xy 141.11986 -392.016488)
			(xy 141.111478 -392.016234) (xy 141.100843 -392.016465) (xy 141.081167 -392.024481) (xy 141.073378 -392.031728)
			(xy 140.513529 -392.646916) (xy 148.921468 -392.646916) (xy 148.925539 -392.591294) (xy 148.937665 -392.536857)
			(xy 148.957588 -392.484766) (xy 148.984884 -392.436131) (xy 149.01897 -392.391988) (xy 149.059119 -392.353279)
			(xy 149.104477 -392.320828) (xy 149.154077 -392.295327) (xy 149.206861 -392.27732) (xy 149.261704 -392.26719)
			(xy 149.317438 -392.265153) (xy 149.372875 -392.271253) (xy 149.426832 -392.285359) (xy 149.478161 -392.307171)
			(xy 149.525767 -392.336225) (xy 149.568635 -392.3719) (xy 149.605852 -392.413437) (xy 149.636625 -392.45995)
			(xy 149.660297 -392.510447) (xy 149.676365 -392.563854) (xy 149.684485 -392.61903) (xy 149.684994 -392.646916)
			(xy 149.684485 -392.674802) (xy 149.676365 -392.729978) (xy 149.673844 -392.738356) (xy 150.953468 -392.738356)
			(xy 150.957539 -392.682734) (xy 150.969665 -392.628297) (xy 150.989588 -392.576206) (xy 151.016884 -392.527571)
			(xy 151.05097 -392.483428) (xy 151.091119 -392.444719) (xy 151.136477 -392.412268) (xy 151.186077 -392.386767)
			(xy 151.238861 -392.36876) (xy 151.293704 -392.35863) (xy 151.349438 -392.356593) (xy 151.404875 -392.362693)
			(xy 151.458832 -392.376799) (xy 151.510161 -392.398611) (xy 151.557767 -392.427665) (xy 151.600635 -392.46334)
			(xy 151.637852 -392.504877) (xy 151.668625 -392.55139) (xy 151.692297 -392.601887) (xy 151.708365 -392.655294)
			(xy 151.716485 -392.71047) (xy 151.716994 -392.738356) (xy 151.716485 -392.766242) (xy 151.708365 -392.821418)
			(xy 151.692297 -392.874825) (xy 151.668625 -392.925322) (xy 151.637852 -392.971835) (xy 151.600635 -393.013372)
			(xy 151.557767 -393.049047) (xy 151.510161 -393.078101) (xy 151.458832 -393.099913) (xy 151.404875 -393.114019)
			(xy 151.349438 -393.120119) (xy 151.293704 -393.118082) (xy 151.238861 -393.107952) (xy 151.186077 -393.089945)
			(xy 151.136477 -393.064444) (xy 151.091119 -393.031993) (xy 151.05097 -392.993284) (xy 151.016884 -392.949141)
			(xy 150.989588 -392.900506) (xy 150.969665 -392.848415) (xy 150.957539 -392.793978) (xy 150.953468 -392.738356)
			(xy 149.673844 -392.738356) (xy 149.660297 -392.783385) (xy 149.636625 -392.833882) (xy 149.605852 -392.880395)
			(xy 149.568635 -392.921932) (xy 149.525767 -392.957607) (xy 149.478161 -392.986661) (xy 149.426832 -393.008473)
			(xy 149.372875 -393.022579) (xy 149.317438 -393.028679) (xy 149.261704 -393.026642) (xy 149.206861 -393.016512)
			(xy 149.154077 -392.998505) (xy 149.104477 -392.973004) (xy 149.059119 -392.940553) (xy 149.01897 -392.901844)
			(xy 148.984884 -392.857701) (xy 148.957588 -392.809066) (xy 148.937665 -392.756975) (xy 148.925539 -392.702538)
			(xy 148.921468 -392.646916) (xy 140.513529 -392.646916) (xy 140.456666 -392.7094) (xy 140.425335 -392.743104)
			(xy 140.357388 -392.80517) (xy 140.283959 -392.860644) (xy 140.205688 -392.909044) (xy 140.123252 -392.949952)
			(xy 140.080492 -392.966956) (xy 138.553698 -393.555474) (xy 138.546078 -393.558522) (xy 138.531092 -393.564364)
			(xy 137.883646 -393.813792) (xy 134.340092 -395.17955) (xy 134.33806 -395.180566) (xy 134.09422 -395.2875)
			(xy 134.080758 -395.300962) (xy 134.079996 -395.302486) (xy 134.07644 -395.317472) (xy 134.07644 -395.31798)
			(xy 134.068408 -395.351315) (xy 134.045549 -395.415964) (xy 134.015236 -395.477471) (xy 133.977891 -395.53498)
			(xy 133.934033 -395.587692) (xy 133.884274 -395.634872) (xy 133.829304 -395.675864) (xy 133.799834 -395.693392)
			(xy 133.76817 -395.711011) (xy 133.701379 -395.739118) (xy 133.631608 -395.758691) (xy 133.559944 -395.769425)
			(xy 133.523736 -395.770862) (xy 133.508496 -395.770862) (xy 133.499515 -395.771166) (xy 133.482631 -395.777283)
			(xy 133.468907 -395.788866) (xy 133.460041 -395.804482) (xy 133.458204 -395.81328) (xy 133.435344 -395.951964)
			(xy 133.433977 -395.964442) (xy 133.442106 -395.988158) (xy 133.450838 -395.997176) (xy 133.452616 -395.998954)
			(xy 133.459982 -396.001494) (xy 133.483604 -396.005304) (xy 133.488938 -396.00505) (xy 133.504686 -396.004542)
			(xy 133.510528 -396.004542) (xy 133.542298 -396.005095) (xy 133.605287 -396.01345) (xy 133.666648 -396.029948)
			(xy 133.725334 -396.054308) (xy 133.780342 -396.086114) (xy 133.830732 -396.124821) (xy 133.875643 -396.16977)
			(xy 133.914309 -396.220192) (xy 133.946069 -396.275226) (xy 133.970381 -396.333932) (xy 133.986829 -396.395307)
			(xy 133.995132 -396.458303) (xy 133.995148 -396.521844) (xy 133.986878 -396.584844) (xy 133.970463 -396.646227)
			(xy 133.946182 -396.704946) (xy 133.91445 -396.759996) (xy 133.875811 -396.810439) (xy 133.830923 -396.855411)
			(xy 133.780553 -396.894145) (xy 133.725562 -396.925979) (xy 133.666889 -396.95037) (xy 133.605536 -396.9669)
			(xy 133.542552 -396.975288) (xy 133.510782 -396.975838) (xy 133.509512 -396.975838) (xy 133.484112 -396.975076)
			(xy 133.47954 -396.975076) (xy 133.472875 -396.975278) (xy 133.460009 -396.978765) (xy 133.45414 -396.981934)
			(xy 133.448044 -396.98549) (xy 133.391402 -397.039592) (xy 133.384167 -397.047037) (xy 133.375895 -397.066054)
			(xy 133.3754 -397.076422) (xy 133.3754 -397.203676) (xy 133.375818 -397.212441) (xy 133.381801 -397.228926)
			(xy 133.387084 -397.235934) (xy 133.389624 -397.238982) (xy 133.452616 -397.298926) (xy 133.463284 -397.302482)
			(xy 133.472936 -397.305784) (xy 133.482842 -397.305276) (xy 133.504686 -397.304514) (xy 133.510528 -397.304514)
			(xy 133.5423 -397.305067) (xy 133.605292 -397.313422) (xy 133.666657 -397.329922) (xy 133.725346 -397.354283)
			(xy 133.780357 -397.386091) (xy 133.83075 -397.4248) (xy 133.875664 -397.469752) (xy 133.914333 -397.520176)
			(xy 133.946094 -397.575213) (xy 133.952222 -397.59001) (xy 135.22402 -397.59001) (xy 135.228011 -397.527843)
			(xy 135.23992 -397.466696) (xy 135.259549 -397.407575) (xy 135.286578 -397.351449) (xy 135.320562 -397.29924)
			(xy 135.360944 -397.251805) (xy 135.40706 -397.209924) (xy 135.458152 -397.174284) (xy 135.513383 -397.14547)
			(xy 135.571845 -397.123956) (xy 135.632579 -397.110094) (xy 135.694586 -397.104112) (xy 135.756849 -397.106108)
			(xy 135.818346 -397.116051) (xy 135.878067 -397.133775) (xy 135.93503 -397.158992) (xy 135.988301 -397.191285)
			(xy 136.037006 -397.230125) (xy 136.080343 -397.274875) (xy 136.117603 -397.324799) (xy 136.148172 -397.379078)
			(xy 136.17155 -397.436821) (xy 136.187351 -397.497079) (xy 136.195317 -397.558862) (xy 136.195816 -397.59001)
			(xy 136.195317 -397.621158) (xy 136.187351 -397.682941) (xy 136.17155 -397.743199) (xy 136.148172 -397.800942)
			(xy 136.117603 -397.855221) (xy 136.080343 -397.905145) (xy 136.037006 -397.949895) (xy 135.988301 -397.988735)
			(xy 135.93503 -398.021028) (xy 135.878067 -398.046245) (xy 135.818346 -398.063969) (xy 135.756849 -398.073912)
			(xy 135.694586 -398.075908) (xy 135.632579 -398.069926) (xy 135.571845 -398.056064) (xy 135.513383 -398.03455)
			(xy 135.458152 -398.005736) (xy 135.40706 -397.970096) (xy 135.360944 -397.928215) (xy 135.320562 -397.88078)
			(xy 135.286578 -397.828571) (xy 135.259549 -397.772445) (xy 135.23992 -397.713324) (xy 135.228011 -397.652177)
			(xy 135.22402 -397.59001) (xy 133.952222 -397.59001) (xy 133.970407 -397.633923) (xy 133.986856 -397.695301)
			(xy 133.99516 -397.758301) (xy 133.995176 -397.821845) (xy 133.986906 -397.884849) (xy 133.970489 -397.946236)
			(xy 133.946207 -398.004958) (xy 133.914474 -398.060012) (xy 133.875832 -398.110457) (xy 133.830941 -398.155432)
			(xy 133.780569 -398.194168) (xy 133.725575 -398.226004) (xy 133.666898 -398.250396) (xy 133.605542 -398.266928)
			(xy 133.542553 -398.275316) (xy 133.510782 -398.27581) (xy 133.509512 -398.27581) (xy 133.484112 -398.275048)
			(xy 133.47954 -398.275048) (xy 133.472874 -398.275249) (xy 133.460007 -398.278735) (xy 133.45414 -398.281906)
			(xy 133.448044 -398.285462) (xy 133.391402 -398.339564) (xy 133.384163 -398.347008) (xy 133.37588 -398.366024)
			(xy 133.3754 -398.376394) (xy 133.3754 -398.890236) (xy 135.22402 -398.890236) (xy 135.228011 -398.828069)
			(xy 135.23992 -398.766922) (xy 135.259549 -398.707801) (xy 135.286578 -398.651675) (xy 135.320562 -398.599466)
			(xy 135.360944 -398.552031) (xy 135.40706 -398.51015) (xy 135.458152 -398.47451) (xy 135.513383 -398.445696)
			(xy 135.571845 -398.424182) (xy 135.632579 -398.41032) (xy 135.694586 -398.404338) (xy 135.756849 -398.406334)
			(xy 135.818346 -398.416277) (xy 135.878067 -398.434001) (xy 135.93503 -398.459218) (xy 135.988301 -398.491511)
			(xy 136.037006 -398.530351) (xy 136.080343 -398.575101) (xy 136.117603 -398.625025) (xy 136.148172 -398.679304)
			(xy 136.17155 -398.737047) (xy 136.187351 -398.797305) (xy 136.195317 -398.859088) (xy 136.195816 -398.890236)
			(xy 136.195317 -398.921384) (xy 136.187351 -398.983167) (xy 136.17155 -399.043425) (xy 136.148172 -399.101168)
			(xy 136.117603 -399.155447) (xy 136.080343 -399.205371) (xy 136.037006 -399.250121) (xy 135.988301 -399.288961)
			(xy 135.93503 -399.321254) (xy 135.878067 -399.346471) (xy 135.818346 -399.364195) (xy 135.756849 -399.374138)
			(xy 135.694586 -399.376134) (xy 135.632579 -399.370152) (xy 135.571845 -399.35629) (xy 135.513383 -399.334776)
			(xy 135.458152 -399.305962) (xy 135.40706 -399.270322) (xy 135.360944 -399.228441) (xy 135.320562 -399.181006)
			(xy 135.286578 -399.128797) (xy 135.259549 -399.072671) (xy 135.23992 -399.01355) (xy 135.228011 -398.952403)
			(xy 135.22402 -398.890236) (xy 133.3754 -398.890236) (xy 133.3754 -399.80362) (xy 133.375809 -399.812389)
			(xy 133.381778 -399.828885) (xy 133.387084 -399.835878) (xy 133.389624 -399.838926) (xy 133.452616 -399.89887)
			(xy 133.463284 -399.902426) (xy 133.472936 -399.905728) (xy 133.482842 -399.90522) (xy 133.504686 -399.904458)
			(xy 133.510528 -399.904458) (xy 133.542297 -399.905011) (xy 133.605284 -399.913366) (xy 133.666643 -399.929863)
			(xy 133.725327 -399.954223) (xy 133.780333 -399.986027) (xy 133.830721 -400.024733) (xy 133.875631 -400.069681)
			(xy 133.914296 -400.120101) (xy 133.946055 -400.175133) (xy 133.970366 -400.233837) (xy 133.986813 -400.29521)
			(xy 133.995116 -400.358204) (xy 133.995132 -400.421742) (xy 133.986863 -400.484741) (xy 133.970447 -400.546122)
			(xy 133.946167 -400.604839) (xy 133.914437 -400.659888) (xy 133.875799 -400.710328) (xy 133.830912 -400.755299)
			(xy 133.780544 -400.794031) (xy 133.725555 -400.825865) (xy 133.666884 -400.850255) (xy 133.605533 -400.866785)
			(xy 133.54255 -400.875172) (xy 133.510782 -400.875754) (xy 133.509512 -400.875754) (xy 133.484112 -400.874992)
			(xy 133.47954 -400.874992) (xy 133.472875 -400.875194) (xy 133.460009 -400.878683) (xy 133.45414 -400.88185)
			(xy 133.448044 -400.885406) (xy 133.391402 -400.939508) (xy 133.38417 -400.946954) (xy 133.375903 -400.965971)
			(xy 133.3754 -400.976338) (xy 133.3754 -401.103592) (xy 133.37582 -401.112356) (xy 133.381808 -401.128837)
			(xy 133.387084 -401.13585) (xy 133.389624 -401.138898) (xy 133.452616 -401.198842) (xy 133.463284 -401.202398)
			(xy 133.472936 -401.2057) (xy 133.482842 -401.205192) (xy 133.504686 -401.20443) (xy 133.510528 -401.20443)
			(xy 133.542299 -401.204983) (xy 133.605289 -401.213338) (xy 133.666652 -401.229837) (xy 133.725339 -401.254198)
			(xy 133.780348 -401.286004) (xy 133.83074 -401.324712) (xy 133.875652 -401.369662) (xy 133.914319 -401.420085)
			(xy 133.94608 -401.475121) (xy 133.952316 -401.49018) (xy 135.22402 -401.49018) (xy 135.228011 -401.428013)
			(xy 135.23992 -401.366866) (xy 135.259549 -401.307745) (xy 135.286578 -401.251619) (xy 135.320562 -401.19941)
			(xy 135.360944 -401.151975) (xy 135.40706 -401.110094) (xy 135.458152 -401.074454) (xy 135.513383 -401.04564)
			(xy 135.571845 -401.024126) (xy 135.632579 -401.010264) (xy 135.694586 -401.004282) (xy 135.756849 -401.006278)
			(xy 135.818346 -401.016221) (xy 135.878067 -401.033945) (xy 135.93503 -401.059162) (xy 135.988301 -401.091455)
			(xy 136.037006 -401.130295) (xy 136.080343 -401.175045) (xy 136.117603 -401.224969) (xy 136.148172 -401.279248)
			(xy 136.17155 -401.336991) (xy 136.187351 -401.397249) (xy 136.195317 -401.459032) (xy 136.195816 -401.49018)
			(xy 136.195317 -401.521328) (xy 136.187351 -401.583111) (xy 136.17155 -401.643369) (xy 136.148172 -401.701112)
			(xy 136.117603 -401.755391) (xy 136.080343 -401.805315) (xy 136.037006 -401.850065) (xy 135.988301 -401.888905)
			(xy 135.93503 -401.921198) (xy 135.878067 -401.946415) (xy 135.818346 -401.964139) (xy 135.756849 -401.974082)
			(xy 135.694586 -401.976078) (xy 135.632579 -401.970096) (xy 135.571845 -401.956234) (xy 135.513383 -401.93472)
			(xy 135.458152 -401.905906) (xy 135.40706 -401.870266) (xy 135.360944 -401.828385) (xy 135.320562 -401.78095)
			(xy 135.286578 -401.728741) (xy 135.259549 -401.672615) (xy 135.23992 -401.613494) (xy 135.228011 -401.552347)
			(xy 135.22402 -401.49018) (xy 133.952316 -401.49018) (xy 133.970392 -401.533828) (xy 133.98684 -401.595204)
			(xy 133.995144 -401.658202) (xy 133.99516 -401.721744) (xy 133.98689 -401.784746) (xy 133.970474 -401.846131)
			(xy 133.946192 -401.904851) (xy 133.91446 -401.959903) (xy 133.87582 -402.010346) (xy 133.830931 -402.05532)
			(xy 133.78056 -402.094055) (xy 133.725567 -402.12589) (xy 133.666893 -402.150281) (xy 133.605539 -402.166812)
			(xy 133.542552 -402.1752) (xy 133.510782 -402.175726) (xy 133.509512 -402.175726) (xy 133.484112 -402.174964)
			(xy 133.47954 -402.174964) (xy 133.472875 -402.175166) (xy 133.460008 -402.178653) (xy 133.45414 -402.181822)
			(xy 133.448044 -402.185378) (xy 133.391402 -402.23948) (xy 133.384166 -402.246924) (xy 133.375888 -402.265941)
			(xy 133.3754 -402.27631) (xy 133.3754 -402.790152) (xy 135.22402 -402.790152) (xy 135.228011 -402.727985)
			(xy 135.23992 -402.666838) (xy 135.259549 -402.607717) (xy 135.286578 -402.551591) (xy 135.320562 -402.499382)
			(xy 135.360944 -402.451947) (xy 135.40706 -402.410066) (xy 135.458152 -402.374426) (xy 135.513383 -402.345612)
			(xy 135.571845 -402.324098) (xy 135.632579 -402.310236) (xy 135.694586 -402.304254) (xy 135.756849 -402.30625)
			(xy 135.818346 -402.316193) (xy 135.878067 -402.333917) (xy 135.93503 -402.359134) (xy 135.988301 -402.391427)
			(xy 136.037006 -402.430267) (xy 136.080343 -402.475017) (xy 136.117603 -402.524941) (xy 136.148172 -402.57922)
			(xy 136.17155 -402.636963) (xy 136.187351 -402.697221) (xy 136.195317 -402.759004) (xy 136.195816 -402.790152)
			(xy 136.195317 -402.8213) (xy 136.187351 -402.883083) (xy 136.17155 -402.943341) (xy 136.148172 -403.001084)
			(xy 136.117603 -403.055363) (xy 136.080343 -403.105287) (xy 136.037006 -403.150037) (xy 135.988301 -403.188877)
			(xy 135.93503 -403.22117) (xy 135.878067 -403.246387) (xy 135.818346 -403.264111) (xy 135.756849 -403.274054)
			(xy 135.694586 -403.27605) (xy 135.632579 -403.270068) (xy 135.571845 -403.256206) (xy 135.513383 -403.234692)
			(xy 135.458152 -403.205878) (xy 135.40706 -403.170238) (xy 135.360944 -403.128357) (xy 135.320562 -403.080922)
			(xy 135.286578 -403.028713) (xy 135.259549 -402.972587) (xy 135.23992 -402.913466) (xy 135.228011 -402.852319)
			(xy 135.22402 -402.790152) (xy 133.3754 -402.790152) (xy 133.3754 -403.703536) (xy 133.375811 -403.712304)
			(xy 133.381785 -403.728796) (xy 133.387084 -403.735794) (xy 133.389624 -403.738842) (xy 133.452616 -403.798786)
			(xy 133.463284 -403.802342) (xy 133.472936 -403.805644) (xy 133.482842 -403.805136) (xy 133.504686 -403.804374)
			(xy 133.510528 -403.804374) (xy 133.542296 -403.804927) (xy 133.605281 -403.813281) (xy 133.666638 -403.829779)
			(xy 133.72532 -403.854137) (xy 133.780324 -403.88594) (xy 133.830711 -403.924646) (xy 133.875619 -403.969591)
			(xy 133.914283 -404.02001) (xy 133.946041 -404.07504) (xy 133.970351 -404.133742) (xy 133.986797 -404.195113)
			(xy 133.9951 -404.258105) (xy 133.995116 -404.321641) (xy 133.986847 -404.384638) (xy 133.970432 -404.446017)
			(xy 133.946153 -404.504732) (xy 133.914424 -404.559779) (xy 133.875787 -404.610218) (xy 133.830902 -404.655187)
			(xy 133.780535 -404.693918) (xy 133.725548 -404.72575) (xy 133.666879 -404.750139) (xy 133.60553 -404.766669)
			(xy 133.542549 -404.775056) (xy 133.510782 -404.77567) (xy 133.509512 -404.77567) (xy 133.484112 -404.774908)
			(xy 133.47954 -404.774908) (xy 133.472875 -404.77511) (xy 133.46001 -404.7786) (xy 133.45414 -404.781766)
			(xy 133.448044 -404.785322) (xy 133.391402 -404.839424) (xy 133.384173 -404.846871) (xy 133.375912 -404.865888)
			(xy 133.3754 -404.876254) (xy 133.3754 -405.003508) (xy 133.375807 -405.012278) (xy 133.381774 -405.028776)
			(xy 133.387084 -405.035766) (xy 133.389624 -405.038814) (xy 133.452616 -405.098758) (xy 133.463284 -405.102314)
			(xy 133.472936 -405.105616) (xy 133.482842 -405.105108) (xy 133.504686 -405.104346) (xy 133.510528 -405.104346)
			(xy 133.542303 -405.104899) (xy 133.605301 -405.113257) (xy 133.666671 -405.12976) (xy 133.725364 -405.154128)
			(xy 133.780377 -405.185942) (xy 133.830771 -405.224661) (xy 133.875683 -405.269622) (xy 133.914348 -405.320057)
			(xy 133.946104 -405.375105) (xy 133.952309 -405.390096) (xy 135.22402 -405.390096) (xy 135.228011 -405.327929)
			(xy 135.23992 -405.266782) (xy 135.259549 -405.207661) (xy 135.286578 -405.151535) (xy 135.320562 -405.099326)
			(xy 135.360944 -405.051891) (xy 135.40706 -405.01001) (xy 135.458152 -404.97437) (xy 135.513383 -404.945556)
			(xy 135.571845 -404.924042) (xy 135.632579 -404.91018) (xy 135.694586 -404.904198) (xy 135.756849 -404.906194)
			(xy 135.818346 -404.916137) (xy 135.878067 -404.933861) (xy 135.93503 -404.959078) (xy 135.988301 -404.991371)
			(xy 136.037006 -405.030211) (xy 136.080343 -405.074961) (xy 136.117603 -405.124885) (xy 136.148172 -405.179164)
			(xy 136.17155 -405.236907) (xy 136.187351 -405.297165) (xy 136.195317 -405.358948) (xy 136.195816 -405.390096)
			(xy 136.195317 -405.421244) (xy 136.187351 -405.483027) (xy 136.17155 -405.543285) (xy 136.148172 -405.601028)
			(xy 136.117603 -405.655307) (xy 136.080343 -405.705231) (xy 136.037006 -405.749981) (xy 135.988301 -405.788821)
			(xy 135.93503 -405.821114) (xy 135.878067 -405.846331) (xy 135.818346 -405.864055) (xy 135.756849 -405.873998)
			(xy 135.694586 -405.875994) (xy 135.632579 -405.870012) (xy 135.571845 -405.85615) (xy 135.513383 -405.834636)
			(xy 135.458152 -405.805822) (xy 135.40706 -405.770182) (xy 135.360944 -405.728301) (xy 135.320562 -405.680866)
			(xy 135.286578 -405.628657) (xy 135.259549 -405.572531) (xy 135.23992 -405.51341) (xy 135.228011 -405.452263)
			(xy 135.22402 -405.390096) (xy 133.952309 -405.390096) (xy 133.970408 -405.433824) (xy 133.986845 -405.495212)
			(xy 133.995135 -405.558219) (xy 133.995668 -405.589994) (xy 133.995148 -405.621792) (xy 133.986849 -405.684843)
			(xy 133.97039 -405.746272) (xy 133.946054 -405.805027) (xy 133.914258 -405.860103) (xy 133.875544 -405.910557)
			(xy 133.830577 -405.955527) (xy 133.780124 -405.994243) (xy 133.72505 -406.026043) (xy 133.666297 -406.050382)
			(xy 133.604869 -406.066843) (xy 133.541818 -406.075147) (xy 133.51002 -406.075642) (xy 133.509512 -406.075642)
			(xy 133.478797 -406.07517) (xy 133.417859 -406.067415) (xy 133.358388 -406.052028) (xy 133.32968 -406.041098)
			(xy 133.320282 -406.039066) (xy 133.306312 -406.039066) (xy 133.293358 -406.041098) (xy 133.290056 -406.042114)
			(xy 133.27126 -406.047702) (xy 133.268212 -406.048718) (xy 133.264834 -406.050026) (xy 133.258464 -406.053476)
			(xy 133.255512 -406.055576) (xy 133.247638 -406.070308) (xy 133.224142 -406.112664) (xy 133.170109 -406.193061)
			(xy 133.10853 -406.267835) (xy 133.074664 -406.302464) (xy 132.68706 -406.690068) (xy 135.22402 -406.690068)
			(xy 135.228011 -406.627901) (xy 135.23992 -406.566754) (xy 135.259549 -406.507633) (xy 135.286578 -406.451507)
			(xy 135.320562 -406.399298) (xy 135.360944 -406.351863) (xy 135.40706 -406.309982) (xy 135.458152 -406.274342)
			(xy 135.513383 -406.245528) (xy 135.571845 -406.224014) (xy 135.632579 -406.210152) (xy 135.694586 -406.20417)
			(xy 135.756849 -406.206166) (xy 135.818346 -406.216109) (xy 135.878067 -406.233833) (xy 135.93503 -406.25905)
			(xy 135.988301 -406.291343) (xy 136.037006 -406.330183) (xy 136.080343 -406.374933) (xy 136.117603 -406.424857)
			(xy 136.148172 -406.479136) (xy 136.17155 -406.536879) (xy 136.187351 -406.597137) (xy 136.195317 -406.65892)
			(xy 136.195816 -406.690068) (xy 136.195317 -406.721216) (xy 136.187351 -406.782999) (xy 136.17155 -406.843257)
			(xy 136.148172 -406.901) (xy 136.117603 -406.955279) (xy 136.080343 -407.005203) (xy 136.037006 -407.049953)
			(xy 135.988301 -407.088793) (xy 135.93503 -407.121086) (xy 135.878067 -407.146303) (xy 135.818346 -407.164027)
			(xy 135.756849 -407.17397) (xy 135.694586 -407.175966) (xy 135.632579 -407.169984) (xy 135.571845 -407.156122)
			(xy 135.513383 -407.134608) (xy 135.458152 -407.105794) (xy 135.40706 -407.070154) (xy 135.360944 -407.028273)
			(xy 135.320562 -406.980838) (xy 135.286578 -406.928629) (xy 135.259549 -406.872503) (xy 135.23992 -406.813382)
			(xy 135.228011 -406.752235) (xy 135.22402 -406.690068) (xy 132.68706 -406.690068) (xy 132.491226 -406.885902)
			(xy 132.454927 -406.921372) (xy 132.3763 -406.985553) (xy 132.291569 -407.041428) (xy 132.246878 -407.06548)
			(xy 132.239362 -407.069746) (xy 132.227552 -407.082349) (xy 132.223764 -407.090118) (xy 132.205496 -407.130609)
			(xy 132.162756 -407.20849) (xy 132.113258 -407.28226) (xy 132.057395 -407.351334) (xy 131.995608 -407.415166)
			(xy 131.928389 -407.473249) (xy 131.85627 -407.525123) (xy 131.779822 -407.570376) (xy 131.699653 -407.60865)
			(xy 131.616396 -407.639641) (xy 131.530713 -407.663104) (xy 131.443283 -407.678852) (xy 131.354799 -407.686761)
			(xy 131.31038 -407.687272) (xy 131.310126 -407.687272) (xy 131.263734 -407.686743) (xy 131.17135 -407.678128)
			(xy 131.080166 -407.660969) (xy 130.99097 -407.635417) (xy 130.904533 -407.60169) (xy 130.862832 -407.581354)
			(xy 130.854704 -407.58237) (xy 130.850386 -407.58364) (xy 130.825547 -407.590475) (xy 130.774546 -407.597742)
			(xy 130.748786 -407.598118) (xy 130.74777 -407.598118) (xy 130.719788 -407.597567) (xy 130.664514 -407.588808)
			(xy 130.61129 -407.571511) (xy 130.561428 -407.546102) (xy 130.516153 -407.513205) (xy 130.476582 -407.473632)
			(xy 130.443688 -407.428355) (xy 130.418281 -407.378491) (xy 130.400987 -407.325267) (xy 130.392232 -407.269992)
			(xy 130.391662 -407.24201) (xy 130.391662 -407.241502) (xy 130.392212 -407.21227) (xy 130.401661 -407.154576)
			(xy 130.410458 -407.126694) (xy 130.41122 -407.122376) (xy 130.392289 -407.081857) (xy 130.360899 -406.998105)
			(xy 130.337133 -406.911879) (xy 130.321184 -406.823871) (xy 130.313178 -406.734789) (xy 130.312668 -406.690068)
			(xy 130.312668 -406.308052) (xy 130.313131 -406.26502) (xy 130.320563 -406.179277) (xy 130.335352 -406.094493)
			(xy 130.345942 -406.052782) (xy 130.34772 -406.039828) (xy 130.345942 -406.026874) (xy 130.339932 -406.003538)
			(xy 130.329894 -405.9564) (xy 130.325876 -405.93264) (xy 130.323844 -405.91994) (xy 130.312414 -405.905208)
			(xy 130.309874 -405.90216) (xy 130.307334 -405.89962) (xy 130.303607 -405.896093) (xy 130.295037 -405.890453)
			(xy 130.290316 -405.888444) (xy 130.268472 -405.879554) (xy 130.267964 -405.879554) (xy 130.227578 -405.863298)
			(xy 130.223251 -405.861628) (xy 130.214177 -405.859703) (xy 130.209544 -405.859488) (xy 130.189478 -405.874728)
			(xy 130.155532 -405.900031) (xy 130.084061 -405.945433) (xy 130.04673 -405.965406) (xy 130.039213 -405.969673)
			(xy 130.027397 -405.982271) (xy 130.023616 -405.990044) (xy 130.005344 -406.030549) (xy 129.962593 -406.108455)
			(xy 129.913082 -406.182249) (xy 129.857204 -406.251348) (xy 129.795402 -406.315203) (xy 129.728165 -406.373308)
			(xy 129.656026 -406.425202) (xy 129.579558 -406.470474) (xy 129.499366 -406.508765) (xy 129.416086 -406.539773)
			(xy 129.330378 -406.56325) (xy 129.242922 -406.57901) (xy 129.15441 -406.58693) (xy 129.109978 -406.587452)
			(xy 129.066042 -406.586954) (xy 128.978513 -406.579181) (xy 128.892008 -406.563733) (xy 128.807199 -406.54073)
			(xy 128.765808 -406.525984) (xy 128.7526 -406.529286) (xy 128.74879 -406.531318) (xy 128.747266 -406.53208)
			(xy 128.716232 -406.547215) (xy 128.650586 -406.568609) (xy 128.582398 -406.579446) (xy 128.547876 -406.580086)
			(xy 128.547368 -406.580086) (xy 128.532076 -406.579934) (xy 128.501569 -406.577771) (xy 128.486408 -406.575768)
			(xy 128.474216 -406.57399) (xy 128.46304 -406.5778) (xy 128.457599 -406.579861) (xy 128.447732 -406.586019)
			(xy 128.443482 -406.589992) (xy 128.157478 -406.875996) (xy 128.150874 -406.8826) (xy 128.13411 -406.899364)
			(xy 128.08839 -406.94229) (xy 128.04905 -406.976078) (xy 127.964492 -407.036123) (xy 127.874114 -407.086991)
			(xy 127.82677 -407.108152) (xy 127.818642 -407.111708) (xy 127.817626 -407.112724) (xy 127.806196 -407.127964)
			(xy 127.785342 -407.169409) (xy 127.737022 -407.24862) (xy 127.681554 -407.323) (xy 127.619417 -407.391907)
			(xy 127.551149 -407.454745) (xy 127.477339 -407.510971) (xy 127.398626 -407.560097) (xy 127.31569 -407.601701)
			(xy 127.229249 -407.635422) (xy 127.140049 -407.660968) (xy 127.048862 -407.678119) (xy 126.956477 -407.686726)
			(xy 126.910084 -407.687272) (xy 126.909576 -407.687272) (xy 126.864881 -407.686759) (xy 126.775852 -407.678733)
			(xy 126.687898 -407.662774) (xy 126.601724 -407.639011) (xy 126.518022 -407.607633) (xy 126.477522 -407.58872)
			(xy 126.462536 -407.581608) (xy 126.456694 -407.581608) (xy 126.44882 -407.58364) (xy 126.448312 -407.583894)
			(xy 126.441708 -407.585672) (xy 126.418903 -407.591462) (xy 126.372269 -407.597701) (xy 126.348744 -407.598118)
			(xy 126.347728 -407.598118) (xy 126.319807 -407.597576) (xy 126.264648 -407.588864) (xy 126.211524 -407.571649)
			(xy 126.16174 -407.546354) (xy 126.116513 -407.513597) (xy 126.076954 -407.474183) (xy 126.044032 -407.429077)
			(xy 126.018553 -407.379385) (xy 126.001143 -407.326326) (xy 125.992229 -407.271199) (xy 125.99162 -407.24328)
			(xy 125.99162 -407.241756) (xy 125.99214 -407.214788) (xy 126.000308 -407.161474) (xy 126.007876 -407.135584)
			(xy 126.0094 -407.130758) (xy 126.010416 -407.120852) (xy 126.010416 -407.120598) (xy 125.991665 -407.080271)
			(xy 125.960583 -406.996937) (xy 125.937056 -406.911164) (xy 125.921269 -406.823635) (xy 125.91335 -406.735047)
			(xy 125.91288 -406.690576) (xy 125.91288 -406.30729) (xy 125.913345 -406.265133) (xy 125.920506 -406.181124)
			(xy 125.934724 -406.098017) (xy 125.944884 -406.0571) (xy 125.947932 -406.045416) (xy 125.946408 -406.038558)
			(xy 125.946408 -406.037796) (xy 125.944884 -406.0317) (xy 125.94209 -406.019762) (xy 125.919484 -405.991822)
			(xy 125.916944 -405.989536) (xy 125.909832 -405.982678) (xy 125.857762 -405.959818) (xy 125.857254 -405.959818)
			(xy 125.84811 -405.955246) (xy 125.836172 -405.955246) (xy 125.830147 -405.955471) (xy 125.81846 -405.958412)
			(xy 125.813058 -405.961088) (xy 125.812804 -405.961342) (xy 125.788234 -405.974058) (xy 125.737913 -405.997059)
			(xy 125.71222 -406.007316) (xy 125.685753 -406.017482) (xy 125.631872 -406.035144) (xy 125.604524 -406.042622)
			(xy 125.603762 -406.042876) (xy 125.595888 -406.048464) (xy 125.574564 -406.088592) (xy 125.525638 -406.165175)
			(xy 125.469946 -406.236988) (xy 125.407951 -406.303436) (xy 125.340166 -406.363968) (xy 125.267156 -406.41808)
			(xy 125.189524 -406.465325) (xy 125.107915 -406.50531) (xy 125.023006 -406.537703) (xy 124.935503 -406.562235)
			(xy 124.84613 -406.578704) (xy 124.755629 -406.586972) (xy 124.71019 -406.587452) (xy 124.665608 -406.586945)
			(xy 124.576802 -406.578962) (xy 124.489063 -406.563088) (xy 124.403089 -406.539448) (xy 124.319568 -406.508232)
			(xy 124.279152 -406.489408) (xy 124.274072 -406.486868) (xy 124.262896 -406.484328) (xy 124.246386 -406.484328)
			(xy 124.240036 -406.486106) (xy 124.217652 -406.491678) (xy 124.171914 -406.497669) (xy 124.14885 -406.498044)
			(xy 124.141992 -406.498044) (xy 124.134626 -406.49779) (xy 124.105416 -406.49525) (xy 124.103892 -406.49525)
			(xy 124.096526 -406.494488) (xy 124.07519 -406.502108) (xy 123.691142 -406.885902) (xy 123.659831 -406.916576)
			(xy 123.592678 -406.972919) (xy 123.55703 -406.998424) (xy 123.553474 -407.000964) (xy 123.513088 -407.04135)
			(xy 123.509569 -407.045082) (xy 123.503945 -407.053658) (xy 123.501912 -407.058368) (xy 123.498356 -407.067004)
			(xy 123.498356 -407.078434) (xy 123.497811 -407.088418) (xy 123.490084 -407.106837) (xy 123.48337 -407.114248)
			(xy 123.304046 -407.293572) (xy 123.302014 -407.296112) (xy 123.275028 -407.330625) (xy 123.215902 -407.395283)
			(xy 123.151321 -407.454494) (xy 123.116848 -407.481532) (xy 123.114308 -407.483564) (xy 122.934222 -407.663396)
			(xy 122.926873 -407.670195) (xy 122.90841 -407.677899) (xy 122.898408 -407.678382) (xy 122.6439 -407.678382)
			(xy 122.640598 -407.67889) (xy 122.608106 -407.682862) (xy 122.542775 -407.687053) (xy 122.510042 -407.687272)
			(xy 122.477309 -407.687058) (xy 122.411978 -407.682866) (xy 122.379486 -407.67889) (xy 122.376184 -407.678382)
			(xy 122.121676 -407.678382) (xy 122.111691 -407.67784) (xy 122.093267 -407.670118) (xy 122.085862 -407.663396)
			(xy 122.032776 -407.610564) (xy 122.025363 -407.603887) (xy 122.006928 -407.59632) (xy 121.996962 -407.595832)
			(xy 121.990612 -407.595832) (xy 121.988072 -407.596086) (xy 121.97826 -407.597075) (xy 121.958564 -407.59809)
			(xy 121.948702 -407.598118) (xy 121.947686 -407.598118) (xy 121.919703 -407.597568) (xy 121.864427 -407.588811)
			(xy 121.811201 -407.571516) (xy 121.761336 -407.546107) (xy 121.71606 -407.513211) (xy 121.676487 -407.473637)
			(xy 121.643591 -407.42836) (xy 121.618183 -407.378495) (xy 121.600888 -407.325269) (xy 121.592132 -407.269993)
			(xy 121.591578 -407.24201) (xy 121.591578 -407.241248) (xy 121.591676 -407.230808) (xy 121.592948 -407.209967)
			(xy 121.594118 -407.199592) (xy 121.594118 -407.198576) (xy 121.594552 -407.19352) (xy 121.593653 -407.183412)
			(xy 121.59234 -407.17851) (xy 121.591832 -407.176986) (xy 121.591578 -407.176478) (xy 121.58952 -407.171036)
			(xy 121.583365 -407.161165) (xy 121.579386 -407.15692) (xy 121.536714 -407.114248) (xy 121.52991 -407.106901)
			(xy 121.522194 -407.088438) (xy 121.521728 -407.078434) (xy 121.521728 -406.823926) (xy 121.52122 -406.820624)
			(xy 121.517176 -406.788137) (xy 121.512856 -406.722805) (xy 121.512584 -406.690068) (xy 121.512584 -406.308052)
			(xy 121.512852 -406.275315) (xy 121.517171 -406.209983) (xy 121.52122 -406.177496) (xy 121.521728 -406.174194)
			(xy 121.521728 -405.93518) (xy 121.521399 -405.926575) (xy 121.515692 -405.910339) (xy 121.510552 -405.90343)
			(xy 121.502678 -405.895556) (xy 121.496836 -405.891492) (xy 121.489216 -405.887682) (xy 121.45137 -405.872696)
			(xy 121.451116 -405.872696) (xy 121.425716 -405.86279) (xy 121.425208 -405.86279) (xy 121.42089 -405.860758)
			(xy 121.420128 -405.860504) (xy 121.417334 -405.861012) (xy 121.411383 -405.862197) (xy 121.400223 -405.866953)
			(xy 121.395236 -405.87041) (xy 121.389648 -405.874728) (xy 121.357136 -405.89835) (xy 121.35358 -405.90089)
			(xy 121.313194 -405.941276) (xy 121.30967 -405.945005) (xy 121.304033 -405.953576) (xy 121.302018 -405.958294)
			(xy 121.298462 -405.96693) (xy 121.298462 -405.97836) (xy 121.297931 -405.98835) (xy 121.290223 -406.006789)
			(xy 121.283476 -406.014174) (xy 121.103644 -406.19426) (xy 121.101612 -406.1968) (xy 121.07468 -406.231163)
			(xy 121.015702 -406.295548) (xy 120.951321 -406.354531) (xy 120.916954 -406.381458) (xy 120.914414 -406.38349)
			(xy 120.734328 -406.563322) (xy 120.726983 -406.57013) (xy 120.708519 -406.577848) (xy 120.698514 -406.578308)
			(xy 120.444006 -406.578308) (xy 120.440704 -406.578816) (xy 120.397369 -406.584095) (xy 120.310148 -406.587939)
			(xy 120.222927 -406.584095) (xy 120.179592 -406.578816) (xy 120.17629 -406.578308) (xy 119.921782 -406.578308)
			(xy 119.911796 -406.577767) (xy 119.893368 -406.57005) (xy 119.885968 -406.563322) (xy 119.8372 -406.514554)
			(xy 119.82958 -406.508204) (xy 119.816372 -406.499314) (xy 119.816118 -406.499314) (xy 119.815356 -406.498806)
			(xy 119.810063 -406.496823) (xy 119.798906 -406.495034) (xy 119.793258 -406.49525) (xy 119.78894 -406.495758)
			(xy 119.778815 -406.496842) (xy 119.758482 -406.497983) (xy 119.7483 -406.498044) (xy 119.74195 -406.498044)
			(xy 119.734584 -406.49779) (xy 119.705374 -406.49525) (xy 119.70385 -406.49525) (xy 119.696484 -406.494488)
			(xy 119.675148 -406.502108) (xy 119.2911 -406.885902) (xy 119.259733 -406.916646) (xy 119.19245 -406.973114)
			(xy 119.156734 -406.998678) (xy 119.153178 -407.001218) (xy 119.113046 -407.04135) (xy 119.10636 -407.04876)
			(xy 119.098768 -407.067195) (xy 119.098314 -407.077164) (xy 119.098314 -407.078434) (xy 119.097771 -407.088419)
			(xy 119.09005 -407.106843) (xy 119.083328 -407.114248) (xy 118.903496 -407.294334) (xy 118.901464 -407.296874)
			(xy 118.874529 -407.331234) (xy 118.815546 -407.395614) (xy 118.751161 -407.45459) (xy 118.716806 -407.481532)
			(xy 118.714266 -407.483564) (xy 118.53418 -407.663396) (xy 118.526834 -407.670204) (xy 118.508371 -407.677929)
			(xy 118.498366 -407.678382) (xy 118.243858 -407.678382) (xy 118.240556 -407.67889) (xy 118.208064 -407.682864)
			(xy 118.142733 -407.687059) (xy 118.11 -407.687272) (xy 118.077267 -407.687057) (xy 118.011936 -407.682862)
			(xy 117.979444 -407.67889) (xy 117.976142 -407.678382) (xy 117.721634 -407.678382) (xy 117.711644 -407.67785)
			(xy 117.693205 -407.670143) (xy 117.68582 -407.663396) (xy 117.633242 -407.610818) (xy 117.630315 -407.607929)
			(xy 117.623676 -407.603077) (xy 117.620034 -407.601166) (xy 117.611906 -407.597102) (xy 117.597428 -407.594816)
			(xy 117.590062 -407.595578) (xy 117.553232 -407.598118) (xy 117.54612 -407.598118) (xy 117.518276 -407.597464)
			(xy 117.463299 -407.588566) (xy 117.410377 -407.571218) (xy 117.360801 -407.545843) (xy 117.315779 -407.51306)
			(xy 117.27641 -407.473669) (xy 117.243652 -407.428629) (xy 117.218305 -407.379038) (xy 117.200987 -407.326107)
			(xy 117.19212 -407.271124) (xy 117.191536 -407.24328) (xy 117.191536 -407.242772) (xy 117.191536 -407.241756)
			(xy 117.191536 -407.241502) (xy 117.191611 -407.230871) (xy 117.192879 -407.209647) (xy 117.194076 -407.199084)
			(xy 117.1956 -407.187146) (xy 117.19179 -407.176478) (xy 117.18978 -407.17117) (xy 117.183744 -407.161561)
			(xy 117.179852 -407.157428) (xy 117.136672 -407.114248) (xy 117.129862 -407.106904) (xy 117.122137 -407.08844)
			(xy 117.121686 -407.078434) (xy 117.121686 -406.823926) (xy 117.121178 -406.820624) (xy 117.117205 -406.788132)
			(xy 117.113012 -406.722801) (xy 117.112796 -406.690068) (xy 117.112796 -406.308052) (xy 117.113009 -406.275319)
			(xy 117.117201 -406.209987) (xy 117.121178 -406.177496) (xy 117.121686 -406.174194) (xy 117.121686 -405.937466)
			(xy 117.12145 -405.931095) (xy 117.118227 -405.918765) (xy 117.115336 -405.913082) (xy 117.112288 -405.908002)
			(xy 117.108212 -405.90204) (xy 117.097377 -405.892504) (xy 117.090952 -405.889206) (xy 117.033548 -405.86533)
			(xy 117.033294 -405.86533) (xy 117.026436 -405.862536) (xy 117.011958 -405.861012) (xy 117.005862 -405.862028)
			(xy 116.957094 -405.89835) (xy 116.953538 -405.90089) (xy 116.913152 -405.941276) (xy 116.90963 -405.945006)
			(xy 116.903998 -405.953579) (xy 116.901976 -405.958294) (xy 116.89842 -405.96693) (xy 116.89842 -405.97836)
			(xy 116.897891 -405.988351) (xy 116.890189 -406.006796) (xy 116.883434 -406.014174) (xy 116.703602 -406.19426)
			(xy 116.70157 -406.1968) (xy 116.674637 -406.231162) (xy 116.615657 -406.295545) (xy 116.551275 -406.354526)
			(xy 116.516912 -406.381458) (xy 116.514372 -406.38349) (xy 116.334286 -406.563322) (xy 116.326944 -406.570139)
			(xy 116.30848 -406.577878) (xy 116.298472 -406.578308) (xy 116.043964 -406.578308) (xy 116.040662 -406.578816)
			(xy 115.997327 -406.584095) (xy 115.910106 -406.587939) (xy 115.822885 -406.584095) (xy 115.77955 -406.578816)
			(xy 115.776248 -406.578308) (xy 115.52174 -406.578308) (xy 115.511749 -406.577778) (xy 115.493306 -406.570075)
			(xy 115.485926 -406.563322) (xy 115.437158 -406.514554) (xy 115.429538 -406.508204) (xy 115.41633 -406.499314)
			(xy 115.416076 -406.499314) (xy 115.415314 -406.498806) (xy 115.410022 -406.496817) (xy 115.398864 -406.495015)
			(xy 115.393216 -406.49525) (xy 115.388898 -406.495758) (xy 115.351306 -406.498044) (xy 115.34648 -406.498044)
			(xy 115.318779 -406.497414) (xy 115.264074 -406.488631) (xy 115.211389 -406.471483) (xy 115.161995 -406.446382)
			(xy 115.117084 -406.413935) (xy 115.07774 -406.374924) (xy 115.044912 -406.330292) (xy 115.019391 -406.281113)
			(xy 115.001794 -406.228576) (xy 114.992546 -406.173948) (xy 114.991642 -406.146254) (xy 114.991642 -406.140412)
			(xy 114.99175 -406.130099) (xy 114.993019 -406.109512) (xy 114.994182 -406.099264) (xy 114.994182 -406.098756)
			(xy 114.994805 -406.088093) (xy 114.988381 -406.067748) (xy 114.981736 -406.059386) (xy 114.936778 -406.014174)
			(xy 114.929963 -406.006831) (xy 114.922228 -405.988368) (xy 114.921792 -405.97836) (xy 114.921792 -405.723852)
			(xy 114.921284 -405.72055) (xy 114.917239 -405.688063) (xy 114.912916 -405.622731) (xy 114.912648 -405.589994)
			(xy 114.912648 -405.207978) (xy 114.912918 -405.175241) (xy 114.917242 -405.10991) (xy 114.921284 -405.077422)
			(xy 114.921792 -405.07412) (xy 114.921792 -404.805642) (xy 114.921284 -404.80234) (xy 114.917239 -404.769853)
			(xy 114.912917 -404.704521) (xy 114.912648 -404.671784) (xy 114.912648 -404.290022) (xy 114.912917 -404.257285)
			(xy 114.917238 -404.191953) (xy 114.921284 -404.159466) (xy 114.921792 -404.156164) (xy 114.921792 -403.901656)
			(xy 114.922319 -403.891664) (xy 114.930018 -403.873216) (xy 114.936778 -403.865842) (xy 114.957352 -403.845268)
			(xy 114.96152 -403.840914) (xy 114.967811 -403.830638) (xy 114.969798 -403.824948) (xy 114.973354 -403.813518)
			(xy 114.971322 -403.801326) (xy 114.968949 -403.785942) (xy 114.966404 -403.754915) (xy 114.966242 -403.73935)
			(xy 114.966242 -403.738588) (xy 114.96673 -403.710986) (xy 114.974683 -403.656357) (xy 114.990422 -403.603444)
			(xy 115.013618 -403.553349) (xy 115.043787 -403.507118) (xy 115.080301 -403.465715) (xy 115.122398 -403.430002)
			(xy 115.145566 -403.414992) (xy 115.149376 -403.412706) (xy 115.179856 -403.395942) (xy 115.201786 -403.385615)
			(xy 115.247667 -403.369973) (xy 115.29516 -403.360274) (xy 115.319302 -403.358096) (xy 115.342924 -403.35708)
			(xy 115.346734 -403.35708) (xy 115.348258 -403.35708) (xy 115.348766 -403.35708) (xy 115.359688 -403.357334)
			(xy 115.361212 -403.357334) (xy 115.370325 -403.356956) (xy 115.387398 -403.350576) (xy 115.401161 -403.338627)
			(xy 115.409875 -403.322619) (xy 115.411504 -403.313646) (xy 115.413028 -403.302978) (xy 115.407694 -403.281388)
			(xy 115.404138 -403.275038) (xy 115.403884 -403.274784) (xy 115.386848 -403.243387) (xy 115.359729 -403.177302)
			(xy 115.340928 -403.108388) (xy 115.330732 -403.037686) (xy 115.329462 -403.001988) (xy 115.329462 -402.99132)
			(xy 115.329208 -402.985732) (xy 115.330022 -402.950034) (xy 115.339307 -402.879235) (xy 115.3572 -402.810107)
			(xy 115.383431 -402.743694) (xy 115.417605 -402.680997) (xy 115.459206 -402.622961) (xy 115.507607 -402.570462)
			(xy 115.562078 -402.524292) (xy 115.621798 -402.485147) (xy 115.653566 -402.468842) (xy 115.661186 -402.465032)
			(xy 115.690396 -402.419312) (xy 115.690396 -402.35378) (xy 115.689904 -402.343775) (xy 115.682241 -402.325291)
			(xy 115.668089 -402.311145) (xy 115.649601 -402.303491) (xy 115.639596 -402.30298) (xy 115.551966 -402.30298)
			(xy 115.541811 -402.302479) (xy 115.523051 -402.294699) (xy 115.508692 -402.280336) (xy 115.500918 -402.261573)
			(xy 115.500404 -402.251418) (xy 115.500404 -401.96897) (xy 115.500305 -401.965089) (xy 115.499035 -401.957431)
			(xy 115.497864 -401.95373) (xy 115.493038 -401.938998) (xy 115.490244 -401.934426) (xy 115.474623 -401.906551)
			(xy 115.450026 -401.847574) (xy 115.43338 -401.78588) (xy 115.424973 -401.722536) (xy 115.424458 -401.690586)
			(xy 115.424458 -401.690078) (xy 115.424969 -401.658097) (xy 115.433364 -401.594688) (xy 115.450008 -401.53293)
			(xy 115.474612 -401.473889) (xy 115.490244 -401.445984) (xy 115.492784 -401.441666) (xy 115.497864 -401.426172)
			(xy 115.498994 -401.422461) (xy 115.500274 -401.414809) (xy 115.500404 -401.410932) (xy 115.500404 -400.668998)
			(xy 115.500299 -400.665118) (xy 115.499018 -400.657464) (xy 115.497864 -400.653758) (xy 115.493038 -400.639026)
			(xy 115.490244 -400.634454) (xy 115.474621 -400.606579) (xy 115.450021 -400.547603) (xy 115.433371 -400.485909)
			(xy 115.42496 -400.422564) (xy 115.424458 -400.390614) (xy 115.424458 -400.390106) (xy 115.424967 -400.358124)
			(xy 115.433359 -400.294714) (xy 115.45 -400.232954) (xy 115.474601 -400.173911) (xy 115.490244 -400.146012)
			(xy 115.492784 -400.141694) (xy 115.497864 -400.1262) (xy 115.498989 -400.122488) (xy 115.500258 -400.114836)
			(xy 115.500404 -400.11096) (xy 115.500404 -399.828766) (xy 115.500905 -399.81861) (xy 115.508684 -399.799847)
			(xy 115.523047 -399.785484) (xy 115.54181 -399.777705) (xy 115.551966 -399.777204) (xy 115.639596 -399.777204)
			(xy 115.649604 -399.776717) (xy 115.668098 -399.769058) (xy 115.682253 -399.754905) (xy 115.689915 -399.736412)
			(xy 115.690396 -399.726404) (xy 115.690396 -399.660872) (xy 115.66144 -399.615152) (xy 115.630448 -399.59993)
			(xy 115.571984 -399.563193) (xy 115.518285 -399.519785) (xy 115.47011 -399.470319) (xy 115.428137 -399.415492)
			(xy 115.392957 -399.356077) (xy 115.365067 -399.292911) (xy 115.34486 -399.226886) (xy 115.332621 -399.15893)
			(xy 115.328521 -399.090003) (xy 115.33262 -399.021076) (xy 115.344859 -398.95312) (xy 115.365065 -398.887094)
			(xy 115.392954 -398.823928) (xy 115.428133 -398.764513) (xy 115.470106 -398.709685) (xy 115.518281 -398.660219)
			(xy 115.571979 -398.616811) (xy 115.630443 -398.580073) (xy 115.66144 -398.564862) (xy 115.690396 -398.519142)
			(xy 115.690396 -398.453864) (xy 115.689902 -398.443861) (xy 115.682236 -398.425383) (xy 115.668084 -398.411242)
			(xy 115.649599 -398.403591) (xy 115.639596 -398.403064) (xy 115.551966 -398.403064) (xy 115.541813 -398.402563)
			(xy 115.523055 -398.394782) (xy 115.5087 -398.380418) (xy 115.500931 -398.361656) (xy 115.500404 -398.351502)
			(xy 115.500404 -398.069054) (xy 115.500304 -398.065173) (xy 115.499031 -398.057516) (xy 115.497864 -398.053814)
			(xy 115.493038 -398.039082) (xy 115.490244 -398.03451) (xy 115.474624 -398.006634) (xy 115.450029 -397.947658)
			(xy 115.433385 -397.885964) (xy 115.42498 -397.82262) (xy 115.424458 -397.79067) (xy 115.424458 -397.790162)
			(xy 115.42497 -397.758181) (xy 115.433367 -397.694773) (xy 115.450013 -397.633016) (xy 115.474619 -397.573976)
			(xy 115.490244 -397.546068) (xy 115.492784 -397.54175) (xy 115.497864 -397.526256) (xy 115.498993 -397.522545)
			(xy 115.50027 -397.514893) (xy 115.500404 -397.511016) (xy 115.500404 -396.769082) (xy 115.500306 -396.765201)
			(xy 115.499037 -396.757542) (xy 115.497864 -396.753842) (xy 115.493038 -396.73911) (xy 115.490244 -396.734538)
			(xy 115.474622 -396.706663) (xy 115.450024 -396.647687) (xy 115.433376 -396.585993) (xy 115.424967 -396.522648)
			(xy 115.424458 -396.490698) (xy 115.424458 -396.49019) (xy 115.424968 -396.458209) (xy 115.433362 -396.3948)
			(xy 115.450005 -396.33304) (xy 115.474608 -396.273999) (xy 115.490244 -396.246096) (xy 115.492784 -396.241778)
			(xy 115.497864 -396.226284) (xy 115.498995 -396.222573) (xy 115.500276 -396.214921) (xy 115.500404 -396.211044)
			(xy 115.500404 -395.92885) (xy 115.500821 -395.918669) (xy 115.508595 -395.899852) (xy 115.522981 -395.885443)
			(xy 115.541786 -395.877637) (xy 115.551966 -395.877288) (xy 115.714018 -395.877288) (xy 115.724159 -395.876844)
			(xy 115.742864 -395.868999) (xy 115.757083 -395.854535) (xy 115.761262 -395.845284) (xy 115.765326 -395.83487)
			(xy 115.773962 -395.813788) (xy 115.777537 -395.803833) (xy 115.777148 -395.782707) (xy 115.7732 -395.772894)
			(xy 115.76685 -395.759432) (xy 115.758722 -395.753844) (xy 115.752118 -395.749272) (xy 115.741704 -395.74597)
			(xy 115.74145 -395.745716) (xy 115.70935 -395.735482) (xy 115.647566 -395.708609) (xy 115.589309 -395.67476)
			(xy 115.535365 -395.634391) (xy 115.48646 -395.588046) (xy 115.443252 -395.536349) (xy 115.406322 -395.479995)
			(xy 115.376168 -395.419744) (xy 115.353196 -395.356405) (xy 115.337714 -395.290831) (xy 115.329931 -395.223906)
			(xy 115.329462 -395.190218) (xy 115.32997 -395.155126) (xy 115.338428 -395.085453) (xy 115.355222 -395.017307)
			(xy 115.380109 -394.951683) (xy 115.412724 -394.889537) (xy 115.452592 -394.831776) (xy 115.499133 -394.779241)
			(xy 115.551666 -394.7327) (xy 115.609427 -394.69283) (xy 115.671572 -394.660214) (xy 115.737196 -394.635326)
			(xy 115.805341 -394.61853) (xy 115.875014 -394.610071) (xy 115.910106 -394.609574) (xy 115.910868 -394.609574)
			(xy 115.944777 -394.610055) (xy 116.012133 -394.617951) (xy 116.045234 -394.625322) (xy 116.048028 -394.626084)
			(xy 116.053616 -394.626846) (xy 116.064702 -394.627687) (xy 116.08586 -394.62094) (xy 116.102209 -394.60591)
			(xy 116.106956 -394.595858) (xy 116.415312 -393.852654) (xy 116.45646 -393.75334) (xy 116.45955 -393.746578)
			(xy 116.468976 -393.73509) (xy 116.475002 -393.730734) (xy 116.69522 -393.583668) (xy 116.695728 -393.58316)
			(xy 116.711476 -393.572492) (xy 116.865146 -393.469622) (xy 116.873178 -393.463664) (xy 116.884289 -393.447061)
			(xy 116.886736 -393.437364) (xy 116.9162 -393.28979) (xy 116.916708 -393.288774) (xy 117.225064 -393.08278)
			(xy 117.22608 -393.082272) (xy 117.238846 -393.073019) (xy 117.264885 -393.055235) (xy 117.27815 -393.046712)
			(xy 117.279166 -393.046204) (xy 117.53723 -392.873992) (xy 117.62486 -392.815572) (xy 117.64264 -392.803888)
			(xy 117.643148 -392.803634) (xy 117.854984 -392.661902) (xy 117.916198 -392.621008) (xy 117.964458 -392.58875)
			(xy 118.183914 -392.442192) (xy 118.184422 -392.441938) (xy 118.194074 -392.435334) (xy 118.194328 -392.435334)
			(xy 118.222268 -392.416538) (xy 118.222522 -392.41603) (xy 118.525544 -392.213592) (xy 118.525798 -392.213592)
			(xy 118.561866 -392.189462) (xy 118.570756 -392.18362) (xy 118.57101 -392.183366) (xy 118.902226 -391.961878)
			(xy 118.90248 -391.961878) (xy 119.132604 -391.808462) (xy 119.132858 -391.808208) (xy 119.160036 -391.78992)
			(xy 119.16029 -391.789412) (xy 119.463312 -391.586974) (xy 119.463566 -391.586974) (xy 119.499634 -391.562844)
			(xy 119.508524 -391.557002) (xy 119.508778 -391.556748) (xy 119.839994 -391.33526) (xy 119.840248 -391.33526)
			(xy 120.071134 -391.181336) (xy 120.098312 -391.163048) (xy 120.098312 -391.162032) (xy 120.412764 -390.952736)
			(xy 120.437402 -390.936226) (xy 120.446292 -390.930384) (xy 120.446546 -390.93013) (xy 120.668542 -390.78154)
			(xy 120.668542 -390.781286) (xy 120.743472 -390.731502) (xy 120.74398 -390.731502) (xy 120.777762 -390.708642)
			(xy 120.778016 -390.708642) (xy 120.994678 -390.564116) (xy 120.995186 -390.563862) (xy 121.007378 -390.55548)
			(xy 121.007632 -390.55548) (xy 121.37517 -390.309608) (xy 121.38406 -390.303766) (xy 121.384314 -390.303512)
			(xy 121.698766 -390.0932) (xy 121.70735 -390.088043) (xy 121.726963 -390.084105) (xy 121.736866 -390.08558)
			(xy 121.863866 -390.111234) (xy 121.871934 -390.112476) (xy 121.888116 -390.110395) (xy 121.895616 -390.10717)
			(xy 121.90222 -390.104122) (xy 121.962418 -390.06399) (xy 122.066558 -389.994394) (xy 122.075448 -389.989568)
			(xy 122.152664 -389.957564) (xy 122.152918 -389.957564) (xy 122.936762 -389.632698) (xy 131.328668 -386.155946)
			(xy 131.33324 -386.153914) (xy 132.491226 -385.386326) (xy 132.872226 -385.13258) (xy 132.879084 -385.126992)
			(xy 132.892292 -385.113784) (xy 132.954268 -385.052316) (xy 132.959376 -385.046282) (xy 132.965984 -385.031929)
			(xy 132.967222 -385.024122) (xy 132.967476 -385.018026) (xy 132.967476 -384.997198) (xy 132.964428 -384.988816)
			(xy 132.951646 -384.951957) (xy 132.934952 -384.875751) (xy 132.931154 -384.836924) (xy 132.930138 -384.823208)
			(xy 132.929122 -384.790188) (xy 132.92957 -384.75744) (xy 132.936932 -384.69236) (xy 132.951562 -384.628519)
			(xy 132.973273 -384.566727) (xy 133.001792 -384.507767) (xy 133.036756 -384.452385) (xy 133.077722 -384.401283)
			(xy 133.124173 -384.355109) (xy 133.175518 -384.314448) (xy 133.231108 -384.279815) (xy 133.290237 -384.251649)
			(xy 133.321044 -384.240532) (xy 133.327902 -384.238246) (xy 133.33349 -384.234436) (xy 133.336461 -384.232235)
			(xy 133.341817 -384.227137) (xy 133.344158 -384.224276) (xy 133.35889 -384.205734) (xy 133.359144 -384.20548)
			(xy 133.363917 -384.198966) (xy 133.369484 -384.183816) (xy 133.370066 -384.175762) (xy 133.37032 -384.15595)
			(xy 133.37032 -384.155442) (xy 133.370574 -384.130296) (xy 133.370209 -384.115219) (xy 133.36176 -384.086283)
			(xy 133.345241 -384.061069) (xy 133.322088 -384.041766) (xy 133.294314 -384.030053) (xy 133.26433 -384.026947)
			(xy 133.234744 -384.032718) (xy 133.208126 -384.046864) (xy 133.197092 -384.057144) (xy 133.190234 -384.064002)
			(xy 133.187694 -384.067558) (xy 133.162103 -384.103426) (xy 133.105503 -384.170962) (xy 133.074664 -384.202432)
			(xy 132.491226 -384.78587) (xy 132.459913 -384.816542) (xy 132.392757 -384.872881) (xy 132.357114 -384.898392)
			(xy 132.353558 -384.900932) (xy 132.313172 -384.941318) (xy 132.309652 -384.945049) (xy 132.304024 -384.953624)
			(xy 132.301996 -384.958336) (xy 132.29844 -384.966972) (xy 132.29844 -384.978402) (xy 132.297901 -384.988388)
			(xy 132.29018 -385.006814) (xy 132.283454 -385.014216) (xy 132.103622 -385.194302) (xy 132.10159 -385.196842)
			(xy 132.074656 -385.231204) (xy 132.015676 -385.295586) (xy 131.951293 -385.354565) (xy 131.916932 -385.3815)
			(xy 131.914392 -385.383532) (xy 131.734306 -385.563364) (xy 131.726963 -385.570179) (xy 131.7085 -385.57792)
			(xy 131.698492 -385.57835) (xy 131.443984 -385.57835) (xy 131.440682 -385.578858) (xy 131.40819 -385.582833)
			(xy 131.342859 -385.58703) (xy 131.310126 -385.58724) (xy 131.277393 -385.587026) (xy 131.212062 -385.582832)
			(xy 131.17957 -385.578858) (xy 131.176268 -385.57835) (xy 130.92176 -385.57835) (xy 130.911777 -385.577804)
			(xy 130.89336 -385.570075) (xy 130.885946 -385.563364) (xy 130.83286 -385.510532) (xy 130.825488 -385.503793)
			(xy 130.807027 -385.49621) (xy 130.797046 -385.4958) (xy 130.790696 -385.4958) (xy 130.788156 -385.496054)
			(xy 130.778344 -385.497042) (xy 130.758648 -385.498057) (xy 130.748786 -385.498086) (xy 130.74777 -385.498086)
			(xy 130.719789 -385.497535) (xy 130.664517 -385.488776) (xy 130.611295 -385.471478) (xy 130.561435 -385.446068)
			(xy 130.516163 -385.413171) (xy 130.476595 -385.373597) (xy 130.443704 -385.328321) (xy 130.418302 -385.278457)
			(xy 130.401012 -385.225233) (xy 130.392261 -385.169959) (xy 130.391662 -385.141978) (xy 130.391662 -385.141216)
			(xy 130.391758 -385.130776) (xy 130.393026 -385.109934) (xy 130.394202 -385.09956) (xy 130.394202 -385.098544)
			(xy 130.394642 -385.093487) (xy 130.393757 -385.083376) (xy 130.392424 -385.078478) (xy 130.391916 -385.076954)
			(xy 130.391662 -385.076446) (xy 130.389604 -385.071003) (xy 130.383452 -385.06113) (xy 130.37947 -385.056888)
			(xy 130.336798 -385.014216) (xy 130.330001 -385.006866) (xy 130.322299 -384.988403) (xy 130.321812 -384.978402)
			(xy 130.321812 -384.723894) (xy 130.321304 -384.720592) (xy 130.317257 -384.688105) (xy 130.312933 -384.622773)
			(xy 130.312668 -384.590036) (xy 130.312668 -384.20802) (xy 130.312937 -384.175283) (xy 130.317258 -384.109951)
			(xy 130.321304 -384.077464) (xy 130.321812 -384.074162) (xy 130.321812 -383.83591) (xy 130.321468 -383.827217)
			(xy 130.315632 -383.810842) (xy 130.310382 -383.803906) (xy 130.30708 -383.800096) (xy 130.30581 -383.798826)
			(xy 130.29819 -383.79146) (xy 130.237484 -383.766822) (xy 130.233928 -383.765552) (xy 130.227391 -383.76299)
			(xy 130.213472 -383.761193) (xy 130.206496 -383.761996) (xy 130.189986 -383.774442) (xy 130.156458 -383.798826)
			(xy 130.152902 -383.80162) (xy 130.113024 -383.841498) (xy 130.106337 -383.848906) (xy 130.09875 -383.867343)
			(xy 130.098292 -383.877312) (xy 130.098292 -383.878582) (xy 130.097758 -383.888571) (xy 130.090048 -383.907007)
			(xy 130.083306 -383.914396) (xy 129.903474 -384.094482) (xy 129.901442 -384.097022) (xy 129.874508 -384.131383)
			(xy 129.815526 -384.195764) (xy 129.751142 -384.254742) (xy 129.716784 -384.28168) (xy 129.714244 -384.283712)
			(xy 129.534158 -384.463544) (xy 129.526813 -384.470354) (xy 129.50835 -384.47808) (xy 129.498344 -384.47853)
			(xy 129.243836 -384.47853) (xy 129.240534 -384.479038) (xy 129.208042 -384.483011) (xy 129.142711 -384.487205)
			(xy 129.109978 -384.48742) (xy 129.077245 -384.487204) (xy 129.011914 -384.483007) (xy 128.979422 -384.479038)
			(xy 128.97612 -384.47853) (xy 128.721612 -384.47853) (xy 128.711623 -384.477996) (xy 128.693185 -384.470289)
			(xy 128.685798 -384.463544) (xy 128.632966 -384.410712) (xy 128.630039 -384.407822) (xy 128.623401 -384.402968)
			(xy 128.619758 -384.40106) (xy 128.61163 -384.396996) (xy 128.596898 -384.39471) (xy 128.594866 -384.394964)
			(xy 128.582983 -384.396428) (xy 128.559087 -384.397953) (xy 128.547114 -384.398012) (xy 128.544828 -384.398012)
			(xy 128.508252 -384.39598) (xy 128.496822 -384.39471) (xy 128.475232 -384.402076) (xy 128.091184 -384.78587)
			(xy 128.059873 -384.816543) (xy 127.992719 -384.872886) (xy 127.957072 -384.898392) (xy 127.953516 -384.900932)
			(xy 127.91313 -384.941318) (xy 127.909606 -384.945047) (xy 127.903973 -384.95362) (xy 127.901954 -384.958336)
			(xy 127.898398 -384.966972) (xy 127.898398 -384.978402) (xy 127.89786 -384.988389) (xy 127.890146 -385.006821)
			(xy 127.883412 -385.014216) (xy 127.70358 -385.194302) (xy 127.701548 -385.196842) (xy 127.674613 -385.231203)
			(xy 127.615631 -385.295583) (xy 127.551247 -385.35456) (xy 127.51689 -385.3815) (xy 127.51435 -385.383532)
			(xy 127.334264 -385.563364) (xy 127.326919 -385.570173) (xy 127.308456 -385.577898) (xy 127.29845 -385.57835)
			(xy 127.043942 -385.57835) (xy 127.04064 -385.578858) (xy 127.008148 -385.582831) (xy 126.942817 -385.587026)
			(xy 126.910084 -385.58724) (xy 126.877351 -385.587025) (xy 126.81202 -385.582828) (xy 126.779528 -385.578858)
			(xy 126.776226 -385.57835) (xy 126.521718 -385.57835) (xy 126.51173 -385.577814) (xy 126.493298 -385.5701)
			(xy 126.485904 -385.563364) (xy 126.433326 -385.510786) (xy 126.430397 -385.5079) (xy 126.423756 -385.503052)
			(xy 126.420118 -385.501134) (xy 126.41199 -385.49707) (xy 126.397512 -385.494784) (xy 126.390146 -385.495546)
			(xy 126.353316 -385.498086) (xy 126.346204 -385.498086) (xy 126.318362 -385.497431) (xy 126.263388 -385.488531)
			(xy 126.210471 -385.471181) (xy 126.160899 -385.445805) (xy 126.115882 -385.413021) (xy 126.076518 -385.373629)
			(xy 126.043765 -385.328589) (xy 126.018424 -385.279) (xy 126.001111 -385.22607) (xy 125.992249 -385.171091)
			(xy 125.99162 -385.143248) (xy 125.99162 -385.14274) (xy 125.99162 -385.141724) (xy 125.99162 -385.14147)
			(xy 125.991696 -385.130839) (xy 125.992966 -385.109616) (xy 125.99416 -385.099052) (xy 125.995684 -385.087114)
			(xy 125.991874 -385.076446) (xy 125.989873 -385.071132) (xy 125.983853 -385.061506) (xy 125.979936 -385.057396)
			(xy 125.936756 -385.014216) (xy 125.929953 -385.006869) (xy 125.922242 -384.988405) (xy 125.92177 -384.978402)
			(xy 125.92177 -384.723894) (xy 125.921262 -384.720592) (xy 125.91729 -384.6881) (xy 125.913099 -384.622769)
			(xy 125.91288 -384.590036) (xy 125.91288 -384.20802) (xy 125.913094 -384.175287) (xy 125.917288 -384.109956)
			(xy 125.921262 -384.077464) (xy 125.92177 -384.074162) (xy 125.92177 -383.83591) (xy 125.921516 -383.8321)
			(xy 125.920512 -383.823116) (xy 125.913051 -383.806665) (xy 125.900338 -383.79383) (xy 125.892306 -383.789682)
			(xy 125.846332 -383.770886) (xy 125.845824 -383.770886) (xy 125.833886 -383.765806) (xy 125.827287 -383.763224)
			(xy 125.813237 -383.761418) (xy 125.8062 -383.76225) (xy 125.78969 -383.77495) (xy 125.757178 -383.798572)
			(xy 125.753622 -383.801112) (xy 125.713236 -383.841498) (xy 125.709711 -383.845226) (xy 125.704074 -383.853797)
			(xy 125.70206 -383.858516) (xy 125.698504 -383.867152) (xy 125.698504 -383.878582) (xy 125.69797 -383.888571)
			(xy 125.690261 -383.907008) (xy 125.683518 -383.914396) (xy 125.504194 -384.09372) (xy 125.502162 -384.09626)
			(xy 125.475178 -384.130775) (xy 125.416056 -384.195438) (xy 125.351478 -384.254654) (xy 125.316996 -384.28168)
			(xy 125.314456 -384.283712) (xy 125.13437 -384.463544) (xy 125.127026 -384.470356) (xy 125.108563 -384.478086)
			(xy 125.098556 -384.47853) (xy 124.844048 -384.47853) (xy 124.840746 -384.479038) (xy 124.808254 -384.483011)
			(xy 124.742923 -384.487206) (xy 124.71019 -384.48742) (xy 124.677457 -384.487205) (xy 124.612126 -384.483009)
			(xy 124.579634 -384.479038) (xy 124.576332 -384.47853) (xy 124.321824 -384.47853) (xy 124.311834 -384.477998)
			(xy 124.293393 -384.470294) (xy 124.28601 -384.463544) (xy 124.233178 -384.410712) (xy 124.230248 -384.407827)
			(xy 124.223605 -384.402983) (xy 124.21997 -384.40106) (xy 124.211842 -384.396996) (xy 124.197364 -384.39471)
			(xy 124.19203 -384.395218) (xy 124.190252 -384.395472) (xy 124.180003 -384.396625) (xy 124.159417 -384.397893)
			(xy 124.149104 -384.398012) (xy 124.146564 -384.398012) (xy 124.136957 -384.397953) (xy 124.11777 -384.396937)
			(xy 124.10821 -384.39598) (xy 124.09678 -384.39471) (xy 124.07519 -384.402076) (xy 123.691142 -384.78587)
			(xy 123.65983 -384.816542) (xy 123.592674 -384.872882) (xy 123.55703 -384.898392) (xy 123.553474 -384.900932)
			(xy 123.513088 -384.941318) (xy 123.509567 -384.945048) (xy 123.503938 -384.953623) (xy 123.501912 -384.958336)
			(xy 123.498356 -384.966972) (xy 123.498356 -384.978402) (xy 123.497817 -384.988388) (xy 123.490098 -385.006816)
			(xy 123.48337 -385.014216) (xy 123.303538 -385.194302) (xy 123.301506 -385.196842) (xy 123.274572 -385.231204)
			(xy 123.215593 -385.295587) (xy 123.15121 -385.354567) (xy 123.116848 -385.3815) (xy 123.114308 -385.383532)
			(xy 122.934222 -385.563364) (xy 122.926874 -385.570166) (xy 122.908411 -385.577876) (xy 122.898408 -385.57835)
			(xy 122.6439 -385.57835) (xy 122.640598 -385.578858) (xy 122.608106 -385.58283) (xy 122.542775 -385.587021)
			(xy 122.510042 -385.58724) (xy 122.477309 -385.587026) (xy 122.411978 -385.582834) (xy 122.379486 -385.578858)
			(xy 122.376184 -385.57835) (xy 122.121676 -385.57835) (xy 122.111692 -385.577807) (xy 122.093271 -385.570082)
			(xy 122.085862 -385.563364) (xy 122.032776 -385.510532) (xy 122.025405 -385.50379) (xy 122.006943 -385.496202)
			(xy 121.996962 -385.4958) (xy 121.990612 -385.4958) (xy 121.988072 -385.496054) (xy 121.97826 -385.497042)
			(xy 121.958564 -385.498058) (xy 121.948702 -385.498086) (xy 121.947686 -385.498086) (xy 121.919702 -385.497564)
			(xy 121.864423 -385.488807) (xy 121.811195 -385.471509) (xy 121.761329 -385.446098) (xy 121.716051 -385.413199)
			(xy 121.676478 -385.373621) (xy 121.643583 -385.328341) (xy 121.618177 -385.278471) (xy 121.600885 -385.225242)
			(xy 121.592133 -385.169962) (xy 121.591578 -385.141978) (xy 121.591578 -385.141216) (xy 121.591674 -385.130776)
			(xy 121.592942 -385.109934) (xy 121.594118 -385.09956) (xy 121.594118 -385.098544) (xy 121.594558 -385.093487)
			(xy 121.593673 -385.083376) (xy 121.59234 -385.078478) (xy 121.591832 -385.076954) (xy 121.591578 -385.076446)
			(xy 121.589517 -385.071006) (xy 121.583358 -385.061139) (xy 121.579386 -385.056888) (xy 121.536714 -385.014216)
			(xy 121.529915 -385.006867) (xy 121.522211 -384.988404) (xy 121.521728 -384.978402) (xy 121.521728 -384.723894)
			(xy 121.52122 -384.720592) (xy 121.517173 -384.688105) (xy 121.512849 -384.622773) (xy 121.512584 -384.590036)
			(xy 121.512584 -384.20802) (xy 121.512853 -384.175283) (xy 121.517174 -384.109951) (xy 121.52122 -384.077464)
			(xy 121.521728 -384.074162) (xy 121.521728 -383.83591) (xy 121.521338 -383.826351) (xy 121.514327 -383.808565)
			(xy 121.501252 -383.794618) (xy 121.492772 -383.79019) (xy 121.473976 -383.782062) (xy 121.473468 -383.782062)
			(xy 121.439178 -383.768092) (xy 121.43867 -383.768092) (xy 121.43232 -383.765552) (xy 121.410222 -383.765552)
			(xy 121.401078 -383.766314) (xy 121.388378 -383.775966) (xy 121.357136 -383.798572) (xy 121.35358 -383.801112)
			(xy 121.313194 -383.841498) (xy 121.309671 -383.845227) (xy 121.304038 -383.8538) (xy 121.302018 -383.858516)
			(xy 121.298462 -383.867152) (xy 121.298462 -383.878582) (xy 121.297927 -383.88857) (xy 121.290214 -383.907003)
			(xy 121.283476 -383.914396) (xy 121.103644 -384.094482) (xy 121.101612 -384.097022) (xy 121.074679 -384.131385)
			(xy 121.0157 -384.195769) (xy 120.951319 -384.25475) (xy 120.916954 -384.28168) (xy 120.914414 -384.283712)
			(xy 120.734328 -384.463544) (xy 120.726982 -384.47035) (xy 120.708518 -384.478065) (xy 120.698514 -384.47853)
			(xy 120.444006 -384.47853) (xy 120.440704 -384.479038) (xy 120.408212 -384.48301) (xy 120.342881 -384.487202)
			(xy 120.310148 -384.48742) (xy 120.277415 -384.487207) (xy 120.212083 -384.483014) (xy 120.179592 -384.479038)
			(xy 120.17629 -384.47853) (xy 119.921782 -384.47853) (xy 119.911795 -384.47799) (xy 119.893365 -384.470276)
			(xy 119.885968 -384.463544) (xy 119.833136 -384.410712) (xy 119.830208 -384.407824) (xy 119.823569 -384.402973)
			(xy 119.819928 -384.40106) (xy 119.8118 -384.396996) (xy 119.797322 -384.39471) (xy 119.791988 -384.395218)
			(xy 119.79021 -384.395472) (xy 119.779961 -384.396626) (xy 119.759375 -384.397898) (xy 119.749062 -384.398012)
			(xy 119.746522 -384.398012) (xy 119.736915 -384.397952) (xy 119.717728 -384.396933) (xy 119.708168 -384.39598)
			(xy 119.696738 -384.39471) (xy 119.675148 -384.402076) (xy 119.2911 -384.78587) (xy 119.259789 -384.816544)
			(xy 119.192636 -384.872887) (xy 119.156988 -384.898392) (xy 119.153432 -384.900932) (xy 119.113046 -384.941318)
			(xy 119.109527 -384.94505) (xy 119.103902 -384.953626) (xy 119.10187 -384.958336) (xy 119.098314 -384.966972)
			(xy 119.098314 -384.978402) (xy 119.097776 -384.98839) (xy 119.090064 -385.006822) (xy 119.083328 -385.014216)
			(xy 118.903496 -385.194302) (xy 118.901464 -385.196842) (xy 118.87453 -385.231203) (xy 118.815548 -385.295584)
			(xy 118.751164 -385.354562) (xy 118.716806 -385.3815) (xy 118.714266 -385.383532) (xy 118.53418 -385.563364)
			(xy 118.526835 -385.570175) (xy 118.508373 -385.577906) (xy 118.498366 -385.57835) (xy 118.243858 -385.57835)
			(xy 118.240556 -385.578858) (xy 118.208064 -385.582832) (xy 118.142733 -385.587027) (xy 118.11 -385.58724)
			(xy 118.077267 -385.587025) (xy 118.011936 -385.58283) (xy 117.979444 -385.578858) (xy 117.976142 -385.57835)
			(xy 117.721634 -385.57835) (xy 117.711645 -385.577817) (xy 117.693209 -385.570107) (xy 117.68582 -385.563364)
			(xy 117.633242 -385.510786) (xy 117.630314 -385.507899) (xy 117.623673 -385.503049) (xy 117.620034 -385.501134)
			(xy 117.611906 -385.49707) (xy 117.597428 -385.494784) (xy 117.590062 -385.495546) (xy 117.553232 -385.498086)
			(xy 117.54612 -385.498086) (xy 117.518277 -385.497432) (xy 117.463302 -385.488534) (xy 117.410382 -385.471185)
			(xy 117.360808 -385.44581) (xy 117.315789 -385.413027) (xy 117.276422 -385.373634) (xy 117.243668 -385.328594)
			(xy 117.218325 -385.279004) (xy 117.201011 -385.226073) (xy 117.192149 -385.171091) (xy 117.191536 -385.143248)
			(xy 117.191536 -385.14274) (xy 117.191536 -385.141724) (xy 117.191536 -385.14147) (xy 117.191612 -385.130839)
			(xy 117.192882 -385.109616) (xy 117.194076 -385.099052) (xy 117.1956 -385.087114) (xy 117.19179 -385.076446)
			(xy 117.189786 -385.071134) (xy 117.183759 -385.061516) (xy 117.179852 -385.057396) (xy 117.136672 -385.014216)
			(xy 117.129867 -385.00687) (xy 117.122154 -384.988406) (xy 117.121686 -384.978402) (xy 117.121686 -384.723894)
			(xy 117.121178 -384.720592) (xy 117.117206 -384.6881) (xy 117.113015 -384.622769) (xy 117.112796 -384.590036)
			(xy 117.112796 -384.20802) (xy 117.11301 -384.175287) (xy 117.117205 -384.109956) (xy 117.121178 -384.077464)
			(xy 117.121686 -384.074162) (xy 117.121686 -383.835402) (xy 117.12126 -383.825653) (xy 117.113978 -383.807568)
			(xy 117.100441 -383.793539) (xy 117.091714 -383.789174) (xy 117.04955 -383.772156) (xy 117.049042 -383.772156)
			(xy 117.03304 -383.765552) (xy 117.026593 -383.763163) (xy 117.012936 -383.761628) (xy 117.006116 -383.762504)
			(xy 116.989606 -383.77495) (xy 116.957094 -383.798572) (xy 116.953538 -383.801112) (xy 116.913152 -383.841498)
			(xy 116.909631 -383.845229) (xy 116.904002 -383.853803) (xy 116.901976 -383.858516) (xy 116.89842 -383.867152)
			(xy 116.89842 -383.878582) (xy 116.897887 -383.888571) (xy 116.89018 -383.90701) (xy 116.883434 -383.914396)
			(xy 116.70411 -384.09372) (xy 116.702078 -384.09626) (xy 116.674982 -384.130878) (xy 116.615613 -384.195723)
			(xy 116.550767 -384.255091) (xy 116.51615 -384.282188) (xy 116.51361 -384.28422) (xy 116.334286 -384.463544)
			(xy 116.326943 -384.470359) (xy 116.30848 -384.478095) (xy 116.298472 -384.47853) (xy 116.043964 -384.47853)
			(xy 116.040662 -384.479038) (xy 116.00817 -384.483012) (xy 115.942839 -384.487208) (xy 115.910106 -384.48742)
			(xy 115.877373 -384.487205) (xy 115.812042 -384.48301) (xy 115.77955 -384.479038) (xy 115.776248 -384.47853)
			(xy 115.52174 -384.47853) (xy 115.511749 -384.478001) (xy 115.493303 -384.470301) (xy 115.485926 -384.463544)
			(xy 115.436904 -384.414522) (xy 115.429284 -384.408172) (xy 115.416076 -384.399282) (xy 115.415822 -384.399282)
			(xy 115.41506 -384.398774) (xy 115.409767 -384.396792) (xy 115.39861 -384.395003) (xy 115.392962 -384.395218)
			(xy 115.388644 -384.395726) (xy 115.378456 -384.396818) (xy 115.357996 -384.397964) (xy 115.34775 -384.398012)
			(xy 115.319769 -384.397459) (xy 115.264498 -384.388698) (xy 115.211277 -384.371399) (xy 115.161418 -384.345988)
			(xy 115.116147 -384.313092) (xy 115.076579 -384.273518) (xy 115.043687 -384.228243) (xy 115.018283 -384.17838)
			(xy 115.000991 -384.125157) (xy 114.992237 -384.069885) (xy 114.991642 -384.041904) (xy 114.991642 -384.04038)
			(xy 114.991688 -384.030007) (xy 114.992831 -384.009293) (xy 114.993928 -383.998978) (xy 114.993928 -383.998724)
			(xy 114.994569 -383.987333) (xy 114.987057 -383.965823) (xy 114.97945 -383.957322) (xy 114.936778 -383.914396)
			(xy 114.92996 -383.907054) (xy 114.922217 -383.888591) (xy 114.921792 -383.878582) (xy 114.921792 -383.624074)
			(xy 114.921284 -383.620772) (xy 114.917238 -383.588285) (xy 114.912914 -383.522953) (xy 114.912648 -383.490216)
			(xy 114.912648 -383.1082) (xy 114.912918 -383.075463) (xy 114.91724 -383.010132) (xy 114.921284 -382.977644)
			(xy 114.921792 -382.974342) (xy 114.921792 -382.705864) (xy 114.921284 -382.702562) (xy 114.917238 -382.670075)
			(xy 114.912915 -382.604743) (xy 114.912648 -382.572006) (xy 114.912648 -382.18999) (xy 114.912918 -382.157253)
			(xy 114.917241 -382.091922) (xy 114.921284 -382.059434) (xy 114.921792 -382.056132) (xy 114.921792 -381.801624)
			(xy 114.922325 -381.791634) (xy 114.930031 -381.773195) (xy 114.936778 -381.76581) (xy 114.957352 -381.745236)
			(xy 114.961517 -381.740881) (xy 114.967802 -381.730603) (xy 114.969798 -381.724916) (xy 114.973354 -381.713486)
			(xy 114.971322 -381.701294) (xy 114.968951 -381.68591) (xy 114.966407 -381.654883) (xy 114.966242 -381.639318)
			(xy 114.966242 -381.638556) (xy 114.966732 -381.610955) (xy 114.974689 -381.556329) (xy 114.990431 -381.503419)
			(xy 115.01363 -381.453328) (xy 115.043801 -381.4071) (xy 115.080315 -381.3657) (xy 115.122412 -381.329991)
			(xy 115.145566 -381.31496) (xy 115.149376 -381.312674) (xy 115.179856 -381.29591) (xy 115.201786 -381.285584)
			(xy 115.247667 -381.269943) (xy 115.295161 -381.260245) (xy 115.319302 -381.258064) (xy 115.342924 -381.257048)
			(xy 115.346734 -381.257048) (xy 115.348258 -381.257048) (xy 115.348766 -381.257048) (xy 115.359688 -381.257302)
			(xy 115.361212 -381.257302) (xy 115.370323 -381.256923) (xy 115.387392 -381.250542) (xy 115.401148 -381.238592)
			(xy 115.409853 -381.222582) (xy 115.411504 -381.213614) (xy 115.413028 -381.202946) (xy 115.407694 -381.181356)
			(xy 115.404138 -381.175006) (xy 115.388509 -381.146353) (xy 115.363058 -381.086249) (xy 115.344505 -381.023671)
			(xy 115.338352 -380.991618) (xy 115.335727 -380.976349) (xy 115.331916 -380.945598) (xy 115.330732 -380.93015)
			(xy 115.32997 -380.917958) (xy 115.329208 -380.890018) (xy 115.329208 -380.869698) (xy 115.32997 -380.86284)
			(xy 115.32997 -380.861316) (xy 115.33204 -380.828635) (xy 115.342622 -380.764008) (xy 115.360405 -380.700982)
			(xy 115.385163 -380.640355) (xy 115.416584 -380.582898) (xy 115.454268 -380.52934) (xy 115.497736 -380.48036)
			(xy 115.546438 -380.43658) (xy 115.599755 -380.398555) (xy 115.628166 -380.382272) (xy 115.63604 -380.378208)
			(xy 115.63731 -380.377446) (xy 115.639342 -380.37643) (xy 115.63985 -380.376176) (xy 115.640104 -380.375922)
			(xy 115.661948 -380.364492) (xy 115.668552 -380.36119) (xy 115.674902 -380.355348) (xy 115.683792 -380.344934)
			(xy 115.686586 -380.340616) (xy 115.690396 -380.3269) (xy 115.690396 -380.22022) (xy 115.682886 -380.212382)
			(xy 115.66314 -380.203417) (xy 115.652296 -380.202948) (xy 115.551966 -380.202948) (xy 115.541814 -380.202447)
			(xy 115.523059 -380.194666) (xy 115.508707 -380.180301) (xy 115.500944 -380.161539) (xy 115.500404 -380.151386)
			(xy 115.500404 -379.869192) (xy 115.500318 -379.865248) (xy 115.499044 -379.857462) (xy 115.497864 -379.853698)
			(xy 115.493292 -379.840236) (xy 115.490752 -379.835664) (xy 115.474953 -379.807642) (xy 115.450067 -379.74832)
			(xy 115.433231 -379.686232) (xy 115.424738 -379.622465) (xy 115.424204 -379.5903) (xy 115.424204 -379.589792)
			(xy 115.424739 -379.557659) (xy 115.433249 -379.493957) (xy 115.450092 -379.431936) (xy 115.474975 -379.372681)
			(xy 115.490752 -379.344682) (xy 115.493546 -379.339856) (xy 115.497864 -379.326394) (xy 115.500404 -379.318774)
			(xy 115.500404 -378.56922) (xy 115.500312 -378.565277) (xy 115.499028 -378.557495) (xy 115.497864 -378.553726)
			(xy 115.493292 -378.540264) (xy 115.490752 -378.535692) (xy 115.474951 -378.50767) (xy 115.450062 -378.448349)
			(xy 115.433222 -378.386261) (xy 115.424726 -378.322494) (xy 115.424204 -378.290328) (xy 115.424204 -378.28982)
			(xy 115.424737 -378.257686) (xy 115.433243 -378.193983) (xy 115.450084 -378.13196) (xy 115.474964 -378.072703)
			(xy 115.490752 -378.04471) (xy 115.493546 -378.039884) (xy 115.497864 -378.026422) (xy 115.500404 -378.018802)
			(xy 115.500404 -377.728734) (xy 115.500893 -377.718569) (xy 115.50866 -377.699783) (xy 115.523025 -377.685398)
			(xy 115.541802 -377.677606) (xy 115.551966 -377.677172) (xy 115.652296 -377.677172) (xy 115.663127 -377.676651)
			(xy 115.682852 -377.667692) (xy 115.690396 -377.6599) (xy 115.690396 -377.56084) (xy 115.690183 -377.55403)
			(xy 115.686583 -377.540893) (xy 115.683284 -377.534932) (xy 115.682522 -377.533662) (xy 115.67668 -377.528582)
			(xy 115.676426 -377.528328) (xy 115.660678 -377.514612) (xy 115.654582 -377.511564) (xy 115.654328 -377.511564)
			(xy 115.623951 -377.496102) (xy 115.566703 -377.459103) (xy 115.514178 -377.415658) (xy 115.467098 -377.366365)
			(xy 115.426111 -377.3119) (xy 115.391779 -377.253013) (xy 115.364574 -377.190514) (xy 115.344871 -377.125259)
			(xy 115.332939 -377.058148) (xy 115.328944 -376.990101) (xy 115.332939 -376.922054) (xy 115.34487 -376.854942)
			(xy 115.364573 -376.789688) (xy 115.391778 -376.727188) (xy 115.42611 -376.668301) (xy 115.467097 -376.613837)
			(xy 115.514177 -376.564543) (xy 115.566701 -376.521098) (xy 115.623949 -376.484098) (xy 115.654328 -376.46864)
			(xy 115.654582 -376.46864) (xy 115.660678 -376.465592) (xy 115.676172 -376.45213) (xy 115.677696 -376.450606)
			(xy 115.686078 -376.440446) (xy 115.690396 -376.433334) (xy 115.690396 -376.320304) (xy 115.682885 -376.312468)
			(xy 115.663139 -376.303506) (xy 115.652296 -376.303032) (xy 115.551966 -376.303032) (xy 115.541815 -376.302531)
			(xy 115.523063 -376.294749) (xy 115.508715 -376.280384) (xy 115.500957 -376.261622) (xy 115.500404 -376.25147)
			(xy 115.500404 -376.009408) (xy 115.50015 -376.004836) (xy 115.498372 -375.993914) (xy 115.497102 -375.98858)
			(xy 115.493546 -375.975626) (xy 115.48872 -375.965974) (xy 115.484402 -375.957846) (xy 115.483386 -375.956068)
			(xy 115.465326 -375.926053) (xy 115.436791 -375.862081) (xy 115.417426 -375.794763) (xy 115.407608 -375.725407)
			(xy 115.406932 -375.690384) (xy 115.406932 -375.689622) (xy 115.407352 -375.660584) (xy 115.414065 -375.602898)
			(xy 115.427394 -375.546373) (xy 115.436904 -375.518934) (xy 115.438428 -375.51487) (xy 115.43919 -375.51106)
			(xy 115.442746 -375.501916) (xy 115.440968 -375.489216) (xy 115.439867 -375.482914) (xy 115.434973 -375.471098)
			(xy 115.431316 -375.465848) (xy 115.39601 -375.41835) (xy 115.393724 -375.416064) (xy 115.393216 -375.415302)
			(xy 115.388898 -375.410984) (xy 115.381488 -375.404302) (xy 115.363052 -375.396723) (xy 115.353084 -375.396252)
			(xy 115.347242 -375.396252) (xy 115.346734 -375.396252) (xy 115.322649 -375.395801) (xy 115.274933 -375.3892)
			(xy 115.228543 -375.376222) (xy 115.206272 -375.367042) (xy 115.205764 -375.366788) (xy 115.200938 -375.364756)
			(xy 115.19027 -375.36247) (xy 115.182142 -375.35993) (xy 115.176554 -375.357644) (xy 115.17503 -375.357136)
			(xy 115.170087 -375.355053) (xy 115.161123 -375.349163) (xy 115.15725 -375.345452) (xy 115.146836 -375.335038)
			(xy 115.141756 -375.33072) (xy 115.139978 -375.32945) (xy 115.117457 -375.312625) (xy 115.077515 -375.273069)
			(xy 115.060476 -375.25071) (xy 115.044264 -375.227698) (xy 115.018545 -375.177628) (xy 115.001038 -375.124131)
			(xy 114.992183 -375.068543) (xy 114.991642 -375.040398) (xy 114.991642 -375.03735) (xy 114.992351 -375.01015)
			(xy 115.001009 -374.956436) (xy 115.017733 -374.904662) (xy 115.029488 -374.880124) (xy 115.040098 -374.859679)
			(xy 115.06581 -374.82146) (xy 115.096235 -374.786874) (xy 115.113308 -374.771412) (xy 115.117372 -374.767856)
			(xy 115.131342 -374.749314) (xy 115.134898 -374.74144) (xy 115.135406 -374.74017) (xy 115.13947 -374.730772)
			(xy 115.141476 -374.725932) (xy 115.143658 -374.715689) (xy 115.143788 -374.710452) (xy 115.143788 -374.203468)
			(xy 115.142518 -374.192292) (xy 115.140232 -374.18391) (xy 115.138708 -374.177052) (xy 115.127278 -374.156224)
			(xy 115.125479 -374.153111) (xy 115.121143 -374.147376) (xy 115.118642 -374.144794) (xy 115.11407 -374.140222)
			(xy 115.111784 -374.138444) (xy 115.089481 -374.12025) (xy 115.050082 -374.078292) (xy 115.017435 -374.03089)
			(xy 114.992278 -373.979123) (xy 114.975184 -373.924163) (xy 114.966541 -373.86726) (xy 114.966543 -373.809703)
			(xy 114.975193 -373.7528) (xy 114.992292 -373.697843) (xy 115.017453 -373.646078) (xy 115.050106 -373.59868)
			(xy 115.089508 -373.556725) (xy 115.111784 -373.538496) (xy 115.11407 -373.536718) (xy 115.119404 -373.531384)
			(xy 115.122114 -373.528607) (xy 115.126711 -373.522356) (xy 115.128548 -373.518938) (xy 115.1382 -373.500396)
			(xy 115.1382 -373.499888) (xy 115.143788 -373.4943) (xy 115.143788 -372.672356) (xy 115.143704 -372.668148)
			(xy 115.142292 -372.65985) (xy 115.140994 -372.655846) (xy 115.137946 -372.647464) (xy 115.13566 -372.641876)
			(xy 115.124484 -372.620032) (xy 115.116864 -372.613428) (xy 115.099077 -372.597734) (xy 115.067405 -372.56242)
			(xy 115.040707 -372.523211) (xy 115.029742 -372.502176) (xy 115.017735 -372.477182) (xy 115.000754 -372.424401)
			(xy 114.992159 -372.369625) (xy 114.992159 -372.314179) (xy 115.000753 -372.259403) (xy 115.017734 -372.206621)
			(xy 115.029742 -372.181628) (xy 115.040462 -372.16115) (xy 115.066416 -372.122902) (xy 115.097107 -372.088339)
			(xy 115.114324 -372.072916) (xy 115.115848 -372.071646) (xy 115.120166 -372.067328) (xy 115.123272 -372.064068)
			(xy 115.128387 -372.056659) (xy 115.130326 -372.052596) (xy 115.133628 -372.045484) (xy 115.134644 -372.044468)
			(xy 115.13947 -372.033292) (xy 115.141477 -372.028453) (xy 115.143664 -372.018209) (xy 115.143788 -372.012972)
			(xy 115.143788 -371.470682) (xy 115.143706 -371.466473) (xy 115.142299 -371.458174) (xy 115.140994 -371.454172)
			(xy 115.137946 -371.44579) (xy 115.13566 -371.440202) (xy 115.124484 -371.418358) (xy 115.116864 -371.411754)
			(xy 115.099076 -371.39606) (xy 115.067402 -371.360748) (xy 115.040701 -371.32154) (xy 115.029742 -371.300502)
			(xy 115.017733 -371.275508) (xy 115.000748 -371.222726) (xy 114.992149 -371.167949) (xy 114.992145 -371.112501)
			(xy 115.000736 -371.057723) (xy 115.017714 -371.004938) (xy 115.029742 -370.979954) (xy 115.040465 -370.959478)
			(xy 115.066425 -370.921236) (xy 115.097121 -370.886679) (xy 115.114324 -370.871242) (xy 115.115848 -370.869972)
			(xy 115.120166 -370.865654) (xy 115.123273 -370.862395) (xy 115.128392 -370.854988) (xy 115.130326 -370.850922)
			(xy 115.133628 -370.84381) (xy 115.134644 -370.842794) (xy 115.13947 -370.831618) (xy 115.14147 -370.826778)
			(xy 115.143642 -370.816534) (xy 115.143788 -370.811298) (xy 115.143788 -369.383564) (xy 115.143693 -369.378686)
			(xy 115.141905 -369.369097) (xy 115.140232 -369.364514) (xy 115.136422 -369.35537) (xy 110.984792 -365.20374)
			(xy 110.977956 -365.196338) (xy 110.970244 -365.17774) (xy 110.969806 -365.167672) (xy 110.969806 -352.068892)
			(xy 110.969679 -352.063103) (xy 110.967112 -352.051816) (xy 110.964726 -352.04654) (xy 110.94554 -352.005799)
			(xy 110.913738 -351.921542) (xy 110.88966 -351.83476) (xy 110.873503 -351.746162) (xy 110.865399 -351.656468)
			(xy 110.864904 -351.611438) (xy 110.865393 -351.566408) (xy 110.873495 -351.476714) (xy 110.889655 -351.388116)
			(xy 110.91374 -351.301337) (xy 110.945555 -351.217084) (xy 110.964726 -351.176336) (xy 110.967102 -351.171057)
			(xy 110.969666 -351.159771) (xy 110.969806 -351.153984) (xy 110.969806 -349.043244) (xy 110.969685 -349.037454)
			(xy 110.967128 -349.026161) (xy 110.964726 -349.020892) (xy 110.945542 -348.98015) (xy 110.913744 -348.895893)
			(xy 110.88967 -348.809111) (xy 110.873518 -348.720513) (xy 110.865418 -348.630819) (xy 110.864904 -348.58579)
			(xy 110.865391 -348.54076) (xy 110.873488 -348.451064) (xy 110.889644 -348.362464) (xy 110.913725 -348.275683)
			(xy 110.945536 -348.191428) (xy 110.964726 -348.150688) (xy 110.967096 -348.145408) (xy 110.96965 -348.134122)
			(xy 110.969806 -348.128336) (xy 110.969806 -345.534742) (xy 110.96879 -345.529916) (xy 110.965804 -345.513891)
			(xy 110.962628 -345.481446) (xy 110.96244 -345.465146) (xy 110.962623 -345.448846) (xy 110.965802 -345.416401)
			(xy 110.96879 -345.400376) (xy 110.969806 -345.39555) (xy 110.969806 -342.509094) (xy 110.96879 -342.504268)
			(xy 110.965802 -342.488243) (xy 110.962621 -342.455798) (xy 110.96244 -342.439498) (xy 110.962625 -342.423198)
			(xy 110.965809 -342.390754) (xy 110.96879 -342.374728) (xy 110.969806 -342.369902) (xy 110.969806 -339.181186)
			(xy 110.970232 -339.171117) (xy 110.977951 -339.152517) (xy 110.984792 -339.145118) (xy 112.87379 -337.25612)
			(xy 112.881187 -337.24927) (xy 112.899785 -337.241528) (xy 112.909858 -337.241134) (xy 117.446806 -337.241134)
			(xy 117.453615 -337.240915) (xy 117.466746 -337.237308) (xy 117.472714 -337.234022) (xy 129.589784 -329.970892)
			(xy 129.624999 -329.950282) (xy 129.698205 -329.914231) (xy 129.774116 -329.884294) (xy 129.81305 -329.872086)
			(xy 135.068056 -328.277982) (xy 135.073942 -328.275959) (xy 135.084602 -328.269543) (xy 135.089138 -328.265282)
			(xy 138.97737 -324.37705) (xy 138.984212 -324.36965) (xy 138.991933 -324.351052) (xy 138.992356 -324.340982)
			(xy 138.992356 -320.994786) (xy 138.991929 -320.984718) (xy 138.984206 -320.966121) (xy 138.97737 -320.958718)
			(xy 136.567926 -318.549274) (xy 136.560527 -318.542431) (xy 136.541928 -318.534712) (xy 136.531858 -318.534288)
			(xy 96.050608 -318.534288) (xy 96.040537 -318.534709) (xy 96.021929 -318.54242) (xy 96.01454 -318.549274)
			(xy 94.791022 -319.772792) (xy 94.784172 -319.780189) (xy 94.776431 -319.798787) (xy 94.776036 -319.80886)
			(xy 94.776036 -320.08064) (xy 106.2228 -320.08064) (xy 106.223347 -320.051724) (xy 106.23207 -319.994554)
			(xy 106.249322 -319.939356) (xy 106.274709 -319.887394) (xy 106.307647 -319.83986) (xy 106.347383 -319.797841)
			(xy 106.369866 -319.77965) (xy 106.378652 -319.772023) (xy 106.388844 -319.751137) (xy 106.389424 -319.739518)
			(xy 106.389424 -319.659762) (xy 106.388919 -319.648125) (xy 106.378709 -319.627214) (xy 106.369866 -319.61963)
			(xy 106.34739 -319.601431) (xy 106.307656 -319.559412) (xy 106.274717 -319.511878) (xy 106.249328 -319.459919)
			(xy 106.232069 -319.404723) (xy 106.223337 -319.347555) (xy 106.2228 -319.31864) (xy 106.223293 -319.291388)
			(xy 106.231044 -319.237437) (xy 106.246396 -319.18514) (xy 106.269034 -319.135559) (xy 106.298499 -319.089705)
			(xy 106.334189 -319.048512) (xy 106.37538 -319.012818) (xy 106.421231 -318.983349) (xy 106.47081 -318.960707)
			(xy 106.523106 -318.945351) (xy 106.577056 -318.937595) (xy 106.604308 -318.937132) (xy 106.633223 -318.937704)
			(xy 106.690392 -318.946421) (xy 106.74559 -318.963667) (xy 106.797553 -318.989048) (xy 106.845088 -319.021983)
			(xy 106.887106 -319.061716) (xy 106.905298 -319.084198) (xy 106.912916 -319.092994) (xy 106.933808 -319.103184)
			(xy 106.94543 -319.103756) (xy 107.025186 -319.103756) (xy 107.036817 -319.10321) (xy 107.057728 -319.093028)
			(xy 107.065318 -319.084198) (xy 107.082071 -319.063415) (xy 107.120425 -319.026285) (xy 107.163579 -318.994863)
			(xy 107.210693 -318.969764) (xy 107.260845 -318.951478) (xy 107.313056 -318.940361) (xy 107.366308 -318.936631)
			(xy 107.41956 -318.940361) (xy 107.471771 -318.951478) (xy 107.521923 -318.969764) (xy 107.569037 -318.994863)
			(xy 107.612191 -319.026285) (xy 107.650545 -319.063415) (xy 107.667298 -319.084198) (xy 107.674916 -319.092994)
			(xy 107.695808 -319.103184) (xy 107.70743 -319.103756) (xy 107.787186 -319.103756) (xy 107.798817 -319.10321)
			(xy 107.819728 -319.093028) (xy 107.827318 -319.084198) (xy 107.844071 -319.063415) (xy 107.882425 -319.026285)
			(xy 107.925579 -318.994863) (xy 107.972693 -318.969764) (xy 108.022845 -318.951478) (xy 108.075056 -318.940361)
			(xy 108.128308 -318.936631) (xy 108.18156 -318.940361) (xy 108.233771 -318.951478) (xy 108.283923 -318.969764)
			(xy 108.331037 -318.994863) (xy 108.374191 -319.026285) (xy 108.412545 -319.063415) (xy 108.429298 -319.084198)
			(xy 108.436916 -319.092994) (xy 108.457808 -319.103184) (xy 108.46943 -319.103756) (xy 108.549186 -319.103756)
			(xy 108.560817 -319.10321) (xy 108.581728 -319.093028) (xy 108.589318 -319.084198) (xy 108.606071 -319.063415)
			(xy 108.644425 -319.026285) (xy 108.687579 -318.994863) (xy 108.734693 -318.969764) (xy 108.784845 -318.951478)
			(xy 108.837056 -318.940361) (xy 108.890308 -318.936631) (xy 108.94356 -318.940361) (xy 108.995771 -318.951478)
			(xy 109.045923 -318.969764) (xy 109.093037 -318.994863) (xy 109.136191 -319.026285) (xy 109.174545 -319.063415)
			(xy 109.191298 -319.084198) (xy 109.198916 -319.092994) (xy 109.219808 -319.103184) (xy 109.23143 -319.103756)
			(xy 109.311186 -319.103756) (xy 109.322817 -319.10321) (xy 109.343728 -319.093028) (xy 109.351318 -319.084198)
			(xy 109.368071 -319.063415) (xy 109.406425 -319.026285) (xy 109.449579 -318.994863) (xy 109.496693 -318.969764)
			(xy 109.546845 -318.951478) (xy 109.599056 -318.940361) (xy 109.652308 -318.936631) (xy 109.70556 -318.940361)
			(xy 109.757771 -318.951478) (xy 109.807923 -318.969764) (xy 109.855037 -318.994863) (xy 109.898191 -319.026285)
			(xy 109.936545 -319.063415) (xy 109.953298 -319.084198) (xy 109.960916 -319.092994) (xy 109.981808 -319.103184)
			(xy 109.99343 -319.103756) (xy 110.073186 -319.103756) (xy 110.084817 -319.10321) (xy 110.105728 -319.093028)
			(xy 110.113318 -319.084198) (xy 110.130071 -319.063415) (xy 110.168425 -319.026285) (xy 110.211579 -318.994863)
			(xy 110.258693 -318.969764) (xy 110.308845 -318.951478) (xy 110.361056 -318.940361) (xy 110.414308 -318.936631)
			(xy 110.46756 -318.940361) (xy 110.519771 -318.951478) (xy 110.569923 -318.969764) (xy 110.617037 -318.994863)
			(xy 110.660191 -319.026285) (xy 110.698545 -319.063415) (xy 110.715298 -319.084198) (xy 110.722916 -319.092994)
			(xy 110.743808 -319.103184) (xy 110.75543 -319.103756) (xy 110.835186 -319.103756) (xy 110.846817 -319.10321)
			(xy 110.867728 -319.093028) (xy 110.875318 -319.084198) (xy 110.892071 -319.063415) (xy 110.930425 -319.026285)
			(xy 110.973579 -318.994863) (xy 111.020693 -318.969764) (xy 111.070845 -318.951478) (xy 111.123056 -318.940361)
			(xy 111.176308 -318.936631) (xy 111.22956 -318.940361) (xy 111.281771 -318.951478) (xy 111.331923 -318.969764)
			(xy 111.379037 -318.994863) (xy 111.422191 -319.026285) (xy 111.460545 -319.063415) (xy 111.477298 -319.084198)
			(xy 111.484916 -319.092994) (xy 111.505808 -319.103184) (xy 111.51743 -319.103756) (xy 111.597186 -319.103756)
			(xy 111.608817 -319.10321) (xy 111.629728 -319.093028) (xy 111.637318 -319.084198) (xy 111.654071 -319.063415)
			(xy 111.692425 -319.026285) (xy 111.735579 -318.994863) (xy 111.782693 -318.969764) (xy 111.832845 -318.951478)
			(xy 111.885056 -318.940361) (xy 111.938308 -318.936631) (xy 111.99156 -318.940361) (xy 112.043771 -318.951478)
			(xy 112.093923 -318.969764) (xy 112.141037 -318.994863) (xy 112.184191 -319.026285) (xy 112.222545 -319.063415)
			(xy 112.239298 -319.084198) (xy 112.246916 -319.092994) (xy 112.267808 -319.103184) (xy 112.27943 -319.103756)
			(xy 112.359186 -319.103756) (xy 112.370817 -319.10321) (xy 112.391728 -319.093028) (xy 112.399318 -319.084198)
			(xy 112.416071 -319.063415) (xy 112.454425 -319.026285) (xy 112.497579 -318.994863) (xy 112.544693 -318.969764)
			(xy 112.594845 -318.951478) (xy 112.647056 -318.940361) (xy 112.700308 -318.936631) (xy 112.75356 -318.940361)
			(xy 112.805771 -318.951478) (xy 112.855923 -318.969764) (xy 112.903037 -318.994863) (xy 112.946191 -319.026285)
			(xy 112.984545 -319.063415) (xy 113.001298 -319.084198) (xy 113.008916 -319.092994) (xy 113.029808 -319.103184)
			(xy 113.04143 -319.103756) (xy 113.121186 -319.103756) (xy 113.132817 -319.10321) (xy 113.153728 -319.093028)
			(xy 113.161318 -319.084198) (xy 113.178071 -319.063415) (xy 113.216425 -319.026285) (xy 113.259579 -318.994863)
			(xy 113.306693 -318.969764) (xy 113.356845 -318.951478) (xy 113.409056 -318.940361) (xy 113.462308 -318.936631)
			(xy 113.51556 -318.940361) (xy 113.567771 -318.951478) (xy 113.617923 -318.969764) (xy 113.665037 -318.994863)
			(xy 113.708191 -319.026285) (xy 113.746545 -319.063415) (xy 113.763298 -319.084198) (xy 113.770916 -319.092994)
			(xy 113.791808 -319.103184) (xy 113.80343 -319.103756) (xy 113.883186 -319.103756) (xy 113.894817 -319.10321)
			(xy 113.915728 -319.093028) (xy 113.923318 -319.084198) (xy 113.941498 -319.061705) (xy 113.98352 -319.021971)
			(xy 114.031058 -318.989033) (xy 114.083021 -318.963646) (xy 114.13822 -318.946392) (xy 114.195391 -318.937666)
			(xy 114.224308 -318.937132) (xy 114.251563 -318.937548) (xy 114.305518 -318.945307) (xy 114.357819 -318.960666)
			(xy 114.407402 -318.983313) (xy 114.453257 -319.012785) (xy 114.49445 -319.048484) (xy 114.530144 -319.089682)
			(xy 114.559611 -319.135541) (xy 114.582251 -319.185126) (xy 114.597603 -319.237429) (xy 114.605355 -319.291385)
			(xy 114.605816 -319.31864) (xy 114.605286 -319.347557) (xy 114.596564 -319.404729) (xy 114.57931 -319.459929)
			(xy 114.553921 -319.511891) (xy 114.520978 -319.559425) (xy 114.481236 -319.601441) (xy 114.45875 -319.61963)
			(xy 114.449931 -319.627225) (xy 114.439756 -319.648135) (xy 114.439192 -319.659762) (xy 114.439192 -319.739518)
			(xy 114.439738 -319.751149) (xy 114.449922 -319.772058) (xy 114.45875 -319.77965) (xy 114.48122 -319.797857)
			(xy 114.520954 -319.839875) (xy 114.553893 -319.887407) (xy 114.579283 -319.939365) (xy 114.596543 -319.994559)
			(xy 114.605278 -320.051725) (xy 114.605816 -320.08064) (xy 119.41683 -320.08064) (xy 119.417366 -320.051724)
			(xy 119.426089 -319.994553) (xy 119.443343 -319.939354) (xy 119.468732 -319.887392) (xy 119.501673 -319.839857)
			(xy 119.541411 -319.79784) (xy 119.563896 -319.77965) (xy 119.57267 -319.772011) (xy 119.582872 -319.751134)
			(xy 119.583454 -319.739518) (xy 119.583454 -319.659762) (xy 119.582939 -319.648127) (xy 119.572735 -319.627216)
			(xy 119.563896 -319.61963) (xy 119.541426 -319.601423) (xy 119.50169 -319.559407) (xy 119.46875 -319.511875)
			(xy 119.443359 -319.459917) (xy 119.4261 -319.404722) (xy 119.417367 -319.347555) (xy 119.41683 -319.31864)
			(xy 119.417293 -319.291386) (xy 119.425045 -319.237433) (xy 119.440398 -319.185133) (xy 119.463039 -319.135551)
			(xy 119.492506 -319.089696) (xy 119.5282 -319.048501) (xy 119.569394 -319.012807) (xy 119.615249 -318.98334)
			(xy 119.664831 -318.960699) (xy 119.717132 -318.945346) (xy 119.771084 -318.937593) (xy 119.798338 -318.937132)
			(xy 119.827254 -318.937683) (xy 119.884424 -318.946403) (xy 119.939623 -318.963654) (xy 119.991585 -318.989039)
			(xy 120.03912 -319.021978) (xy 120.081137 -319.061714) (xy 120.099328 -319.084198) (xy 120.106933 -319.093008)
			(xy 120.127835 -319.10319) (xy 120.13946 -319.103756) (xy 120.219216 -319.103756) (xy 120.23085 -319.103227)
			(xy 120.25176 -319.093033) (xy 120.259348 -319.084198) (xy 120.276101 -319.063415) (xy 120.314455 -319.026285)
			(xy 120.357609 -318.994863) (xy 120.404723 -318.969764) (xy 120.454875 -318.951478) (xy 120.507086 -318.940361)
			(xy 120.560338 -318.936631) (xy 120.61359 -318.940361) (xy 120.665801 -318.951478) (xy 120.715953 -318.969764)
			(xy 120.763067 -318.994863) (xy 120.806221 -319.026285) (xy 120.844575 -319.063415) (xy 120.861328 -319.084198)
			(xy 120.868933 -319.093008) (xy 120.889835 -319.10319) (xy 120.90146 -319.103756) (xy 120.981216 -319.103756)
			(xy 120.99285 -319.103227) (xy 121.01376 -319.093033) (xy 121.021348 -319.084198) (xy 121.038101 -319.063415)
			(xy 121.076455 -319.026285) (xy 121.119609 -318.994863) (xy 121.166723 -318.969764) (xy 121.216875 -318.951478)
			(xy 121.269086 -318.940361) (xy 121.322338 -318.936631) (xy 121.37559 -318.940361) (xy 121.427801 -318.951478)
			(xy 121.477953 -318.969764) (xy 121.525067 -318.994863) (xy 121.568221 -319.026285) (xy 121.606575 -319.063415)
			(xy 121.623328 -319.084198) (xy 121.630933 -319.093008) (xy 121.651835 -319.10319) (xy 121.66346 -319.103756)
			(xy 121.743216 -319.103756) (xy 121.75485 -319.103227) (xy 121.77576 -319.093033) (xy 121.783348 -319.084198)
			(xy 121.800101 -319.063415) (xy 121.838455 -319.026285) (xy 121.881609 -318.994863) (xy 121.928723 -318.969764)
			(xy 121.978875 -318.951478) (xy 122.031086 -318.940361) (xy 122.084338 -318.936631) (xy 122.13759 -318.940361)
			(xy 122.189801 -318.951478) (xy 122.239953 -318.969764) (xy 122.287067 -318.994863) (xy 122.330221 -319.026285)
			(xy 122.368575 -319.063415) (xy 122.385328 -319.084198) (xy 122.392933 -319.093008) (xy 122.413835 -319.10319)
			(xy 122.42546 -319.103756) (xy 122.505216 -319.103756) (xy 122.51685 -319.103227) (xy 122.53776 -319.093033)
			(xy 122.545348 -319.084198) (xy 122.562101 -319.063415) (xy 122.600455 -319.026285) (xy 122.643609 -318.994863)
			(xy 122.690723 -318.969764) (xy 122.740875 -318.951478) (xy 122.793086 -318.940361) (xy 122.846338 -318.936631)
			(xy 122.89959 -318.940361) (xy 122.951801 -318.951478) (xy 123.001953 -318.969764) (xy 123.049067 -318.994863)
			(xy 123.092221 -319.026285) (xy 123.130575 -319.063415) (xy 123.147328 -319.084198) (xy 123.154933 -319.093008)
			(xy 123.175835 -319.10319) (xy 123.18746 -319.103756) (xy 123.267216 -319.103756) (xy 123.27885 -319.103227)
			(xy 123.29976 -319.093033) (xy 123.307348 -319.084198) (xy 123.324101 -319.063415) (xy 123.362455 -319.026285)
			(xy 123.405609 -318.994863) (xy 123.452723 -318.969764) (xy 123.502875 -318.951478) (xy 123.555086 -318.940361)
			(xy 123.608338 -318.936631) (xy 123.66159 -318.940361) (xy 123.713801 -318.951478) (xy 123.763953 -318.969764)
			(xy 123.811067 -318.994863) (xy 123.854221 -319.026285) (xy 123.892575 -319.063415) (xy 123.909328 -319.084198)
			(xy 123.916933 -319.093008) (xy 123.937835 -319.10319) (xy 123.94946 -319.103756) (xy 124.029216 -319.103756)
			(xy 124.04085 -319.103227) (xy 124.06176 -319.093033) (xy 124.069348 -319.084198) (xy 124.086101 -319.063415)
			(xy 124.124455 -319.026285) (xy 124.167609 -318.994863) (xy 124.214723 -318.969764) (xy 124.264875 -318.951478)
			(xy 124.317086 -318.940361) (xy 124.370338 -318.936631) (xy 124.42359 -318.940361) (xy 124.475801 -318.951478)
			(xy 124.525953 -318.969764) (xy 124.573067 -318.994863) (xy 124.616221 -319.026285) (xy 124.654575 -319.063415)
			(xy 124.671328 -319.084198) (xy 124.678933 -319.093008) (xy 124.699835 -319.10319) (xy 124.71146 -319.103756)
			(xy 124.791216 -319.103756) (xy 124.80285 -319.103227) (xy 124.82376 -319.093033) (xy 124.831348 -319.084198)
			(xy 124.848101 -319.063415) (xy 124.886455 -319.026285) (xy 124.929609 -318.994863) (xy 124.976723 -318.969764)
			(xy 125.026875 -318.951478) (xy 125.079086 -318.940361) (xy 125.132338 -318.936631) (xy 125.18559 -318.940361)
			(xy 125.237801 -318.951478) (xy 125.287953 -318.969764) (xy 125.335067 -318.994863) (xy 125.378221 -319.026285)
			(xy 125.416575 -319.063415) (xy 125.433328 -319.084198) (xy 125.440933 -319.093008) (xy 125.461835 -319.10319)
			(xy 125.47346 -319.103756) (xy 125.553216 -319.103756) (xy 125.56485 -319.103227) (xy 125.58576 -319.093033)
			(xy 125.593348 -319.084198) (xy 125.610101 -319.063415) (xy 125.648455 -319.026285) (xy 125.691609 -318.994863)
			(xy 125.738723 -318.969764) (xy 125.788875 -318.951478) (xy 125.841086 -318.940361) (xy 125.894338 -318.936631)
			(xy 125.94759 -318.940361) (xy 125.999801 -318.951478) (xy 126.049953 -318.969764) (xy 126.097067 -318.994863)
			(xy 126.140221 -319.026285) (xy 126.178575 -319.063415) (xy 126.195328 -319.084198) (xy 126.202933 -319.093008)
			(xy 126.223835 -319.10319) (xy 126.23546 -319.103756) (xy 126.315216 -319.103756) (xy 126.32685 -319.103227)
			(xy 126.34776 -319.093033) (xy 126.355348 -319.084198) (xy 126.372101 -319.063415) (xy 126.410455 -319.026285)
			(xy 126.453609 -318.994863) (xy 126.500723 -318.969764) (xy 126.550875 -318.951478) (xy 126.603086 -318.940361)
			(xy 126.656338 -318.936631) (xy 126.70959 -318.940361) (xy 126.761801 -318.951478) (xy 126.811953 -318.969764)
			(xy 126.859067 -318.994863) (xy 126.902221 -319.026285) (xy 126.940575 -319.063415) (xy 126.957328 -319.084198)
			(xy 126.964933 -319.093008) (xy 126.985835 -319.10319) (xy 126.99746 -319.103756) (xy 127.077216 -319.103756)
			(xy 127.08885 -319.103227) (xy 127.10976 -319.093033) (xy 127.117348 -319.084198) (xy 127.134101 -319.063415)
			(xy 127.172455 -319.026285) (xy 127.215609 -318.994863) (xy 127.262723 -318.969764) (xy 127.312875 -318.951478)
			(xy 127.365086 -318.940361) (xy 127.418338 -318.936631) (xy 127.47159 -318.940361) (xy 127.523801 -318.951478)
			(xy 127.573953 -318.969764) (xy 127.621067 -318.994863) (xy 127.664221 -319.026285) (xy 127.702575 -319.063415)
			(xy 127.719328 -319.084198) (xy 127.726933 -319.093008) (xy 127.747835 -319.10319) (xy 127.75946 -319.103756)
			(xy 127.839216 -319.103756) (xy 127.85085 -319.103227) (xy 127.87176 -319.093033) (xy 127.879348 -319.084198)
			(xy 127.897568 -319.061739) (xy 127.939582 -319.022002) (xy 127.987111 -318.989061) (xy 128.039066 -318.963668)
			(xy 128.094259 -318.946406) (xy 128.151424 -318.937671) (xy 128.180338 -318.937132) (xy 128.21046 -318.937747)
			(xy 128.269954 -318.947218) (xy 128.327221 -318.965919) (xy 128.380839 -318.993385) (xy 128.429475 -319.028934)
			(xy 128.451102 -319.049908) (xy 128.458506 -319.056742) (xy 128.477102 -319.064465) (xy 128.48717 -319.064894)
			(xy 128.559306 -319.064894) (xy 128.569376 -319.064473) (xy 128.587974 -319.056749) (xy 128.595374 -319.049908)
			(xy 128.616988 -319.028916) (xy 128.66562 -318.993349) (xy 128.719239 -318.965871) (xy 128.776512 -318.947166)
			(xy 128.836013 -318.937698) (xy 128.866138 -318.937132) (xy 128.893394 -318.93752) (xy 128.947349 -318.945283)
			(xy 128.999651 -318.960646) (xy 129.049234 -318.983296) (xy 129.095089 -319.012771) (xy 129.136282 -319.048473)
			(xy 129.171975 -319.089673) (xy 129.201442 -319.135534) (xy 129.224082 -319.185122) (xy 129.239434 -319.237427)
			(xy 129.247186 -319.291384) (xy 129.247646 -319.31864) (xy 129.247105 -319.347556) (xy 129.238383 -319.404727)
			(xy 129.221131 -319.459927) (xy 129.195744 -319.511889) (xy 129.162803 -319.559423) (xy 129.123064 -319.60144)
			(xy 129.10058 -319.61963) (xy 129.091766 -319.62723) (xy 129.081587 -319.648136) (xy 129.081022 -319.659762)
			(xy 129.081022 -319.739518) (xy 129.081557 -319.751151) (xy 129.091748 -319.772061) (xy 129.10058 -319.77965)
			(xy 129.123035 -319.797874) (xy 129.162773 -319.839887) (xy 129.195716 -319.887414) (xy 129.221109 -319.939369)
			(xy 129.238372 -319.994561) (xy 129.247107 -320.051726) (xy 129.247646 -320.08064) (xy 129.24716 -320.107891)
			(xy 129.239399 -320.161836) (xy 129.22404 -320.214129) (xy 129.201397 -320.263703) (xy 129.17193 -320.309552)
			(xy 129.136239 -320.350741) (xy 129.09505 -320.386432) (xy 129.049202 -320.415898) (xy 128.999627 -320.438541)
			(xy 128.947334 -320.453899) (xy 128.893389 -320.46166) (xy 128.866138 -320.462148) (xy 128.836016 -320.461554)
			(xy 128.77652 -320.452079) (xy 128.719252 -320.433373) (xy 128.665635 -320.405903) (xy 128.617 -320.370349)
			(xy 128.595374 -320.349372) (xy 128.58798 -320.342524) (xy 128.569376 -320.33481) (xy 128.559306 -320.334386)
			(xy 128.48717 -320.334386) (xy 128.477096 -320.334773) (xy 128.458497 -320.342518) (xy 128.451102 -320.349372)
			(xy 128.429495 -320.370372) (xy 128.380862 -320.405938) (xy 128.327241 -320.433415) (xy 128.269967 -320.452119)
			(xy 128.210464 -320.461584) (xy 128.180338 -320.462148) (xy 128.151421 -320.461622) (xy 128.094249 -320.452898)
			(xy 128.03905 -320.435642) (xy 127.987088 -320.410252) (xy 127.939554 -320.377309) (xy 127.897537 -320.337568)
			(xy 127.879348 -320.315082) (xy 127.871713 -320.306303) (xy 127.850833 -320.296105) (xy 127.839216 -320.295524)
			(xy 127.75946 -320.295524) (xy 127.747826 -320.296046) (xy 127.726916 -320.306246) (xy 127.719328 -320.315082)
			(xy 127.702575 -320.335865) (xy 127.664221 -320.372995) (xy 127.621067 -320.404417) (xy 127.573953 -320.429516)
			(xy 127.523801 -320.447802) (xy 127.47159 -320.458919) (xy 127.418338 -320.462649) (xy 127.365086 -320.458919)
			(xy 127.312875 -320.447802) (xy 127.262723 -320.429516) (xy 127.215609 -320.404417) (xy 127.172455 -320.372995)
			(xy 127.134101 -320.335865) (xy 127.117348 -320.315082) (xy 127.109713 -320.306303) (xy 127.088833 -320.296105)
			(xy 127.077216 -320.295524) (xy 126.99746 -320.295524) (xy 126.985826 -320.296046) (xy 126.964916 -320.306246)
			(xy 126.957328 -320.315082) (xy 126.940575 -320.335865) (xy 126.902221 -320.372995) (xy 126.859067 -320.404417)
			(xy 126.811953 -320.429516) (xy 126.761801 -320.447802) (xy 126.70959 -320.458919) (xy 126.656338 -320.462649)
			(xy 126.603086 -320.458919) (xy 126.550875 -320.447802) (xy 126.500723 -320.429516) (xy 126.453609 -320.404417)
			(xy 126.410455 -320.372995) (xy 126.372101 -320.335865) (xy 126.355348 -320.315082) (xy 126.347713 -320.306303)
			(xy 126.326833 -320.296105) (xy 126.315216 -320.295524) (xy 126.23546 -320.295524) (xy 126.223826 -320.296046)
			(xy 126.202916 -320.306246) (xy 126.195328 -320.315082) (xy 126.178575 -320.335865) (xy 126.140221 -320.372995)
			(xy 126.097067 -320.404417) (xy 126.049953 -320.429516) (xy 125.999801 -320.447802) (xy 125.94759 -320.458919)
			(xy 125.894338 -320.462649) (xy 125.841086 -320.458919) (xy 125.788875 -320.447802) (xy 125.738723 -320.429516)
			(xy 125.691609 -320.404417) (xy 125.648455 -320.372995) (xy 125.610101 -320.335865) (xy 125.593348 -320.315082)
			(xy 125.585713 -320.306303) (xy 125.564833 -320.296105) (xy 125.553216 -320.295524) (xy 125.47346 -320.295524)
			(xy 125.461826 -320.296046) (xy 125.440916 -320.306246) (xy 125.433328 -320.315082) (xy 125.416575 -320.335865)
			(xy 125.378221 -320.372995) (xy 125.335067 -320.404417) (xy 125.287953 -320.429516) (xy 125.237801 -320.447802)
			(xy 125.18559 -320.458919) (xy 125.132338 -320.462649) (xy 125.079086 -320.458919) (xy 125.026875 -320.447802)
			(xy 124.976723 -320.429516) (xy 124.929609 -320.404417) (xy 124.886455 -320.372995) (xy 124.848101 -320.335865)
			(xy 124.831348 -320.315082) (xy 124.823713 -320.306303) (xy 124.802833 -320.296105) (xy 124.791216 -320.295524)
			(xy 124.71146 -320.295524) (xy 124.699826 -320.296046) (xy 124.678916 -320.306246) (xy 124.671328 -320.315082)
			(xy 124.654575 -320.335865) (xy 124.616221 -320.372995) (xy 124.573067 -320.404417) (xy 124.525953 -320.429516)
			(xy 124.475801 -320.447802) (xy 124.42359 -320.458919) (xy 124.370338 -320.462649) (xy 124.317086 -320.458919)
			(xy 124.264875 -320.447802) (xy 124.214723 -320.429516) (xy 124.167609 -320.404417) (xy 124.124455 -320.372995)
			(xy 124.086101 -320.335865) (xy 124.069348 -320.315082) (xy 124.061713 -320.306303) (xy 124.040833 -320.296105)
			(xy 124.029216 -320.295524) (xy 123.94946 -320.295524) (xy 123.937826 -320.296046) (xy 123.916916 -320.306246)
			(xy 123.909328 -320.315082) (xy 123.892575 -320.335865) (xy 123.854221 -320.372995) (xy 123.811067 -320.404417)
			(xy 123.763953 -320.429516) (xy 123.713801 -320.447802) (xy 123.66159 -320.458919) (xy 123.608338 -320.462649)
			(xy 123.555086 -320.458919) (xy 123.502875 -320.447802) (xy 123.452723 -320.429516) (xy 123.405609 -320.404417)
			(xy 123.362455 -320.372995) (xy 123.324101 -320.335865) (xy 123.307348 -320.315082) (xy 123.299713 -320.306303)
			(xy 123.278833 -320.296105) (xy 123.267216 -320.295524) (xy 123.18746 -320.295524) (xy 123.175826 -320.296046)
			(xy 123.154916 -320.306246) (xy 123.147328 -320.315082) (xy 123.130575 -320.335865) (xy 123.092221 -320.372995)
			(xy 123.049067 -320.404417) (xy 123.001953 -320.429516) (xy 122.951801 -320.447802) (xy 122.89959 -320.458919)
			(xy 122.846338 -320.462649) (xy 122.793086 -320.458919) (xy 122.740875 -320.447802) (xy 122.690723 -320.429516)
			(xy 122.643609 -320.404417) (xy 122.600455 -320.372995) (xy 122.562101 -320.335865) (xy 122.545348 -320.315082)
			(xy 122.537713 -320.306303) (xy 122.516833 -320.296105) (xy 122.505216 -320.295524) (xy 122.42546 -320.295524)
			(xy 122.413826 -320.296046) (xy 122.392916 -320.306246) (xy 122.385328 -320.315082) (xy 122.368575 -320.335865)
			(xy 122.330221 -320.372995) (xy 122.287067 -320.404417) (xy 122.239953 -320.429516) (xy 122.189801 -320.447802)
			(xy 122.13759 -320.458919) (xy 122.084338 -320.462649) (xy 122.031086 -320.458919) (xy 121.978875 -320.447802)
			(xy 121.928723 -320.429516) (xy 121.881609 -320.404417) (xy 121.838455 -320.372995) (xy 121.800101 -320.335865)
			(xy 121.783348 -320.315082) (xy 121.775713 -320.306303) (xy 121.754833 -320.296105) (xy 121.743216 -320.295524)
			(xy 121.66346 -320.295524) (xy 121.651826 -320.296046) (xy 121.630916 -320.306246) (xy 121.623328 -320.315082)
			(xy 121.606575 -320.335865) (xy 121.568221 -320.372995) (xy 121.525067 -320.404417) (xy 121.477953 -320.429516)
			(xy 121.427801 -320.447802) (xy 121.37559 -320.458919) (xy 121.322338 -320.462649) (xy 121.269086 -320.458919)
			(xy 121.216875 -320.447802) (xy 121.166723 -320.429516) (xy 121.119609 -320.404417) (xy 121.076455 -320.372995)
			(xy 121.038101 -320.335865) (xy 121.021348 -320.315082) (xy 121.013713 -320.306303) (xy 120.992833 -320.296105)
			(xy 120.981216 -320.295524) (xy 120.90146 -320.295524) (xy 120.889826 -320.296046) (xy 120.868916 -320.306246)
			(xy 120.861328 -320.315082) (xy 120.844575 -320.335865) (xy 120.806221 -320.372995) (xy 120.763067 -320.404417)
			(xy 120.715953 -320.429516) (xy 120.665801 -320.447802) (xy 120.61359 -320.458919) (xy 120.560338 -320.462649)
			(xy 120.507086 -320.458919) (xy 120.454875 -320.447802) (xy 120.404723 -320.429516) (xy 120.357609 -320.404417)
			(xy 120.314455 -320.372995) (xy 120.276101 -320.335865) (xy 120.259348 -320.315082) (xy 120.251713 -320.306303)
			(xy 120.230833 -320.296105) (xy 120.219216 -320.295524) (xy 120.13946 -320.295524) (xy 120.127826 -320.296046)
			(xy 120.106916 -320.306246) (xy 120.099328 -320.315082) (xy 120.081117 -320.337548) (xy 120.039102 -320.377285)
			(xy 119.991571 -320.410227) (xy 119.939614 -320.435618) (xy 119.88442 -320.452878) (xy 119.827253 -320.461611)
			(xy 119.798338 -320.462148) (xy 119.77109 -320.461587) (xy 119.717147 -320.453836) (xy 119.664856 -320.438488)
			(xy 119.615281 -320.415854) (xy 119.569433 -320.386396) (xy 119.528243 -320.350712) (xy 119.492551 -320.30953)
			(xy 119.463083 -320.263687) (xy 119.440439 -320.214117) (xy 119.42508 -320.16183) (xy 119.417319 -320.107888)
			(xy 119.41683 -320.08064) (xy 114.605816 -320.08064) (xy 114.605359 -320.107892) (xy 114.597598 -320.16184)
			(xy 114.582238 -320.214135) (xy 114.559593 -320.263712) (xy 114.530123 -320.309562) (xy 114.494429 -320.350751)
			(xy 114.453236 -320.386442) (xy 114.407384 -320.415908) (xy 114.357805 -320.438549) (xy 114.305509 -320.453904)
			(xy 114.25156 -320.461662) (xy 114.224308 -320.462148) (xy 114.19539 -320.461644) (xy 114.138218 -320.452914)
			(xy 114.083018 -320.435655) (xy 114.031056 -320.410261) (xy 113.983522 -320.377314) (xy 113.941507 -320.337569)
			(xy 113.923318 -320.315082) (xy 113.915696 -320.30629) (xy 113.894807 -320.296099) (xy 113.883186 -320.295524)
			(xy 113.80343 -320.295524) (xy 113.791801 -320.296086) (xy 113.77089 -320.306258) (xy 113.763298 -320.315082)
			(xy 113.746545 -320.335865) (xy 113.708191 -320.372995) (xy 113.665037 -320.404417) (xy 113.617923 -320.429516)
			(xy 113.567771 -320.447802) (xy 113.51556 -320.458919) (xy 113.462308 -320.462649) (xy 113.409056 -320.458919)
			(xy 113.356845 -320.447802) (xy 113.306693 -320.429516) (xy 113.259579 -320.404417) (xy 113.216425 -320.372995)
			(xy 113.178071 -320.335865) (xy 113.161318 -320.315082) (xy 113.153696 -320.30629) (xy 113.132807 -320.296099)
			(xy 113.121186 -320.295524) (xy 113.04143 -320.295524) (xy 113.029801 -320.296086) (xy 113.00889 -320.306258)
			(xy 113.001298 -320.315082) (xy 112.984545 -320.335865) (xy 112.946191 -320.372995) (xy 112.903037 -320.404417)
			(xy 112.855923 -320.429516) (xy 112.805771 -320.447802) (xy 112.75356 -320.458919) (xy 112.700308 -320.462649)
			(xy 112.647056 -320.458919) (xy 112.594845 -320.447802) (xy 112.544693 -320.429516) (xy 112.497579 -320.404417)
			(xy 112.454425 -320.372995) (xy 112.416071 -320.335865) (xy 112.399318 -320.315082) (xy 112.391696 -320.30629)
			(xy 112.370807 -320.296099) (xy 112.359186 -320.295524) (xy 112.27943 -320.295524) (xy 112.267801 -320.296086)
			(xy 112.24689 -320.306258) (xy 112.239298 -320.315082) (xy 112.222545 -320.335865) (xy 112.184191 -320.372995)
			(xy 112.141037 -320.404417) (xy 112.093923 -320.429516) (xy 112.043771 -320.447802) (xy 111.99156 -320.458919)
			(xy 111.938308 -320.462649) (xy 111.885056 -320.458919) (xy 111.832845 -320.447802) (xy 111.782693 -320.429516)
			(xy 111.735579 -320.404417) (xy 111.692425 -320.372995) (xy 111.654071 -320.335865) (xy 111.637318 -320.315082)
			(xy 111.629696 -320.30629) (xy 111.608807 -320.296099) (xy 111.597186 -320.295524) (xy 111.51743 -320.295524)
			(xy 111.505801 -320.296086) (xy 111.48489 -320.306258) (xy 111.477298 -320.315082) (xy 111.460545 -320.335865)
			(xy 111.422191 -320.372995) (xy 111.379037 -320.404417) (xy 111.331923 -320.429516) (xy 111.281771 -320.447802)
			(xy 111.22956 -320.458919) (xy 111.176308 -320.462649) (xy 111.123056 -320.458919) (xy 111.070845 -320.447802)
			(xy 111.020693 -320.429516) (xy 110.973579 -320.404417) (xy 110.930425 -320.372995) (xy 110.892071 -320.335865)
			(xy 110.875318 -320.315082) (xy 110.867696 -320.30629) (xy 110.846807 -320.296099) (xy 110.835186 -320.295524)
			(xy 110.75543 -320.295524) (xy 110.743801 -320.296086) (xy 110.72289 -320.306258) (xy 110.715298 -320.315082)
			(xy 110.698545 -320.335865) (xy 110.660191 -320.372995) (xy 110.617037 -320.404417) (xy 110.569923 -320.429516)
			(xy 110.519771 -320.447802) (xy 110.46756 -320.458919) (xy 110.414308 -320.462649) (xy 110.361056 -320.458919)
			(xy 110.308845 -320.447802) (xy 110.258693 -320.429516) (xy 110.211579 -320.404417) (xy 110.168425 -320.372995)
			(xy 110.130071 -320.335865) (xy 110.113318 -320.315082) (xy 110.105696 -320.30629) (xy 110.084807 -320.296099)
			(xy 110.073186 -320.295524) (xy 109.99343 -320.295524) (xy 109.981801 -320.296086) (xy 109.96089 -320.306258)
			(xy 109.953298 -320.315082) (xy 109.936545 -320.335865) (xy 109.898191 -320.372995) (xy 109.855037 -320.404417)
			(xy 109.807923 -320.429516) (xy 109.757771 -320.447802) (xy 109.70556 -320.458919) (xy 109.652308 -320.462649)
			(xy 109.599056 -320.458919) (xy 109.546845 -320.447802) (xy 109.496693 -320.429516) (xy 109.449579 -320.404417)
			(xy 109.406425 -320.372995) (xy 109.368071 -320.335865) (xy 109.351318 -320.315082) (xy 109.343696 -320.30629)
			(xy 109.322807 -320.296099) (xy 109.311186 -320.295524) (xy 109.23143 -320.295524) (xy 109.219801 -320.296086)
			(xy 109.19889 -320.306258) (xy 109.191298 -320.315082) (xy 109.174545 -320.335865) (xy 109.136191 -320.372995)
			(xy 109.093037 -320.404417) (xy 109.045923 -320.429516) (xy 108.995771 -320.447802) (xy 108.94356 -320.458919)
			(xy 108.890308 -320.462649) (xy 108.837056 -320.458919) (xy 108.784845 -320.447802) (xy 108.734693 -320.429516)
			(xy 108.687579 -320.404417) (xy 108.644425 -320.372995) (xy 108.606071 -320.335865) (xy 108.589318 -320.315082)
			(xy 108.581696 -320.30629) (xy 108.560807 -320.296099) (xy 108.549186 -320.295524) (xy 108.46943 -320.295524)
			(xy 108.457801 -320.296086) (xy 108.43689 -320.306258) (xy 108.429298 -320.315082) (xy 108.412545 -320.335865)
			(xy 108.374191 -320.372995) (xy 108.331037 -320.404417) (xy 108.283923 -320.429516) (xy 108.233771 -320.447802)
			(xy 108.18156 -320.458919) (xy 108.128308 -320.462649) (xy 108.075056 -320.458919) (xy 108.022845 -320.447802)
			(xy 107.972693 -320.429516) (xy 107.925579 -320.404417) (xy 107.882425 -320.372995) (xy 107.844071 -320.335865)
			(xy 107.827318 -320.315082) (xy 107.819696 -320.30629) (xy 107.798807 -320.296099) (xy 107.787186 -320.295524)
			(xy 107.70743 -320.295524) (xy 107.695801 -320.296086) (xy 107.67489 -320.306258) (xy 107.667298 -320.315082)
			(xy 107.650545 -320.335865) (xy 107.612191 -320.372995) (xy 107.569037 -320.404417) (xy 107.521923 -320.429516)
			(xy 107.471771 -320.447802) (xy 107.41956 -320.458919) (xy 107.366308 -320.462649) (xy 107.313056 -320.458919)
			(xy 107.260845 -320.447802) (xy 107.210693 -320.429516) (xy 107.163579 -320.404417) (xy 107.120425 -320.372995)
			(xy 107.082071 -320.335865) (xy 107.065318 -320.315082) (xy 107.057696 -320.30629) (xy 107.036807 -320.296099)
			(xy 107.025186 -320.295524) (xy 106.94543 -320.295524) (xy 106.933801 -320.296086) (xy 106.91289 -320.306258)
			(xy 106.905298 -320.315082) (xy 106.887104 -320.337563) (xy 106.845085 -320.377299) (xy 106.797551 -320.410239)
			(xy 106.74559 -320.435628) (xy 106.690393 -320.452884) (xy 106.633224 -320.461613) (xy 106.604308 -320.462148)
			(xy 106.577059 -320.461615) (xy 106.523115 -320.453861) (xy 106.470823 -320.438508) (xy 106.421249 -320.415871)
			(xy 106.3754 -320.386409) (xy 106.334211 -320.350723) (xy 106.298519 -320.309538) (xy 106.269052 -320.263693)
			(xy 106.246408 -320.214122) (xy 106.23105 -320.161832) (xy 106.223289 -320.107889) (xy 106.2228 -320.08064)
			(xy 94.776036 -320.08064) (xy 94.776036 -323.059806) (xy 102.316278 -323.059806) (xy 102.320349 -323.004184)
			(xy 102.332475 -322.949747) (xy 102.352398 -322.897656) (xy 102.379694 -322.849021) (xy 102.41378 -322.804878)
			(xy 102.453929 -322.766169) (xy 102.499287 -322.733718) (xy 102.548887 -322.708217) (xy 102.601671 -322.69021)
			(xy 102.656514 -322.68008) (xy 102.712248 -322.678043) (xy 102.767685 -322.684143) (xy 102.821642 -322.698249)
			(xy 102.872971 -322.720061) (xy 102.920577 -322.749115) (xy 102.963445 -322.78479) (xy 103.000662 -322.826327)
			(xy 103.031435 -322.87284) (xy 103.055107 -322.923337) (xy 103.071175 -322.976744) (xy 103.079295 -323.03192)
			(xy 103.079804 -323.059806) (xy 103.079295 -323.087692) (xy 103.071175 -323.142868) (xy 103.055107 -323.196275)
			(xy 103.031435 -323.246772) (xy 103.000662 -323.293285) (xy 102.963445 -323.334822) (xy 102.920577 -323.370497)
			(xy 102.872971 -323.399551) (xy 102.821642 -323.421363) (xy 102.767685 -323.435469) (xy 102.712248 -323.441569)
			(xy 102.656514 -323.439532) (xy 102.601671 -323.429402) (xy 102.548887 -323.411395) (xy 102.499287 -323.385894)
			(xy 102.453929 -323.353443) (xy 102.41378 -323.314734) (xy 102.379694 -323.270591) (xy 102.352398 -323.221956)
			(xy 102.332475 -323.169865) (xy 102.320349 -323.115428) (xy 102.316278 -323.059806) (xy 94.776036 -323.059806)
			(xy 94.776036 -324.075806) (xy 102.316278 -324.075806) (xy 102.320349 -324.020184) (xy 102.332475 -323.965747)
			(xy 102.352398 -323.913656) (xy 102.379694 -323.865021) (xy 102.41378 -323.820878) (xy 102.453929 -323.782169)
			(xy 102.499287 -323.749718) (xy 102.548887 -323.724217) (xy 102.601671 -323.70621) (xy 102.656514 -323.69608)
			(xy 102.712248 -323.694043) (xy 102.767685 -323.700143) (xy 102.821642 -323.714249) (xy 102.872971 -323.736061)
			(xy 102.920577 -323.765115) (xy 102.963445 -323.80079) (xy 103.000662 -323.842327) (xy 103.031435 -323.88884)
			(xy 103.055107 -323.939337) (xy 103.071175 -323.992744) (xy 103.079295 -324.04792) (xy 103.079804 -324.075806)
			(xy 103.079295 -324.103692) (xy 103.071175 -324.158868) (xy 103.055107 -324.212275) (xy 103.031435 -324.262772)
			(xy 103.000662 -324.309285) (xy 102.963445 -324.350822) (xy 102.920577 -324.386497) (xy 102.872971 -324.415551)
			(xy 102.821642 -324.437363) (xy 102.767685 -324.451469) (xy 102.712248 -324.457569) (xy 102.656514 -324.455532)
			(xy 102.601671 -324.445402) (xy 102.548887 -324.427395) (xy 102.499287 -324.401894) (xy 102.453929 -324.369443)
			(xy 102.41378 -324.330734) (xy 102.379694 -324.286591) (xy 102.352398 -324.237956) (xy 102.332475 -324.185865)
			(xy 102.320349 -324.131428) (xy 102.316278 -324.075806) (xy 94.776036 -324.075806) (xy 94.776036 -326.713596)
			(xy 109.961678 -326.713596) (xy 109.965749 -326.657974) (xy 109.977875 -326.603537) (xy 109.997798 -326.551446)
			(xy 110.025094 -326.502811) (xy 110.05918 -326.458668) (xy 110.099329 -326.419959) (xy 110.144687 -326.387508)
			(xy 110.194287 -326.362007) (xy 110.247071 -326.344) (xy 110.301914 -326.33387) (xy 110.357648 -326.331833)
			(xy 110.413085 -326.337933) (xy 110.467042 -326.352039) (xy 110.518371 -326.373851) (xy 110.565977 -326.402905)
			(xy 110.608845 -326.43858) (xy 110.646062 -326.480117) (xy 110.676835 -326.52663) (xy 110.700507 -326.577127)
			(xy 110.716575 -326.630534) (xy 110.724695 -326.68571) (xy 110.725204 -326.713596) (xy 110.724695 -326.741482)
			(xy 110.716575 -326.796658) (xy 110.700507 -326.850065) (xy 110.676835 -326.900562) (xy 110.646062 -326.947075)
			(xy 110.608845 -326.988612) (xy 110.565977 -327.024287) (xy 110.518371 -327.053341) (xy 110.467042 -327.075153)
			(xy 110.413085 -327.089259) (xy 110.357648 -327.095359) (xy 110.301914 -327.093322) (xy 110.247071 -327.083192)
			(xy 110.194287 -327.065185) (xy 110.144687 -327.039684) (xy 110.099329 -327.007233) (xy 110.05918 -326.968524)
			(xy 110.025094 -326.924381) (xy 109.997798 -326.875746) (xy 109.977875 -326.823655) (xy 109.965749 -326.769218)
			(xy 109.961678 -326.713596) (xy 94.776036 -326.713596) (xy 94.776036 -327.390252) (xy 104.653586 -327.390252)
			(xy 104.657657 -327.33463) (xy 104.669783 -327.280193) (xy 104.689706 -327.228102) (xy 104.717002 -327.179467)
			(xy 104.751088 -327.135324) (xy 104.791237 -327.096615) (xy 104.836595 -327.064164) (xy 104.886195 -327.038663)
			(xy 104.938979 -327.020656) (xy 104.993822 -327.010526) (xy 105.049556 -327.008489) (xy 105.104993 -327.014589)
			(xy 105.15895 -327.028695) (xy 105.210279 -327.050507) (xy 105.257885 -327.079561) (xy 105.300753 -327.115236)
			(xy 105.33797 -327.156773) (xy 105.368743 -327.203286) (xy 105.392415 -327.253783) (xy 105.408483 -327.30719)
			(xy 105.416603 -327.362366) (xy 105.416672 -327.366122) (xy 106.29214 -327.366122) (xy 106.296211 -327.3105)
			(xy 106.308337 -327.256063) (xy 106.32826 -327.203972) (xy 106.355556 -327.155337) (xy 106.389642 -327.111194)
			(xy 106.429791 -327.072485) (xy 106.475149 -327.040034) (xy 106.524749 -327.014533) (xy 106.577533 -326.996526)
			(xy 106.632376 -326.986396) (xy 106.68811 -326.984359) (xy 106.743547 -326.990459) (xy 106.797504 -327.004565)
			(xy 106.848833 -327.026377) (xy 106.896439 -327.055431) (xy 106.939307 -327.091106) (xy 106.976524 -327.132643)
			(xy 107.007297 -327.179156) (xy 107.030969 -327.229653) (xy 107.047037 -327.28306) (xy 107.055157 -327.338236)
			(xy 107.055666 -327.366122) (xy 107.055157 -327.394008) (xy 107.047037 -327.449184) (xy 107.044898 -327.456292)
			(xy 108.97184 -327.456292) (xy 108.975911 -327.40067) (xy 108.988037 -327.346233) (xy 109.00796 -327.294142)
			(xy 109.035256 -327.245507) (xy 109.069342 -327.201364) (xy 109.109491 -327.162655) (xy 109.154849 -327.130204)
			(xy 109.204449 -327.104703) (xy 109.257233 -327.086696) (xy 109.312076 -327.076566) (xy 109.36781 -327.074529)
			(xy 109.423247 -327.080629) (xy 109.477204 -327.094735) (xy 109.528533 -327.116547) (xy 109.576139 -327.145601)
			(xy 109.619007 -327.181276) (xy 109.656224 -327.222813) (xy 109.686997 -327.269326) (xy 109.710669 -327.319823)
			(xy 109.726737 -327.37323) (xy 109.734857 -327.428406) (xy 109.735366 -327.456292) (xy 111.608106 -327.456292)
			(xy 111.612177 -327.40067) (xy 111.624303 -327.346233) (xy 111.644226 -327.294142) (xy 111.671522 -327.245507)
			(xy 111.705608 -327.201364) (xy 111.745757 -327.162655) (xy 111.791115 -327.130204) (xy 111.840715 -327.104703)
			(xy 111.893499 -327.086696) (xy 111.948342 -327.076566) (xy 112.004076 -327.074529) (xy 112.059513 -327.080629)
			(xy 112.11347 -327.094735) (xy 112.164799 -327.116547) (xy 112.212405 -327.145601) (xy 112.255273 -327.181276)
			(xy 112.29249 -327.222813) (xy 112.323263 -327.269326) (xy 112.346935 -327.319823) (xy 112.363003 -327.37323)
			(xy 112.371123 -327.428406) (xy 112.371632 -327.456292) (xy 112.371123 -327.484178) (xy 112.363003 -327.539354)
			(xy 112.346935 -327.592761) (xy 112.323263 -327.643258) (xy 112.29249 -327.689771) (xy 112.255273 -327.731308)
			(xy 112.212405 -327.766983) (xy 112.164799 -327.796037) (xy 112.11347 -327.817849) (xy 112.059513 -327.831955)
			(xy 112.004076 -327.838055) (xy 111.948342 -327.836018) (xy 111.893499 -327.825888) (xy 111.840715 -327.807881)
			(xy 111.791115 -327.78238) (xy 111.745757 -327.749929) (xy 111.705608 -327.71122) (xy 111.671522 -327.667077)
			(xy 111.644226 -327.618442) (xy 111.624303 -327.566351) (xy 111.612177 -327.511914) (xy 111.608106 -327.456292)
			(xy 109.735366 -327.456292) (xy 109.734857 -327.484178) (xy 109.726737 -327.539354) (xy 109.710669 -327.592761)
			(xy 109.686997 -327.643258) (xy 109.656224 -327.689771) (xy 109.619007 -327.731308) (xy 109.576139 -327.766983)
			(xy 109.528533 -327.796037) (xy 109.477204 -327.817849) (xy 109.423247 -327.831955) (xy 109.36781 -327.838055)
			(xy 109.312076 -327.836018) (xy 109.257233 -327.825888) (xy 109.204449 -327.807881) (xy 109.154849 -327.78238)
			(xy 109.109491 -327.749929) (xy 109.069342 -327.71122) (xy 109.035256 -327.667077) (xy 109.00796 -327.618442)
			(xy 108.988037 -327.566351) (xy 108.975911 -327.511914) (xy 108.97184 -327.456292) (xy 107.044898 -327.456292)
			(xy 107.030969 -327.502591) (xy 107.007297 -327.553088) (xy 106.976524 -327.599601) (xy 106.939307 -327.641138)
			(xy 106.896439 -327.676813) (xy 106.848833 -327.705867) (xy 106.797504 -327.727679) (xy 106.743547 -327.741785)
			(xy 106.68811 -327.747885) (xy 106.632376 -327.745848) (xy 106.577533 -327.735718) (xy 106.524749 -327.717711)
			(xy 106.475149 -327.69221) (xy 106.429791 -327.659759) (xy 106.389642 -327.62105) (xy 106.355556 -327.576907)
			(xy 106.32826 -327.528272) (xy 106.308337 -327.476181) (xy 106.296211 -327.421744) (xy 106.29214 -327.366122)
			(xy 105.416672 -327.366122) (xy 105.417112 -327.390252) (xy 105.416603 -327.418138) (xy 105.408483 -327.473314)
			(xy 105.392415 -327.526721) (xy 105.368743 -327.577218) (xy 105.33797 -327.623731) (xy 105.300753 -327.665268)
			(xy 105.257885 -327.700943) (xy 105.210279 -327.729997) (xy 105.15895 -327.751809) (xy 105.104993 -327.765915)
			(xy 105.049556 -327.772015) (xy 104.993822 -327.769978) (xy 104.938979 -327.759848) (xy 104.886195 -327.741841)
			(xy 104.836595 -327.71634) (xy 104.791237 -327.683889) (xy 104.751088 -327.64518) (xy 104.717002 -327.601037)
			(xy 104.689706 -327.552402) (xy 104.669783 -327.500311) (xy 104.657657 -327.445874) (xy 104.653586 -327.390252)
			(xy 94.776036 -327.390252) (xy 94.776036 -328.218292) (xy 103.1908 -328.218292) (xy 103.194871 -328.16267)
			(xy 103.206997 -328.108233) (xy 103.22692 -328.056142) (xy 103.254216 -328.007507) (xy 103.288302 -327.963364)
			(xy 103.328451 -327.924655) (xy 103.373809 -327.892204) (xy 103.423409 -327.866703) (xy 103.476193 -327.848696)
			(xy 103.531036 -327.838566) (xy 103.58677 -327.836529) (xy 103.642207 -327.842629) (xy 103.696164 -327.856735)
			(xy 103.747493 -327.878547) (xy 103.795099 -327.907601) (xy 103.837967 -327.943276) (xy 103.875184 -327.984813)
			(xy 103.905957 -328.031326) (xy 103.929629 -328.081823) (xy 103.945697 -328.13523) (xy 103.953817 -328.190406)
			(xy 103.954326 -328.218292) (xy 103.953817 -328.246178) (xy 103.945697 -328.301354) (xy 103.929629 -328.354761)
			(xy 103.915255 -328.385424) (xy 104.682542 -328.385424) (xy 104.686613 -328.329802) (xy 104.698739 -328.275365)
			(xy 104.718662 -328.223274) (xy 104.745958 -328.174639) (xy 104.780044 -328.130496) (xy 104.820193 -328.091787)
			(xy 104.865551 -328.059336) (xy 104.915151 -328.033835) (xy 104.967935 -328.015828) (xy 105.022778 -328.005698)
			(xy 105.078512 -328.003661) (xy 105.133949 -328.009761) (xy 105.187906 -328.023867) (xy 105.239235 -328.045679)
			(xy 105.286841 -328.074733) (xy 105.329709 -328.110408) (xy 105.366926 -328.151945) (xy 105.397699 -328.198458)
			(xy 105.421371 -328.248955) (xy 105.437439 -328.302362) (xy 105.445559 -328.357538) (xy 105.446068 -328.385424)
			(xy 105.445559 -328.41331) (xy 105.437439 -328.468486) (xy 105.421371 -328.521893) (xy 105.397699 -328.57239)
			(xy 105.366926 -328.618903) (xy 105.329709 -328.66044) (xy 105.286841 -328.696115) (xy 105.239235 -328.725169)
			(xy 105.187906 -328.746981) (xy 105.133949 -328.761087) (xy 105.078512 -328.767187) (xy 105.022778 -328.76515)
			(xy 104.967935 -328.75502) (xy 104.915151 -328.737013) (xy 104.865551 -328.711512) (xy 104.820193 -328.679061)
			(xy 104.780044 -328.640352) (xy 104.745958 -328.596209) (xy 104.718662 -328.547574) (xy 104.698739 -328.495483)
			(xy 104.686613 -328.441046) (xy 104.682542 -328.385424) (xy 103.915255 -328.385424) (xy 103.905957 -328.405258)
			(xy 103.875184 -328.451771) (xy 103.837967 -328.493308) (xy 103.795099 -328.528983) (xy 103.747493 -328.558037)
			(xy 103.696164 -328.579849) (xy 103.642207 -328.593955) (xy 103.58677 -328.600055) (xy 103.531036 -328.598018)
			(xy 103.476193 -328.587888) (xy 103.423409 -328.569881) (xy 103.373809 -328.54438) (xy 103.328451 -328.511929)
			(xy 103.288302 -328.47322) (xy 103.254216 -328.429077) (xy 103.22692 -328.380442) (xy 103.206997 -328.328351)
			(xy 103.194871 -328.273914) (xy 103.1908 -328.218292) (xy 94.776036 -328.218292) (xy 94.776036 -329.038204)
			(xy 102.152194 -329.038204) (xy 102.156265 -328.982582) (xy 102.168391 -328.928145) (xy 102.188314 -328.876054)
			(xy 102.21561 -328.827419) (xy 102.249696 -328.783276) (xy 102.289845 -328.744567) (xy 102.335203 -328.712116)
			(xy 102.384803 -328.686615) (xy 102.437587 -328.668608) (xy 102.49243 -328.658478) (xy 102.548164 -328.656441)
			(xy 102.603601 -328.662541) (xy 102.657558 -328.676647) (xy 102.708887 -328.698459) (xy 102.756493 -328.727513)
			(xy 102.799361 -328.763188) (xy 102.836578 -328.804725) (xy 102.867351 -328.851238) (xy 102.891023 -328.901735)
			(xy 102.907091 -328.955142) (xy 102.915211 -329.010318) (xy 102.91572 -329.038204) (xy 102.915211 -329.06609)
			(xy 102.907091 -329.121266) (xy 102.891023 -329.174673) (xy 102.867351 -329.22517) (xy 102.836578 -329.271683)
			(xy 102.799361 -329.31322) (xy 102.756493 -329.348895) (xy 102.708887 -329.377949) (xy 102.657558 -329.399761)
			(xy 102.603601 -329.413867) (xy 102.548164 -329.419967) (xy 102.49243 -329.41793) (xy 102.437587 -329.4078)
			(xy 102.384803 -329.389793) (xy 102.335203 -329.364292) (xy 102.289845 -329.331841) (xy 102.249696 -329.293132)
			(xy 102.21561 -329.248989) (xy 102.188314 -329.200354) (xy 102.168391 -329.148263) (xy 102.156265 -329.093826)
			(xy 102.152194 -329.038204) (xy 94.776036 -329.038204) (xy 94.776036 -330.416662) (xy 97.355152 -330.416662)
			(xy 97.355152 -329.553062) (xy 97.355642 -329.523078) (xy 97.36347 -329.463622) (xy 97.378991 -329.405697)
			(xy 97.40194 -329.350293) (xy 97.431924 -329.298359) (xy 97.46843 -329.250783) (xy 97.510835 -329.208378)
			(xy 97.558411 -329.171872) (xy 97.610345 -329.141888) (xy 97.665749 -329.118939) (xy 97.723674 -329.103418)
			(xy 97.78313 -329.09559) (xy 97.843098 -329.09559) (xy 97.902554 -329.103418) (xy 97.960479 -329.118939)
			(xy 98.015883 -329.141888) (xy 98.067817 -329.171872) (xy 98.115393 -329.208378) (xy 98.157798 -329.250783)
			(xy 98.194304 -329.298359) (xy 98.224288 -329.350293) (xy 98.247237 -329.405697) (xy 98.258955 -329.44943)
			(xy 114.249198 -329.44943) (xy 114.253269 -329.393808) (xy 114.265395 -329.339371) (xy 114.285318 -329.28728)
			(xy 114.312614 -329.238645) (xy 114.3467 -329.194502) (xy 114.386849 -329.155793) (xy 114.432207 -329.123342)
			(xy 114.481807 -329.097841) (xy 114.534591 -329.079834) (xy 114.589434 -329.069704) (xy 114.645168 -329.067667)
			(xy 114.700605 -329.073767) (xy 114.754562 -329.087873) (xy 114.805891 -329.109685) (xy 114.853497 -329.138739)
			(xy 114.896365 -329.174414) (xy 114.933582 -329.215951) (xy 114.964355 -329.262464) (xy 114.988027 -329.312961)
			(xy 115.004095 -329.366368) (xy 115.012215 -329.421544) (xy 115.012678 -329.44689) (xy 116.277642 -329.44689)
			(xy 116.281713 -329.391268) (xy 116.293839 -329.336831) (xy 116.313762 -329.28474) (xy 116.341058 -329.236105)
			(xy 116.375144 -329.191962) (xy 116.415293 -329.153253) (xy 116.460651 -329.120802) (xy 116.510251 -329.095301)
			(xy 116.563035 -329.077294) (xy 116.617878 -329.067164) (xy 116.673612 -329.065127) (xy 116.729049 -329.071227)
			(xy 116.783006 -329.085333) (xy 116.834335 -329.107145) (xy 116.881941 -329.136199) (xy 116.924809 -329.171874)
			(xy 116.962026 -329.213411) (xy 116.992799 -329.259924) (xy 117.016471 -329.310421) (xy 117.032539 -329.363828)
			(xy 117.040659 -329.419004) (xy 117.041168 -329.44689) (xy 117.293642 -329.44689) (xy 117.297713 -329.391268)
			(xy 117.309839 -329.336831) (xy 117.329762 -329.28474) (xy 117.357058 -329.236105) (xy 117.391144 -329.191962)
			(xy 117.431293 -329.153253) (xy 117.476651 -329.120802) (xy 117.526251 -329.095301) (xy 117.579035 -329.077294)
			(xy 117.633878 -329.067164) (xy 117.689612 -329.065127) (xy 117.745049 -329.071227) (xy 117.799006 -329.085333)
			(xy 117.850335 -329.107145) (xy 117.897941 -329.136199) (xy 117.940809 -329.171874) (xy 117.978026 -329.213411)
			(xy 118.008799 -329.259924) (xy 118.032471 -329.310421) (xy 118.048539 -329.363828) (xy 118.056659 -329.419004)
			(xy 118.057168 -329.44689) (xy 118.056659 -329.474776) (xy 118.048539 -329.529952) (xy 118.032471 -329.583359)
			(xy 118.008799 -329.633856) (xy 117.978026 -329.680369) (xy 117.940809 -329.721906) (xy 117.897941 -329.757581)
			(xy 117.850335 -329.786635) (xy 117.799006 -329.808447) (xy 117.745049 -329.822553) (xy 117.689612 -329.828653)
			(xy 117.633878 -329.826616) (xy 117.579035 -329.816486) (xy 117.526251 -329.798479) (xy 117.476651 -329.772978)
			(xy 117.431293 -329.740527) (xy 117.391144 -329.701818) (xy 117.357058 -329.657675) (xy 117.329762 -329.60904)
			(xy 117.309839 -329.556949) (xy 117.297713 -329.502512) (xy 117.293642 -329.44689) (xy 117.041168 -329.44689)
			(xy 117.040659 -329.474776) (xy 117.032539 -329.529952) (xy 117.016471 -329.583359) (xy 116.992799 -329.633856)
			(xy 116.962026 -329.680369) (xy 116.924809 -329.721906) (xy 116.881941 -329.757581) (xy 116.834335 -329.786635)
			(xy 116.783006 -329.808447) (xy 116.729049 -329.822553) (xy 116.673612 -329.828653) (xy 116.617878 -329.826616)
			(xy 116.563035 -329.816486) (xy 116.510251 -329.798479) (xy 116.460651 -329.772978) (xy 116.415293 -329.740527)
			(xy 116.375144 -329.701818) (xy 116.341058 -329.657675) (xy 116.313762 -329.60904) (xy 116.293839 -329.556949)
			(xy 116.281713 -329.502512) (xy 116.277642 -329.44689) (xy 115.012678 -329.44689) (xy 115.012724 -329.44943)
			(xy 115.012215 -329.477316) (xy 115.004095 -329.532492) (xy 114.988027 -329.585899) (xy 114.964355 -329.636396)
			(xy 114.933582 -329.682909) (xy 114.896365 -329.724446) (xy 114.853497 -329.760121) (xy 114.805891 -329.789175)
			(xy 114.754562 -329.810987) (xy 114.700605 -329.825093) (xy 114.645168 -329.831193) (xy 114.589434 -329.829156)
			(xy 114.534591 -329.819026) (xy 114.481807 -329.801019) (xy 114.432207 -329.775518) (xy 114.386849 -329.743067)
			(xy 114.3467 -329.704358) (xy 114.312614 -329.660215) (xy 114.285318 -329.61158) (xy 114.265395 -329.559489)
			(xy 114.253269 -329.505052) (xy 114.249198 -329.44943) (xy 98.258955 -329.44943) (xy 98.262758 -329.463622)
			(xy 98.270586 -329.523078) (xy 98.271076 -329.553062) (xy 98.271076 -330.416662) (xy 98.270586 -330.446646)
			(xy 98.262758 -330.506102) (xy 98.247237 -330.564027) (xy 98.224288 -330.619431) (xy 98.194304 -330.671365)
			(xy 98.157798 -330.718941) (xy 98.115393 -330.761346) (xy 98.067817 -330.797852) (xy 98.015883 -330.827836)
			(xy 97.960479 -330.850785) (xy 97.902554 -330.866306) (xy 97.843098 -330.874134) (xy 97.78313 -330.874134)
			(xy 97.723674 -330.866306) (xy 97.665749 -330.850785) (xy 97.610345 -330.827836) (xy 97.558411 -330.797852)
			(xy 97.510835 -330.761346) (xy 97.46843 -330.718941) (xy 97.431924 -330.671365) (xy 97.40194 -330.619431)
			(xy 97.378991 -330.564027) (xy 97.36347 -330.506102) (xy 97.355642 -330.446646) (xy 97.355152 -330.416662)
			(xy 94.776036 -330.416662) (xy 94.776036 -331.53223) (xy 114.955828 -331.53223) (xy 114.955828 -330.66863)
			(xy 114.956318 -330.638646) (xy 114.964146 -330.57919) (xy 114.979667 -330.521265) (xy 115.002616 -330.465861)
			(xy 115.0326 -330.413927) (xy 115.069106 -330.366351) (xy 115.111511 -330.323946) (xy 115.159087 -330.28744)
			(xy 115.211021 -330.257456) (xy 115.266425 -330.234507) (xy 115.32435 -330.218986) (xy 115.383806 -330.211158)
			(xy 115.443774 -330.211158) (xy 115.50323 -330.218986) (xy 115.561155 -330.234507) (xy 115.616559 -330.257456)
			(xy 115.668493 -330.28744) (xy 115.716069 -330.323946) (xy 115.758474 -330.366351) (xy 115.79498 -330.413927)
			(xy 115.824964 -330.465861) (xy 115.847913 -330.521265) (xy 115.863434 -330.57919) (xy 115.871262 -330.638646)
			(xy 115.871752 -330.66863) (xy 115.871752 -330.760651) (xy 123.469378 -330.760651) (xy 123.469378 -330.706149)
			(xy 123.477134 -330.652201) (xy 123.492489 -330.599906) (xy 123.515131 -330.550329) (xy 123.544597 -330.504479)
			(xy 123.580288 -330.463288) (xy 123.621479 -330.427597) (xy 123.667329 -330.398131) (xy 123.716906 -330.375489)
			(xy 123.769201 -330.360134) (xy 123.823149 -330.352378) (xy 123.8504 -330.351892) (xy 123.87777 -330.35236)
			(xy 123.931949 -330.360178) (xy 123.984452 -330.375666) (xy 124.034199 -330.398508) (xy 124.080166 -330.428231)
			(xy 124.101098 -330.445872) (xy 124.101352 -330.446126) (xy 124.108446 -330.451702) (xy 124.125357 -330.457954)
			(xy 124.134372 -330.458318) (xy 124.201428 -330.458318) (xy 124.210446 -330.457971) (xy 124.227363 -330.451716)
			(xy 124.234448 -330.446126) (xy 124.234448 -330.445872) (xy 124.234702 -330.445872) (xy 124.255619 -330.428214)
			(xy 124.301596 -330.398506) (xy 124.351348 -330.375674) (xy 124.403852 -330.360187) (xy 124.45803 -330.352364)
			(xy 124.4854 -330.351892) (xy 124.512651 -330.352378) (xy 124.566599 -330.360134) (xy 124.618894 -330.375489)
			(xy 124.668471 -330.398131) (xy 124.714321 -330.427597) (xy 124.755512 -330.463288) (xy 124.791203 -330.504479)
			(xy 124.820669 -330.550329) (xy 124.843311 -330.599906) (xy 124.858666 -330.652201) (xy 124.866422 -330.706149)
			(xy 124.866422 -330.760651) (xy 124.858666 -330.814599) (xy 124.843311 -330.866894) (xy 124.820669 -330.916471)
			(xy 124.791203 -330.962321) (xy 124.755512 -331.003512) (xy 124.714321 -331.039203) (xy 124.668471 -331.068669)
			(xy 124.618894 -331.091311) (xy 124.566599 -331.106666) (xy 124.512651 -331.114422) (xy 124.4854 -331.114908)
			(xy 124.45803 -331.11444) (xy 124.403851 -331.106622) (xy 124.351348 -331.091134) (xy 124.301601 -331.068292)
			(xy 124.255634 -331.038569) (xy 124.234702 -331.020928) (xy 124.234448 -331.020674) (xy 124.227354 -331.015098)
			(xy 124.210443 -331.008846) (xy 124.201428 -331.008482) (xy 124.134372 -331.008482) (xy 124.125354 -331.008829)
			(xy 124.108437 -331.015084) (xy 124.101352 -331.020674) (xy 124.101352 -331.020928) (xy 124.101098 -331.020928)
			(xy 124.080181 -331.038586) (xy 124.034204 -331.068294) (xy 123.984452 -331.091126) (xy 123.931948 -331.106613)
			(xy 123.87777 -331.114436) (xy 123.8504 -331.114908) (xy 123.823149 -331.114422) (xy 123.769201 -331.106666)
			(xy 123.716906 -331.091311) (xy 123.667329 -331.068669) (xy 123.621479 -331.039203) (xy 123.580288 -331.003512)
			(xy 123.544597 -330.962321) (xy 123.515131 -330.916471) (xy 123.492489 -330.866894) (xy 123.477134 -330.814599)
			(xy 123.469378 -330.760651) (xy 115.871752 -330.760651) (xy 115.871752 -331.53223) (xy 115.871262 -331.562214)
			(xy 115.863434 -331.62167) (xy 115.847913 -331.679595) (xy 115.824964 -331.734999) (xy 115.79498 -331.786933)
			(xy 115.758474 -331.834509) (xy 115.716069 -331.876914) (xy 115.668493 -331.91342) (xy 115.616559 -331.943404)
			(xy 115.561155 -331.966353) (xy 115.50323 -331.981874) (xy 115.443774 -331.989702) (xy 115.383806 -331.989702)
			(xy 115.32435 -331.981874) (xy 115.266425 -331.966353) (xy 115.211021 -331.943404) (xy 115.159087 -331.91342)
			(xy 115.111511 -331.876914) (xy 115.069106 -331.834509) (xy 115.0326 -331.786933) (xy 115.002616 -331.734999)
			(xy 114.979667 -331.679595) (xy 114.964146 -331.62167) (xy 114.956318 -331.562214) (xy 114.955828 -331.53223)
			(xy 94.776036 -331.53223) (xy 94.776036 -332.043532) (xy 101.474776 -332.043532) (xy 101.478847 -331.98791)
			(xy 101.490973 -331.933473) (xy 101.510896 -331.881382) (xy 101.538192 -331.832747) (xy 101.572278 -331.788604)
			(xy 101.612427 -331.749895) (xy 101.657785 -331.717444) (xy 101.707385 -331.691943) (xy 101.760169 -331.673936)
			(xy 101.815012 -331.663806) (xy 101.870746 -331.661769) (xy 101.926183 -331.667869) (xy 101.98014 -331.681975)
			(xy 102.031469 -331.703787) (xy 102.079075 -331.732841) (xy 102.121943 -331.768516) (xy 102.15916 -331.810053)
			(xy 102.189933 -331.856566) (xy 102.213605 -331.907063) (xy 102.229673 -331.96047) (xy 102.237793 -332.015646)
			(xy 102.238302 -332.043532) (xy 102.237793 -332.071418) (xy 102.229673 -332.126594) (xy 102.213605 -332.180001)
			(xy 102.189933 -332.230498) (xy 102.15916 -332.277011) (xy 102.121943 -332.318548) (xy 102.079075 -332.354223)
			(xy 102.031469 -332.383277) (xy 101.98014 -332.405089) (xy 101.926183 -332.419195) (xy 101.870746 -332.425295)
			(xy 101.815012 -332.423258) (xy 101.760169 -332.413128) (xy 101.707385 -332.395121) (xy 101.657785 -332.36962)
			(xy 101.612427 -332.337169) (xy 101.572278 -332.29846) (xy 101.538192 -332.254317) (xy 101.510896 -332.205682)
			(xy 101.490973 -332.153591) (xy 101.478847 -332.099154) (xy 101.474776 -332.043532) (xy 94.776036 -332.043532)
			(xy 94.776036 -333.049118) (xy 94.77656 -333.059014) (xy 94.784149 -333.077301) (xy 94.790768 -333.084678)
			(xy 94.801436 -333.0956) (xy 94.847918 -333.142082) (xy 94.85476 -333.149481) (xy 94.862478 -333.16808)
			(xy 94.862904 -333.17815) (xy 94.862904 -333.614522) (xy 100.858318 -333.614522) (xy 100.862389 -333.5589)
			(xy 100.874515 -333.504463) (xy 100.894438 -333.452372) (xy 100.921734 -333.403737) (xy 100.95582 -333.359594)
			(xy 100.995969 -333.320885) (xy 101.041327 -333.288434) (xy 101.090927 -333.262933) (xy 101.143711 -333.244926)
			(xy 101.198554 -333.234796) (xy 101.254288 -333.232759) (xy 101.309725 -333.238859) (xy 101.363682 -333.252965)
			(xy 101.415011 -333.274777) (xy 101.462617 -333.303831) (xy 101.505485 -333.339506) (xy 101.542702 -333.381043)
			(xy 101.573475 -333.427556) (xy 101.597147 -333.478053) (xy 101.613215 -333.53146) (xy 101.621335 -333.586636)
			(xy 101.621844 -333.614522) (xy 101.621335 -333.642408) (xy 101.613215 -333.697584) (xy 101.597147 -333.750991)
			(xy 101.573475 -333.801488) (xy 101.542702 -333.848001) (xy 101.505485 -333.889538) (xy 101.462617 -333.925213)
			(xy 101.415011 -333.954267) (xy 101.363682 -333.976079) (xy 101.309725 -333.990185) (xy 101.254288 -333.996285)
			(xy 101.198554 -333.994248) (xy 101.143711 -333.984118) (xy 101.090927 -333.966111) (xy 101.041327 -333.94061)
			(xy 100.995969 -333.908159) (xy 100.95582 -333.86945) (xy 100.921734 -333.825307) (xy 100.894438 -333.776672)
			(xy 100.874515 -333.724581) (xy 100.862389 -333.670144) (xy 100.858318 -333.614522) (xy 94.862904 -333.614522)
			(xy 94.862904 -334.297274) (xy 102.382064 -334.297274) (xy 102.386135 -334.241652) (xy 102.398261 -334.187215)
			(xy 102.418184 -334.135124) (xy 102.44548 -334.086489) (xy 102.479566 -334.042346) (xy 102.519715 -334.003637)
			(xy 102.565073 -333.971186) (xy 102.614673 -333.945685) (xy 102.667457 -333.927678) (xy 102.7223 -333.917548)
			(xy 102.778034 -333.915511) (xy 102.833471 -333.921611) (xy 102.887428 -333.935717) (xy 102.938757 -333.957529)
			(xy 102.986363 -333.986583) (xy 103.029231 -334.022258) (xy 103.066448 -334.063795) (xy 103.097221 -334.110308)
			(xy 103.111639 -334.141064) (xy 103.559862 -334.141064) (xy 103.563933 -334.085442) (xy 103.576059 -334.031005)
			(xy 103.595982 -333.978914) (xy 103.623278 -333.930279) (xy 103.657364 -333.886136) (xy 103.697513 -333.847427)
			(xy 103.742871 -333.814976) (xy 103.792471 -333.789475) (xy 103.845255 -333.771468) (xy 103.900098 -333.761338)
			(xy 103.955832 -333.759301) (xy 104.011269 -333.765401) (xy 104.065226 -333.779507) (xy 104.116555 -333.801319)
			(xy 104.164161 -333.830373) (xy 104.207029 -333.866048) (xy 104.244246 -333.907585) (xy 104.275019 -333.954098)
			(xy 104.298691 -334.004595) (xy 104.314759 -334.058002) (xy 104.322879 -334.113178) (xy 104.323388 -334.141064)
			(xy 104.322879 -334.16895) (xy 104.314759 -334.224126) (xy 104.298691 -334.277533) (xy 104.275019 -334.32803)
			(xy 104.244246 -334.374543) (xy 104.207029 -334.41608) (xy 104.164161 -334.451755) (xy 104.116555 -334.480809)
			(xy 104.065226 -334.502621) (xy 104.011269 -334.516727) (xy 103.955832 -334.522827) (xy 103.900098 -334.52079)
			(xy 103.845255 -334.51066) (xy 103.792471 -334.492653) (xy 103.742871 -334.467152) (xy 103.697513 -334.434701)
			(xy 103.657364 -334.395992) (xy 103.623278 -334.351849) (xy 103.595982 -334.303214) (xy 103.576059 -334.251123)
			(xy 103.563933 -334.196686) (xy 103.559862 -334.141064) (xy 103.111639 -334.141064) (xy 103.120893 -334.160805)
			(xy 103.136961 -334.214212) (xy 103.145081 -334.269388) (xy 103.14559 -334.297274) (xy 103.145081 -334.32516)
			(xy 103.136961 -334.380336) (xy 103.120893 -334.433743) (xy 103.097221 -334.48424) (xy 103.066448 -334.530753)
			(xy 103.029231 -334.57229) (xy 102.986363 -334.607965) (xy 102.938757 -334.637019) (xy 102.887428 -334.658831)
			(xy 102.833471 -334.672937) (xy 102.778034 -334.679037) (xy 102.7223 -334.677) (xy 102.667457 -334.66687)
			(xy 102.614673 -334.648863) (xy 102.565073 -334.623362) (xy 102.519715 -334.590911) (xy 102.479566 -334.552202)
			(xy 102.44548 -334.508059) (xy 102.418184 -334.459424) (xy 102.398261 -334.407333) (xy 102.386135 -334.352896)
			(xy 102.382064 -334.297274) (xy 94.862904 -334.297274) (xy 94.862904 -334.774794) (xy 104.55224 -334.774794)
			(xy 104.556311 -334.719172) (xy 104.568437 -334.664735) (xy 104.58836 -334.612644) (xy 104.615656 -334.564009)
			(xy 104.649742 -334.519866) (xy 104.689891 -334.481157) (xy 104.735249 -334.448706) (xy 104.784849 -334.423205)
			(xy 104.837633 -334.405198) (xy 104.892476 -334.395068) (xy 104.94821 -334.393031) (xy 105.003647 -334.399131)
			(xy 105.057604 -334.413237) (xy 105.108933 -334.435049) (xy 105.156539 -334.464103) (xy 105.199407 -334.499778)
			(xy 105.236624 -334.541315) (xy 105.267397 -334.587828) (xy 105.291069 -334.638325) (xy 105.307137 -334.691732)
			(xy 105.308558 -334.701388) (xy 106.182412 -334.701388) (xy 106.186483 -334.645766) (xy 106.198609 -334.591329)
			(xy 106.218532 -334.539238) (xy 106.245828 -334.490603) (xy 106.279914 -334.44646) (xy 106.320063 -334.407751)
			(xy 106.365421 -334.3753) (xy 106.415021 -334.349799) (xy 106.467805 -334.331792) (xy 106.522648 -334.321662)
			(xy 106.578382 -334.319625) (xy 106.633819 -334.325725) (xy 106.687776 -334.339831) (xy 106.739105 -334.361643)
			(xy 106.786711 -334.390697) (xy 106.829579 -334.426372) (xy 106.866796 -334.467909) (xy 106.897569 -334.514422)
			(xy 106.921241 -334.564919) (xy 106.937309 -334.618326) (xy 106.945429 -334.673502) (xy 106.945938 -334.701388)
			(xy 106.945429 -334.729274) (xy 106.937309 -334.78445) (xy 106.921241 -334.837857) (xy 106.897569 -334.888354)
			(xy 106.866796 -334.934867) (xy 106.829579 -334.976404) (xy 106.786711 -335.012079) (xy 106.739105 -335.041133)
			(xy 106.687776 -335.062945) (xy 106.633819 -335.077051) (xy 106.578382 -335.083151) (xy 106.522648 -335.081114)
			(xy 106.467805 -335.070984) (xy 106.415021 -335.052977) (xy 106.365421 -335.027476) (xy 106.320063 -334.995025)
			(xy 106.279914 -334.956316) (xy 106.245828 -334.912173) (xy 106.218532 -334.863538) (xy 106.198609 -334.811447)
			(xy 106.186483 -334.75701) (xy 106.182412 -334.701388) (xy 105.308558 -334.701388) (xy 105.315257 -334.746908)
			(xy 105.315766 -334.774794) (xy 105.315257 -334.80268) (xy 105.307137 -334.857856) (xy 105.291069 -334.911263)
			(xy 105.267397 -334.96176) (xy 105.236624 -335.008273) (xy 105.199407 -335.04981) (xy 105.156539 -335.085485)
			(xy 105.108933 -335.114539) (xy 105.057604 -335.136351) (xy 105.003647 -335.150457) (xy 104.94821 -335.156557)
			(xy 104.892476 -335.15452) (xy 104.837633 -335.14439) (xy 104.784849 -335.126383) (xy 104.735249 -335.100882)
			(xy 104.689891 -335.068431) (xy 104.649742 -335.029722) (xy 104.615656 -334.985579) (xy 104.58836 -334.936944)
			(xy 104.568437 -334.884853) (xy 104.556311 -334.830416) (xy 104.55224 -334.774794) (xy 94.862904 -334.774794)
			(xy 94.862904 -335.23301) (xy 101.97211 -335.23301) (xy 101.972596 -335.205759) (xy 101.980352 -335.151811)
			(xy 101.995707 -335.099516) (xy 102.018349 -335.049939) (xy 102.047815 -335.004089) (xy 102.083506 -334.962898)
			(xy 102.124697 -334.927207) (xy 102.170547 -334.897741) (xy 102.220124 -334.875099) (xy 102.272419 -334.859744)
			(xy 102.326367 -334.851988) (xy 102.380869 -334.851988) (xy 102.434817 -334.859744) (xy 102.487112 -334.875099)
			(xy 102.536689 -334.897741) (xy 102.582539 -334.927207) (xy 102.62373 -334.962898) (xy 102.659421 -335.004089)
			(xy 102.688887 -335.049939) (xy 102.711529 -335.099516) (xy 102.726884 -335.151811) (xy 102.73464 -335.205759)
			(xy 102.735126 -335.23301) (xy 102.734618 -335.253584) (xy 102.734591 -335.264185) (xy 102.742074 -335.283996)
			(xy 102.749096 -335.291938) (xy 102.801166 -335.345532) (xy 102.808864 -335.352652) (xy 102.828275 -335.360522)
			(xy 102.838758 -335.360772) (xy 102.839012 -335.360772) (xy 102.84968 -335.360518) (xy 102.850188 -335.360518)
			(xy 102.877429 -335.360964) (xy 102.931353 -335.368755) (xy 102.98362 -335.384138) (xy 103.033167 -335.406799)
			(xy 103.078987 -335.436278) (xy 103.120147 -335.471976) (xy 103.15581 -335.513165) (xy 103.185252 -335.559009)
			(xy 103.207872 -335.608575) (xy 103.223212 -335.660854) (xy 103.230959 -335.714784) (xy 103.231334 -335.73593)
			(xy 103.44988 -335.73593) (xy 103.453951 -335.680308) (xy 103.466077 -335.625871) (xy 103.486 -335.57378)
			(xy 103.513296 -335.525145) (xy 103.547382 -335.481002) (xy 103.587531 -335.442293) (xy 103.632889 -335.409842)
			(xy 103.682489 -335.384341) (xy 103.735273 -335.366334) (xy 103.790116 -335.356204) (xy 103.84585 -335.354167)
			(xy 103.901287 -335.360267) (xy 103.955244 -335.374373) (xy 104.006573 -335.396185) (xy 104.054179 -335.425239)
			(xy 104.097047 -335.460914) (xy 104.134264 -335.502451) (xy 104.165037 -335.548964) (xy 104.188709 -335.599461)
			(xy 104.204777 -335.652868) (xy 104.212897 -335.708044) (xy 104.213406 -335.73593) (xy 104.212897 -335.763816)
			(xy 104.204777 -335.818992) (xy 104.188709 -335.872399) (xy 104.165037 -335.922896) (xy 104.134264 -335.969409)
			(xy 104.097047 -336.010946) (xy 104.054179 -336.046621) (xy 104.006573 -336.075675) (xy 103.955244 -336.097487)
			(xy 103.901287 -336.111593) (xy 103.84585 -336.117693) (xy 103.790116 -336.115656) (xy 103.735273 -336.105526)
			(xy 103.682489 -336.087519) (xy 103.632889 -336.062018) (xy 103.587531 -336.029567) (xy 103.547382 -335.990858)
			(xy 103.513296 -335.946715) (xy 103.486 -335.89808) (xy 103.466077 -335.845989) (xy 103.453951 -335.791552)
			(xy 103.44988 -335.73593) (xy 103.231334 -335.73593) (xy 103.231442 -335.742026) (xy 103.230956 -335.769277)
			(xy 103.2232 -335.823225) (xy 103.207845 -335.87552) (xy 103.185203 -335.925097) (xy 103.155737 -335.970947)
			(xy 103.120046 -336.012138) (xy 103.078855 -336.047829) (xy 103.033005 -336.077295) (xy 102.983428 -336.099937)
			(xy 102.931133 -336.115292) (xy 102.877185 -336.123048) (xy 102.822683 -336.123048) (xy 102.768735 -336.115292)
			(xy 102.71644 -336.099937) (xy 102.666863 -336.077295) (xy 102.621013 -336.047829) (xy 102.579822 -336.012138)
			(xy 102.544131 -335.970947) (xy 102.514665 -335.925097) (xy 102.492023 -335.87552) (xy 102.476668 -335.823225)
			(xy 102.468912 -335.769277) (xy 102.468426 -335.742026) (xy 102.468934 -335.721452) (xy 102.468954 -335.710851)
			(xy 102.461478 -335.69104) (xy 102.454456 -335.683098) (xy 102.402386 -335.629504) (xy 102.394677 -335.622399)
			(xy 102.375274 -335.614522) (xy 102.364794 -335.614264) (xy 102.36454 -335.614264) (xy 102.353872 -335.614518)
			(xy 102.353364 -335.614518) (xy 102.326126 -335.613988) (xy 102.272207 -335.606204) (xy 102.219944 -335.59083)
			(xy 102.170399 -335.568177) (xy 102.124581 -335.538707) (xy 102.083421 -335.503019) (xy 102.047757 -335.461838)
			(xy 102.018314 -335.416002) (xy 101.995691 -335.366444) (xy 101.980347 -335.314172) (xy 101.972596 -335.260249)
			(xy 101.97211 -335.23301) (xy 94.862904 -335.23301) (xy 94.862904 -335.69783) (xy 97.767392 -335.69783)
			(xy 97.771463 -335.642208) (xy 97.783589 -335.587771) (xy 97.803512 -335.53568) (xy 97.830808 -335.487045)
			(xy 97.864894 -335.442902) (xy 97.905043 -335.404193) (xy 97.950401 -335.371742) (xy 98.000001 -335.346241)
			(xy 98.052785 -335.328234) (xy 98.107628 -335.318104) (xy 98.163362 -335.316067) (xy 98.218799 -335.322167)
			(xy 98.272756 -335.336273) (xy 98.324085 -335.358085) (xy 98.371691 -335.387139) (xy 98.414559 -335.422814)
			(xy 98.451776 -335.464351) (xy 98.482549 -335.510864) (xy 98.506221 -335.561361) (xy 98.522289 -335.614768)
			(xy 98.530409 -335.669944) (xy 98.530918 -335.69783) (xy 98.530409 -335.725716) (xy 98.522289 -335.780892)
			(xy 98.506221 -335.834299) (xy 98.482549 -335.884796) (xy 98.451776 -335.931309) (xy 98.414559 -335.972846)
			(xy 98.371691 -336.008521) (xy 98.324085 -336.037575) (xy 98.272756 -336.059387) (xy 98.218799 -336.073493)
			(xy 98.163362 -336.079593) (xy 98.107628 -336.077556) (xy 98.052785 -336.067426) (xy 98.000001 -336.049419)
			(xy 97.950401 -336.023918) (xy 97.905043 -335.991467) (xy 97.864894 -335.952758) (xy 97.830808 -335.908615)
			(xy 97.803512 -335.85998) (xy 97.783589 -335.807889) (xy 97.771463 -335.753452) (xy 97.767392 -335.69783)
			(xy 94.862904 -335.69783) (xy 94.862904 -336.255614) (xy 107.272836 -336.255614) (xy 107.272836 -334.904842)
			(xy 107.272969 -334.899951) (xy 107.27489 -334.890359) (xy 107.276646 -334.885792) (xy 107.315254 -334.790034)
			(xy 107.317424 -334.785205) (xy 107.32344 -334.776497) (xy 107.327192 -334.772762) (xy 107.363514 -334.737456)
			(xy 107.364022 -334.736948) (xy 108.800138 -333.300578) (xy 108.817412 -333.283907) (xy 108.856227 -333.255658)
			(xy 108.898983 -333.233829) (xy 108.944627 -333.218957) (xy 108.992035 -333.211407) (xy 109.016038 -333.210916)
			(xy 109.217206 -333.210916) (xy 109.245514 -333.211598) (xy 109.301148 -333.222108) (xy 109.353892 -333.242693)
			(xy 109.378242 -333.257144) (xy 109.387916 -333.262556) (xy 109.409896 -333.265251) (xy 109.430963 -333.258427)
			(xy 109.439456 -333.251302) (xy 109.46075 -333.232316) (xy 109.507916 -333.200226) (xy 109.559333 -333.175512)
			(xy 109.613854 -333.158723) (xy 109.670266 -333.150233) (xy 109.69879 -333.149702) (xy 109.725656 -333.150133)
			(xy 109.778854 -333.157696) (xy 109.830465 -333.172647) (xy 109.879469 -333.194689) (xy 109.924896 -333.223387)
			(xy 109.965849 -333.258173) (xy 110.001518 -333.298359) (xy 110.031197 -333.343152) (xy 110.0543 -333.391664)
			(xy 110.062772 -333.417164) (xy 110.065443 -333.424743) (xy 110.074769 -333.437819) (xy 110.08106 -333.442818)
			(xy 110.104428 -333.460344) (xy 110.110977 -333.464796) (xy 110.125983 -333.469834) (xy 110.133892 -333.47025)
			(xy 110.157319 -333.471097) (xy 110.203508 -333.479092) (xy 110.247929 -333.494065) (xy 110.289533 -333.515662)
			(xy 110.32734 -333.543375) (xy 110.344204 -333.559658) (xy 110.431072 -333.646272) (xy 110.447677 -333.663559)
			(xy 110.475841 -333.702341) (xy 110.497608 -333.745044) (xy 110.512443 -333.79062) (xy 110.519983 -333.837954)
			(xy 110.520343 -333.855314) (xy 112.467134 -333.855314) (xy 112.471205 -333.799692) (xy 112.483331 -333.745255)
			(xy 112.503254 -333.693164) (xy 112.53055 -333.644529) (xy 112.564636 -333.600386) (xy 112.604785 -333.561677)
			(xy 112.650143 -333.529226) (xy 112.699743 -333.503725) (xy 112.752527 -333.485718) (xy 112.80737 -333.475588)
			(xy 112.863104 -333.473551) (xy 112.918541 -333.479651) (xy 112.972498 -333.493757) (xy 113.023827 -333.515569)
			(xy 113.071433 -333.544623) (xy 113.114301 -333.580298) (xy 113.151518 -333.621835) (xy 113.182291 -333.668348)
			(xy 113.205963 -333.718845) (xy 113.222031 -333.772252) (xy 113.230151 -333.827428) (xy 113.23066 -333.855314)
			(xy 113.230151 -333.8832) (xy 113.222031 -333.938376) (xy 113.205963 -333.991783) (xy 113.182291 -334.04228)
			(xy 113.151518 -334.088793) (xy 113.114301 -334.13033) (xy 113.071433 -334.166005) (xy 113.023827 -334.195059)
			(xy 112.972498 -334.216871) (xy 112.918541 -334.230977) (xy 112.863104 -334.237077) (xy 112.80737 -334.23504)
			(xy 112.752527 -334.22491) (xy 112.699743 -334.206903) (xy 112.650143 -334.181402) (xy 112.604785 -334.148951)
			(xy 112.564636 -334.110242) (xy 112.53055 -334.066099) (xy 112.503254 -334.017464) (xy 112.483331 -333.965373)
			(xy 112.471205 -333.910936) (xy 112.467134 -333.855314) (xy 110.520343 -333.855314) (xy 110.52048 -333.861918)
			(xy 110.52048 -335.881726) (xy 111.234218 -335.881726) (xy 111.238289 -335.826104) (xy 111.250415 -335.771667)
			(xy 111.270338 -335.719576) (xy 111.297634 -335.670941) (xy 111.33172 -335.626798) (xy 111.371869 -335.588089)
			(xy 111.417227 -335.555638) (xy 111.466827 -335.530137) (xy 111.519611 -335.51213) (xy 111.574454 -335.502)
			(xy 111.630188 -335.499963) (xy 111.685625 -335.506063) (xy 111.739582 -335.520169) (xy 111.790911 -335.541981)
			(xy 111.838517 -335.571035) (xy 111.881385 -335.60671) (xy 111.918602 -335.648247) (xy 111.949375 -335.69476)
			(xy 111.973047 -335.745257) (xy 111.989115 -335.798664) (xy 111.997235 -335.85384) (xy 111.997744 -335.881726)
			(xy 111.997235 -335.909612) (xy 111.989115 -335.964788) (xy 111.973047 -336.018195) (xy 111.949375 -336.068692)
			(xy 111.918602 -336.115205) (xy 111.881385 -336.156742) (xy 111.838517 -336.192417) (xy 111.790911 -336.221471)
			(xy 111.739582 -336.243283) (xy 111.685625 -336.257389) (xy 111.630188 -336.263489) (xy 111.574454 -336.261452)
			(xy 111.519611 -336.251322) (xy 111.466827 -336.233315) (xy 111.417227 -336.207814) (xy 111.371869 -336.175363)
			(xy 111.33172 -336.136654) (xy 111.297634 -336.092511) (xy 111.270338 -336.043876) (xy 111.250415 -335.991785)
			(xy 111.238289 -335.937348) (xy 111.234218 -335.881726) (xy 110.52048 -335.881726) (xy 110.52048 -336.381852)
			(xy 110.520011 -336.406638) (xy 110.511941 -336.45555) (xy 110.496069 -336.502515) (xy 110.472815 -336.546295)
			(xy 110.442788 -336.585741) (xy 110.40678 -336.619814) (xy 110.365738 -336.647617) (xy 110.343442 -336.658458)
			(xy 110.30458 -336.676492) (xy 110.304326 -336.676492) (xy 110.27918 -336.686906) (xy 110.167928 -336.726784)
			(xy 110.161669 -336.728843) (xy 110.148545 -336.72999) (xy 110.14202 -336.72907) (xy 110.009178 -336.70621)
			(xy 110.002661 -336.70488) (xy 109.99057 -336.699349) (xy 109.985302 -336.695288) (xy 109.932724 -336.6516)
			(xy 109.93247 -336.651346) (xy 109.920935 -336.642354) (xy 109.894768 -336.629312) (xy 109.866316 -336.62258)
			(xy 109.851698 -336.622136) (xy 109.85119 -336.622136) (xy 109.833632 -336.622717) (xy 109.79984 -336.632266)
			(xy 109.769932 -336.650665) (xy 109.746172 -336.676521) (xy 109.73036 -336.707874) (xy 109.726476 -336.725006)
			(xy 109.713776 -336.791554) (xy 109.712308 -336.798096) (xy 109.706526 -336.810188) (xy 109.702346 -336.81543)
			(xy 109.613954 -336.917792) (xy 109.60952 -336.922636) (xy 109.59872 -336.930097) (xy 109.592618 -336.932524)
			(xy 108.614464 -337.282536) (xy 108.61421 -337.282536) (xy 108.589434 -337.290821) (xy 108.537967 -337.299759)
			(xy 108.511848 -337.300316) (xy 108.317538 -337.300316) (xy 108.293567 -337.299854) (xy 108.246214 -337.292363)
			(xy 108.200619 -337.277544) (xy 108.157911 -337.255762) (xy 108.119143 -337.227557) (xy 108.101892 -337.210908)
			(xy 107.362244 -336.47126) (xy 107.345658 -336.453956) (xy 107.31749 -336.415179) (xy 107.295719 -336.372481)
			(xy 107.28088 -336.326908) (xy 107.273335 -336.279577) (xy 107.272836 -336.255614) (xy 94.862904 -336.255614)
			(xy 94.862904 -336.98561) (xy 99.107496 -336.98561) (xy 99.111567 -336.929988) (xy 99.123693 -336.875551)
			(xy 99.143616 -336.82346) (xy 99.170912 -336.774825) (xy 99.204998 -336.730682) (xy 99.245147 -336.691973)
			(xy 99.290505 -336.659522) (xy 99.340105 -336.634021) (xy 99.392889 -336.616014) (xy 99.447732 -336.605884)
			(xy 99.503466 -336.603847) (xy 99.558903 -336.609947) (xy 99.61286 -336.624053) (xy 99.664189 -336.645865)
			(xy 99.711795 -336.674919) (xy 99.754663 -336.710594) (xy 99.79188 -336.752131) (xy 99.822653 -336.798644)
			(xy 99.846325 -336.849141) (xy 99.862393 -336.902548) (xy 99.870513 -336.957724) (xy 99.871022 -336.98561)
			(xy 99.870513 -337.013496) (xy 99.862393 -337.068672) (xy 99.846325 -337.122079) (xy 99.822653 -337.172576)
			(xy 99.79188 -337.219089) (xy 99.754663 -337.260626) (xy 99.711795 -337.296301) (xy 99.664189 -337.325355)
			(xy 99.61286 -337.347167) (xy 99.558903 -337.361273) (xy 99.503466 -337.367373) (xy 99.447732 -337.365336)
			(xy 99.392889 -337.355206) (xy 99.340105 -337.337199) (xy 99.290505 -337.311698) (xy 99.245147 -337.279247)
			(xy 99.204998 -337.240538) (xy 99.170912 -337.196395) (xy 99.143616 -337.14776) (xy 99.123693 -337.095669)
			(xy 99.111567 -337.041232) (xy 99.107496 -336.98561) (xy 94.862904 -336.98561) (xy 94.862904 -338.82203)
			(xy 94.863333 -338.832098) (xy 94.871055 -338.850694) (xy 94.87789 -338.858098) (xy 95.640144 -339.620352)
			(xy 95.646988 -339.627751) (xy 95.654713 -339.646349) (xy 95.65513 -339.65642) (xy 95.65513 -340.776052)
			(xy 95.655563 -340.786117) (xy 95.663294 -340.804705) (xy 95.670116 -340.81212) (xy 95.798386 -340.94039)
			(xy 95.805236 -340.947787) (xy 95.812976 -340.966385) (xy 95.813372 -340.976458) (xy 95.813372 -342.694268)
			(xy 102.35157 -342.694268) (xy 102.35157 -342.634332) (xy 102.359393 -342.574909) (xy 102.374905 -342.517016)
			(xy 102.397841 -342.461642) (xy 102.427809 -342.409736) (xy 102.464294 -342.362185) (xy 102.506675 -342.319804)
			(xy 102.554224 -342.283316) (xy 102.60613 -342.253347) (xy 102.661502 -342.23041) (xy 102.719395 -342.214896)
			(xy 102.778818 -342.207071) (xy 102.808786 -342.20658) (xy 103.672386 -342.20658) (xy 103.702355 -342.207072)
			(xy 103.76178 -342.214894) (xy 103.819676 -342.230405) (xy 103.875051 -342.253341) (xy 103.926959 -342.283309)
			(xy 103.974512 -342.319796) (xy 104.016895 -342.362178) (xy 104.053383 -342.409729) (xy 104.083352 -342.461636)
			(xy 104.10629 -342.517011) (xy 104.121803 -342.574906) (xy 104.129627 -342.634331) (xy 104.129627 -342.694269)
			(xy 104.121803 -342.753694) (xy 104.10629 -342.811589) (xy 104.083352 -342.866964) (xy 104.053383 -342.918871)
			(xy 104.016895 -342.966422) (xy 103.974512 -343.008804) (xy 103.926959 -343.045291) (xy 103.875051 -343.075259)
			(xy 103.819676 -343.098195) (xy 103.76178 -343.113706) (xy 103.702355 -343.121528) (xy 103.672386 -343.121996)
			(xy 102.808786 -343.121996) (xy 102.778818 -343.121529) (xy 102.719395 -343.113704) (xy 102.661502 -343.09819)
			(xy 102.60613 -343.075253) (xy 102.554224 -343.045284) (xy 102.506675 -343.008796) (xy 102.464294 -342.966415)
			(xy 102.427809 -342.918864) (xy 102.397841 -342.866958) (xy 102.374905 -342.811584) (xy 102.359393 -342.753691)
			(xy 102.35157 -342.694268) (xy 95.813372 -342.694268) (xy 95.813372 -343.446862) (xy 101.207568 -343.446862)
			(xy 101.211639 -343.39124) (xy 101.223765 -343.336803) (xy 101.243688 -343.284712) (xy 101.270984 -343.236077)
			(xy 101.30507 -343.191934) (xy 101.345219 -343.153225) (xy 101.390577 -343.120774) (xy 101.440177 -343.095273)
			(xy 101.492961 -343.077266) (xy 101.547804 -343.067136) (xy 101.603538 -343.065099) (xy 101.658975 -343.071199)
			(xy 101.712932 -343.085305) (xy 101.764261 -343.107117) (xy 101.811867 -343.136171) (xy 101.854735 -343.171846)
			(xy 101.891952 -343.213383) (xy 101.922725 -343.259896) (xy 101.946397 -343.310393) (xy 101.962465 -343.3638)
			(xy 101.970585 -343.418976) (xy 101.971094 -343.446862) (xy 101.970585 -343.474748) (xy 101.962465 -343.529924)
			(xy 101.946397 -343.583331) (xy 101.922725 -343.633828) (xy 101.891952 -343.680341) (xy 101.854735 -343.721878)
			(xy 101.811867 -343.757553) (xy 101.764261 -343.786607) (xy 101.712932 -343.808419) (xy 101.658975 -343.822525)
			(xy 101.603538 -343.828625) (xy 101.547804 -343.826588) (xy 101.492961 -343.816458) (xy 101.440177 -343.798451)
			(xy 101.390577 -343.77295) (xy 101.345219 -343.740499) (xy 101.30507 -343.70179) (xy 101.270984 -343.657647)
			(xy 101.243688 -343.609012) (xy 101.223765 -343.556921) (xy 101.211639 -343.502484) (xy 101.207568 -343.446862)
			(xy 95.813372 -343.446862) (xy 95.813372 -345.585034) (xy 105.220008 -345.585034) (xy 105.220008 -344.26144)
			(xy 105.220452 -344.251373) (xy 105.228159 -344.232775) (xy 105.234994 -344.225372) (xy 105.816146 -343.644474)
			(xy 105.823567 -343.637661) (xy 105.84215 -343.629926) (xy 105.852214 -343.629488) (xy 108.771436 -343.629488)
			(xy 108.781511 -343.629871) (xy 108.800109 -343.637619) (xy 108.807504 -343.644474) (xy 109.208062 -344.044778)
			(xy 109.21488 -344.052196) (xy 109.222614 -344.070781) (xy 109.223048 -344.080846) (xy 109.223048 -345.830652)
			(xy 109.222611 -345.84072) (xy 109.2149 -345.859319) (xy 109.208062 -345.86672) (xy 108.829094 -346.245434)
			(xy 108.821694 -346.252274) (xy 108.803095 -346.259993) (xy 108.793026 -346.26042) (xy 108.494576 -346.26042)
			(xy 108.483257 -346.261059) (xy 108.462823 -346.270818) (xy 108.455206 -346.279216) (xy 108.398056 -346.349574)
			(xy 108.392976 -346.371926) (xy 108.395262 -346.383102) (xy 108.399066 -346.402372) (xy 108.403136 -346.44144)
			(xy 108.40339 -346.46108) (xy 108.40339 -346.461842) (xy 108.402961 -346.489095) (xy 108.395199 -346.543046)
			(xy 108.379837 -346.595343) (xy 108.35719 -346.644921) (xy 108.327717 -346.690772) (xy 108.29202 -346.731963)
			(xy 108.250824 -346.767653) (xy 108.204969 -346.797119) (xy 108.155386 -346.819758) (xy 108.103087 -346.835111)
			(xy 108.049135 -346.842865) (xy 108.021882 -346.84335) (xy 107.996334 -346.842954) (xy 107.945694 -346.836142)
			(xy 107.896417 -346.82263) (xy 107.849386 -346.802658) (xy 107.805443 -346.776586) (xy 107.785154 -346.761054)
			(xy 107.7849 -346.7608) (xy 107.777177 -346.755245) (xy 107.758989 -346.749718) (xy 107.740036 -346.751181)
			(xy 107.731306 -346.754958) (xy 107.64901 -346.794836) (xy 107.640596 -346.799319) (xy 107.627643 -346.81329)
			(xy 107.620695 -346.83103) (xy 107.620308 -346.840556) (xy 107.620308 -348.541848) (xy 107.61988 -348.551917)
			(xy 107.612164 -348.570517) (xy 107.605322 -348.577916) (xy 107.30738 -348.875858) (xy 107.299976 -348.882693)
			(xy 107.28138 -348.890417) (xy 107.271312 -348.890844) (xy 106.100372 -348.890844) (xy 106.090326 -348.890478)
			(xy 106.071729 -348.882888) (xy 106.064304 -348.876112) (xy 105.90022 -348.712028) (xy 105.8672 -348.707202)
			(xy 105.852214 -348.715076) (xy 105.82425 -348.729429) (xy 105.764787 -348.749791) (xy 105.702792 -348.760134)
			(xy 105.671366 -348.760796) (xy 105.644113 -348.760354) (xy 105.590163 -348.752592) (xy 105.537867 -348.737232)
			(xy 105.488289 -348.714586) (xy 105.442438 -348.685115) (xy 105.401248 -348.649419) (xy 105.365557 -348.608225)
			(xy 105.336092 -348.562371) (xy 105.313452 -348.51279) (xy 105.298098 -348.460492) (xy 105.290343 -348.406541)
			(xy 105.289858 -348.379288) (xy 105.290341 -348.352187) (xy 105.298014 -348.29853) (xy 105.313203 -348.2465)
			(xy 105.335603 -348.197143) (xy 105.364763 -348.151452) (xy 105.400095 -348.110349) (xy 105.44089 -348.07466)
			(xy 105.486324 -348.045103) (xy 105.535484 -348.022274) (xy 105.58738 -348.006632) (xy 105.640968 -347.998492)
			(xy 105.668064 -347.99778) (xy 105.677987 -347.997193) (xy 105.696289 -347.9895) (xy 105.703624 -347.982794)
			(xy 105.753916 -347.93174) (xy 105.76055 -347.924374) (xy 105.768131 -347.906079) (xy 105.768648 -347.89618)
			(xy 105.768648 -346.175838) (xy 105.768216 -346.165769) (xy 105.760502 -346.14717) (xy 105.753662 -346.13977)
			(xy 105.234994 -345.621102) (xy 105.228162 -345.613696) (xy 105.220438 -345.595101) (xy 105.220008 -345.585034)
			(xy 95.813372 -345.585034) (xy 95.813372 -346.583254) (xy 99.245418 -346.583254) (xy 99.249489 -346.527632)
			(xy 99.261615 -346.473195) (xy 99.281538 -346.421104) (xy 99.308834 -346.372469) (xy 99.34292 -346.328326)
			(xy 99.383069 -346.289617) (xy 99.428427 -346.257166) (xy 99.478027 -346.231665) (xy 99.530811 -346.213658)
			(xy 99.585654 -346.203528) (xy 99.641388 -346.201491) (xy 99.696825 -346.207591) (xy 99.750782 -346.221697)
			(xy 99.802111 -346.243509) (xy 99.849717 -346.272563) (xy 99.892585 -346.308238) (xy 99.929802 -346.349775)
			(xy 99.960575 -346.396288) (xy 99.984247 -346.446785) (xy 100.000315 -346.500192) (xy 100.008435 -346.555368)
			(xy 100.008944 -346.583254) (xy 100.008435 -346.61114) (xy 100.000315 -346.666316) (xy 99.984247 -346.719723)
			(xy 99.960575 -346.77022) (xy 99.929802 -346.816733) (xy 99.892585 -346.85827) (xy 99.849717 -346.893945)
			(xy 99.802111 -346.922999) (xy 99.750782 -346.944811) (xy 99.696825 -346.958917) (xy 99.641388 -346.965017)
			(xy 99.585654 -346.96298) (xy 99.530811 -346.95285) (xy 99.478027 -346.934843) (xy 99.428427 -346.909342)
			(xy 99.383069 -346.876891) (xy 99.34292 -346.838182) (xy 99.308834 -346.794039) (xy 99.281538 -346.745404)
			(xy 99.261615 -346.693313) (xy 99.249489 -346.638876) (xy 99.245418 -346.583254) (xy 95.813372 -346.583254)
			(xy 95.813372 -347.873066) (xy 99.245418 -347.873066) (xy 99.249489 -347.817444) (xy 99.261615 -347.763007)
			(xy 99.281538 -347.710916) (xy 99.308834 -347.662281) (xy 99.34292 -347.618138) (xy 99.383069 -347.579429)
			(xy 99.428427 -347.546978) (xy 99.478027 -347.521477) (xy 99.530811 -347.50347) (xy 99.585654 -347.49334)
			(xy 99.641388 -347.491303) (xy 99.696825 -347.497403) (xy 99.750782 -347.511509) (xy 99.802111 -347.533321)
			(xy 99.849717 -347.562375) (xy 99.892585 -347.59805) (xy 99.929802 -347.639587) (xy 99.960575 -347.6861)
			(xy 99.984247 -347.736597) (xy 100.000315 -347.790004) (xy 100.008435 -347.84518) (xy 100.008944 -347.873066)
			(xy 100.008435 -347.900952) (xy 100.000315 -347.956128) (xy 99.984247 -348.009535) (xy 99.960575 -348.060032)
			(xy 99.929802 -348.106545) (xy 99.892585 -348.148082) (xy 99.849717 -348.183757) (xy 99.802111 -348.212811)
			(xy 99.750782 -348.234623) (xy 99.696825 -348.248729) (xy 99.641388 -348.254829) (xy 99.585654 -348.252792)
			(xy 99.530811 -348.242662) (xy 99.478027 -348.224655) (xy 99.428427 -348.199154) (xy 99.383069 -348.166703)
			(xy 99.34292 -348.127994) (xy 99.308834 -348.083851) (xy 99.281538 -348.035216) (xy 99.261615 -347.983125)
			(xy 99.249489 -347.928688) (xy 99.245418 -347.873066) (xy 95.813372 -347.873066) (xy 95.813372 -351.40392)
			(xy 99.12426 -351.40392) (xy 99.128331 -351.348298) (xy 99.140457 -351.293861) (xy 99.16038 -351.24177)
			(xy 99.187676 -351.193135) (xy 99.221762 -351.148992) (xy 99.261911 -351.110283) (xy 99.307269 -351.077832)
			(xy 99.356869 -351.052331) (xy 99.409653 -351.034324) (xy 99.464496 -351.024194) (xy 99.52023 -351.022157)
			(xy 99.575667 -351.028257) (xy 99.629624 -351.042363) (xy 99.680953 -351.064175) (xy 99.728559 -351.093229)
			(xy 99.771427 -351.128904) (xy 99.808644 -351.170441) (xy 99.839417 -351.216954) (xy 99.863089 -351.267451)
			(xy 99.879157 -351.320858) (xy 99.887277 -351.376034) (xy 99.887786 -351.40392) (xy 99.887277 -351.431806)
			(xy 99.879157 -351.486982) (xy 99.871134 -351.513648) (xy 106.459526 -351.513648) (xy 106.463597 -351.458026)
			(xy 106.475723 -351.403589) (xy 106.495646 -351.351498) (xy 106.522942 -351.302863) (xy 106.557028 -351.25872)
			(xy 106.597177 -351.220011) (xy 106.642535 -351.18756) (xy 106.692135 -351.162059) (xy 106.744919 -351.144052)
			(xy 106.799762 -351.133922) (xy 106.855496 -351.131885) (xy 106.910933 -351.137985) (xy 106.96489 -351.152091)
			(xy 107.016219 -351.173903) (xy 107.063825 -351.202957) (xy 107.106693 -351.238632) (xy 107.14391 -351.280169)
			(xy 107.174683 -351.326682) (xy 107.198355 -351.377179) (xy 107.214423 -351.430586) (xy 107.222543 -351.485762)
			(xy 107.223052 -351.513648) (xy 107.222543 -351.541534) (xy 107.214423 -351.59671) (xy 107.198355 -351.650117)
			(xy 107.174683 -351.700614) (xy 107.14391 -351.747127) (xy 107.106693 -351.788664) (xy 107.063825 -351.824339)
			(xy 107.016219 -351.853393) (xy 106.96489 -351.875205) (xy 106.910933 -351.889311) (xy 106.855496 -351.895411)
			(xy 106.799762 -351.893374) (xy 106.744919 -351.883244) (xy 106.692135 -351.865237) (xy 106.642535 -351.839736)
			(xy 106.597177 -351.807285) (xy 106.557028 -351.768576) (xy 106.522942 -351.724433) (xy 106.495646 -351.675798)
			(xy 106.475723 -351.623707) (xy 106.463597 -351.56927) (xy 106.459526 -351.513648) (xy 99.871134 -351.513648)
			(xy 99.863089 -351.540389) (xy 99.839417 -351.590886) (xy 99.808644 -351.637399) (xy 99.771427 -351.678936)
			(xy 99.728559 -351.714611) (xy 99.680953 -351.743665) (xy 99.629624 -351.765477) (xy 99.575667 -351.779583)
			(xy 99.52023 -351.785683) (xy 99.464496 -351.783646) (xy 99.409653 -351.773516) (xy 99.356869 -351.755509)
			(xy 99.307269 -351.730008) (xy 99.261911 -351.697557) (xy 99.221762 -351.658848) (xy 99.187676 -351.614705)
			(xy 99.16038 -351.56607) (xy 99.140457 -351.513979) (xy 99.128331 -351.459542) (xy 99.12426 -351.40392)
			(xy 95.813372 -351.40392) (xy 95.813372 -353.042474) (xy 99.14839 -353.042474) (xy 99.152461 -352.986852)
			(xy 99.164587 -352.932415) (xy 99.18451 -352.880324) (xy 99.211806 -352.831689) (xy 99.245892 -352.787546)
			(xy 99.286041 -352.748837) (xy 99.331399 -352.716386) (xy 99.380999 -352.690885) (xy 99.433783 -352.672878)
			(xy 99.488626 -352.662748) (xy 99.54436 -352.660711) (xy 99.599797 -352.666811) (xy 99.653754 -352.680917)
			(xy 99.705083 -352.702729) (xy 99.752689 -352.731783) (xy 99.795557 -352.767458) (xy 99.832774 -352.808995)
			(xy 99.863547 -352.855508) (xy 99.887219 -352.906005) (xy 99.903287 -352.959412) (xy 99.91125 -353.013518)
			(xy 100.143562 -353.013518) (xy 100.147633 -352.957896) (xy 100.159759 -352.903459) (xy 100.179682 -352.851368)
			(xy 100.206978 -352.802733) (xy 100.241064 -352.75859) (xy 100.281213 -352.719881) (xy 100.326571 -352.68743)
			(xy 100.376171 -352.661929) (xy 100.428955 -352.643922) (xy 100.483798 -352.633792) (xy 100.539532 -352.631755)
			(xy 100.594969 -352.637855) (xy 100.648926 -352.651961) (xy 100.700255 -352.673773) (xy 100.747861 -352.702827)
			(xy 100.790729 -352.738502) (xy 100.827946 -352.780039) (xy 100.858719 -352.826552) (xy 100.882391 -352.877049)
			(xy 100.898459 -352.930456) (xy 100.906579 -352.985632) (xy 100.907088 -353.013518) (xy 100.906579 -353.041404)
			(xy 100.898459 -353.09658) (xy 100.884246 -353.14382) (xy 106.532932 -353.14382) (xy 106.537003 -353.088198)
			(xy 106.549129 -353.033761) (xy 106.569052 -352.98167) (xy 106.596348 -352.933035) (xy 106.630434 -352.888892)
			(xy 106.670583 -352.850183) (xy 106.715941 -352.817732) (xy 106.765541 -352.792231) (xy 106.818325 -352.774224)
			(xy 106.873168 -352.764094) (xy 106.928902 -352.762057) (xy 106.984339 -352.768157) (xy 107.038296 -352.782263)
			(xy 107.089625 -352.804075) (xy 107.137231 -352.833129) (xy 107.180099 -352.868804) (xy 107.217316 -352.910341)
			(xy 107.248089 -352.956854) (xy 107.271761 -353.007351) (xy 107.287829 -353.060758) (xy 107.295949 -353.115934)
			(xy 107.296458 -353.14382) (xy 107.295949 -353.171706) (xy 107.287829 -353.226882) (xy 107.271761 -353.280289)
			(xy 107.248089 -353.330786) (xy 107.217316 -353.377299) (xy 107.180099 -353.418836) (xy 107.137231 -353.454511)
			(xy 107.089625 -353.483565) (xy 107.038296 -353.505377) (xy 106.984339 -353.519483) (xy 106.928902 -353.525583)
			(xy 106.873168 -353.523546) (xy 106.818325 -353.513416) (xy 106.765541 -353.495409) (xy 106.715941 -353.469908)
			(xy 106.670583 -353.437457) (xy 106.630434 -353.398748) (xy 106.596348 -353.354605) (xy 106.569052 -353.30597)
			(xy 106.549129 -353.253879) (xy 106.537003 -353.199442) (xy 106.532932 -353.14382) (xy 100.884246 -353.14382)
			(xy 100.882391 -353.149987) (xy 100.858719 -353.200484) (xy 100.827946 -353.246997) (xy 100.790729 -353.288534)
			(xy 100.747861 -353.324209) (xy 100.700255 -353.353263) (xy 100.648926 -353.375075) (xy 100.594969 -353.389181)
			(xy 100.539532 -353.395281) (xy 100.483798 -353.393244) (xy 100.428955 -353.383114) (xy 100.376171 -353.365107)
			(xy 100.326571 -353.339606) (xy 100.281213 -353.307155) (xy 100.241064 -353.268446) (xy 100.206978 -353.224303)
			(xy 100.179682 -353.175668) (xy 100.159759 -353.123577) (xy 100.147633 -353.06914) (xy 100.143562 -353.013518)
			(xy 99.91125 -353.013518) (xy 99.911407 -353.014588) (xy 99.911916 -353.042474) (xy 99.911407 -353.07036)
			(xy 99.903287 -353.125536) (xy 99.887219 -353.178943) (xy 99.863547 -353.22944) (xy 99.832774 -353.275953)
			(xy 99.795557 -353.31749) (xy 99.752689 -353.353165) (xy 99.705083 -353.382219) (xy 99.653754 -353.404031)
			(xy 99.599797 -353.418137) (xy 99.54436 -353.424237) (xy 99.488626 -353.4222) (xy 99.433783 -353.41207)
			(xy 99.380999 -353.394063) (xy 99.331399 -353.368562) (xy 99.286041 -353.336111) (xy 99.245892 -353.297402)
			(xy 99.211806 -353.253259) (xy 99.18451 -353.204624) (xy 99.164587 -353.152533) (xy 99.152461 -353.098096)
			(xy 99.14839 -353.042474) (xy 95.813372 -353.042474) (xy 95.813372 -354.50526) (xy 99.97643 -354.50526)
			(xy 99.980501 -354.449638) (xy 99.992627 -354.395201) (xy 100.01255 -354.34311) (xy 100.039846 -354.294475)
			(xy 100.073932 -354.250332) (xy 100.114081 -354.211623) (xy 100.159439 -354.179172) (xy 100.209039 -354.153671)
			(xy 100.261823 -354.135664) (xy 100.316666 -354.125534) (xy 100.3724 -354.123497) (xy 100.427837 -354.129597)
			(xy 100.453087 -354.136198) (xy 105.899202 -354.136198) (xy 105.903273 -354.080576) (xy 105.915399 -354.026139)
			(xy 105.935322 -353.974048) (xy 105.962618 -353.925413) (xy 105.996704 -353.88127) (xy 106.036853 -353.842561)
			(xy 106.082211 -353.81011) (xy 106.131811 -353.784609) (xy 106.184595 -353.766602) (xy 106.239438 -353.756472)
			(xy 106.295172 -353.754435) (xy 106.350609 -353.760535) (xy 106.404566 -353.774641) (xy 106.455895 -353.796453)
			(xy 106.503501 -353.825507) (xy 106.546369 -353.861182) (xy 106.583586 -353.902719) (xy 106.614359 -353.949232)
			(xy 106.638031 -353.999729) (xy 106.654099 -354.053136) (xy 106.662219 -354.108312) (xy 106.662728 -354.136198)
			(xy 106.662219 -354.164084) (xy 106.654099 -354.21926) (xy 106.638031 -354.272667) (xy 106.614359 -354.323164)
			(xy 106.583586 -354.369677) (xy 106.546369 -354.411214) (xy 106.503501 -354.446889) (xy 106.455895 -354.475943)
			(xy 106.404566 -354.497755) (xy 106.350609 -354.511861) (xy 106.295172 -354.517961) (xy 106.239438 -354.515924)
			(xy 106.184595 -354.505794) (xy 106.131811 -354.487787) (xy 106.082211 -354.462286) (xy 106.036853 -354.429835)
			(xy 105.996704 -354.391126) (xy 105.962618 -354.346983) (xy 105.935322 -354.298348) (xy 105.915399 -354.246257)
			(xy 105.903273 -354.19182) (xy 105.899202 -354.136198) (xy 100.453087 -354.136198) (xy 100.481794 -354.143703)
			(xy 100.533123 -354.165515) (xy 100.580729 -354.194569) (xy 100.623597 -354.230244) (xy 100.660814 -354.271781)
			(xy 100.691587 -354.318294) (xy 100.715259 -354.368791) (xy 100.731327 -354.422198) (xy 100.739447 -354.477374)
			(xy 100.739956 -354.50526) (xy 100.739447 -354.533146) (xy 100.731327 -354.588322) (xy 100.715259 -354.641729)
			(xy 100.691587 -354.692226) (xy 100.660814 -354.738739) (xy 100.623597 -354.780276) (xy 100.580729 -354.815951)
			(xy 100.533123 -354.845005) (xy 100.481794 -354.866817) (xy 100.427837 -354.880923) (xy 100.3724 -354.887023)
			(xy 100.316666 -354.884986) (xy 100.261823 -354.874856) (xy 100.209039 -354.856849) (xy 100.159439 -354.831348)
			(xy 100.114081 -354.798897) (xy 100.073932 -354.760188) (xy 100.039846 -354.716045) (xy 100.01255 -354.66741)
			(xy 99.992627 -354.615319) (xy 99.980501 -354.560882) (xy 99.97643 -354.50526) (xy 95.813372 -354.50526)
			(xy 95.813372 -355.543866) (xy 100.796342 -355.543866) (xy 100.800413 -355.488244) (xy 100.812539 -355.433807)
			(xy 100.832462 -355.381716) (xy 100.859758 -355.333081) (xy 100.893844 -355.288938) (xy 100.933993 -355.250229)
			(xy 100.979351 -355.217778) (xy 101.028951 -355.192277) (xy 101.081735 -355.17427) (xy 101.136578 -355.16414)
			(xy 101.192312 -355.162103) (xy 101.247749 -355.168203) (xy 101.301706 -355.182309) (xy 101.353035 -355.204121)
			(xy 101.400641 -355.233175) (xy 101.443509 -355.26885) (xy 101.480726 -355.310387) (xy 101.483114 -355.313996)
			(xy 106.055922 -355.313996) (xy 106.056408 -355.286745) (xy 106.064164 -355.232797) (xy 106.079519 -355.180502)
			(xy 106.102161 -355.130925) (xy 106.131627 -355.085075) (xy 106.167318 -355.043884) (xy 106.208509 -355.008193)
			(xy 106.254359 -354.978727) (xy 106.303936 -354.956085) (xy 106.356231 -354.94073) (xy 106.410179 -354.932974)
			(xy 106.464681 -354.932974) (xy 106.518629 -354.94073) (xy 106.570924 -354.956085) (xy 106.620501 -354.978727)
			(xy 106.666351 -355.008193) (xy 106.707542 -355.043884) (xy 106.743233 -355.085075) (xy 106.772699 -355.130925)
			(xy 106.795341 -355.180502) (xy 106.810696 -355.232797) (xy 106.818452 -355.286745) (xy 106.818938 -355.313996)
			(xy 106.818455 -355.342566) (xy 106.809941 -355.399069) (xy 106.793088 -355.453667) (xy 106.768274 -355.505138)
			(xy 106.736054 -355.552329) (xy 106.697152 -355.594181) (xy 106.652438 -355.629757) (xy 106.62793 -355.64445)
			(xy 106.616417 -355.651599) (xy 106.59736 -355.670853) (xy 106.58403 -355.694437) (xy 106.577363 -355.720694)
			(xy 106.577428 -355.72446) (xy 106.991658 -355.72446) (xy 106.992258 -355.695119) (xy 107.001235 -355.637129)
			(xy 107.018987 -355.581197) (xy 107.045094 -355.528644) (xy 107.078941 -355.480708) (xy 107.11973 -355.438521)
			(xy 107.166498 -355.403077) (xy 107.192064 -355.388672) (xy 107.202143 -355.382558) (xy 107.215788 -355.363374)
			(xy 107.218226 -355.351842) (xy 107.230926 -355.272086) (xy 107.232114 -355.260326) (xy 107.224966 -355.237825)
			(xy 107.21721 -355.228906) (xy 107.197458 -355.207456) (xy 107.164022 -355.159689) (xy 107.13824 -355.107392)
			(xy 107.120711 -355.051782) (xy 107.111844 -354.994153) (xy 107.111292 -354.965) (xy 107.111733 -354.93833)
			(xy 107.119151 -354.885508) (xy 107.133856 -354.834235) (xy 107.155563 -354.785511) (xy 107.183846 -354.740286)
			(xy 107.218155 -354.699444) (xy 107.257819 -354.66378) (xy 107.279694 -354.648516) (xy 107.288969 -354.64155)
			(xy 107.300474 -354.621434) (xy 107.301792 -354.609908) (xy 107.308142 -354.517706) (xy 107.299252 -354.496116)
			(xy 107.290362 -354.488242) (xy 107.270564 -354.470073) (xy 107.235771 -354.429123) (xy 107.207072 -354.383695)
			(xy 107.185034 -354.334687) (xy 107.170096 -354.28307) (xy 107.162552 -354.229867) (xy 107.162092 -354.203)
			(xy 107.162578 -354.175749) (xy 107.170334 -354.121801) (xy 107.185689 -354.069506) (xy 107.208331 -354.019929)
			(xy 107.237797 -353.974079) (xy 107.273488 -353.932888) (xy 107.314679 -353.897197) (xy 107.360529 -353.867731)
			(xy 107.410106 -353.845089) (xy 107.462401 -353.829734) (xy 107.516349 -353.821978) (xy 107.570851 -353.821978)
			(xy 107.624799 -353.829734) (xy 107.677094 -353.845089) (xy 107.726671 -353.867731) (xy 107.772521 -353.897197)
			(xy 107.813712 -353.932888) (xy 107.849403 -353.974079) (xy 107.878869 -354.019929) (xy 107.901511 -354.069506)
			(xy 107.916866 -354.121801) (xy 107.924622 -354.175749) (xy 107.925108 -354.203) (xy 107.924667 -354.22967)
			(xy 107.917249 -354.282492) (xy 107.902544 -354.333765) (xy 107.880837 -354.382489) (xy 107.852554 -354.427714)
			(xy 107.818245 -354.468556) (xy 107.778581 -354.50422) (xy 107.756706 -354.519484) (xy 107.747431 -354.52645)
			(xy 107.735926 -354.546566) (xy 107.734608 -354.558092) (xy 107.728258 -354.650294) (xy 107.737148 -354.671884)
			(xy 107.746038 -354.679758) (xy 107.765836 -354.697927) (xy 107.800629 -354.738877) (xy 107.829328 -354.784305)
			(xy 107.851366 -354.833313) (xy 107.866304 -354.88493) (xy 107.873848 -354.938133) (xy 107.874308 -354.965)
			(xy 107.873774 -354.994343) (xy 107.864787 -355.052338) (xy 107.847025 -355.108272) (xy 107.820907 -355.160826)
			(xy 107.787049 -355.208761) (xy 107.746251 -355.250946) (xy 107.699473 -355.286385) (xy 107.673902 -355.300788)
			(xy 107.663795 -355.306864) (xy 107.650165 -355.326076) (xy 107.64774 -355.337618) (xy 107.63504 -355.417374)
			(xy 107.63386 -355.429134) (xy 107.641 -355.451636) (xy 107.648756 -355.460554) (xy 107.668531 -355.481984)
			(xy 107.701965 -355.529756) (xy 107.727743 -355.582058) (xy 107.745266 -355.637672) (xy 107.754127 -355.695305)
			(xy 107.754674 -355.72446) (xy 107.754188 -355.751711) (xy 107.746432 -355.805659) (xy 107.731077 -355.857954)
			(xy 107.708435 -355.907531) (xy 107.678969 -355.953381) (xy 107.643278 -355.994572) (xy 107.602087 -356.030263)
			(xy 107.556237 -356.059729) (xy 107.50666 -356.082371) (xy 107.454365 -356.097726) (xy 107.400417 -356.105482)
			(xy 107.345915 -356.105482) (xy 107.291967 -356.097726) (xy 107.239672 -356.082371) (xy 107.190095 -356.059729)
			(xy 107.144245 -356.030263) (xy 107.103054 -355.994572) (xy 107.067363 -355.953381) (xy 107.037897 -355.907531)
			(xy 107.015255 -355.857954) (xy 106.9999 -355.805659) (xy 106.992144 -355.751711) (xy 106.991658 -355.72446)
			(xy 106.577428 -355.72446) (xy 106.577827 -355.747781) (xy 106.585391 -355.773795) (xy 106.599522 -355.796908)
			(xy 106.619228 -355.815497) (xy 106.630978 -355.82225) (xy 106.65669 -355.836645) (xy 106.703806 -355.872029)
			(xy 106.744919 -355.914239) (xy 106.779048 -355.962272) (xy 106.805383 -356.014982) (xy 106.823295 -356.071117)
			(xy 106.832359 -356.129338) (xy 106.832908 -356.1588) (xy 106.832422 -356.186051) (xy 106.824666 -356.239999)
			(xy 106.809311 -356.292294) (xy 106.786669 -356.341871) (xy 106.757203 -356.387721) (xy 106.721512 -356.428912)
			(xy 106.680321 -356.464603) (xy 106.634471 -356.494069) (xy 106.584894 -356.516711) (xy 106.532599 -356.532066)
			(xy 106.478651 -356.539822) (xy 106.424149 -356.539822) (xy 106.370201 -356.532066) (xy 106.317906 -356.516711)
			(xy 106.268329 -356.494069) (xy 106.222479 -356.464603) (xy 106.181288 -356.428912) (xy 106.145597 -356.387721)
			(xy 106.116131 -356.341871) (xy 106.093489 -356.292294) (xy 106.078134 -356.239999) (xy 106.070378 -356.186051)
			(xy 106.069892 -356.1588) (xy 106.070357 -356.130229) (xy 106.078872 -356.073725) (xy 106.095727 -356.019125)
			(xy 106.120544 -355.967654) (xy 106.152767 -355.920463) (xy 106.191673 -355.878612) (xy 106.236391 -355.843038)
			(xy 106.2609 -355.828346) (xy 106.272424 -355.821209) (xy 106.291495 -355.801958) (xy 106.304835 -355.778371)
			(xy 106.311507 -355.752107) (xy 106.311041 -355.725013) (xy 106.303471 -355.698994) (xy 106.289329 -355.67588)
			(xy 106.269608 -355.657295) (xy 106.257852 -355.650546) (xy 106.232122 -355.636182) (xy 106.185009 -355.60079)
			(xy 106.1439 -355.558573) (xy 106.109774 -355.510535) (xy 106.083443 -355.45782) (xy 106.065533 -355.401683)
			(xy 106.05647 -355.343459) (xy 106.055922 -355.313996) (xy 101.483114 -355.313996) (xy 101.511499 -355.3569)
			(xy 101.535171 -355.407397) (xy 101.551239 -355.460804) (xy 101.559359 -355.51598) (xy 101.559868 -355.543866)
			(xy 101.559359 -355.571752) (xy 101.551239 -355.626928) (xy 101.535171 -355.680335) (xy 101.511499 -355.730832)
			(xy 101.480726 -355.777345) (xy 101.443509 -355.818882) (xy 101.400641 -355.854557) (xy 101.353035 -355.883611)
			(xy 101.301706 -355.905423) (xy 101.247749 -355.919529) (xy 101.192312 -355.925629) (xy 101.136578 -355.923592)
			(xy 101.081735 -355.913462) (xy 101.028951 -355.895455) (xy 100.979351 -355.869954) (xy 100.933993 -355.837503)
			(xy 100.893844 -355.798794) (xy 100.859758 -355.754651) (xy 100.832462 -355.706016) (xy 100.812539 -355.653925)
			(xy 100.800413 -355.599488) (xy 100.796342 -355.543866) (xy 95.813372 -355.543866) (xy 95.813372 -356.221284)
			(xy 103.80167 -356.221284) (xy 103.805741 -356.165662) (xy 103.817867 -356.111225) (xy 103.83779 -356.059134)
			(xy 103.865086 -356.010499) (xy 103.899172 -355.966356) (xy 103.939321 -355.927647) (xy 103.984679 -355.895196)
			(xy 104.034279 -355.869695) (xy 104.087063 -355.851688) (xy 104.141906 -355.841558) (xy 104.19764 -355.839521)
			(xy 104.253077 -355.845621) (xy 104.307034 -355.859727) (xy 104.358363 -355.881539) (xy 104.405969 -355.910593)
			(xy 104.448837 -355.946268) (xy 104.486054 -355.987805) (xy 104.516827 -356.034318) (xy 104.540499 -356.084815)
			(xy 104.556567 -356.138222) (xy 104.564687 -356.193398) (xy 104.565196 -356.221284) (xy 104.564687 -356.24917)
			(xy 104.556567 -356.304346) (xy 104.540499 -356.357753) (xy 104.516827 -356.40825) (xy 104.486054 -356.454763)
			(xy 104.448837 -356.4963) (xy 104.405969 -356.531975) (xy 104.358363 -356.561029) (xy 104.307034 -356.582841)
			(xy 104.253077 -356.596947) (xy 104.19764 -356.603047) (xy 104.141906 -356.60101) (xy 104.087063 -356.59088)
			(xy 104.034279 -356.572873) (xy 103.984679 -356.547372) (xy 103.939321 -356.514921) (xy 103.899172 -356.476212)
			(xy 103.865086 -356.432069) (xy 103.83779 -356.383434) (xy 103.817867 -356.331343) (xy 103.805741 -356.276906)
			(xy 103.80167 -356.221284) (xy 95.813372 -356.221284) (xy 95.813372 -360.017783) (xy 101.774757 -360.017783)
			(xy 101.774757 -359.957817) (xy 101.782584 -359.898365) (xy 101.798104 -359.840443) (xy 101.821052 -359.785042)
			(xy 101.851035 -359.733111) (xy 101.88754 -359.685538) (xy 101.929942 -359.643136) (xy 101.977516 -359.606632)
			(xy 102.029448 -359.57665) (xy 102.084849 -359.553703) (xy 102.142771 -359.538183) (xy 102.202223 -359.530357)
			(xy 102.232206 -359.529888) (xy 103.095806 -359.529888) (xy 103.125793 -359.530279) (xy 103.185255 -359.538108)
			(xy 103.243186 -359.553631) (xy 103.298595 -359.576583) (xy 103.350534 -359.60657) (xy 103.398115 -359.643081)
			(xy 103.440523 -359.68549) (xy 103.477033 -359.733071) (xy 103.50702 -359.785011) (xy 103.529971 -359.84042)
			(xy 103.545494 -359.898351) (xy 103.553322 -359.957813) (xy 103.553322 -360.017787) (xy 103.545494 -360.077249)
			(xy 103.529971 -360.13518) (xy 103.525241 -360.1466) (xy 106.603292 -360.1466) (xy 106.603805 -360.117682)
			(xy 106.612541 -360.060509) (xy 106.629813 -360.005313) (xy 106.655224 -359.953358) (xy 106.688191 -359.905838)
			(xy 106.707686 -359.884472) (xy 106.713736 -359.877544) (xy 106.720898 -359.860618) (xy 106.721656 -359.851452)
			(xy 106.724704 -359.775252) (xy 106.718862 -359.75798) (xy 106.71302 -359.750868) (xy 106.69712 -359.730454)
			(xy 106.670426 -359.686126) (xy 106.649966 -359.638599) (xy 106.636113 -359.588743) (xy 106.629123 -359.537472)
			(xy 106.628692 -359.5116) (xy 106.629178 -359.484349) (xy 106.636934 -359.430401) (xy 106.652289 -359.378106)
			(xy 106.674931 -359.328529) (xy 106.704397 -359.282679) (xy 106.740088 -359.241488) (xy 106.781279 -359.205797)
			(xy 106.827129 -359.176331) (xy 106.876706 -359.153689) (xy 106.929001 -359.138334) (xy 106.982949 -359.130578)
			(xy 107.037451 -359.130578) (xy 107.091399 -359.138334) (xy 107.143694 -359.153689) (xy 107.193271 -359.176331)
			(xy 107.239121 -359.205797) (xy 107.280312 -359.241488) (xy 107.316003 -359.282679) (xy 107.345469 -359.328529)
			(xy 107.368111 -359.378106) (xy 107.383466 -359.430401) (xy 107.391222 -359.484349) (xy 107.391708 -359.5116)
			(xy 107.391195 -359.540518) (xy 107.382459 -359.597691) (xy 107.365187 -359.652887) (xy 107.339776 -359.704842)
			(xy 107.306809 -359.752362) (xy 107.287314 -359.773728) (xy 107.281264 -359.780656) (xy 107.274102 -359.797582)
			(xy 107.273344 -359.806748) (xy 107.270296 -359.882948) (xy 107.276138 -359.90022) (xy 107.28198 -359.907332)
			(xy 107.29788 -359.927746) (xy 107.324574 -359.972074) (xy 107.345034 -360.019601) (xy 107.358887 -360.069457)
			(xy 107.365877 -360.120728) (xy 107.366308 -360.1466) (xy 107.365822 -360.173851) (xy 107.358066 -360.227799)
			(xy 107.342711 -360.280094) (xy 107.320069 -360.329671) (xy 107.290603 -360.375521) (xy 107.254912 -360.416712)
			(xy 107.213721 -360.452403) (xy 107.167871 -360.481869) (xy 107.118294 -360.504511) (xy 107.065999 -360.519866)
			(xy 107.012051 -360.527622) (xy 106.957549 -360.527622) (xy 106.903601 -360.519866) (xy 106.851306 -360.504511)
			(xy 106.801729 -360.481869) (xy 106.755879 -360.452403) (xy 106.714688 -360.416712) (xy 106.678997 -360.375521)
			(xy 106.649531 -360.329671) (xy 106.626889 -360.280094) (xy 106.611534 -360.227799) (xy 106.603778 -360.173851)
			(xy 106.603292 -360.1466) (xy 103.525241 -360.1466) (xy 103.50702 -360.190589) (xy 103.477033 -360.242529)
			(xy 103.440523 -360.29011) (xy 103.398115 -360.332519) (xy 103.350534 -360.36903) (xy 103.298595 -360.399017)
			(xy 103.243186 -360.421969) (xy 103.185255 -360.437492) (xy 103.125793 -360.445321) (xy 103.095806 -360.445812)
			(xy 102.232206 -360.445812) (xy 102.202223 -360.445243) (xy 102.142771 -360.437417) (xy 102.084849 -360.421897)
			(xy 102.029448 -360.39895) (xy 101.977516 -360.368968) (xy 101.929942 -360.332464) (xy 101.88754 -360.290062)
			(xy 101.851035 -360.242489) (xy 101.821052 -360.190558) (xy 101.798104 -360.135157) (xy 101.782584 -360.077235)
			(xy 101.774757 -360.017783) (xy 95.813372 -360.017783) (xy 95.813372 -361.5944) (xy 99.489292 -361.5944)
			(xy 99.493275 -361.541253) (xy 99.505134 -361.489292) (xy 99.524605 -361.43968) (xy 99.551252 -361.393523)
			(xy 99.58448 -361.351854) (xy 99.623548 -361.315602) (xy 99.667582 -361.285577) (xy 99.7156 -361.26245)
			(xy 99.766527 -361.246738) (xy 99.819228 -361.238791) (xy 99.845876 -361.238292) (xy 99.872284 -361.238789)
			(xy 99.924522 -361.246586) (xy 99.975035 -361.262015) (xy 100.022714 -361.284735) (xy 100.066515 -361.314249)
			(xy 100.105476 -361.349909) (xy 100.122482 -361.370118) (xy 100.130079 -361.378543) (xy 100.150524 -361.388305)
			(xy 100.161852 -361.388914) (xy 100.2411 -361.388914) (xy 100.252421 -361.388283) (xy 100.272856 -361.37852)
			(xy 100.28047 -361.370118) (xy 100.297489 -361.349919) (xy 100.336446 -361.314256) (xy 100.380244 -361.284738)
			(xy 100.427921 -361.262012) (xy 100.478432 -361.246578) (xy 100.530668 -361.238773) (xy 100.557076 -361.238292)
			(xy 100.583728 -361.238764) (xy 100.636438 -361.246705) (xy 100.687375 -361.262414) (xy 100.735402 -361.28554)
			(xy 100.779446 -361.315565) (xy 100.818522 -361.35182) (xy 100.851758 -361.393494) (xy 100.878411 -361.439657)
			(xy 100.897886 -361.489276) (xy 100.909748 -361.541244) (xy 100.913732 -361.5944) (xy 100.909748 -361.647556)
			(xy 100.897886 -361.699524) (xy 100.878411 -361.749143) (xy 100.851758 -361.795306) (xy 100.818522 -361.83698)
			(xy 100.779446 -361.873235) (xy 100.735402 -361.90326) (xy 100.687375 -361.926386) (xy 100.636438 -361.942095)
			(xy 100.583728 -361.950036) (xy 100.557076 -361.950508) (xy 100.530667 -361.950046) (xy 100.478427 -361.942241)
			(xy 100.427914 -361.926806) (xy 100.380234 -361.904079) (xy 100.336434 -361.874559) (xy 100.297475 -361.838894)
			(xy 100.28047 -361.818682) (xy 100.272893 -361.810235) (xy 100.252433 -361.800485) (xy 100.2411 -361.799886)
			(xy 100.161852 -361.799886) (xy 100.150528 -361.80049) (xy 100.130094 -361.810272) (xy 100.122482 -361.818682)
			(xy 100.105489 -361.838904) (xy 100.066527 -361.874566) (xy 100.022724 -361.904081) (xy 99.975041 -361.926803)
			(xy 99.924526 -361.942232) (xy 99.872286 -361.95003) (xy 99.845876 -361.950508) (xy 99.819228 -361.950009)
			(xy 99.766527 -361.942062) (xy 99.7156 -361.92635) (xy 99.667582 -361.903223) (xy 99.623548 -361.873198)
			(xy 99.58448 -361.836946) (xy 99.551252 -361.795277) (xy 99.524605 -361.74912) (xy 99.505134 -361.699508)
			(xy 99.493275 -361.647547) (xy 99.489292 -361.5944) (xy 95.813372 -361.5944) (xy 95.813372 -364.276894)
			(xy 95.812949 -364.286964) (xy 95.805233 -364.305568) (xy 95.798386 -364.312962) (xy 92.430522 -367.680826)
			(xy 99.682623 -367.680826) (xy 99.682626 -367.626333) (xy 99.690383 -367.572394) (xy 99.705738 -367.520109)
			(xy 99.728377 -367.47054) (xy 99.75784 -367.424698) (xy 99.793527 -367.383516) (xy 99.834711 -367.347831)
			(xy 99.880554 -367.31837) (xy 99.930124 -367.295733) (xy 99.98241 -367.28038) (xy 100.036349 -367.272624)
			(xy 100.090842 -367.272624) (xy 100.144781 -367.280378) (xy 100.197068 -367.295729) (xy 100.246637 -367.318365)
			(xy 100.292481 -367.347825) (xy 100.333666 -367.383509) (xy 100.369354 -367.424691) (xy 100.398818 -367.470532)
			(xy 100.421459 -367.5201) (xy 100.436815 -367.572385) (xy 100.444574 -367.626323) (xy 100.445062 -367.65357)
			(xy 100.444303 -367.687997) (xy 100.431907 -367.755726) (xy 100.420424 -367.78819) (xy 100.415625 -367.80207)
			(xy 100.413449 -367.83135) (xy 100.419694 -367.860038) (xy 100.433846 -367.885763) (xy 100.454732 -367.906397)
			(xy 100.480627 -367.920234) (xy 100.509389 -367.926131) (xy 100.524056 -367.92535) (xy 100.555552 -367.92408)
			(xy 100.582809 -367.924504) (xy 100.63677 -367.932255) (xy 100.689078 -367.947608) (xy 100.738668 -367.970248)
			(xy 100.784532 -367.999716) (xy 100.825735 -368.035411) (xy 100.861438 -368.076607) (xy 100.890915 -368.122465)
			(xy 100.913566 -368.172051) (xy 100.928929 -368.224356) (xy 100.93464 -368.264054) (xy 103.243332 -368.264054)
			(xy 103.243332 -368.209546) (xy 103.251089 -368.155594) (xy 103.266445 -368.103294) (xy 103.289087 -368.053713)
			(xy 103.318555 -368.007858) (xy 103.354249 -367.966663) (xy 103.395442 -367.930967) (xy 103.441295 -367.901497)
			(xy 103.490876 -367.878852) (xy 103.543174 -367.863493) (xy 103.597126 -367.855733) (xy 103.62438 -367.855246)
			(xy 103.651658 -367.855674) (xy 103.705657 -367.863443) (xy 103.757999 -367.878824) (xy 103.807616 -367.901505)
			(xy 103.853496 -367.931023) (xy 103.894704 -367.966775) (xy 103.930398 -368.008032) (xy 103.959852 -368.053954)
			(xy 103.982463 -368.103603) (xy 103.997771 -368.155966) (xy 104.002078 -368.182906) (xy 104.004785 -368.197766)
			(xy 104.017581 -368.225105) (xy 104.037808 -368.247511) (xy 104.063699 -368.263029) (xy 104.092995 -368.270304)
			(xy 104.123138 -368.268701) (xy 104.151497 -368.25836) (xy 104.163876 -368.249708) (xy 104.188882 -368.23155)
			(xy 104.243532 -368.202707) (xy 104.302116 -368.183048) (xy 104.363103 -368.173089) (xy 104.394 -368.172492)
			(xy 104.421251 -368.172978) (xy 104.475199 -368.180734) (xy 104.527494 -368.196089) (xy 104.577071 -368.218731)
			(xy 104.622921 -368.248197) (xy 104.664112 -368.283888) (xy 104.699803 -368.325079) (xy 104.729269 -368.370929)
			(xy 104.751911 -368.420506) (xy 104.767266 -368.472801) (xy 104.775022 -368.526749) (xy 104.775022 -368.581251)
			(xy 104.767266 -368.635199) (xy 104.751911 -368.687494) (xy 104.729269 -368.737071) (xy 104.699803 -368.782921)
			(xy 104.664112 -368.824112) (xy 104.622921 -368.859803) (xy 104.577071 -368.889269) (xy 104.527494 -368.911911)
			(xy 104.475199 -368.927266) (xy 104.421251 -368.935022) (xy 104.394 -368.935508) (xy 104.366724 -368.935053)
			(xy 104.312728 -368.927283) (xy 104.260389 -368.911901) (xy 104.210775 -368.889222) (xy 104.164896 -368.859707)
			(xy 104.12369 -368.823958) (xy 104.087995 -368.782705) (xy 104.05854 -368.736788) (xy 104.035925 -368.687144)
			(xy 104.020612 -368.634786) (xy 104.016302 -368.607848) (xy 104.013597 -368.592985) (xy 104.000809 -368.565637)
			(xy 103.980584 -368.543223) (xy 103.95469 -368.5277) (xy 103.925389 -368.520426) (xy 103.895241 -368.522035)
			(xy 103.866881 -368.532388) (xy 103.854504 -368.541046) (xy 103.829509 -368.55922) (xy 103.774855 -368.588058)
			(xy 103.716267 -368.607711) (xy 103.655278 -368.617667) (xy 103.62438 -368.618262) (xy 103.597126 -368.617867)
			(xy 103.543174 -368.610107) (xy 103.490876 -368.594748) (xy 103.441295 -368.572103) (xy 103.395442 -368.542633)
			(xy 103.354249 -368.506937) (xy 103.318555 -368.465742) (xy 103.289087 -368.419887) (xy 103.266445 -368.370306)
			(xy 103.251089 -368.318006) (xy 103.243332 -368.264054) (xy 100.93464 -368.264054) (xy 100.936691 -368.278315)
			(xy 100.936695 -368.332829) (xy 100.92894 -368.386789) (xy 100.913585 -368.439097) (xy 100.890942 -368.488686)
			(xy 100.861472 -368.534548) (xy 100.825775 -368.575749) (xy 100.784577 -368.61145) (xy 100.738718 -368.640925)
			(xy 100.68913 -368.663573) (xy 100.636825 -368.678933) (xy 100.582865 -368.686692) (xy 100.528351 -368.686694)
			(xy 100.474391 -368.678936) (xy 100.422085 -368.663578) (xy 100.372496 -368.640933) (xy 100.326636 -368.61146)
			(xy 100.285437 -368.57576) (xy 100.249738 -368.534561) (xy 100.220266 -368.4887) (xy 100.19762 -368.439112)
			(xy 100.182263 -368.386805) (xy 100.174506 -368.332845) (xy 100.174044 -368.305588) (xy 100.174792 -368.271161)
			(xy 100.187196 -368.203431) (xy 100.198682 -368.170968) (xy 100.203407 -368.157064) (xy 100.205595 -368.127796)
			(xy 100.199362 -368.099115) (xy 100.185224 -368.073394) (xy 100.164349 -368.052762) (xy 100.138465 -368.038925)
			(xy 100.109713 -368.033028) (xy 100.09505 -368.033808) (xy 100.063554 -368.035078) (xy 100.036307 -368.034573)
			(xy 99.982369 -368.026811) (xy 99.930085 -368.011453) (xy 99.880518 -367.98881) (xy 99.834678 -367.959345)
			(xy 99.793498 -367.923655) (xy 99.757815 -367.882469) (xy 99.728358 -367.836623) (xy 99.705724 -367.787053)
			(xy 99.690375 -367.734766) (xy 99.682623 -367.680826) (xy 92.430522 -367.680826) (xy 91.766136 -368.345212)
			(xy 91.76385 -368.347752) (xy 91.762072 -368.349784) (xy 91.75536 -368.359302) (xy 91.75057 -368.382069)
			(xy 91.752928 -368.393472) (xy 91.76258 -368.426238) (xy 91.770708 -368.45367) (xy 91.77401 -368.461798)
			(xy 91.783916 -368.482118) (xy 91.786027 -368.486223) (xy 91.791527 -368.493634) (xy 91.794838 -368.49685)
			(xy 91.805252 -368.506502) (xy 91.816428 -368.51463) (xy 91.822016 -368.517424) (xy 91.828112 -368.518948)
			(xy 91.859203 -368.527303) (xy 91.919019 -368.551107) (xy 91.97517 -368.5826) (xy 92.026671 -368.62123)
			(xy 92.072622 -368.666321) (xy 92.112217 -368.717084) (xy 92.144763 -368.772631) (xy 92.169691 -368.831988)
			(xy 92.186565 -368.894116) (xy 92.192026 -368.935) (xy 102.360982 -368.935) (xy 102.365053 -368.879378)
			(xy 102.377179 -368.824941) (xy 102.397102 -368.77285) (xy 102.424398 -368.724215) (xy 102.458484 -368.680072)
			(xy 102.498633 -368.641363) (xy 102.543991 -368.608912) (xy 102.593591 -368.583411) (xy 102.646375 -368.565404)
			(xy 102.701218 -368.555274) (xy 102.756952 -368.553237) (xy 102.812389 -368.559337) (xy 102.866346 -368.573443)
			(xy 102.917675 -368.595255) (xy 102.965281 -368.624309) (xy 103.008149 -368.659984) (xy 103.045366 -368.701521)
			(xy 103.076139 -368.748034) (xy 103.099811 -368.798531) (xy 103.115879 -368.851938) (xy 103.123999 -368.907114)
			(xy 103.124508 -368.935) (xy 103.123999 -368.962886) (xy 103.115879 -369.018062) (xy 103.099811 -369.071469)
			(xy 103.076139 -369.121966) (xy 103.045366 -369.168479) (xy 103.008149 -369.210016) (xy 102.965281 -369.245691)
			(xy 102.917675 -369.274745) (xy 102.866346 -369.296557) (xy 102.812389 -369.310663) (xy 102.756952 -369.316763)
			(xy 102.701218 -369.314726) (xy 102.646375 -369.304596) (xy 102.593591 -369.286589) (xy 102.543991 -369.261088)
			(xy 102.498633 -369.228637) (xy 102.458484 -369.189928) (xy 102.424398 -369.145785) (xy 102.397102 -369.09715)
			(xy 102.377179 -369.045059) (xy 102.365053 -368.990622) (xy 102.360982 -368.935) (xy 92.192026 -368.935)
			(xy 92.195088 -368.957929) (xy 92.19565 -368.990118) (xy 92.195129 -369.021914) (xy 92.186826 -369.084962)
			(xy 92.170366 -369.146388) (xy 92.146028 -369.205139) (xy 92.114231 -369.260211) (xy 92.075517 -369.310661)
			(xy 92.030549 -369.355627) (xy 91.980098 -369.394339) (xy 91.925024 -369.426135) (xy 91.866272 -369.450471)
			(xy 91.804847 -369.466929) (xy 91.741798 -369.47523) (xy 91.710002 -369.475766) (xy 91.680161 -369.475311)
			(xy 91.620928 -369.467996) (xy 91.563038 -369.453476) (xy 91.507365 -369.431971) (xy 91.454747 -369.403804)
			(xy 91.405978 -369.369401) (xy 91.361793 -369.32928) (xy 91.322859 -369.284045) (xy 91.289763 -369.23438)
			(xy 91.263004 -369.181032) (xy 91.242984 -369.124807) (xy 91.236038 -369.095782) (xy 91.236038 -369.095274)
			(xy 91.235784 -369.09502) (xy 91.234112 -369.088363) (xy 91.22767 -369.07625) (xy 91.223084 -369.071144)
			(xy 91.218258 -369.066318) (xy 91.206574 -369.05946) (xy 91.189302 -369.054888) (xy 91.188794 -369.054888)
			(xy 91.11488 -369.033552) (xy 91.106064 -369.031419) (xy 91.087989 -369.032803) (xy 91.071512 -369.040359)
			(xy 91.064842 -369.046506) (xy 89.94013 -370.171218) (xy 89.937425 -370.17407) (xy 89.932835 -370.180449)
			(xy 89.930986 -370.183918) (xy 89.928401 -370.189344) (xy 89.925572 -370.201024) (xy 89.925398 -370.207032)
			(xy 89.925398 -370.224812) (xy 89.927176 -370.23802) (xy 89.9287 -370.243608) (xy 89.932002 -370.24945)
			(xy 89.946871 -370.276598) (xy 89.970375 -370.333861) (xy 89.986423 -370.393644) (xy 89.994754 -370.454979)
			(xy 89.995502 -370.485924) (xy 89.995502 -370.494052) (xy 89.994788 -370.524033) (xy 89.986872 -370.58348)
			(xy 89.971697 -370.6415) (xy 89.949495 -370.69721) (xy 89.920603 -370.749764) (xy 89.88546 -370.79836)
			(xy 89.844603 -370.842261) (xy 89.798651 -370.880797) (xy 89.748305 -370.913383) (xy 89.69433 -370.939523)
			(xy 89.637547 -370.958819) (xy 89.598031 -370.967) (xy 104.011992 -370.967) (xy 104.015722 -370.913749)
			(xy 104.026838 -370.861537) (xy 104.045124 -370.811385) (xy 104.070223 -370.764271) (xy 104.101645 -370.721117)
			(xy 104.138775 -370.682763) (xy 104.159558 -370.66601) (xy 104.16836 -370.658399) (xy 104.178544 -370.637501)
			(xy 104.179116 -370.625878) (xy 104.179116 -370.546122) (xy 104.178544 -370.534494) (xy 104.168378 -370.513585)
			(xy 104.159558 -370.50599) (xy 104.138775 -370.489237) (xy 104.101645 -370.450883) (xy 104.070223 -370.407729)
			(xy 104.045124 -370.360615) (xy 104.026838 -370.310463) (xy 104.015722 -370.258251) (xy 104.011992 -370.205)
			(xy 104.015722 -370.151749) (xy 104.026838 -370.099537) (xy 104.045124 -370.049385) (xy 104.070223 -370.002271)
			(xy 104.101645 -369.959117) (xy 104.138775 -369.920763) (xy 104.159558 -369.90401) (xy 104.16836 -369.896399)
			(xy 104.178544 -369.875501) (xy 104.179116 -369.863878) (xy 104.179116 -369.784122) (xy 104.178544 -369.772494)
			(xy 104.168378 -369.751585) (xy 104.159558 -369.74399) (xy 104.137061 -369.725815) (xy 104.097329 -369.683791)
			(xy 104.064392 -369.636252) (xy 104.039007 -369.584288) (xy 104.021753 -369.529088) (xy 104.013026 -369.471917)
			(xy 104.012492 -369.443) (xy 104.012978 -369.415749) (xy 104.020734 -369.361801) (xy 104.036089 -369.309506)
			(xy 104.058731 -369.259929) (xy 104.088197 -369.214079) (xy 104.123888 -369.172888) (xy 104.165079 -369.137197)
			(xy 104.210929 -369.107731) (xy 104.260506 -369.085089) (xy 104.312801 -369.069734) (xy 104.366749 -369.061978)
			(xy 104.421251 -369.061978) (xy 104.475199 -369.069734) (xy 104.527494 -369.085089) (xy 104.577071 -369.107731)
			(xy 104.622921 -369.137197) (xy 104.664112 -369.172888) (xy 104.699803 -369.214079) (xy 104.729269 -369.259929)
			(xy 104.751911 -369.309506) (xy 104.767266 -369.361801) (xy 104.775022 -369.415749) (xy 104.775508 -369.443)
			(xy 104.775025 -369.471919) (xy 104.766293 -369.529093) (xy 104.749031 -369.584294) (xy 104.723633 -369.636256)
			(xy 104.690681 -369.683789) (xy 104.650932 -369.725803) (xy 104.628442 -369.74399) (xy 104.61964 -369.751601)
			(xy 104.609456 -369.772499) (xy 104.608884 -369.784122) (xy 104.608884 -369.863878) (xy 104.609456 -369.875506)
			(xy 104.619622 -369.896415) (xy 104.628442 -369.90401) (xy 104.649225 -369.920763) (xy 104.686355 -369.959117)
			(xy 104.717777 -370.002271) (xy 104.742876 -370.049385) (xy 104.761162 -370.099537) (xy 104.772278 -370.151749)
			(xy 104.776008 -370.205) (xy 104.772278 -370.258251) (xy 104.761162 -370.310463) (xy 104.742876 -370.360615)
			(xy 104.717777 -370.407729) (xy 104.686355 -370.450883) (xy 104.649225 -370.489237) (xy 104.628442 -370.50599)
			(xy 104.61964 -370.513601) (xy 104.609456 -370.534499) (xy 104.608884 -370.546122) (xy 104.608884 -370.625878)
			(xy 104.609456 -370.637506) (xy 104.619622 -370.658415) (xy 104.628442 -370.66601) (xy 104.649225 -370.682763)
			(xy 104.686355 -370.721117) (xy 104.717777 -370.764271) (xy 104.742876 -370.811385) (xy 104.761162 -370.861537)
			(xy 104.772278 -370.913749) (xy 104.776008 -370.967) (xy 104.772278 -371.020251) (xy 104.761162 -371.072463)
			(xy 104.742876 -371.122615) (xy 104.717777 -371.169729) (xy 104.686355 -371.212883) (xy 104.649225 -371.251237)
			(xy 104.628442 -371.26799) (xy 104.61964 -371.275601) (xy 104.609456 -371.296499) (xy 104.608884 -371.308122)
			(xy 104.608884 -371.387878) (xy 104.609456 -371.399506) (xy 104.619622 -371.420415) (xy 104.628442 -371.42801)
			(xy 104.650939 -371.446185) (xy 104.690671 -371.488209) (xy 104.723608 -371.535748) (xy 104.748993 -371.587712)
			(xy 104.766247 -371.642912) (xy 104.774974 -371.700083) (xy 104.775508 -371.729) (xy 104.775022 -371.756251)
			(xy 104.767266 -371.810199) (xy 104.751911 -371.862494) (xy 104.729269 -371.912071) (xy 104.699803 -371.957921)
			(xy 104.664112 -371.999112) (xy 104.622921 -372.034803) (xy 104.577071 -372.064269) (xy 104.527494 -372.086911)
			(xy 104.475199 -372.102266) (xy 104.421251 -372.110022) (xy 104.366749 -372.110022) (xy 104.312801 -372.102266)
			(xy 104.260506 -372.086911) (xy 104.210929 -372.064269) (xy 104.165079 -372.034803) (xy 104.123888 -371.999112)
			(xy 104.088197 -371.957921) (xy 104.058731 -371.912071) (xy 104.036089 -371.862494) (xy 104.020734 -371.810199)
			(xy 104.012978 -371.756251) (xy 104.012492 -371.729) (xy 104.012975 -371.700081) (xy 104.021707 -371.642907)
			(xy 104.038969 -371.587706) (xy 104.064367 -371.535744) (xy 104.097319 -371.488211) (xy 104.137068 -371.446197)
			(xy 104.159558 -371.42801) (xy 104.16836 -371.420399) (xy 104.178544 -371.399501) (xy 104.179116 -371.387878)
			(xy 104.179116 -371.308122) (xy 104.178544 -371.296494) (xy 104.168378 -371.275585) (xy 104.159558 -371.26799)
			(xy 104.138775 -371.251237) (xy 104.101645 -371.212883) (xy 104.070223 -371.169729) (xy 104.045124 -371.122615)
			(xy 104.026838 -371.072463) (xy 104.015722 -371.020251) (xy 104.011992 -370.967) (xy 89.598031 -370.967)
			(xy 89.578821 -370.970977) (xy 89.54897 -370.973858) (xy 89.539791 -370.975107) (xy 89.523136 -370.983185)
			(xy 89.516458 -370.989606) (xy 89.49563 -371.011196) (xy 89.489245 -371.018517) (xy 89.482054 -371.036543)
			(xy 89.48166 -371.046248) (xy 89.48166 -371.233954) (xy 89.482088 -371.243653) (xy 89.489265 -371.261676)
			(xy 89.49563 -371.269006) (xy 89.516458 -371.290596) (xy 89.52309 -371.297083) (xy 89.539769 -371.305164)
			(xy 89.54897 -371.306344) (xy 89.580292 -371.309373) (xy 89.641835 -371.322501) (xy 89.701166 -371.343471)
			(xy 89.75729 -371.371933) (xy 89.809265 -371.407408) (xy 89.856221 -371.449302) (xy 89.897369 -371.496913)
			(xy 89.932019 -371.549442) (xy 89.951818 -371.590062) (xy 91.223854 -371.590062) (xy 91.227845 -371.527895)
			(xy 91.239754 -371.466748) (xy 91.259383 -371.407627) (xy 91.286412 -371.351501) (xy 91.320396 -371.299292)
			(xy 91.360778 -371.251857) (xy 91.406894 -371.209976) (xy 91.457986 -371.174336) (xy 91.513217 -371.145522)
			(xy 91.571679 -371.124008) (xy 91.632413 -371.110146) (xy 91.69442 -371.104164) (xy 91.756683 -371.10616)
			(xy 91.81818 -371.116103) (xy 91.877901 -371.133827) (xy 91.934864 -371.159044) (xy 91.988135 -371.191337)
			(xy 92.03684 -371.230177) (xy 92.080177 -371.274927) (xy 92.117437 -371.324851) (xy 92.148006 -371.37913)
			(xy 92.171384 -371.436873) (xy 92.187185 -371.497131) (xy 92.195151 -371.558914) (xy 92.19565 -371.590062)
			(xy 92.195151 -371.62121) (xy 92.187185 -371.682993) (xy 92.171384 -371.743251) (xy 92.148006 -371.800994)
			(xy 92.117437 -371.855273) (xy 92.080177 -371.905197) (xy 92.03684 -371.949947) (xy 91.988135 -371.988787)
			(xy 91.934864 -372.02108) (xy 91.877901 -372.046297) (xy 91.81818 -372.064021) (xy 91.756683 -372.073964)
			(xy 91.69442 -372.07596) (xy 91.632413 -372.069978) (xy 91.571679 -372.056116) (xy 91.513217 -372.034602)
			(xy 91.457986 -372.005788) (xy 91.406894 -371.970148) (xy 91.360778 -371.928267) (xy 91.320396 -371.880832)
			(xy 91.286412 -371.828623) (xy 91.259383 -371.772497) (xy 91.239754 -371.713376) (xy 91.227845 -371.652229)
			(xy 91.223854 -371.590062) (xy 89.951818 -371.590062) (xy 89.959591 -371.606008) (xy 89.979623 -371.665662)
			(xy 89.991778 -371.727405) (xy 89.995852 -371.790201) (xy 89.991777 -371.852997) (xy 89.979622 -371.91474)
			(xy 89.959591 -371.974394) (xy 89.932018 -372.03096) (xy 89.897367 -372.083489) (xy 89.856219 -372.131099)
			(xy 89.809264 -372.172993) (xy 89.757288 -372.208468) (xy 89.701164 -372.236929) (xy 89.641833 -372.2579)
			(xy 89.58029 -372.271027) (xy 89.54897 -372.274084) (xy 89.539792 -372.275333) (xy 89.523139 -372.283414)
			(xy 89.516458 -372.289832) (xy 89.49563 -372.311422) (xy 89.489249 -372.318744) (xy 89.482067 -372.33677)
			(xy 89.48166 -372.346474) (xy 89.48166 -372.890034) (xy 91.223854 -372.890034) (xy 91.227845 -372.827867)
			(xy 91.239754 -372.76672) (xy 91.259383 -372.707599) (xy 91.286412 -372.651473) (xy 91.320396 -372.599264)
			(xy 91.360778 -372.551829) (xy 91.406894 -372.509948) (xy 91.457986 -372.474308) (xy 91.513217 -372.445494)
			(xy 91.571679 -372.42398) (xy 91.632413 -372.410118) (xy 91.69442 -372.404136) (xy 91.756683 -372.406132)
			(xy 91.81818 -372.416075) (xy 91.877901 -372.433799) (xy 91.934864 -372.459016) (xy 91.988135 -372.491309)
			(xy 92.03684 -372.530149) (xy 92.080177 -372.574899) (xy 92.117437 -372.624823) (xy 92.148006 -372.679102)
			(xy 92.171384 -372.736845) (xy 92.187185 -372.797103) (xy 92.195151 -372.858886) (xy 92.19565 -372.890034)
			(xy 92.195151 -372.921182) (xy 92.187185 -372.982965) (xy 92.171384 -373.043223) (xy 92.148006 -373.100966)
			(xy 92.117437 -373.155245) (xy 92.080177 -373.205169) (xy 92.03684 -373.249919) (xy 91.988135 -373.288759)
			(xy 91.934864 -373.321052) (xy 91.877901 -373.346269) (xy 91.81818 -373.363993) (xy 91.756683 -373.373936)
			(xy 91.69442 -373.375932) (xy 91.632413 -373.36995) (xy 91.571679 -373.356088) (xy 91.513217 -373.334574)
			(xy 91.457986 -373.30576) (xy 91.406894 -373.27012) (xy 91.360778 -373.228239) (xy 91.320396 -373.180804)
			(xy 91.286412 -373.128595) (xy 91.259383 -373.072469) (xy 91.239754 -373.013348) (xy 91.227845 -372.952201)
			(xy 91.223854 -372.890034) (xy 89.48166 -372.890034) (xy 89.48166 -373.869204) (xy 89.489026 -373.887492)
			(xy 89.489534 -373.888) (xy 89.49469 -373.892884) (xy 89.507069 -373.899833) (xy 89.513918 -373.901716)
			(xy 89.526364 -373.904764) (xy 89.531444 -373.905018) (xy 89.562286 -373.906877) (xy 89.623164 -373.917437)
			(xy 89.682211 -373.935634) (xy 89.738474 -373.961173) (xy 89.791042 -373.993641) (xy 89.839069 -374.032515)
			(xy 89.881776 -374.077167) (xy 89.918476 -374.126875) (xy 89.948574 -374.180836) (xy 89.971585 -374.238178)
			(xy 89.987137 -374.297976) (xy 89.994979 -374.359264) (xy 89.995502 -374.390158) (xy 89.99502 -374.421076)
			(xy 89.987175 -374.482414) (xy 89.971607 -374.542259) (xy 89.948567 -374.599643) (xy 89.918429 -374.653638)
			(xy 89.881679 -374.70337) (xy 89.838914 -374.748034) (xy 89.790824 -374.786908) (xy 89.738188 -374.819362)
			(xy 89.681858 -374.844871) (xy 89.622745 -374.863022) (xy 89.561806 -374.873523) (xy 89.530936 -374.875298)
			(xy 89.52611 -374.875552) (xy 89.512902 -374.8786) (xy 89.50071 -374.88368) (xy 89.497656 -374.885481)
			(xy 89.492044 -374.889813) (xy 89.489534 -374.892316) (xy 89.489026 -374.892824) (xy 89.48166 -374.911112)
			(xy 89.48166 -375.169176) (xy 89.489026 -375.187464) (xy 89.489534 -375.187972) (xy 89.494689 -375.192858)
			(xy 89.507067 -375.199811) (xy 89.513918 -375.201688) (xy 89.526364 -375.204736) (xy 89.531444 -375.20499)
			(xy 89.562286 -375.206849) (xy 89.623166 -375.217409) (xy 89.682215 -375.235605) (xy 89.738479 -375.261144)
			(xy 89.791049 -375.293612) (xy 89.839077 -375.332486) (xy 89.881787 -375.377137) (xy 89.918489 -375.426844)
			(xy 89.94859 -375.480805) (xy 89.952374 -375.490232) (xy 91.223854 -375.490232) (xy 91.227845 -375.428065)
			(xy 91.239754 -375.366918) (xy 91.259383 -375.307797) (xy 91.286412 -375.251671) (xy 91.320396 -375.199462)
			(xy 91.360778 -375.152027) (xy 91.406894 -375.110146) (xy 91.457986 -375.074506) (xy 91.513217 -375.045692)
			(xy 91.571679 -375.024178) (xy 91.632413 -375.010316) (xy 91.69442 -375.004334) (xy 91.756683 -375.00633)
			(xy 91.81818 -375.016273) (xy 91.877901 -375.033997) (xy 91.934864 -375.059214) (xy 91.988135 -375.091507)
			(xy 92.03684 -375.130347) (xy 92.080177 -375.175097) (xy 92.108742 -375.213371) (xy 104.681961 -375.213371)
			(xy 104.681961 -375.153429) (xy 104.689785 -375.094001) (xy 104.7053 -375.036103) (xy 104.72824 -374.980725)
			(xy 104.758212 -374.928815) (xy 104.794703 -374.881262) (xy 104.837089 -374.838879) (xy 104.884645 -374.802391)
			(xy 104.936557 -374.772424) (xy 104.991937 -374.749489) (xy 105.049837 -374.733978) (xy 105.109265 -374.726159)
			(xy 105.139236 -374.725692) (xy 106.002836 -374.725692) (xy 106.032802 -374.726184) (xy 106.092221 -374.734011)
			(xy 106.15011 -374.749527) (xy 106.205479 -374.772465) (xy 106.25738 -374.802434) (xy 106.304926 -374.838921)
			(xy 106.347303 -374.881301) (xy 106.383786 -374.92885) (xy 106.413751 -374.980753) (xy 106.436685 -375.036124)
			(xy 106.452196 -375.094014) (xy 106.460018 -375.153434) (xy 106.460018 -375.213366) (xy 106.452196 -375.272786)
			(xy 106.436685 -375.330676) (xy 106.413751 -375.386047) (xy 106.383786 -375.43795) (xy 106.347303 -375.485499)
			(xy 106.304926 -375.527879) (xy 106.25738 -375.564366) (xy 106.205479 -375.594335) (xy 106.15011 -375.617273)
			(xy 106.092221 -375.632789) (xy 106.032802 -375.640616) (xy 106.002836 -375.641108) (xy 105.139236 -375.641108)
			(xy 105.109265 -375.640641) (xy 105.049837 -375.632822) (xy 104.991937 -375.617311) (xy 104.936557 -375.594376)
			(xy 104.884645 -375.564409) (xy 104.837089 -375.527921) (xy 104.794703 -375.485538) (xy 104.758212 -375.437985)
			(xy 104.72824 -375.386075) (xy 104.7053 -375.330697) (xy 104.689785 -375.272799) (xy 104.681961 -375.213371)
			(xy 92.108742 -375.213371) (xy 92.117437 -375.225021) (xy 92.148006 -375.2793) (xy 92.171384 -375.337043)
			(xy 92.187185 -375.397301) (xy 92.195151 -375.459084) (xy 92.19565 -375.490232) (xy 92.195151 -375.52138)
			(xy 92.187185 -375.583163) (xy 92.171384 -375.643421) (xy 92.148006 -375.701164) (xy 92.117437 -375.755443)
			(xy 92.080177 -375.805367) (xy 92.03684 -375.850117) (xy 91.988135 -375.888957) (xy 91.934864 -375.92125)
			(xy 91.877901 -375.946467) (xy 91.81818 -375.964191) (xy 91.756683 -375.974134) (xy 91.69442 -375.97613)
			(xy 91.632413 -375.970148) (xy 91.571679 -375.956286) (xy 91.513217 -375.934772) (xy 91.457986 -375.905958)
			(xy 91.406894 -375.870318) (xy 91.360778 -375.828437) (xy 91.320396 -375.781002) (xy 91.286412 -375.728793)
			(xy 91.259383 -375.672667) (xy 91.239754 -375.613546) (xy 91.227845 -375.552399) (xy 91.223854 -375.490232)
			(xy 89.952374 -375.490232) (xy 89.971605 -375.538148) (xy 89.98716 -375.597947) (xy 89.995005 -375.659236)
			(xy 89.995502 -375.69013) (xy 89.995043 -375.72029) (xy 89.987567 -375.780144) (xy 89.972734 -375.838611)
			(xy 89.950773 -375.89479) (xy 89.922021 -375.947815) (xy 89.886922 -375.996871) (xy 89.846016 -376.041201)
			(xy 89.799934 -376.080122) (xy 89.749385 -376.113034) (xy 89.695149 -376.139431) (xy 89.63806 -376.158906)
			(xy 89.578998 -376.171159) (xy 89.54897 -376.174) (xy 89.539792 -376.17525) (xy 89.523141 -376.183333)
			(xy 89.516458 -376.189748) (xy 89.49563 -376.211338) (xy 89.489252 -376.218661) (xy 89.482075 -376.236687)
			(xy 89.48166 -376.24639) (xy 89.48166 -376.790204) (xy 91.223854 -376.790204) (xy 91.227845 -376.728037)
			(xy 91.239754 -376.66689) (xy 91.259383 -376.607769) (xy 91.286412 -376.551643) (xy 91.320396 -376.499434)
			(xy 91.360778 -376.451999) (xy 91.406894 -376.410118) (xy 91.457986 -376.374478) (xy 91.513217 -376.345664)
			(xy 91.571679 -376.32415) (xy 91.632413 -376.310288) (xy 91.69442 -376.304306) (xy 91.756683 -376.306302)
			(xy 91.81818 -376.316245) (xy 91.877901 -376.333969) (xy 91.934864 -376.359186) (xy 91.988135 -376.391479)
			(xy 92.03684 -376.430319) (xy 92.080177 -376.475069) (xy 92.087322 -376.484642) (xy 99.998528 -376.484642)
			(xy 100.002599 -376.42902) (xy 100.014725 -376.374583) (xy 100.034648 -376.322492) (xy 100.061944 -376.273857)
			(xy 100.09603 -376.229714) (xy 100.136179 -376.191005) (xy 100.181537 -376.158554) (xy 100.231137 -376.133053)
			(xy 100.283921 -376.115046) (xy 100.338764 -376.104916) (xy 100.394498 -376.102879) (xy 100.449935 -376.108979)
			(xy 100.503892 -376.123085) (xy 100.555221 -376.144897) (xy 100.602827 -376.173951) (xy 100.645695 -376.209626)
			(xy 100.682912 -376.251163) (xy 100.713685 -376.297676) (xy 100.737357 -376.348173) (xy 100.753425 -376.40158)
			(xy 100.761545 -376.456756) (xy 100.762054 -376.484642) (xy 100.761545 -376.512528) (xy 100.753425 -376.567704)
			(xy 100.737357 -376.621111) (xy 100.713685 -376.671608) (xy 100.682912 -376.718121) (xy 100.645695 -376.759658)
			(xy 100.602827 -376.795333) (xy 100.555221 -376.824387) (xy 100.503892 -376.846199) (xy 100.449935 -376.860305)
			(xy 100.394498 -376.866405) (xy 100.338764 -376.864368) (xy 100.283921 -376.854238) (xy 100.231137 -376.836231)
			(xy 100.181537 -376.81073) (xy 100.136179 -376.778279) (xy 100.09603 -376.73957) (xy 100.061944 -376.695427)
			(xy 100.034648 -376.646792) (xy 100.014725 -376.594701) (xy 100.002599 -376.540264) (xy 99.998528 -376.484642)
			(xy 92.087322 -376.484642) (xy 92.117437 -376.524993) (xy 92.148006 -376.579272) (xy 92.171384 -376.637015)
			(xy 92.187185 -376.697273) (xy 92.195151 -376.759056) (xy 92.19565 -376.790204) (xy 92.195151 -376.821352)
			(xy 92.187185 -376.883135) (xy 92.171384 -376.943393) (xy 92.148006 -377.001136) (xy 92.117437 -377.055415)
			(xy 92.080177 -377.105339) (xy 92.03684 -377.150089) (xy 91.988135 -377.188929) (xy 91.934864 -377.221222)
			(xy 91.877901 -377.246439) (xy 91.81818 -377.264163) (xy 91.756683 -377.274106) (xy 91.69442 -377.276102)
			(xy 91.632413 -377.27012) (xy 91.571679 -377.256258) (xy 91.513217 -377.234744) (xy 91.457986 -377.20593)
			(xy 91.406894 -377.17029) (xy 91.360778 -377.128409) (xy 91.320396 -377.080974) (xy 91.286412 -377.028765)
			(xy 91.259383 -376.972639) (xy 91.239754 -376.913518) (xy 91.227845 -376.852371) (xy 91.223854 -376.790204)
			(xy 89.48166 -376.790204) (xy 89.48166 -377.387612) (xy 100.044502 -377.387612) (xy 100.048573 -377.33199)
			(xy 100.060699 -377.277553) (xy 100.080622 -377.225462) (xy 100.107918 -377.176827) (xy 100.142004 -377.132684)
			(xy 100.182153 -377.093975) (xy 100.227511 -377.061524) (xy 100.277111 -377.036023) (xy 100.329895 -377.018016)
			(xy 100.384738 -377.007886) (xy 100.440472 -377.005849) (xy 100.495909 -377.011949) (xy 100.549866 -377.026055)
			(xy 100.601195 -377.047867) (xy 100.648801 -377.076921) (xy 100.691669 -377.112596) (xy 100.728886 -377.154133)
			(xy 100.759659 -377.200646) (xy 100.783331 -377.251143) (xy 100.799399 -377.30455) (xy 100.807519 -377.359726)
			(xy 100.808028 -377.387612) (xy 100.807519 -377.415498) (xy 100.799399 -377.470674) (xy 100.783331 -377.524081)
			(xy 100.759659 -377.574578) (xy 100.728886 -377.621091) (xy 100.691669 -377.662628) (xy 100.648801 -377.698303)
			(xy 100.601195 -377.727357) (xy 100.549866 -377.749169) (xy 100.495909 -377.763275) (xy 100.440472 -377.769375)
			(xy 100.384738 -377.767338) (xy 100.329895 -377.757208) (xy 100.277111 -377.739201) (xy 100.227511 -377.7137)
			(xy 100.182153 -377.681249) (xy 100.142004 -377.64254) (xy 100.107918 -377.598397) (xy 100.080622 -377.549762)
			(xy 100.060699 -377.497671) (xy 100.048573 -377.443234) (xy 100.044502 -377.387612) (xy 89.48166 -377.387612)
			(xy 89.48166 -377.733814) (xy 89.482081 -377.743516) (xy 89.489248 -377.761549) (xy 89.49563 -377.768866)
			(xy 89.516458 -377.790456) (xy 89.523087 -377.796947) (xy 89.539767 -377.805036) (xy 89.54897 -377.806204)
			(xy 89.580294 -377.809234) (xy 89.641843 -377.822362) (xy 89.701179 -377.843334) (xy 89.757308 -377.871797)
			(xy 89.809287 -377.907275) (xy 89.856247 -377.949172) (xy 89.897398 -377.996786) (xy 89.932052 -378.049319)
			(xy 89.959627 -378.10589) (xy 89.979661 -378.165549) (xy 89.991817 -378.227297) (xy 89.995892 -378.290098)
			(xy 89.991817 -378.352899) (xy 89.979662 -378.414647) (xy 89.959629 -378.474307) (xy 89.932054 -378.530877)
			(xy 89.897401 -378.58341) (xy 89.85625 -378.631025) (xy 89.809291 -378.672923) (xy 89.757311 -378.708401)
			(xy 89.701183 -378.736865) (xy 89.641847 -378.757837) (xy 89.580299 -378.770966) (xy 89.54897 -378.773944)
			(xy 89.539791 -378.775192) (xy 89.523134 -378.783269) (xy 89.516458 -378.789692) (xy 89.49563 -378.811282)
			(xy 89.489243 -378.818602) (xy 89.482047 -378.836628) (xy 89.48166 -378.846334) (xy 89.48166 -379.033786)
			(xy 89.482094 -379.043483) (xy 89.489279 -379.061497) (xy 89.49563 -379.068838) (xy 89.516458 -379.090428)
			(xy 89.523086 -379.096922) (xy 89.539765 -379.105015) (xy 89.54897 -379.106176) (xy 89.578996 -379.109047)
			(xy 89.638059 -379.12129) (xy 89.695149 -379.140757) (xy 89.749388 -379.167148) (xy 89.799939 -379.200056)
			(xy 89.846022 -379.238974) (xy 89.886928 -379.283303) (xy 89.922027 -379.332358) (xy 89.950776 -379.385385)
			(xy 89.952638 -379.390148) (xy 91.223854 -379.390148) (xy 91.227845 -379.327981) (xy 91.239754 -379.266834)
			(xy 91.259383 -379.207713) (xy 91.286412 -379.151587) (xy 91.320396 -379.099378) (xy 91.360778 -379.051943)
			(xy 91.406894 -379.010062) (xy 91.457986 -378.974422) (xy 91.513217 -378.945608) (xy 91.571679 -378.924094)
			(xy 91.632413 -378.910232) (xy 91.69442 -378.90425) (xy 91.756683 -378.906246) (xy 91.81818 -378.916189)
			(xy 91.877901 -378.933913) (xy 91.934864 -378.95913) (xy 91.988135 -378.991423) (xy 92.03684 -379.030263)
			(xy 92.080177 -379.075013) (xy 92.117437 -379.124937) (xy 92.148006 -379.179216) (xy 92.171384 -379.236959)
			(xy 92.187185 -379.297217) (xy 92.195151 -379.359) (xy 92.19565 -379.390148) (xy 92.195151 -379.421296)
			(xy 92.187185 -379.483079) (xy 92.171384 -379.543337) (xy 92.148006 -379.60108) (xy 92.117437 -379.655359)
			(xy 92.080177 -379.705283) (xy 92.03684 -379.750033) (xy 91.988135 -379.788873) (xy 91.934864 -379.821166)
			(xy 91.877901 -379.846383) (xy 91.81818 -379.864107) (xy 91.756683 -379.87405) (xy 91.69442 -379.876046)
			(xy 91.632413 -379.870064) (xy 91.571679 -379.856202) (xy 91.513217 -379.834688) (xy 91.457986 -379.805874)
			(xy 91.406894 -379.770234) (xy 91.360778 -379.728353) (xy 91.320396 -379.680918) (xy 91.286412 -379.628709)
			(xy 91.259383 -379.572583) (xy 91.239754 -379.513462) (xy 91.227845 -379.452315) (xy 91.223854 -379.390148)
			(xy 89.952638 -379.390148) (xy 89.972733 -379.441565) (xy 89.987561 -379.500032) (xy 89.995029 -379.559887)
			(xy 89.995502 -379.590046) (xy 89.994979 -379.62184) (xy 89.986673 -379.684883) (xy 89.97021 -379.746303)
			(xy 89.94587 -379.805048) (xy 89.914071 -379.860114) (xy 89.875356 -379.910558) (xy 89.830389 -379.955517)
			(xy 89.779937 -379.994222) (xy 89.724865 -380.026011) (xy 89.666116 -380.050339) (xy 89.604693 -380.066791)
			(xy 89.541648 -380.075085) (xy 89.509854 -380.075694) (xy 89.5096 -380.075694) (xy 89.491112 -380.07553)
			(xy 89.454242 -380.072732) (xy 89.43594 -380.070106) (xy 89.425161 -380.068971) (xy 89.404314 -380.074825)
			(xy 89.387736 -380.088755) (xy 89.3826 -380.0983) (xy 89.370544 -380.122796) (xy 89.344112 -380.170574)
			(xy 89.329768 -380.193804) (xy 89.32291 -380.211584) (xy 89.317704 -380.237288) (xy 89.301174 -380.287061)
			(xy 89.277979 -380.334099) (xy 89.248559 -380.377515) (xy 89.213467 -380.41649) (xy 89.173366 -380.45029)
			(xy 89.129011 -380.478276) (xy 89.081241 -380.499921) (xy 89.05621 -380.507748) (xy 89.04986 -380.50978)
			(xy 88.869398 -380.69012) (xy 91.223854 -380.69012) (xy 91.227845 -380.627953) (xy 91.239754 -380.566806)
			(xy 91.259383 -380.507685) (xy 91.286412 -380.451559) (xy 91.320396 -380.39935) (xy 91.360778 -380.351915)
			(xy 91.406894 -380.310034) (xy 91.457986 -380.274394) (xy 91.513217 -380.24558) (xy 91.571679 -380.224066)
			(xy 91.632413 -380.210204) (xy 91.69442 -380.204222) (xy 91.756683 -380.206218) (xy 91.81818 -380.216161)
			(xy 91.877901 -380.233885) (xy 91.934864 -380.259102) (xy 91.988135 -380.291395) (xy 92.03684 -380.330235)
			(xy 92.080177 -380.374985) (xy 92.117437 -380.424909) (xy 92.148006 -380.479188) (xy 92.171384 -380.536931)
			(xy 92.187185 -380.597189) (xy 92.195151 -380.658972) (xy 92.19565 -380.69012) (xy 92.195151 -380.721268)
			(xy 92.187185 -380.783051) (xy 92.171384 -380.843309) (xy 92.148006 -380.901052) (xy 92.117437 -380.955331)
			(xy 92.080177 -381.005255) (xy 92.03684 -381.050005) (xy 91.988135 -381.088845) (xy 91.934864 -381.121138)
			(xy 91.877901 -381.146355) (xy 91.81818 -381.164079) (xy 91.756683 -381.174022) (xy 91.69442 -381.176018)
			(xy 91.632413 -381.170036) (xy 91.571679 -381.156174) (xy 91.513217 -381.13466) (xy 91.457986 -381.105846)
			(xy 91.406894 -381.070206) (xy 91.360778 -381.028325) (xy 91.320396 -380.98089) (xy 91.286412 -380.928681)
			(xy 91.259383 -380.872555) (xy 91.239754 -380.813434) (xy 91.227845 -380.752287) (xy 91.223854 -380.69012)
			(xy 88.869398 -380.69012) (xy 88.673178 -380.886208) (xy 88.639525 -380.919116) (xy 88.56701 -380.979134)
			(xy 88.489159 -381.032048) (xy 88.406666 -381.077386) (xy 88.320266 -381.114745) (xy 88.275668 -381.129794)
			(xy 88.270006 -381.131839) (xy 88.259743 -381.138126) (xy 88.255348 -381.14224) (xy 88.23452 -381.163068)
			(xy 88.110976 -381.286851) (xy 100.042966 -381.286851) (xy 100.042966 -381.232349) (xy 100.050722 -381.178401)
			(xy 100.066077 -381.126106) (xy 100.088717 -381.076529) (xy 100.118182 -381.030678) (xy 100.153873 -380.989487)
			(xy 100.195062 -380.953794) (xy 100.240911 -380.924327) (xy 100.290488 -380.901684) (xy 100.342782 -380.886326)
			(xy 100.396729 -380.878567) (xy 100.42398 -380.87808) (xy 100.453271 -380.878598) (xy 100.511167 -380.887545)
			(xy 100.567016 -380.905232) (xy 100.619507 -380.931244) (xy 100.667407 -380.96497) (xy 100.709593 -381.005618)
			(xy 100.745074 -381.052234) (xy 100.759514 -381.077724) (xy 100.766512 -381.089738) (xy 100.78586 -381.109691)
			(xy 100.809873 -381.123686) (xy 100.83677 -381.130687) (xy 100.864559 -381.130175) (xy 100.89118 -381.122187)
			(xy 100.91466 -381.107316) (xy 100.93326 -381.086664) (xy 100.939854 -381.074422) (xy 100.952016 -381.050864)
			(xy 100.981867 -381.007049) (xy 101.017499 -380.967792) (xy 101.058226 -380.93385) (xy 101.103263 -380.905877)
			(xy 101.15174 -380.884412) (xy 101.202723 -380.86987) (xy 101.25523 -380.862531) (xy 101.281738 -380.862078)
			(xy 101.308986 -380.862595) (xy 101.362928 -380.870355) (xy 101.387499 -380.877572) (xy 105.0036 -380.877572)
			(xy 105.0036 -380.013972) (xy 105.00409 -379.983988) (xy 105.011918 -379.924532) (xy 105.027439 -379.866607)
			(xy 105.050388 -379.811203) (xy 105.080372 -379.759269) (xy 105.116878 -379.711693) (xy 105.159283 -379.669288)
			(xy 105.206859 -379.632782) (xy 105.258793 -379.602798) (xy 105.314197 -379.579849) (xy 105.372122 -379.564328)
			(xy 105.431578 -379.5565) (xy 105.491546 -379.5565) (xy 105.551002 -379.564328) (xy 105.608927 -379.579849)
			(xy 105.664331 -379.602798) (xy 105.716265 -379.632782) (xy 105.763841 -379.669288) (xy 105.806246 -379.711693)
			(xy 105.842752 -379.759269) (xy 105.872736 -379.811203) (xy 105.895685 -379.866607) (xy 105.911206 -379.924532)
			(xy 105.919034 -379.983988) (xy 105.919524 -380.013972) (xy 105.919524 -380.877572) (xy 105.919034 -380.907556)
			(xy 105.911206 -380.967012) (xy 105.895685 -381.024937) (xy 105.872736 -381.080341) (xy 105.842752 -381.132275)
			(xy 105.806246 -381.179851) (xy 105.763841 -381.222256) (xy 105.716265 -381.258762) (xy 105.664331 -381.288746)
			(xy 105.608927 -381.311695) (xy 105.551002 -381.327216) (xy 105.491546 -381.335044) (xy 105.431578 -381.335044)
			(xy 105.372122 -381.327216) (xy 105.314197 -381.311695) (xy 105.258793 -381.288746) (xy 105.206859 -381.258762)
			(xy 105.159283 -381.222256) (xy 105.116878 -381.179851) (xy 105.080372 -381.132275) (xy 105.050388 -381.080341)
			(xy 105.027439 -381.024937) (xy 105.011918 -380.967012) (xy 105.00409 -380.907556) (xy 105.0036 -380.877572)
			(xy 101.387499 -380.877572) (xy 101.415216 -380.885713) (xy 101.464787 -380.908356) (xy 101.510631 -380.937822)
			(xy 101.551815 -380.973512) (xy 101.587501 -381.0147) (xy 101.616963 -381.060547) (xy 101.6396 -381.110119)
			(xy 101.654953 -381.162409) (xy 101.662708 -381.216352) (xy 101.662708 -381.270848) (xy 101.654953 -381.324791)
			(xy 101.6396 -381.377081) (xy 101.616963 -381.426653) (xy 101.587501 -381.4725) (xy 101.551815 -381.513688)
			(xy 101.510631 -381.549378) (xy 101.464787 -381.578844) (xy 101.415216 -381.601487) (xy 101.362928 -381.616845)
			(xy 101.308986 -381.624605) (xy 101.281738 -381.625094) (xy 101.252446 -381.624576) (xy 101.194551 -381.61563)
			(xy 101.138701 -381.597945) (xy 101.086209 -381.571933) (xy 101.038308 -381.538207) (xy 100.996123 -381.497558)
			(xy 100.960643 -381.450941) (xy 100.946204 -381.42545) (xy 100.939178 -381.413456) (xy 100.919833 -381.393509)
			(xy 100.895826 -381.379518) (xy 100.868935 -381.372518) (xy 100.841153 -381.373028) (xy 100.814538 -381.38101)
			(xy 100.79106 -381.395872) (xy 100.77246 -381.416515) (xy 100.765864 -381.428752) (xy 100.753677 -381.452297)
			(xy 100.723831 -381.496112) (xy 100.688202 -381.53537) (xy 100.647479 -381.569314) (xy 100.602446 -381.597289)
			(xy 100.553972 -381.618756) (xy 100.502991 -381.6333) (xy 100.450487 -381.640642) (xy 100.42398 -381.641096)
			(xy 100.396729 -381.640633) (xy 100.342782 -381.632874) (xy 100.290488 -381.617516) (xy 100.240911 -381.594873)
			(xy 100.195062 -381.565406) (xy 100.153873 -381.529713) (xy 100.118182 -381.488522) (xy 100.088717 -381.442671)
			(xy 100.066077 -381.393094) (xy 100.050722 -381.340799) (xy 100.042966 -381.286851) (xy 88.110976 -381.286851)
			(xy 88.103456 -381.294386) (xy 88.101424 -381.296926) (xy 88.074491 -381.331289) (xy 88.015513 -381.395673)
			(xy 87.951132 -381.454655) (xy 87.916766 -381.481584) (xy 87.914226 -381.483616) (xy 87.73414 -381.663448)
			(xy 87.726794 -381.670255) (xy 87.708331 -381.677974) (xy 87.698326 -381.678434) (xy 87.443818 -381.678434)
			(xy 87.440516 -381.678942) (xy 87.408024 -381.682914) (xy 87.342693 -381.687107) (xy 87.30996 -381.687324)
			(xy 87.277227 -381.687111) (xy 87.211895 -381.682919) (xy 87.179404 -381.678942) (xy 87.176102 -381.678434)
			(xy 86.921594 -381.678434) (xy 86.911606 -381.677896) (xy 86.893173 -381.670185) (xy 86.88578 -381.663448)
			(xy 86.854284 -381.632206) (xy 86.849933 -381.628033) (xy 86.83966 -381.621732) (xy 86.833964 -381.61976)
			(xy 86.822534 -381.616204) (xy 86.810342 -381.618236) (xy 86.798794 -381.62006) (xy 86.775537 -381.622473)
			(xy 86.76386 -381.623062) (xy 86.760812 -381.623062) (xy 86.75751 -381.623316) (xy 86.745826 -381.623316)
			(xy 86.718671 -381.622689) (xy 86.664948 -381.614694) (xy 86.612901 -381.59916) (xy 86.563583 -381.576402)
			(xy 86.517992 -381.546879) (xy 86.477048 -381.511189) (xy 86.44158 -381.470053) (xy 86.412305 -381.424302)
			(xy 86.389814 -381.374862) (xy 86.374562 -381.322732) (xy 86.366858 -381.268966) (xy 86.36635 -381.241808)
			(xy 86.36635 -381.240284) (xy 86.366532 -381.224909) (xy 86.369078 -381.194265) (xy 86.37143 -381.17907)
			(xy 86.373462 -381.166878) (xy 86.369906 -381.155448) (xy 86.367859 -381.149787) (xy 86.361569 -381.139527)
			(xy 86.35746 -381.135128) (xy 86.336632 -381.1143) (xy 86.329818 -381.106956) (xy 86.322081 -381.088494)
			(xy 86.321646 -381.078486) (xy 86.321646 -380.823978) (xy 86.321138 -380.820676) (xy 86.317164 -380.788184)
			(xy 86.312967 -380.722853) (xy 86.312756 -380.69012) (xy 86.312756 -380.308104) (xy 86.312971 -380.275371)
			(xy 86.317166 -380.21004) (xy 86.321138 -380.177548) (xy 86.321646 -380.174246) (xy 86.321646 -380.04369)
			(xy 86.321275 -380.034901) (xy 86.31532 -380.018363) (xy 86.304116 -380.004819) (xy 86.296754 -380.000002)
			(xy 86.209632 -379.94844) (xy 86.182962 -379.947932) (xy 86.171024 -379.954536) (xy 86.156762 -379.962379)
			(xy 86.1278 -379.97724) (xy 86.113112 -379.984254) (xy 86.091014 -380.004066) (xy 86.08314 -380.014226)
			(xy 85.903308 -380.194312) (xy 85.901276 -380.196852) (xy 85.874342 -380.231213) (xy 85.81536 -380.295594)
			(xy 85.750977 -380.354572) (xy 85.716618 -380.38151) (xy 85.714078 -380.383542) (xy 85.533992 -380.563374)
			(xy 85.526648 -380.570186) (xy 85.508185 -380.57792) (xy 85.498178 -380.57836) (xy 85.24367 -380.57836)
			(xy 85.240368 -380.578868) (xy 85.197033 -380.584147) (xy 85.109812 -380.587991) (xy 85.022591 -380.584147)
			(xy 84.979256 -380.578868) (xy 84.975954 -380.57836) (xy 84.721446 -380.57836) (xy 84.711456 -380.57783)
			(xy 84.693015 -380.570123) (xy 84.685632 -380.563374) (xy 84.655152 -380.532894) (xy 84.651372 -380.529344)
			(xy 84.642667 -380.523711) (xy 84.63788 -380.521718) (xy 84.273136 -380.886208) (xy 84.239484 -380.919117)
			(xy 84.16697 -380.979139) (xy 84.089121 -381.032057) (xy 84.00663 -381.0774) (xy 83.920231 -381.114764)
			(xy 83.875626 -381.129794) (xy 83.869966 -381.131843) (xy 83.85971 -381.138136) (xy 83.855306 -381.14224)
			(xy 83.83397 -381.163576) (xy 83.703414 -381.294386) (xy 83.701382 -381.296926) (xy 83.674448 -381.331288)
			(xy 83.615468 -381.39567) (xy 83.551086 -381.45465) (xy 83.516724 -381.481584) (xy 83.514184 -381.483616)
			(xy 83.334098 -381.663448) (xy 83.326755 -381.670264) (xy 83.308292 -381.678004) (xy 83.298284 -381.678434)
			(xy 83.043776 -381.678434) (xy 83.040474 -381.678942) (xy 83.007982 -381.682916) (xy 82.942651 -381.687113)
			(xy 82.909918 -381.687324) (xy 82.877185 -381.68711) (xy 82.811854 -381.682915) (xy 82.779362 -381.678942)
			(xy 82.77606 -381.678434) (xy 82.521552 -381.678434) (xy 82.511559 -381.677907) (xy 82.493111 -381.67021)
			(xy 82.485738 -381.663448) (xy 82.455258 -381.632968) (xy 82.447845 -381.626294) (xy 82.429409 -381.618732)
			(xy 82.419444 -381.618236) (xy 82.4103 -381.618236) (xy 82.40649 -381.618744) (xy 82.392042 -381.620864)
			(xy 82.362926 -381.62315) (xy 82.348324 -381.623316) (xy 82.342482 -381.623316) (xy 82.314853 -381.622455)
			(xy 82.260267 -381.613748) (xy 82.207507 -381.597257) (xy 82.157679 -381.573328) (xy 82.111824 -381.54246)
			(xy 82.091022 -381.524256) (xy 82.090514 -381.523494) (xy 82.08772 -381.520954) (xy 82.086704 -381.519938)
			(xy 82.081878 -381.515366) (xy 82.070702 -381.50927) (xy 82.061558 -381.506984) (xy 82.03184 -381.498602)
			(xy 82.022188 -381.499618) (xy 82.011536 -381.500138) (xy 81.9913 -381.493487) (xy 81.975505 -381.479195)
			(xy 81.96687 -381.459723) (xy 81.966308 -381.449072) (xy 81.966308 -381.240538) (xy 81.966434 -381.225618)
			(xy 81.968726 -381.195866) (xy 81.97088 -381.181102) (xy 81.971388 -381.178308) (xy 81.971642 -381.170688)
			(xy 81.971192 -381.160662) (xy 81.963596 -381.142107) (xy 81.95691 -381.13462) (xy 81.93659 -381.1143)
			(xy 81.92978 -381.106954) (xy 81.92205 -381.088492) (xy 81.921604 -381.078486) (xy 81.921604 -380.823978)
			(xy 81.921096 -380.820676) (xy 81.91705 -380.788189) (xy 81.912727 -380.722857) (xy 81.91246 -380.69012)
			(xy 81.91246 -380.308104) (xy 81.91273 -380.275367) (xy 81.917051 -380.210035) (xy 81.921096 -380.177548)
			(xy 81.921604 -380.174246) (xy 81.921604 -380.04369) (xy 81.921234 -380.034899) (xy 81.915283 -380.018356)
			(xy 81.904086 -380.004802) (xy 81.896712 -380.000002) (xy 81.821274 -379.955552) (xy 81.815308 -379.952262)
			(xy 81.802176 -379.948648) (xy 81.795366 -379.94844) (xy 81.770982 -379.95479) (xy 81.756779 -379.962563)
			(xy 81.727945 -379.977299) (xy 81.713324 -379.984254) (xy 81.7066 -379.987683) (xy 81.695372 -379.997758)
			(xy 81.691226 -380.004066) (xy 81.683352 -380.014226) (xy 81.50352 -380.194312) (xy 81.501488 -380.196852)
			(xy 81.474554 -380.231213) (xy 81.415573 -380.295595) (xy 81.35119 -380.354574) (xy 81.31683 -380.38151)
			(xy 81.31429 -380.383542) (xy 81.134204 -380.563374) (xy 81.12686 -380.570188) (xy 81.108398 -380.577926)
			(xy 81.09839 -380.57836) (xy 80.843882 -380.57836) (xy 80.84058 -380.578868) (xy 80.797245 -380.584147)
			(xy 80.710024 -380.587991) (xy 80.622803 -380.584147) (xy 80.579468 -380.578868) (xy 80.576166 -380.57836)
			(xy 80.321658 -380.57836) (xy 80.311675 -380.577814) (xy 80.293258 -380.570085) (xy 80.285844 -380.563374)
			(xy 80.25511 -380.53264) (xy 80.251314 -380.529109) (xy 80.242617 -380.523471) (xy 80.237838 -380.521464)
			(xy 79.873094 -380.886208) (xy 79.839441 -380.919116) (xy 79.766926 -380.979135) (xy 79.689076 -381.03205)
			(xy 79.606583 -381.07739) (xy 79.520184 -381.11475) (xy 79.475584 -381.129794) (xy 79.469921 -381.131838)
			(xy 79.459656 -381.138122) (xy 79.455264 -381.14224) (xy 79.434436 -381.163068) (xy 79.303372 -381.294386)
			(xy 79.30134 -381.296926) (xy 79.274406 -381.331287) (xy 79.215424 -381.395668) (xy 79.15104 -381.454645)
			(xy 79.116682 -381.481584) (xy 79.114142 -381.483616) (xy 78.934056 -381.663448) (xy 78.926711 -381.670257)
			(xy 78.908248 -381.677982) (xy 78.898242 -381.678434) (xy 78.643734 -381.678434) (xy 78.640432 -381.678942)
			(xy 78.60794 -381.682915) (xy 78.542609 -381.687109) (xy 78.509876 -381.687324) (xy 78.477143 -381.687108)
			(xy 78.411812 -381.682911) (xy 78.37932 -381.678942) (xy 78.376018 -381.678434) (xy 78.12151 -381.678434)
			(xy 78.111521 -381.677899) (xy 78.093083 -381.670192) (xy 78.085696 -381.663448) (xy 78.0542 -381.632206)
			(xy 78.04985 -381.628032) (xy 78.039578 -381.621727) (xy 78.03388 -381.61976) (xy 78.02245 -381.616204)
			(xy 78.010258 -381.618236) (xy 77.99871 -381.620061) (xy 77.975453 -381.622475) (xy 77.963776 -381.623062)
			(xy 77.960728 -381.623062) (xy 77.957426 -381.623316) (xy 77.945742 -381.623316) (xy 77.918587 -381.62269)
			(xy 77.864861 -381.614697) (xy 77.812812 -381.599164) (xy 77.763493 -381.576407) (xy 77.7179 -381.546885)
			(xy 77.676954 -381.511195) (xy 77.641484 -381.470058) (xy 77.612208 -381.424307) (xy 77.589715 -381.374865)
			(xy 77.574463 -381.322734) (xy 77.566758 -381.268966) (xy 77.566266 -381.241808) (xy 77.566266 -381.240284)
			(xy 77.566448 -381.224909) (xy 77.568994 -381.194265) (xy 77.571346 -381.17907) (xy 77.573378 -381.166878)
			(xy 77.569822 -381.155448) (xy 77.567776 -381.149787) (xy 77.561488 -381.139525) (xy 77.557376 -381.135128)
			(xy 77.536548 -381.1143) (xy 77.529732 -381.106957) (xy 77.521992 -381.088494) (xy 77.521562 -381.078486)
			(xy 77.521562 -380.823978) (xy 77.521054 -380.820676) (xy 77.51708 -380.788184) (xy 77.512883 -380.722853)
			(xy 77.512672 -380.69012) (xy 77.512672 -380.308104) (xy 77.512887 -380.275371) (xy 77.517082 -380.21004)
			(xy 77.521054 -380.177548) (xy 77.521562 -380.174246) (xy 77.521562 -380.04369) (xy 77.521191 -380.034901)
			(xy 77.515237 -380.018361) (xy 77.504035 -380.004814) (xy 77.49667 -380.000002) (xy 77.421232 -379.955552)
			(xy 77.415265 -379.952267) (xy 77.402133 -379.948664) (xy 77.395324 -379.94844) (xy 77.37094 -379.95479)
			(xy 77.356737 -379.962562) (xy 77.327902 -379.977298) (xy 77.313282 -379.984254) (xy 77.306553 -379.987677)
			(xy 77.295314 -379.997746) (xy 77.291184 -380.004066) (xy 77.28331 -380.014226) (xy 77.103478 -380.194312)
			(xy 77.101446 -380.196852) (xy 77.074511 -380.231213) (xy 77.015529 -380.295592) (xy 76.951144 -380.354569)
			(xy 76.916788 -380.38151) (xy 76.914248 -380.383542) (xy 76.734162 -380.563374) (xy 76.726816 -380.570182)
			(xy 76.708353 -380.577904) (xy 76.698348 -380.57836) (xy 76.44384 -380.57836) (xy 76.440538 -380.578868)
			(xy 76.397203 -380.584147) (xy 76.309982 -380.587991) (xy 76.222761 -380.584147) (xy 76.179426 -380.578868)
			(xy 76.176124 -380.57836) (xy 75.921616 -380.57836) (xy 75.911628 -380.577824) (xy 75.893196 -380.57011)
			(xy 75.885802 -380.563374) (xy 75.855068 -380.53264) (xy 75.851271 -380.529112) (xy 75.842571 -380.52348)
			(xy 75.837796 -380.521464) (xy 75.473052 -380.886208) (xy 75.4394 -380.919118) (xy 75.366887 -380.979141)
			(xy 75.289038 -381.03206) (xy 75.206547 -381.077404) (xy 75.120149 -381.114769) (xy 75.075542 -381.129794)
			(xy 75.069882 -381.131842) (xy 75.059622 -381.138132) (xy 75.055222 -381.14224) (xy 75.033378 -381.164084)
			(xy 74.90333 -381.294386) (xy 74.901298 -381.296926) (xy 74.874365 -381.331288) (xy 74.815385 -381.395671)
			(xy 74.751003 -381.454652) (xy 74.71664 -381.481584) (xy 74.7141 -381.483616) (xy 74.534014 -381.663448)
			(xy 74.526672 -381.670266) (xy 74.508209 -381.678012) (xy 74.4982 -381.678434) (xy 74.243692 -381.678434)
			(xy 74.24039 -381.678942) (xy 74.207898 -381.682914) (xy 74.142567 -381.687105) (xy 74.109834 -381.687324)
			(xy 74.077101 -381.68711) (xy 74.01177 -381.682917) (xy 73.979278 -381.678942) (xy 73.975976 -381.678434)
			(xy 73.721468 -381.678434) (xy 73.711482 -381.677892) (xy 73.693055 -381.670174) (xy 73.685654 -381.663448)
			(xy 73.655174 -381.632968) (xy 73.647762 -381.626291) (xy 73.629326 -381.618724) (xy 73.61936 -381.618236)
			(xy 73.610216 -381.618236) (xy 73.606406 -381.618744) (xy 73.591958 -381.620865) (xy 73.562842 -381.623151)
			(xy 73.54824 -381.623316) (xy 73.542398 -381.623316) (xy 73.514768 -381.622456) (xy 73.460181 -381.613751)
			(xy 73.40742 -381.597262) (xy 73.357591 -381.573334) (xy 73.311734 -381.542468) (xy 73.290938 -381.524256)
			(xy 73.29043 -381.523494) (xy 73.287636 -381.520954) (xy 73.28662 -381.519938) (xy 73.281794 -381.515366)
			(xy 73.270618 -381.50927) (xy 73.261474 -381.506984) (xy 73.231756 -381.498602) (xy 73.222104 -381.499618)
			(xy 73.21145 -381.500141) (xy 73.191208 -381.493494) (xy 73.175407 -381.479201) (xy 73.166769 -381.459725)
			(xy 73.166224 -381.449072) (xy 73.166224 -381.240538) (xy 73.16635 -381.225618) (xy 73.168642 -381.195866)
			(xy 73.170796 -381.181102) (xy 73.171304 -381.178308) (xy 73.171558 -381.170688) (xy 73.171108 -381.160661)
			(xy 73.163514 -381.142106) (xy 73.156826 -381.13462) (xy 73.136506 -381.1143) (xy 73.129695 -381.106955)
			(xy 73.121961 -381.088493) (xy 73.12152 -381.078486) (xy 73.12152 -380.823978) (xy 73.121012 -380.820676)
			(xy 73.116966 -380.788189) (xy 73.112642 -380.722857) (xy 73.112376 -380.69012) (xy 73.112376 -380.308104)
			(xy 73.112646 -380.275367) (xy 73.116967 -380.210035) (xy 73.121012 -380.177548) (xy 73.12152 -380.174246)
			(xy 73.12152 -380.04369) (xy 73.121148 -380.034902) (xy 73.115191 -380.018367) (xy 73.103984 -380.004827)
			(xy 73.096628 -380.000002) (xy 73.02119 -379.955552) (xy 73.015224 -379.95226) (xy 73.002092 -379.948642)
			(xy 72.995282 -379.94844) (xy 72.970898 -379.95479) (xy 72.956694 -379.962562) (xy 72.927859 -379.977296)
			(xy 72.91324 -379.984254) (xy 72.906514 -379.987681) (xy 72.895284 -379.997755) (xy 72.891142 -380.004066)
			(xy 72.883268 -380.014226) (xy 72.703436 -380.194312) (xy 72.701404 -380.196852) (xy 72.67436 -380.231318)
			(xy 72.615137 -380.295887) (xy 72.550489 -380.355023) (xy 72.515984 -380.382018) (xy 72.513444 -380.38405)
			(xy 72.33412 -380.563374) (xy 72.326772 -380.570175) (xy 72.308309 -380.577882) (xy 72.298306 -380.57836)
			(xy 72.043798 -380.57836) (xy 72.040496 -380.578868) (xy 72.01823 -380.581716) (xy 71.973509 -380.585654)
			(xy 71.951088 -380.586742) (xy 71.917052 -380.601728) (xy 71.89597 -380.623318) (xy 71.88938 -380.630696)
			(xy 71.881913 -380.648995) (xy 71.881492 -380.658878) (xy 71.881492 -381.526796) (xy 71.881979 -381.536805)
			(xy 71.889638 -381.555299) (xy 71.903791 -381.569455) (xy 71.922283 -381.577118) (xy 71.932292 -381.577596)
			(xy 72.26808 -381.577596) (xy 72.278204 -381.578016) (xy 72.296912 -381.58576) (xy 72.311231 -381.600074)
			(xy 72.31898 -381.61878) (xy 72.319388 -381.628904) (xy 72.319388 -381.910082) (xy 72.320912 -381.92202)
			(xy 72.324976 -381.93726) (xy 72.328786 -381.94361) (xy 72.344711 -381.971729) (xy 72.369802 -382.031279)
			(xy 72.386781 -382.09363) (xy 72.395346 -382.157681) (xy 72.395347 -382.222302) (xy 72.395292 -382.22271)
			(xy 75.824927 -382.22271) (xy 75.824928 -382.157273) (xy 75.833713 -382.092427) (xy 75.851124 -382.029348)
			(xy 75.876844 -381.969177) (xy 75.893168 -381.940816) (xy 75.896474 -381.934787) (xy 75.900086 -381.921527)
			(xy 75.90028 -381.914654) (xy 75.90028 -381.628904) (xy 75.900725 -381.618753) (xy 75.908515 -381.600004)
			(xy 75.922904 -381.585681) (xy 75.941689 -381.577978) (xy 75.951842 -381.577596) (xy 76.668122 -381.577596)
			(xy 76.678245 -381.578107) (xy 76.696958 -381.585834) (xy 76.711312 -381.600112) (xy 76.719138 -381.618784)
			(xy 76.719684 -381.628904) (xy 76.719684 -381.914654) (xy 76.719895 -381.921526) (xy 76.72349 -381.934789)
			(xy 76.726796 -381.940816) (xy 76.743109 -381.969182) (xy 76.768825 -382.029353) (xy 76.786233 -382.09243)
			(xy 76.795017 -382.157274) (xy 76.795018 -382.222709) (xy 76.786236 -382.287553) (xy 76.768831 -382.350631)
			(xy 76.743116 -382.410802) (xy 76.726796 -382.439164) (xy 76.723494 -382.445195) (xy 76.71988 -382.458454)
			(xy 76.719684 -382.465326) (xy 76.719684 -383.21488) (xy 76.719885 -383.221753) (xy 76.723487 -383.235015)
			(xy 76.726796 -383.241042) (xy 76.743131 -383.269396) (xy 76.768845 -383.329569) (xy 76.786251 -383.39265)
			(xy 76.795032 -383.457495) (xy 76.79503 -383.522932) (xy 76.786245 -383.587777) (xy 76.768836 -383.650857)
			(xy 76.743118 -383.711028) (xy 76.726796 -383.73939) (xy 76.723485 -383.745416) (xy 76.719877 -383.758679)
			(xy 76.719684 -383.765552) (xy 76.719684 -384.051556) (xy 76.719242 -384.061709) (xy 76.711458 -384.080464)
			(xy 76.697067 -384.094789) (xy 76.678277 -384.102488) (xy 76.668122 -384.102864) (xy 75.951842 -384.102864)
			(xy 75.941718 -384.102339) (xy 75.922999 -384.094626) (xy 75.908642 -384.080351) (xy 75.90082 -384.061677)
			(xy 75.90028 -384.051556) (xy 75.90028 -383.765552) (xy 75.900071 -383.75868) (xy 75.896474 -383.745417)
			(xy 75.893168 -383.73939) (xy 75.876858 -383.711022) (xy 75.851138 -383.650852) (xy 75.833727 -383.587775)
			(xy 75.824942 -383.522932) (xy 75.82494 -383.457496) (xy 75.833722 -383.392652) (xy 75.851129 -383.329574)
			(xy 75.876846 -383.269403) (xy 75.893168 -383.241042) (xy 75.896465 -383.235009) (xy 75.900082 -383.221752)
			(xy 75.90028 -383.21488) (xy 75.90028 -382.465326) (xy 75.90008 -382.458453) (xy 75.896478 -382.44519)
			(xy 75.893168 -382.439164) (xy 75.876836 -382.410808) (xy 75.851118 -382.350636) (xy 75.83371 -382.287556)
			(xy 75.824927 -382.22271) (xy 72.395292 -382.22271) (xy 72.386784 -382.286353) (xy 72.369808 -382.348704)
			(xy 72.344718 -382.408256) (xy 72.328786 -382.43637) (xy 72.324976 -382.44272) (xy 72.320912 -382.45796)
			(xy 72.319388 -382.469898) (xy 72.319388 -383.210308) (xy 72.320912 -383.222246) (xy 72.324976 -383.237486)
			(xy 72.328786 -383.243836) (xy 72.344709 -383.271955) (xy 72.366125 -383.322789) (xy 73.624771 -383.322789)
			(xy 73.624775 -383.25735) (xy 73.633562 -383.192503) (xy 73.650975 -383.129423) (xy 73.676696 -383.069252)
			(xy 73.69302 -383.04089) (xy 73.69634 -383.034868) (xy 73.699942 -383.021602) (xy 73.700132 -383.014728)
			(xy 73.700132 -382.728724) (xy 73.700542 -382.718567) (xy 73.708335 -382.699809) (xy 73.722736 -382.685484)
			(xy 73.741535 -382.677789) (xy 73.751694 -382.677416) (xy 74.467974 -382.677416) (xy 74.478096 -382.677947)
			(xy 74.496812 -382.685662) (xy 74.511169 -382.699934) (xy 74.518993 -382.718605) (xy 74.519536 -382.728724)
			(xy 74.519536 -383.014728) (xy 74.519713 -383.021602) (xy 74.523331 -383.034865) (xy 74.526648 -383.04089)
			(xy 74.54294 -383.069268) (xy 74.568661 -383.129435) (xy 74.586073 -383.19251) (xy 74.594861 -383.257352)
			(xy 74.594865 -383.322786) (xy 74.586086 -383.387629) (xy 74.568682 -383.450707) (xy 74.542968 -383.510877)
			(xy 74.526648 -383.539238) (xy 74.523324 -383.545258) (xy 74.519724 -383.558525) (xy 74.519536 -383.5654)
			(xy 74.519536 -384.3147) (xy 74.519724 -384.321574) (xy 74.523334 -384.334837) (xy 74.526648 -384.340862)
			(xy 74.543001 -384.369206) (xy 74.568717 -384.429381) (xy 74.586122 -384.492464) (xy 74.594902 -384.557311)
			(xy 74.5949 -384.590036) (xy 78.024228 -384.590036) (xy 78.024797 -384.557307) (xy 78.033654 -384.492449)
			(xy 78.051143 -384.429369) (xy 78.076948 -384.36921) (xy 78.093316 -384.340862) (xy 78.096645 -384.334845)
			(xy 78.100241 -384.321575) (xy 78.100428 -384.3147) (xy 78.100428 -383.5654) (xy 78.100233 -383.558527)
			(xy 78.096626 -383.545264) (xy 78.093316 -383.539238) (xy 78.076967 -383.51088) (xy 78.051161 -383.450724)
			(xy 78.033666 -383.387647) (xy 78.024801 -383.322792) (xy 78.024228 -383.290064) (xy 78.02481 -383.257335)
			(xy 78.033662 -383.192478) (xy 78.051148 -383.129398) (xy 78.07695 -383.069239) (xy 78.093316 -383.04089)
			(xy 78.096635 -383.034868) (xy 78.100238 -383.021602) (xy 78.100428 -383.014728) (xy 78.100428 -382.728724)
			(xy 78.100836 -382.7186) (xy 78.108582 -382.699891) (xy 78.122901 -382.685575) (xy 78.141611 -382.677834)
			(xy 78.151736 -382.677416) (xy 78.868016 -382.677416) (xy 78.878142 -382.677803) (xy 78.896849 -382.685559)
			(xy 78.911163 -382.699885) (xy 78.918905 -382.718598) (xy 78.919324 -382.728724) (xy 78.919324 -383.014728)
			(xy 78.919502 -383.021602) (xy 78.923119 -383.034865) (xy 78.926436 -383.04089) (xy 78.942791 -383.069245)
			(xy 78.968597 -383.129402) (xy 78.98609 -383.19248) (xy 78.994953 -383.257335) (xy 78.995524 -383.290064)
			(xy 78.994961 -383.322794) (xy 78.986104 -383.387652) (xy 78.968613 -383.450732) (xy 78.951674 -383.490216)
			(xy 80.224376 -383.490216) (xy 80.22493 -383.457486) (xy 80.233789 -383.392627) (xy 80.251283 -383.329547)
			(xy 80.277094 -383.26939) (xy 80.293464 -383.241042) (xy 80.296761 -383.235009) (xy 80.300378 -383.221752)
			(xy 80.300576 -383.21488) (xy 80.300576 -382.465326) (xy 80.300377 -382.458453) (xy 80.296774 -382.44519)
			(xy 80.293464 -382.439164) (xy 80.27709 -382.410819) (xy 80.251289 -382.350658) (xy 80.233801 -382.287578)
			(xy 80.224944 -382.222719) (xy 80.224376 -382.18999) (xy 80.224963 -382.157261) (xy 80.233813 -382.092404)
			(xy 80.251297 -382.029324) (xy 80.277099 -381.969165) (xy 80.293464 -381.940816) (xy 80.29677 -381.934787)
			(xy 80.300382 -381.921527) (xy 80.300576 -381.914654) (xy 80.300576 -381.628904) (xy 80.301088 -381.618798)
			(xy 80.30882 -381.600125) (xy 80.323108 -381.585831) (xy 80.341779 -381.578092) (xy 80.351884 -381.577596)
			(xy 81.068164 -381.577596) (xy 81.078284 -381.578046) (xy 81.096986 -381.585781) (xy 81.111301 -381.600087)
			(xy 81.119048 -381.618785) (xy 81.119472 -381.628904) (xy 81.119472 -381.914654) (xy 81.119685 -381.921526)
			(xy 81.123279 -381.934788) (xy 81.126584 -381.940816) (xy 81.142954 -381.969163) (xy 81.168755 -382.029323)
			(xy 81.186244 -382.092403) (xy 81.195103 -382.157261) (xy 81.195672 -382.18999) (xy 81.195114 -382.22272)
			(xy 81.186255 -382.287578) (xy 81.168762 -382.350658) (xy 81.142953 -382.410816) (xy 81.126584 -382.439164)
			(xy 81.123281 -382.445194) (xy 81.119668 -382.458454) (xy 81.119472 -382.465326) (xy 81.119472 -383.21488)
			(xy 81.119675 -383.221752) (xy 81.123276 -383.235015) (xy 81.126584 -383.241042) (xy 81.142965 -383.269383)
			(xy 81.165866 -383.322789) (xy 82.424857 -383.322789) (xy 82.424861 -383.25735) (xy 82.433648 -383.192504)
			(xy 82.45106 -383.129424) (xy 82.47678 -383.069252) (xy 82.493104 -383.04089) (xy 82.496423 -383.034867)
			(xy 82.500026 -383.021602) (xy 82.500216 -383.014728) (xy 82.500216 -382.728724) (xy 82.500641 -382.718569)
			(xy 82.508432 -382.699814) (xy 82.522828 -382.68549) (xy 82.541621 -382.677792) (xy 82.551778 -382.677416)
			(xy 83.268058 -382.677416) (xy 83.278179 -382.67796) (xy 83.296895 -382.68567) (xy 83.311252 -382.699938)
			(xy 83.319076 -382.718606) (xy 83.31962 -382.728724) (xy 83.31962 -383.014728) (xy 83.319799 -383.021602)
			(xy 83.323416 -383.034865) (xy 83.326732 -383.04089) (xy 83.343025 -383.069268) (xy 83.368747 -383.129435)
			(xy 83.386159 -383.19251) (xy 83.394947 -383.257352) (xy 83.394951 -383.322786) (xy 83.386172 -383.387629)
			(xy 83.368767 -383.450707) (xy 83.351883 -383.490216) (xy 84.624164 -383.490216) (xy 84.624719 -383.457486)
			(xy 84.633579 -383.392628) (xy 84.651072 -383.329548) (xy 84.676882 -383.26939) (xy 84.693252 -383.241042)
			(xy 84.696548 -383.235008) (xy 84.700166 -383.221752) (xy 84.700364 -383.21488) (xy 84.700364 -382.465326)
			(xy 84.700167 -382.458453) (xy 84.696563 -382.44519) (xy 84.693252 -382.439164) (xy 84.676877 -382.41082)
			(xy 84.651076 -382.350659) (xy 84.633589 -382.287578) (xy 84.624732 -382.22272) (xy 84.624164 -382.18999)
			(xy 84.624753 -382.157261) (xy 84.633603 -382.092404) (xy 84.651086 -382.029324) (xy 84.676887 -381.969165)
			(xy 84.693252 -381.940816) (xy 84.696557 -381.934787) (xy 84.700169 -381.921527) (xy 84.700364 -381.914654)
			(xy 84.700364 -381.628904) (xy 84.700888 -381.6188) (xy 84.708617 -381.600129) (xy 84.722902 -381.585835)
			(xy 84.741568 -381.578094) (xy 84.751672 -381.577596) (xy 85.467952 -381.577596) (xy 85.478071 -381.578055)
			(xy 85.496773 -381.585787) (xy 85.511088 -381.60009) (xy 85.518836 -381.618786) (xy 85.51926 -381.628904)
			(xy 85.51926 -381.914654) (xy 85.519474 -381.921526) (xy 85.523068 -381.934788) (xy 85.526372 -381.940816)
			(xy 85.542741 -381.969163) (xy 85.568543 -382.029323) (xy 85.586032 -382.092403) (xy 85.594891 -382.157261)
			(xy 85.59546 -382.18999) (xy 85.594904 -382.22271) (xy 89.024803 -382.22271) (xy 89.024804 -382.157273)
			(xy 89.033589 -382.092428) (xy 89.050998 -382.029349) (xy 89.076717 -381.969177) (xy 89.09304 -381.940816)
			(xy 89.096344 -381.934786) (xy 89.099957 -381.921527) (xy 89.100152 -381.914654) (xy 89.100152 -381.628904)
			(xy 89.100624 -381.618756) (xy 89.108409 -381.600013) (xy 89.12279 -381.585691) (xy 89.141564 -381.577983)
			(xy 89.151714 -381.577596) (xy 89.867994 -381.577596) (xy 89.878115 -381.57813) (xy 89.896828 -381.585848)
			(xy 89.911183 -381.600119) (xy 89.91901 -381.618786) (xy 89.919556 -381.628904) (xy 89.919556 -381.914654)
			(xy 89.919758 -381.921527) (xy 89.923359 -381.93479) (xy 89.926668 -381.940816) (xy 89.942982 -381.969182)
			(xy 89.9687 -382.029352) (xy 89.986108 -382.09243) (xy 89.994893 -382.157273) (xy 89.994894 -382.222709)
			(xy 89.986112 -382.287553) (xy 89.968705 -382.350632) (xy 89.942989 -382.410803) (xy 89.926668 -382.439164)
			(xy 89.923364 -382.445194) (xy 89.919752 -382.458454) (xy 89.919556 -382.465326) (xy 89.919556 -383.21488)
			(xy 89.919749 -383.221753) (xy 89.923356 -383.235016) (xy 89.926668 -383.241042) (xy 89.943004 -383.269396)
			(xy 89.965822 -383.322788) (xy 91.224943 -383.322788) (xy 91.224947 -383.25735) (xy 91.233734 -383.192504)
			(xy 91.251145 -383.129424) (xy 91.276865 -383.069252) (xy 91.293188 -383.04089) (xy 91.296505 -383.034867)
			(xy 91.30011 -383.021602) (xy 91.3003 -383.014728) (xy 91.3003 -382.728724) (xy 91.300741 -382.718571)
			(xy 91.308529 -382.699819) (xy 91.32292 -382.685495) (xy 91.341708 -382.677795) (xy 91.351862 -382.677416)
			(xy 92.068142 -382.677416) (xy 92.078268 -382.677891) (xy 92.096986 -382.685629) (xy 92.11134 -382.699918)
			(xy 92.119162 -382.7186) (xy 92.119704 -382.728724) (xy 92.119704 -383.014728) (xy 92.119885 -383.021602)
			(xy 92.1235 -383.034865) (xy 92.126816 -383.04089) (xy 92.143109 -383.069268) (xy 92.168832 -383.129434)
			(xy 92.186245 -383.19251) (xy 92.195033 -383.257352) (xy 92.195037 -383.322787) (xy 92.186257 -383.38763)
			(xy 92.168852 -383.450707) (xy 92.143137 -383.510877) (xy 92.126816 -383.539238) (xy 92.123489 -383.545257)
			(xy 92.119891 -383.558525) (xy 92.119704 -383.5654) (xy 92.119704 -384.3147) (xy 92.119895 -384.321573)
			(xy 92.123504 -384.334836) (xy 92.126816 -384.340862) (xy 92.14317 -384.369206) (xy 92.168887 -384.429381)
			(xy 92.186294 -384.492463) (xy 92.195074 -384.557311) (xy 92.19507 -384.622751) (xy 92.186281 -384.687598)
			(xy 92.168867 -384.750678) (xy 92.143142 -384.810849) (xy 92.126816 -384.83921) (xy 92.123499 -384.845233)
			(xy 92.119894 -384.858498) (xy 92.119704 -384.865372) (xy 92.119704 -385.151376) (xy 92.119259 -385.161528)
			(xy 92.111472 -385.180279) (xy 92.097082 -385.194603) (xy 92.078296 -385.202305) (xy 92.068142 -385.202684)
			(xy 91.351862 -385.202684) (xy 91.341736 -385.202205) (xy 91.323018 -385.194469) (xy 91.308664 -385.180181)
			(xy 91.300842 -385.1615) (xy 91.3003 -385.151376) (xy 91.3003 -384.865372) (xy 91.300119 -384.858498)
			(xy 91.296503 -384.845235) (xy 91.293188 -384.83921) (xy 91.276898 -384.810831) (xy 91.25118 -384.750664)
			(xy 91.23377 -384.687589) (xy 91.224984 -384.622748) (xy 91.22498 -384.557314) (xy 91.233758 -384.492472)
			(xy 91.25116 -384.429395) (xy 91.27687 -384.369224) (xy 91.293188 -384.340862) (xy 91.296515 -384.334844)
			(xy 91.300113 -384.321575) (xy 91.3003 -384.3147) (xy 91.3003 -383.5654) (xy 91.300108 -383.558527)
			(xy 91.2965 -383.545264) (xy 91.293188 -383.539238) (xy 91.276837 -383.510893) (xy 91.251125 -383.450717)
			(xy 91.233722 -383.387635) (xy 91.224943 -383.322788) (xy 89.965822 -383.322788) (xy 89.96872 -383.329569)
			(xy 89.986126 -383.392649) (xy 89.994908 -383.457495) (xy 89.994906 -383.522933) (xy 89.98612 -383.587778)
			(xy 89.96871 -383.650857) (xy 89.942991 -383.711029) (xy 89.926668 -383.73939) (xy 89.923355 -383.745415)
			(xy 89.919749 -383.758679) (xy 89.919556 -383.765552) (xy 89.919556 -384.051556) (xy 89.919043 -384.0617)
			(xy 89.911273 -384.080441) (xy 89.896905 -384.094764) (xy 89.87814 -384.102475) (xy 89.867994 -384.102864)
			(xy 89.151714 -384.102864) (xy 89.141589 -384.102362) (xy 89.122869 -384.09464) (xy 89.108512 -384.080358)
			(xy 89.100692 -384.061679) (xy 89.100152 -384.051556) (xy 89.100152 -383.765552) (xy 89.099946 -383.75868)
			(xy 89.096348 -383.745417) (xy 89.09304 -383.73939) (xy 89.076731 -383.711021) (xy 89.051012 -383.650852)
			(xy 89.033603 -383.587775) (xy 89.024817 -383.522932) (xy 89.024816 -383.457496) (xy 89.033597 -383.392652)
			(xy 89.051003 -383.329574) (xy 89.076719 -383.269403) (xy 89.09304 -383.241042) (xy 89.096335 -383.235008)
			(xy 89.099954 -383.221752) (xy 89.100152 -383.21488) (xy 89.100152 -382.465326) (xy 89.099956 -382.458453)
			(xy 89.096351 -382.44519) (xy 89.09304 -382.439164) (xy 89.076709 -382.410807) (xy 89.050992 -382.350635)
			(xy 89.033585 -382.287556) (xy 89.024803 -382.22271) (xy 85.594904 -382.22271) (xy 85.594904 -382.22272)
			(xy 85.586044 -382.287578) (xy 85.568551 -382.350658) (xy 85.542741 -382.410816) (xy 85.526372 -382.439164)
			(xy 85.523068 -382.445194) (xy 85.519456 -382.458454) (xy 85.51926 -382.465326) (xy 85.51926 -383.21488)
			(xy 85.519465 -383.221752) (xy 85.523065 -383.235015) (xy 85.526372 -383.241042) (xy 85.542752 -383.269384)
			(xy 85.568551 -383.329546) (xy 85.586037 -383.392628) (xy 85.594892 -383.457486) (xy 85.59546 -383.490216)
			(xy 85.594871 -383.522945) (xy 85.586021 -383.587802) (xy 85.568537 -383.650882) (xy 85.542737 -383.711041)
			(xy 85.526372 -383.73939) (xy 85.523059 -383.745415) (xy 85.519453 -383.758679) (xy 85.51926 -383.765552)
			(xy 85.51926 -384.051556) (xy 85.518847 -384.061681) (xy 85.511106 -384.080391) (xy 85.496787 -384.094708)
			(xy 85.478077 -384.102448) (xy 85.467952 -384.102864) (xy 84.751672 -384.102864) (xy 84.741543 -384.102506)
			(xy 84.722832 -384.094742) (xy 84.708517 -384.080407) (xy 84.70078 -384.061685) (xy 84.700364 -384.051556)
			(xy 84.700364 -383.765552) (xy 84.700157 -383.75868) (xy 84.696559 -383.745417) (xy 84.693252 -383.73939)
			(xy 84.676887 -383.71104) (xy 84.651084 -383.650881) (xy 84.633594 -383.587802) (xy 84.624734 -383.522945)
			(xy 84.624164 -383.490216) (xy 83.351883 -383.490216) (xy 83.343053 -383.510877) (xy 83.326732 -383.539238)
			(xy 83.323406 -383.545257) (xy 83.319807 -383.558525) (xy 83.31962 -383.5654) (xy 83.31962 -384.3147)
			(xy 83.31981 -384.321573) (xy 83.323419 -384.334836) (xy 83.326732 -384.340862) (xy 83.343086 -384.369206)
			(xy 83.368802 -384.429381) (xy 83.386208 -384.492463) (xy 83.394988 -384.557311) (xy 83.394986 -384.590036)
			(xy 86.824312 -384.590036) (xy 86.82487 -384.557306) (xy 86.833728 -384.492448) (xy 86.85122 -384.429367)
			(xy 86.87703 -384.36921) (xy 86.8934 -384.340862) (xy 86.896728 -384.334844) (xy 86.900325 -384.321575)
			(xy 86.900512 -384.3147) (xy 86.900512 -383.5654) (xy 86.900319 -383.558527) (xy 86.896711 -383.545264)
			(xy 86.8934 -383.539238) (xy 86.87705 -383.51088) (xy 86.851244 -383.450724) (xy 86.83375 -383.387647)
			(xy 86.824885 -383.322792) (xy 86.824312 -383.290064) (xy 86.824882 -383.257335) (xy 86.833737 -383.192477)
			(xy 86.851226 -383.129396) (xy 86.877032 -383.069238) (xy 86.8934 -383.04089) (xy 86.896718 -383.034867)
			(xy 86.900322 -383.021602) (xy 86.900512 -383.014728) (xy 86.900512 -382.728724) (xy 86.900936 -382.718602)
			(xy 86.908678 -382.699896) (xy 86.922993 -382.685581) (xy 86.941698 -382.677837) (xy 86.95182 -382.677416)
			(xy 87.6681 -382.677416) (xy 87.678224 -382.677816) (xy 87.696931 -382.685568) (xy 87.711246 -382.699889)
			(xy 87.718988 -382.718599) (xy 87.719408 -382.728724) (xy 87.719408 -383.014728) (xy 87.719588 -383.021602)
			(xy 87.723204 -383.034865) (xy 87.72652 -383.04089) (xy 87.742884 -383.06924) (xy 87.768685 -383.1294)
			(xy 87.786176 -383.192479) (xy 87.795037 -383.257335) (xy 87.795608 -383.290064) (xy 87.795047 -383.322794)
			(xy 87.78619 -383.387652) (xy 87.768698 -383.450732) (xy 87.742889 -383.51089) (xy 87.72652 -383.539238)
			(xy 87.723193 -383.545257) (xy 87.719595 -383.558525) (xy 87.719408 -383.5654) (xy 87.719408 -384.3147)
			(xy 87.719599 -384.321573) (xy 87.723208 -384.334836) (xy 87.72652 -384.340862) (xy 87.742872 -384.369218)
			(xy 87.768677 -384.429376) (xy 87.78617 -384.492453) (xy 87.795035 -384.557308) (xy 87.795608 -384.590036)
			(xy 87.795035 -384.622765) (xy 87.786181 -384.687623) (xy 87.768693 -384.750703) (xy 87.742887 -384.810862)
			(xy 87.72652 -384.83921) (xy 87.723203 -384.845234) (xy 87.719598 -384.858498) (xy 87.719408 -384.865372)
			(xy 87.719408 -385.151376) (xy 87.718965 -385.161496) (xy 87.711226 -385.180198) (xy 87.696918 -385.194512)
			(xy 87.67822 -385.20226) (xy 87.6681 -385.202684) (xy 86.95182 -385.202684) (xy 86.941697 -385.202267)
			(xy 86.922991 -385.194523) (xy 86.908675 -385.180206) (xy 86.900932 -385.161499) (xy 86.900512 -385.151376)
			(xy 86.900512 -384.865372) (xy 86.900329 -384.858498) (xy 86.896715 -384.845235) (xy 86.8934 -384.83921)
			(xy 86.877038 -384.810859) (xy 86.851236 -384.7507) (xy 86.833745 -384.687621) (xy 86.824883 -384.622765)
			(xy 86.824312 -384.590036) (xy 83.394986 -384.590036) (xy 83.394984 -384.622751) (xy 83.386195 -384.687597)
			(xy 83.368781 -384.750677) (xy 83.343058 -384.810849) (xy 83.326732 -384.83921) (xy 83.323416 -384.845234)
			(xy 83.319811 -384.858498) (xy 83.31962 -384.865372) (xy 83.31962 -385.151376) (xy 83.319159 -385.161526)
			(xy 83.311375 -385.180274) (xy 83.296991 -385.194598) (xy 83.27821 -385.202302) (xy 83.268058 -385.202684)
			(xy 82.551778 -385.202684) (xy 82.541653 -385.202192) (xy 82.522936 -385.194462) (xy 82.508581 -385.180178)
			(xy 82.500758 -385.161499) (xy 82.500216 -385.151376) (xy 82.500216 -384.865372) (xy 82.500033 -384.858498)
			(xy 82.496418 -384.845235) (xy 82.493104 -384.83921) (xy 82.476813 -384.810832) (xy 82.451095 -384.750664)
			(xy 82.433685 -384.687589) (xy 82.424898 -384.622748) (xy 82.424894 -384.557314) (xy 82.433672 -384.492472)
			(xy 82.451074 -384.429394) (xy 82.476785 -384.369224) (xy 82.493104 -384.340862) (xy 82.496433 -384.334844)
			(xy 82.500029 -384.321575) (xy 82.500216 -384.3147) (xy 82.500216 -383.5654) (xy 82.500022 -383.558527)
			(xy 82.496415 -383.545264) (xy 82.493104 -383.539238) (xy 82.476752 -383.510893) (xy 82.451039 -383.450718)
			(xy 82.433636 -383.387636) (xy 82.424857 -383.322789) (xy 81.165866 -383.322789) (xy 81.168763 -383.329545)
			(xy 81.186249 -383.392627) (xy 81.195104 -383.457486) (xy 81.195672 -383.490216) (xy 81.195081 -383.522945)
			(xy 81.186231 -383.587802) (xy 81.168748 -383.650882) (xy 81.142949 -383.711041) (xy 81.126584 -383.73939)
			(xy 81.123272 -383.745416) (xy 81.119665 -383.758679) (xy 81.119472 -383.765552) (xy 81.119472 -384.051556)
			(xy 81.119047 -384.061679) (xy 81.111308 -384.080387) (xy 81.096994 -384.094704) (xy 81.078287 -384.102446)
			(xy 81.068164 -384.102864) (xy 80.351884 -384.102864) (xy 80.341756 -384.102496) (xy 80.323045 -384.094736)
			(xy 80.30873 -384.080405) (xy 80.300992 -384.061685) (xy 80.300576 -384.051556) (xy 80.300576 -383.765552)
			(xy 80.300367 -383.75868) (xy 80.296771 -383.745417) (xy 80.293464 -383.73939) (xy 80.277101 -383.711039)
			(xy 80.251297 -383.650881) (xy 80.233806 -383.587802) (xy 80.224946 -383.522945) (xy 80.224376 -383.490216)
			(xy 78.951674 -383.490216) (xy 78.942805 -383.51089) (xy 78.926436 -383.539238) (xy 78.923111 -383.545258)
			(xy 78.919511 -383.558525) (xy 78.919324 -383.5654) (xy 78.919324 -384.3147) (xy 78.919513 -384.321573)
			(xy 78.923123 -384.334836) (xy 78.926436 -384.340862) (xy 78.94278 -384.369223) (xy 78.968589 -384.429378)
			(xy 78.986085 -384.492454) (xy 78.994951 -384.557308) (xy 78.995524 -384.590036) (xy 78.994949 -384.622765)
			(xy 78.986095 -384.687623) (xy 78.968607 -384.750703) (xy 78.942803 -384.810861) (xy 78.926436 -384.83921)
			(xy 78.923121 -384.845234) (xy 78.919515 -384.858498) (xy 78.919324 -384.865372) (xy 78.919324 -385.151376)
			(xy 78.918865 -385.161494) (xy 78.911129 -385.180193) (xy 78.896826 -385.194507) (xy 78.878134 -385.202257)
			(xy 78.868016 -385.202684) (xy 78.151736 -385.202684) (xy 78.141614 -385.202254) (xy 78.122908 -385.194515)
			(xy 78.108592 -385.180202) (xy 78.100848 -385.161498) (xy 78.100428 -385.151376) (xy 78.100428 -384.865372)
			(xy 78.100243 -384.858498) (xy 78.09663 -384.845236) (xy 78.093316 -384.83921) (xy 78.076956 -384.810858)
			(xy 78.051152 -384.750699) (xy 78.033661 -384.687621) (xy 78.024799 -384.622765) (xy 78.024228 -384.590036)
			(xy 74.5949 -384.590036) (xy 74.594898 -384.622751) (xy 74.586109 -384.687597) (xy 74.568696 -384.750677)
			(xy 74.542973 -384.810849) (xy 74.526648 -384.83921) (xy 74.523334 -384.845235) (xy 74.519727 -384.858498)
			(xy 74.519536 -384.865372) (xy 74.519536 -385.151376) (xy 74.51906 -385.161524) (xy 74.511279 -385.180269)
			(xy 74.496899 -385.194592) (xy 74.478124 -385.202299) (xy 74.467974 -385.202684) (xy 73.751694 -385.202684)
			(xy 73.74157 -385.202179) (xy 73.722853 -385.194454) (xy 73.708498 -385.180173) (xy 73.700675 -385.161497)
			(xy 73.700132 -385.151376) (xy 73.700132 -384.865372) (xy 73.699947 -384.858498) (xy 73.696333 -384.845236)
			(xy 73.69302 -384.83921) (xy 73.676729 -384.810832) (xy 73.651009 -384.750664) (xy 73.633599 -384.687589)
			(xy 73.624812 -384.622748) (xy 73.624807 -384.557314) (xy 73.633586 -384.492471) (xy 73.650989 -384.429394)
			(xy 73.676701 -384.369223) (xy 73.69302 -384.340862) (xy 73.69635 -384.334845) (xy 73.699946 -384.321575)
			(xy 73.700132 -384.3147) (xy 73.700132 -383.5654) (xy 73.699936 -383.558527) (xy 73.69633 -383.545264)
			(xy 73.69302 -383.539238) (xy 73.676668 -383.510893) (xy 73.650954 -383.450718) (xy 73.63355 -383.387636)
			(xy 73.624771 -383.322789) (xy 72.366125 -383.322789) (xy 72.369797 -383.331505) (xy 72.386772 -383.393855)
			(xy 72.395335 -383.457904) (xy 72.395333 -383.522523) (xy 72.386767 -383.586572) (xy 72.369788 -383.648921)
			(xy 72.344696 -383.70847) (xy 72.328786 -383.736596) (xy 72.324976 -383.742946) (xy 72.320912 -383.758186)
			(xy 72.319388 -383.770124) (xy 72.319388 -384.051556) (xy 72.318972 -384.061682) (xy 72.311232 -384.080396)
			(xy 72.296916 -384.094719) (xy 72.278206 -384.102467) (xy 72.26808 -384.102864) (xy 71.984362 -384.102864)
			(xy 71.971813 -384.103517) (xy 71.949702 -384.115388) (xy 71.942198 -384.12547) (xy 71.935086 -384.136138)
			(xy 71.932546 -384.161284) (xy 71.94677 -384.195828) (xy 71.968614 -384.212084) (xy 71.98233 -384.213862)
			(xy 72.016996 -384.218746) (xy 72.084907 -384.235758) (xy 72.150282 -384.260809) (xy 72.212172 -384.293535)
			(xy 72.26968 -384.333461) (xy 72.321974 -384.380009) (xy 72.368295 -384.432504) (xy 72.407971 -384.490185)
			(xy 72.440428 -384.552216) (xy 72.465195 -384.617699) (xy 72.481913 -384.685683) (xy 72.49034 -384.755183)
			(xy 72.490838 -384.790188) (xy 72.490584 -384.793998) (xy 72.490584 -384.795522) (xy 72.490464 -384.808623)
			(xy 72.489191 -384.834795) (xy 72.488044 -384.847846) (xy 72.48652 -384.86461) (xy 72.503538 -384.893058)
			(xy 73.75779 -385.412488) (xy 73.782174 -385.410456) (xy 73.787 -385.407408) (xy 73.799594 -385.399073)
			(xy 73.825515 -385.383572) (xy 73.838816 -385.37642) (xy 73.854059 -385.368504) (xy 73.885321 -385.35427)
			(xy 73.9013 -385.347972) (xy 73.933882 -385.335991) (xy 74.001191 -385.318992) (xy 74.070048 -385.310145)
			(xy 74.104754 -385.309364) (xy 74.106532 -385.309364) (xy 74.109834 -385.30911) (xy 74.142825 -385.309568)
			(xy 74.208384 -385.317036) (xy 74.272674 -385.331884) (xy 74.334868 -385.353919) (xy 74.394166 -385.382858)
			(xy 74.449803 -385.41833) (xy 74.501063 -385.459876) (xy 74.547286 -385.506962) (xy 74.587877 -385.558982)
			(xy 74.603146 -385.583938) (xy 100.447856 -385.583938) (xy 100.447856 -384.720338) (xy 100.448346 -384.690354)
			(xy 100.456174 -384.630898) (xy 100.471695 -384.572973) (xy 100.494644 -384.517569) (xy 100.524628 -384.465635)
			(xy 100.561134 -384.418059) (xy 100.603539 -384.375654) (xy 100.651115 -384.339148) (xy 100.703049 -384.309164)
			(xy 100.758453 -384.286215) (xy 100.816378 -384.270694) (xy 100.875834 -384.262866) (xy 100.935802 -384.262866)
			(xy 100.995258 -384.270694) (xy 101.053183 -384.286215) (xy 101.108587 -384.309164) (xy 101.160521 -384.339148)
			(xy 101.208097 -384.375654) (xy 101.250502 -384.418059) (xy 101.287008 -384.465635) (xy 101.316992 -384.517569)
			(xy 101.339941 -384.572973) (xy 101.355462 -384.630898) (xy 101.36329 -384.690354) (xy 101.36378 -384.720338)
			(xy 101.36378 -385.319283) (xy 104.635826 -385.319283) (xy 104.635826 -385.259317) (xy 104.643653 -385.199864)
			(xy 104.659172 -385.141942) (xy 104.682119 -385.08654) (xy 104.7121 -385.034608) (xy 104.748603 -384.987032)
			(xy 104.791004 -384.944628) (xy 104.838576 -384.908121) (xy 104.890506 -384.878136) (xy 104.945906 -384.855184)
			(xy 105.003827 -384.83966) (xy 105.063279 -384.831828) (xy 105.093262 -384.831336) (xy 105.956862 -384.831336)
			(xy 105.986849 -384.831807) (xy 106.046311 -384.83963) (xy 106.104243 -384.855149) (xy 106.159653 -384.878097)
			(xy 106.211594 -384.908081) (xy 106.259176 -384.944589) (xy 106.301586 -384.986995) (xy 106.338098 -385.034574)
			(xy 106.368087 -385.086513) (xy 106.391039 -385.141921) (xy 106.406562 -385.199852) (xy 106.414391 -385.259313)
			(xy 106.414391 -385.319287) (xy 106.406562 -385.378748) (xy 106.391039 -385.436679) (xy 106.368087 -385.492087)
			(xy 106.338098 -385.544026) (xy 106.301586 -385.591605) (xy 106.259176 -385.634011) (xy 106.211594 -385.670519)
			(xy 106.159653 -385.700503) (xy 106.104243 -385.723451) (xy 106.046311 -385.73897) (xy 105.986849 -385.746793)
			(xy 105.956862 -385.74726) (xy 105.093262 -385.74726) (xy 105.063279 -385.746772) (xy 105.003827 -385.73894)
			(xy 104.945906 -385.723416) (xy 104.890506 -385.700464) (xy 104.838576 -385.670479) (xy 104.791004 -385.633972)
			(xy 104.748603 -385.591568) (xy 104.7121 -385.543992) (xy 104.682119 -385.49206) (xy 104.659172 -385.436658)
			(xy 104.643653 -385.378736) (xy 104.635826 -385.319283) (xy 101.36378 -385.319283) (xy 101.36378 -385.583938)
			(xy 101.36329 -385.613922) (xy 101.355462 -385.673378) (xy 101.339941 -385.731303) (xy 101.316992 -385.786707)
			(xy 101.287008 -385.838641) (xy 101.250502 -385.886217) (xy 101.208097 -385.928622) (xy 101.160521 -385.965128)
			(xy 101.108587 -385.995112) (xy 101.053183 -386.018061) (xy 100.995258 -386.033582) (xy 100.935802 -386.04141)
			(xy 100.875834 -386.04141) (xy 100.816378 -386.033582) (xy 100.758453 -386.018061) (xy 100.703049 -385.995112)
			(xy 100.651115 -385.965128) (xy 100.603539 -385.928622) (xy 100.561134 -385.886217) (xy 100.524628 -385.838641)
			(xy 100.494644 -385.786707) (xy 100.471695 -385.731303) (xy 100.456174 -385.673378) (xy 100.448346 -385.613922)
			(xy 100.447856 -385.583938) (xy 74.603146 -385.583938) (xy 74.622313 -385.615265) (xy 74.650151 -385.675088)
			(xy 74.671032 -385.737679) (xy 74.678286 -385.769866) (xy 74.680826 -385.782058) (xy 74.696828 -385.801362)
			(xy 82.205781 -388.911846) (xy 103.494838 -388.911846) (xy 103.498909 -388.856224) (xy 103.511035 -388.801787)
			(xy 103.530958 -388.749696) (xy 103.558254 -388.701061) (xy 103.59234 -388.656918) (xy 103.632489 -388.618209)
			(xy 103.677847 -388.585758) (xy 103.727447 -388.560257) (xy 103.780231 -388.54225) (xy 103.835074 -388.53212)
			(xy 103.890808 -388.530083) (xy 103.946245 -388.536183) (xy 104.000202 -388.550289) (xy 104.051531 -388.572101)
			(xy 104.099137 -388.601155) (xy 104.142005 -388.63683) (xy 104.179222 -388.678367) (xy 104.209995 -388.72488)
			(xy 104.233667 -388.775377) (xy 104.249735 -388.828784) (xy 104.257855 -388.88396) (xy 104.258364 -388.911846)
			(xy 104.257855 -388.939732) (xy 104.249735 -388.994908) (xy 104.233667 -389.048315) (xy 104.209995 -389.098812)
			(xy 104.179222 -389.145325) (xy 104.142005 -389.186862) (xy 104.099137 -389.222537) (xy 104.051531 -389.251591)
			(xy 104.000202 -389.273403) (xy 103.946245 -389.287509) (xy 103.890808 -389.293609) (xy 103.835074 -389.291572)
			(xy 103.780231 -389.281442) (xy 103.727447 -389.263435) (xy 103.677847 -389.237934) (xy 103.632489 -389.205483)
			(xy 103.59234 -389.166774) (xy 103.558254 -389.122631) (xy 103.530958 -389.073996) (xy 103.511035 -389.021905)
			(xy 103.498909 -388.967468) (xy 103.494838 -388.911846) (xy 82.205781 -388.911846) (xy 85.732156 -390.3726)
			(xy 98.601782 -390.3726) (xy 98.605853 -390.316978) (xy 98.617979 -390.262541) (xy 98.637902 -390.21045)
			(xy 98.665198 -390.161815) (xy 98.699284 -390.117672) (xy 98.739433 -390.078963) (xy 98.784791 -390.046512)
			(xy 98.834391 -390.021011) (xy 98.887175 -390.003004) (xy 98.942018 -389.992874) (xy 98.997752 -389.990837)
			(xy 99.053189 -389.996937) (xy 99.107146 -390.011043) (xy 99.158475 -390.032855) (xy 99.206081 -390.061909)
			(xy 99.248949 -390.097584) (xy 99.286166 -390.139121) (xy 99.316939 -390.185634) (xy 99.340611 -390.236131)
			(xy 99.356679 -390.289538) (xy 99.364799 -390.344714) (xy 99.365308 -390.3726) (xy 99.364799 -390.400486)
			(xy 99.356679 -390.455662) (xy 99.340611 -390.509069) (xy 99.316939 -390.559566) (xy 99.291747 -390.597644)
			(xy 99.793806 -390.597644) (xy 99.794296 -390.570275) (xy 99.802108 -390.516097) (xy 99.817591 -390.463594)
			(xy 99.840428 -390.413846) (xy 99.870147 -390.367878) (xy 99.887786 -390.346946) (xy 99.88804 -390.346692)
			(xy 99.893641 -390.339615) (xy 99.899878 -390.322691) (xy 99.900232 -390.313672) (xy 99.900232 -390.246616)
			(xy 99.89986 -390.237601) (xy 99.893622 -390.220684) (xy 99.88804 -390.213596) (xy 99.887786 -390.213596)
			(xy 99.887786 -390.213342) (xy 99.870151 -390.192407) (xy 99.840439 -390.146435) (xy 99.817602 -390.096688)
			(xy 99.80211 -390.044188) (xy 99.794281 -389.990013) (xy 99.793806 -389.962644) (xy 99.794292 -389.935393)
			(xy 99.802048 -389.881445) (xy 99.817403 -389.82915) (xy 99.840045 -389.779573) (xy 99.869511 -389.733723)
			(xy 99.905202 -389.692532) (xy 99.946393 -389.656841) (xy 99.992243 -389.627375) (xy 100.04182 -389.604733)
			(xy 100.094115 -389.589378) (xy 100.148063 -389.581622) (xy 100.202565 -389.581622) (xy 100.256513 -389.589378)
			(xy 100.308808 -389.604733) (xy 100.358385 -389.627375) (xy 100.404235 -389.656841) (xy 100.445426 -389.692532)
			(xy 100.475893 -389.727694) (xy 106.942888 -389.727694) (xy 106.946959 -389.672072) (xy 106.959085 -389.617635)
			(xy 106.979008 -389.565544) (xy 107.006304 -389.516909) (xy 107.04039 -389.472766) (xy 107.080539 -389.434057)
			(xy 107.125897 -389.401606) (xy 107.175497 -389.376105) (xy 107.228281 -389.358098) (xy 107.283124 -389.347968)
			(xy 107.338858 -389.345931) (xy 107.394295 -389.352031) (xy 107.448252 -389.366137) (xy 107.499581 -389.387949)
			(xy 107.547187 -389.417003) (xy 107.590055 -389.452678) (xy 107.627272 -389.494215) (xy 107.658045 -389.540728)
			(xy 107.681717 -389.591225) (xy 107.697785 -389.644632) (xy 107.705905 -389.699808) (xy 107.706414 -389.727694)
			(xy 107.705905 -389.75558) (xy 107.697785 -389.810756) (xy 107.681717 -389.864163) (xy 107.658045 -389.91466)
			(xy 107.627272 -389.961173) (xy 107.590055 -390.00271) (xy 107.547187 -390.038385) (xy 107.499581 -390.067439)
			(xy 107.448252 -390.089251) (xy 107.394295 -390.103357) (xy 107.338858 -390.109457) (xy 107.283124 -390.10742)
			(xy 107.228281 -390.09729) (xy 107.175497 -390.079283) (xy 107.125897 -390.053782) (xy 107.080539 -390.021331)
			(xy 107.04039 -389.982622) (xy 107.006304 -389.938479) (xy 106.979008 -389.889844) (xy 106.959085 -389.837753)
			(xy 106.946959 -389.783316) (xy 106.942888 -389.727694) (xy 100.475893 -389.727694) (xy 100.481117 -389.733723)
			(xy 100.510583 -389.779573) (xy 100.533225 -389.82915) (xy 100.54858 -389.881445) (xy 100.556336 -389.935393)
			(xy 100.556822 -389.962644) (xy 100.556342 -389.990014) (xy 100.548531 -390.044193) (xy 100.533046 -390.096697)
			(xy 100.510207 -390.146444) (xy 100.480483 -390.192411) (xy 100.462842 -390.213342) (xy 100.462588 -390.213596)
			(xy 100.456996 -390.220679) (xy 100.450753 -390.237598) (xy 100.450396 -390.246616) (xy 100.450396 -390.313672)
			(xy 100.450767 -390.322687) (xy 100.457005 -390.339604) (xy 100.462588 -390.346692) (xy 100.462842 -390.346692)
			(xy 100.462842 -390.346946) (xy 100.480476 -390.367882) (xy 100.510187 -390.413854) (xy 100.533024 -390.463601)
			(xy 100.548516 -390.5161) (xy 100.556347 -390.570275) (xy 100.556822 -390.597644) (xy 100.556336 -390.624895)
			(xy 100.54858 -390.678843) (xy 100.533225 -390.731138) (xy 100.510583 -390.780715) (xy 100.481117 -390.826565)
			(xy 100.445426 -390.867756) (xy 100.404235 -390.903447) (xy 100.358385 -390.932913) (xy 100.308808 -390.955555)
			(xy 100.256513 -390.97091) (xy 100.202565 -390.978666) (xy 100.148063 -390.978666) (xy 100.094115 -390.97091)
			(xy 100.04182 -390.955555) (xy 99.992243 -390.932913) (xy 99.946393 -390.903447) (xy 99.905202 -390.867756)
			(xy 99.869511 -390.826565) (xy 99.840045 -390.780715) (xy 99.817403 -390.731138) (xy 99.802048 -390.678843)
			(xy 99.794292 -390.624895) (xy 99.793806 -390.597644) (xy 99.291747 -390.597644) (xy 99.286166 -390.606079)
			(xy 99.248949 -390.647616) (xy 99.206081 -390.683291) (xy 99.158475 -390.712345) (xy 99.107146 -390.734157)
			(xy 99.053189 -390.748263) (xy 98.997752 -390.754363) (xy 98.942018 -390.752326) (xy 98.887175 -390.742196)
			(xy 98.834391 -390.724189) (xy 98.784791 -390.698688) (xy 98.739433 -390.666237) (xy 98.699284 -390.627528)
			(xy 98.665198 -390.583385) (xy 98.637902 -390.53475) (xy 98.617979 -390.482659) (xy 98.605853 -390.428222)
			(xy 98.601782 -390.3726) (xy 85.732156 -390.3726) (xy 85.733382 -390.373108) (xy 85.778378 -390.392413)
			(xy 85.864701 -390.438637) (xy 85.946075 -390.493102) (xy 86.021715 -390.555285) (xy 86.056724 -390.589516)
			(xy 86.761574 -391.294366) (xy 99.119942 -391.294366) (xy 99.124013 -391.238744) (xy 99.136139 -391.184307)
			(xy 99.156062 -391.132216) (xy 99.183358 -391.083581) (xy 99.217444 -391.039438) (xy 99.257593 -391.000729)
			(xy 99.302951 -390.968278) (xy 99.352551 -390.942777) (xy 99.405335 -390.92477) (xy 99.460178 -390.91464)
			(xy 99.515912 -390.912603) (xy 99.571349 -390.918703) (xy 99.625306 -390.932809) (xy 99.676635 -390.954621)
			(xy 99.724241 -390.983675) (xy 99.767109 -391.01935) (xy 99.804326 -391.060887) (xy 99.835099 -391.1074)
			(xy 99.857137 -391.154412) (xy 106.201208 -391.154412) (xy 106.205279 -391.09879) (xy 106.217405 -391.044353)
			(xy 106.237328 -390.992262) (xy 106.264624 -390.943627) (xy 106.29871 -390.899484) (xy 106.338859 -390.860775)
			(xy 106.384217 -390.828324) (xy 106.433817 -390.802823) (xy 106.486601 -390.784816) (xy 106.541444 -390.774686)
			(xy 106.597178 -390.772649) (xy 106.652615 -390.778749) (xy 106.706572 -390.792855) (xy 106.757901 -390.814667)
			(xy 106.805507 -390.843721) (xy 106.848375 -390.879396) (xy 106.885592 -390.920933) (xy 106.916365 -390.967446)
			(xy 106.940037 -391.017943) (xy 106.956105 -391.07135) (xy 106.964225 -391.126526) (xy 106.964734 -391.154412)
			(xy 106.964225 -391.182298) (xy 106.956105 -391.237474) (xy 106.940037 -391.290881) (xy 106.916365 -391.341378)
			(xy 106.885592 -391.387891) (xy 106.848375 -391.429428) (xy 106.805507 -391.465103) (xy 106.757901 -391.494157)
			(xy 106.706572 -391.515969) (xy 106.652615 -391.530075) (xy 106.597178 -391.536175) (xy 106.541444 -391.534138)
			(xy 106.486601 -391.524008) (xy 106.433817 -391.506001) (xy 106.384217 -391.4805) (xy 106.338859 -391.448049)
			(xy 106.29871 -391.40934) (xy 106.264624 -391.365197) (xy 106.237328 -391.316562) (xy 106.217405 -391.264471)
			(xy 106.205279 -391.210034) (xy 106.201208 -391.154412) (xy 99.857137 -391.154412) (xy 99.858771 -391.157897)
			(xy 99.874839 -391.211304) (xy 99.882959 -391.26648) (xy 99.883468 -391.294366) (xy 99.882959 -391.322252)
			(xy 99.874839 -391.377428) (xy 99.858771 -391.430835) (xy 99.835099 -391.481332) (xy 99.804326 -391.527845)
			(xy 99.767109 -391.569382) (xy 99.724241 -391.605057) (xy 99.676635 -391.634111) (xy 99.628565 -391.654538)
			(xy 108.000036 -391.654538) (xy 108.004107 -391.598916) (xy 108.016233 -391.544479) (xy 108.036156 -391.492388)
			(xy 108.063452 -391.443753) (xy 108.097538 -391.39961) (xy 108.137687 -391.360901) (xy 108.183045 -391.32845)
			(xy 108.232645 -391.302949) (xy 108.285429 -391.284942) (xy 108.340272 -391.274812) (xy 108.396006 -391.272775)
			(xy 108.451443 -391.278875) (xy 108.5054 -391.292981) (xy 108.556729 -391.314793) (xy 108.604335 -391.343847)
			(xy 108.647203 -391.379522) (xy 108.68442 -391.421059) (xy 108.715193 -391.467572) (xy 108.738865 -391.518069)
			(xy 108.754933 -391.571476) (xy 108.763053 -391.626652) (xy 108.763562 -391.654538) (xy 108.763053 -391.682424)
			(xy 108.754933 -391.7376) (xy 108.738865 -391.791007) (xy 108.715193 -391.841504) (xy 108.68442 -391.888017)
			(xy 108.647203 -391.929554) (xy 108.604335 -391.965229) (xy 108.556729 -391.994283) (xy 108.5054 -392.016095)
			(xy 108.451443 -392.030201) (xy 108.396006 -392.036301) (xy 108.340272 -392.034264) (xy 108.285429 -392.024134)
			(xy 108.232645 -392.006127) (xy 108.183045 -391.980626) (xy 108.137687 -391.948175) (xy 108.097538 -391.909466)
			(xy 108.063452 -391.865323) (xy 108.036156 -391.816688) (xy 108.016233 -391.764597) (xy 108.004107 -391.71016)
			(xy 108.000036 -391.654538) (xy 99.628565 -391.654538) (xy 99.625306 -391.655923) (xy 99.571349 -391.670029)
			(xy 99.515912 -391.676129) (xy 99.460178 -391.674092) (xy 99.405335 -391.663962) (xy 99.352551 -391.645955)
			(xy 99.302951 -391.620454) (xy 99.257593 -391.588003) (xy 99.217444 -391.549294) (xy 99.183358 -391.505151)
			(xy 99.156062 -391.456516) (xy 99.136139 -391.404425) (xy 99.124013 -391.349988) (xy 99.119942 -391.294366)
			(xy 86.761574 -391.294366) (xy 87.846408 -392.3792) (xy 96.620582 -392.3792) (xy 96.624653 -392.323578)
			(xy 96.636779 -392.269141) (xy 96.656702 -392.21705) (xy 96.683998 -392.168415) (xy 96.718084 -392.124272)
			(xy 96.758233 -392.085563) (xy 96.803591 -392.053112) (xy 96.853191 -392.027611) (xy 96.905975 -392.009604)
			(xy 96.960818 -391.999474) (xy 97.016552 -391.997437) (xy 97.071989 -392.003537) (xy 97.125946 -392.017643)
			(xy 97.177275 -392.039455) (xy 97.224881 -392.068509) (xy 97.267749 -392.104184) (xy 97.304966 -392.145721)
			(xy 97.335739 -392.192234) (xy 97.359411 -392.242731) (xy 97.375479 -392.296138) (xy 97.383599 -392.351314)
			(xy 97.384108 -392.3792) (xy 97.383599 -392.407086) (xy 97.375479 -392.462262) (xy 97.359411 -392.515669)
			(xy 97.335739 -392.566166) (xy 97.320125 -392.589766) (xy 99.119942 -392.589766) (xy 99.124013 -392.534144)
			(xy 99.136139 -392.479707) (xy 99.156062 -392.427616) (xy 99.183358 -392.378981) (xy 99.217444 -392.334838)
			(xy 99.257593 -392.296129) (xy 99.302951 -392.263678) (xy 99.352551 -392.238177) (xy 99.405335 -392.22017)
			(xy 99.460178 -392.21004) (xy 99.515912 -392.208003) (xy 99.571349 -392.214103) (xy 99.625306 -392.228209)
			(xy 99.676635 -392.250021) (xy 99.724241 -392.279075) (xy 99.767109 -392.31475) (xy 99.785029 -392.33475)
			(xy 106.667298 -392.33475) (xy 106.671369 -392.279128) (xy 106.683495 -392.224691) (xy 106.703418 -392.1726)
			(xy 106.730714 -392.123965) (xy 106.7648 -392.079822) (xy 106.804949 -392.041113) (xy 106.850307 -392.008662)
			(xy 106.899907 -391.983161) (xy 106.952691 -391.965154) (xy 107.007534 -391.955024) (xy 107.063268 -391.952987)
			(xy 107.118705 -391.959087) (xy 107.172662 -391.973193) (xy 107.223991 -391.995005) (xy 107.271597 -392.024059)
			(xy 107.314465 -392.059734) (xy 107.351682 -392.101271) (xy 107.382455 -392.147784) (xy 107.406127 -392.198281)
			(xy 107.422195 -392.251688) (xy 107.430315 -392.306864) (xy 107.430824 -392.33475) (xy 107.430315 -392.362636)
			(xy 107.422195 -392.417812) (xy 107.406127 -392.471219) (xy 107.382455 -392.521716) (xy 107.351682 -392.568229)
			(xy 107.314465 -392.609766) (xy 107.271597 -392.645441) (xy 107.223991 -392.674495) (xy 107.172662 -392.696307)
			(xy 107.118705 -392.710413) (xy 107.063268 -392.716513) (xy 107.007534 -392.714476) (xy 106.952691 -392.704346)
			(xy 106.899907 -392.686339) (xy 106.850307 -392.660838) (xy 106.804949 -392.628387) (xy 106.7648 -392.589678)
			(xy 106.730714 -392.545535) (xy 106.703418 -392.4969) (xy 106.683495 -392.444809) (xy 106.671369 -392.390372)
			(xy 106.667298 -392.33475) (xy 99.785029 -392.33475) (xy 99.804326 -392.356287) (xy 99.835099 -392.4028)
			(xy 99.858771 -392.453297) (xy 99.874839 -392.506704) (xy 99.882959 -392.56188) (xy 99.883468 -392.589766)
			(xy 99.882959 -392.617652) (xy 99.874839 -392.672828) (xy 99.858771 -392.726235) (xy 99.835099 -392.776732)
			(xy 99.804326 -392.823245) (xy 99.767109 -392.864782) (xy 99.724241 -392.900457) (xy 99.676635 -392.929511)
			(xy 99.625306 -392.951323) (xy 99.571349 -392.965429) (xy 99.515912 -392.971529) (xy 99.460178 -392.969492)
			(xy 99.405335 -392.959362) (xy 99.352551 -392.941355) (xy 99.302951 -392.915854) (xy 99.257593 -392.883403)
			(xy 99.217444 -392.844694) (xy 99.183358 -392.800551) (xy 99.156062 -392.751916) (xy 99.136139 -392.699825)
			(xy 99.124013 -392.645388) (xy 99.119942 -392.589766) (xy 97.320125 -392.589766) (xy 97.304966 -392.612679)
			(xy 97.267749 -392.654216) (xy 97.224881 -392.689891) (xy 97.177275 -392.718945) (xy 97.125946 -392.740757)
			(xy 97.071989 -392.754863) (xy 97.016552 -392.760963) (xy 96.960818 -392.758926) (xy 96.905975 -392.748796)
			(xy 96.853191 -392.730789) (xy 96.803591 -392.705288) (xy 96.758233 -392.672837) (xy 96.718084 -392.634128)
			(xy 96.683998 -392.589985) (xy 96.656702 -392.54135) (xy 96.636779 -392.489259) (xy 96.624653 -392.434822)
			(xy 96.620582 -392.3792) (xy 87.846408 -392.3792) (xy 89.189306 -393.722098) (xy 89.219754 -393.7532)
			(xy 89.275725 -393.819864) (xy 89.32148 -393.885166) (xy 99.119942 -393.885166) (xy 99.124013 -393.829544)
			(xy 99.136139 -393.775107) (xy 99.156062 -393.723016) (xy 99.183358 -393.674381) (xy 99.217444 -393.630238)
			(xy 99.257593 -393.591529) (xy 99.302951 -393.559078) (xy 99.352551 -393.533577) (xy 99.405335 -393.51557)
			(xy 99.460178 -393.50544) (xy 99.515912 -393.503403) (xy 99.571349 -393.509503) (xy 99.625306 -393.523609)
			(xy 99.676635 -393.545421) (xy 99.724241 -393.574475) (xy 99.767109 -393.61015) (xy 99.804326 -393.651687)
			(xy 99.835099 -393.6982) (xy 99.858771 -393.748697) (xy 99.874839 -393.802104) (xy 99.882959 -393.85728)
			(xy 99.883468 -393.885166) (xy 99.882959 -393.913052) (xy 99.874839 -393.968228) (xy 99.858771 -394.021635)
			(xy 99.835099 -394.072132) (xy 99.804326 -394.118645) (xy 99.767109 -394.160182) (xy 99.724241 -394.195857)
			(xy 99.676635 -394.224911) (xy 99.625306 -394.246723) (xy 99.571349 -394.260829) (xy 99.515912 -394.266929)
			(xy 99.460178 -394.264892) (xy 99.405335 -394.254762) (xy 99.352551 -394.236755) (xy 99.302951 -394.211254)
			(xy 99.257593 -394.178803) (xy 99.217444 -394.140094) (xy 99.183358 -394.095951) (xy 99.156062 -394.047316)
			(xy 99.136139 -393.995225) (xy 99.124013 -393.940788) (xy 99.119942 -393.885166) (xy 89.32148 -393.885166)
			(xy 89.325674 -393.891151) (xy 89.36922 -393.96652) (xy 89.406033 -394.045397) (xy 89.435832 -394.127182)
			(xy 89.458392 -394.211253) (xy 89.473539 -394.296969) (xy 89.476211 -394.32738) (xy 105.828336 -394.32738)
			(xy 105.832407 -394.271758) (xy 105.844533 -394.217321) (xy 105.864456 -394.16523) (xy 105.891752 -394.116595)
			(xy 105.925838 -394.072452) (xy 105.965987 -394.033743) (xy 106.011345 -394.001292) (xy 106.060945 -393.975791)
			(xy 106.113729 -393.957784) (xy 106.168572 -393.947654) (xy 106.224306 -393.945617) (xy 106.279743 -393.951717)
			(xy 106.3337 -393.965823) (xy 106.385029 -393.987635) (xy 106.432635 -394.016689) (xy 106.475503 -394.052364)
			(xy 106.51272 -394.093901) (xy 106.543493 -394.140414) (xy 106.567165 -394.190911) (xy 106.583233 -394.244318)
			(xy 106.591353 -394.299494) (xy 106.591862 -394.32738) (xy 106.591353 -394.355266) (xy 106.583233 -394.410442)
			(xy 106.567165 -394.463849) (xy 106.543493 -394.514346) (xy 106.51272 -394.560859) (xy 106.475503 -394.602396)
			(xy 106.432635 -394.638071) (xy 106.385029 -394.667125) (xy 106.3337 -394.688937) (xy 106.279743 -394.703043)
			(xy 106.224306 -394.709143) (xy 106.168572 -394.707106) (xy 106.113729 -394.696976) (xy 106.060945 -394.678969)
			(xy 106.011345 -394.653468) (xy 105.965987 -394.621017) (xy 105.925838 -394.582308) (xy 105.891752 -394.538165)
			(xy 105.864456 -394.48953) (xy 105.844533 -394.437439) (xy 105.832407 -394.383002) (xy 105.828336 -394.32738)
			(xy 89.476211 -394.32738) (xy 89.481159 -394.38368) (xy 89.48166 -394.427202) (xy 89.48166 -395.180566)
			(xy 99.119942 -395.180566) (xy 99.124013 -395.124944) (xy 99.136139 -395.070507) (xy 99.156062 -395.018416)
			(xy 99.183358 -394.969781) (xy 99.217444 -394.925638) (xy 99.257593 -394.886929) (xy 99.302951 -394.854478)
			(xy 99.352551 -394.828977) (xy 99.405335 -394.81097) (xy 99.460178 -394.80084) (xy 99.515912 -394.798803)
			(xy 99.571349 -394.804903) (xy 99.625306 -394.819009) (xy 99.676635 -394.840821) (xy 99.724241 -394.869875)
			(xy 99.767109 -394.90555) (xy 99.804326 -394.947087) (xy 99.835099 -394.9936) (xy 99.858771 -395.044097)
			(xy 99.874839 -395.097504) (xy 99.882959 -395.15268) (xy 99.883468 -395.180566) (xy 99.883347 -395.18717)
			(xy 101.058724 -395.18717) (xy 101.062795 -395.131548) (xy 101.074921 -395.077111) (xy 101.094844 -395.02502)
			(xy 101.12214 -394.976385) (xy 101.156226 -394.932242) (xy 101.196375 -394.893533) (xy 101.241733 -394.861082)
			(xy 101.291333 -394.835581) (xy 101.344117 -394.817574) (xy 101.39896 -394.807444) (xy 101.454694 -394.805407)
			(xy 101.510131 -394.811507) (xy 101.564088 -394.825613) (xy 101.615417 -394.847425) (xy 101.663023 -394.876479)
			(xy 101.705891 -394.912154) (xy 101.743108 -394.953691) (xy 101.773881 -395.000204) (xy 101.797553 -395.050701)
			(xy 101.813621 -395.104108) (xy 101.821741 -395.159284) (xy 101.82225 -395.18717) (xy 101.821741 -395.215056)
			(xy 101.813621 -395.270232) (xy 101.797553 -395.323639) (xy 101.773881 -395.374136) (xy 101.743108 -395.420649)
			(xy 101.705891 -395.462186) (xy 101.663023 -395.497861) (xy 101.615417 -395.526915) (xy 101.564088 -395.548727)
			(xy 101.510131 -395.562833) (xy 101.454694 -395.568933) (xy 101.39896 -395.566896) (xy 101.344117 -395.556766)
			(xy 101.291333 -395.538759) (xy 101.241733 -395.513258) (xy 101.196375 -395.480807) (xy 101.156226 -395.442098)
			(xy 101.12214 -395.397955) (xy 101.094844 -395.34932) (xy 101.074921 -395.297229) (xy 101.062795 -395.242792)
			(xy 101.058724 -395.18717) (xy 99.883347 -395.18717) (xy 99.882959 -395.208452) (xy 99.874839 -395.263628)
			(xy 99.858771 -395.317035) (xy 99.835099 -395.367532) (xy 99.804326 -395.414045) (xy 99.767109 -395.455582)
			(xy 99.724241 -395.491257) (xy 99.676635 -395.520311) (xy 99.625306 -395.542123) (xy 99.571349 -395.556229)
			(xy 99.515912 -395.562329) (xy 99.460178 -395.560292) (xy 99.405335 -395.550162) (xy 99.352551 -395.532155)
			(xy 99.302951 -395.506654) (xy 99.257593 -395.474203) (xy 99.217444 -395.435494) (xy 99.183358 -395.391351)
			(xy 99.156062 -395.342716) (xy 99.136139 -395.290625) (xy 99.124013 -395.236188) (xy 99.119942 -395.180566)
			(xy 89.48166 -395.180566) (xy 89.48166 -395.87043) (xy 89.487525 -395.873603) (xy 89.500395 -395.877073)
			(xy 89.50706 -395.877288) (xy 89.867994 -395.877288) (xy 89.878163 -395.877714) (xy 89.896951 -395.885499)
			(xy 89.911325 -395.899886) (xy 89.919095 -395.918681) (xy 89.919556 -395.92885) (xy 89.919556 -396.1638)
			(xy 96.6503 -396.1638) (xy 96.654371 -396.108178) (xy 96.666497 -396.053741) (xy 96.68642 -396.00165)
			(xy 96.713716 -395.953015) (xy 96.747802 -395.908872) (xy 96.787951 -395.870163) (xy 96.833309 -395.837712)
			(xy 96.882909 -395.812211) (xy 96.935693 -395.794204) (xy 96.990536 -395.784074) (xy 97.04627 -395.782037)
			(xy 97.101707 -395.788137) (xy 97.155664 -395.802243) (xy 97.206993 -395.824055) (xy 97.254599 -395.853109)
			(xy 97.297467 -395.888784) (xy 97.334684 -395.930321) (xy 97.365457 -395.976834) (xy 97.389129 -396.027331)
			(xy 97.405197 -396.080738) (xy 97.413317 -396.135914) (xy 97.413826 -396.1638) (xy 97.413317 -396.191686)
			(xy 97.405197 -396.246862) (xy 97.389129 -396.300269) (xy 97.365457 -396.350766) (xy 97.334684 -396.397279)
			(xy 97.297467 -396.438816) (xy 97.254599 -396.474491) (xy 97.212644 -396.500096) (xy 100.023166 -396.500096)
			(xy 100.027237 -396.444474) (xy 100.039363 -396.390037) (xy 100.059286 -396.337946) (xy 100.086582 -396.289311)
			(xy 100.120668 -396.245168) (xy 100.160817 -396.206459) (xy 100.206175 -396.174008) (xy 100.255775 -396.148507)
			(xy 100.308559 -396.1305) (xy 100.363402 -396.12037) (xy 100.419136 -396.118333) (xy 100.474573 -396.124433)
			(xy 100.52853 -396.138539) (xy 100.579859 -396.160351) (xy 100.627465 -396.189405) (xy 100.670333 -396.22508)
			(xy 100.70755 -396.266617) (xy 100.738323 -396.31313) (xy 100.761995 -396.363627) (xy 100.778063 -396.417034)
			(xy 100.786183 -396.47221) (xy 100.786692 -396.500096) (xy 101.318566 -396.500096) (xy 101.322637 -396.444474)
			(xy 101.334763 -396.390037) (xy 101.354686 -396.337946) (xy 101.381982 -396.289311) (xy 101.416068 -396.245168)
			(xy 101.456217 -396.206459) (xy 101.501575 -396.174008) (xy 101.551175 -396.148507) (xy 101.603959 -396.1305)
			(xy 101.658802 -396.12037) (xy 101.714536 -396.118333) (xy 101.769973 -396.124433) (xy 101.82393 -396.138539)
			(xy 101.875259 -396.160351) (xy 101.922865 -396.189405) (xy 101.965733 -396.22508) (xy 102.00295 -396.266617)
			(xy 102.033723 -396.31313) (xy 102.057395 -396.363627) (xy 102.073463 -396.417034) (xy 102.081583 -396.47221)
			(xy 102.082092 -396.500096) (xy 102.613966 -396.500096) (xy 102.618037 -396.444474) (xy 102.630163 -396.390037)
			(xy 102.650086 -396.337946) (xy 102.677382 -396.289311) (xy 102.711468 -396.245168) (xy 102.751617 -396.206459)
			(xy 102.796975 -396.174008) (xy 102.846575 -396.148507) (xy 102.899359 -396.1305) (xy 102.954202 -396.12037)
			(xy 103.009936 -396.118333) (xy 103.065373 -396.124433) (xy 103.11933 -396.138539) (xy 103.170659 -396.160351)
			(xy 103.218265 -396.189405) (xy 103.261133 -396.22508) (xy 103.29835 -396.266617) (xy 103.329123 -396.31313)
			(xy 103.352795 -396.363627) (xy 103.368863 -396.417034) (xy 103.376983 -396.47221) (xy 103.377492 -396.500096)
			(xy 103.909366 -396.500096) (xy 103.913437 -396.444474) (xy 103.925563 -396.390037) (xy 103.945486 -396.337946)
			(xy 103.972782 -396.289311) (xy 104.006868 -396.245168) (xy 104.047017 -396.206459) (xy 104.092375 -396.174008)
			(xy 104.141975 -396.148507) (xy 104.194759 -396.1305) (xy 104.249602 -396.12037) (xy 104.305336 -396.118333)
			(xy 104.360773 -396.124433) (xy 104.41473 -396.138539) (xy 104.466059 -396.160351) (xy 104.513665 -396.189405)
			(xy 104.556533 -396.22508) (xy 104.59375 -396.266617) (xy 104.624523 -396.31313) (xy 104.648195 -396.363627)
			(xy 104.664263 -396.417034) (xy 104.672383 -396.47221) (xy 104.672892 -396.500096) (xy 104.672383 -396.527982)
			(xy 104.664263 -396.583158) (xy 104.648195 -396.636565) (xy 104.624523 -396.687062) (xy 104.59375 -396.733575)
			(xy 104.556533 -396.775112) (xy 104.513665 -396.810787) (xy 104.466059 -396.839841) (xy 104.41473 -396.861653)
			(xy 104.360773 -396.875759) (xy 104.305336 -396.881859) (xy 104.249602 -396.879822) (xy 104.194759 -396.869692)
			(xy 104.141975 -396.851685) (xy 104.092375 -396.826184) (xy 104.047017 -396.793733) (xy 104.006868 -396.755024)
			(xy 103.972782 -396.710881) (xy 103.945486 -396.662246) (xy 103.925563 -396.610155) (xy 103.913437 -396.555718)
			(xy 103.909366 -396.500096) (xy 103.377492 -396.500096) (xy 103.376983 -396.527982) (xy 103.368863 -396.583158)
			(xy 103.352795 -396.636565) (xy 103.329123 -396.687062) (xy 103.29835 -396.733575) (xy 103.261133 -396.775112)
			(xy 103.218265 -396.810787) (xy 103.170659 -396.839841) (xy 103.11933 -396.861653) (xy 103.065373 -396.875759)
			(xy 103.009936 -396.881859) (xy 102.954202 -396.879822) (xy 102.899359 -396.869692) (xy 102.846575 -396.851685)
			(xy 102.796975 -396.826184) (xy 102.751617 -396.793733) (xy 102.711468 -396.755024) (xy 102.677382 -396.710881)
			(xy 102.650086 -396.662246) (xy 102.630163 -396.610155) (xy 102.618037 -396.555718) (xy 102.613966 -396.500096)
			(xy 102.082092 -396.500096) (xy 102.081583 -396.527982) (xy 102.073463 -396.583158) (xy 102.057395 -396.636565)
			(xy 102.033723 -396.687062) (xy 102.00295 -396.733575) (xy 101.965733 -396.775112) (xy 101.922865 -396.810787)
			(xy 101.875259 -396.839841) (xy 101.82393 -396.861653) (xy 101.769973 -396.875759) (xy 101.714536 -396.881859)
			(xy 101.658802 -396.879822) (xy 101.603959 -396.869692) (xy 101.551175 -396.851685) (xy 101.501575 -396.826184)
			(xy 101.456217 -396.793733) (xy 101.416068 -396.755024) (xy 101.381982 -396.710881) (xy 101.354686 -396.662246)
			(xy 101.334763 -396.610155) (xy 101.322637 -396.555718) (xy 101.318566 -396.500096) (xy 100.786692 -396.500096)
			(xy 100.786183 -396.527982) (xy 100.778063 -396.583158) (xy 100.761995 -396.636565) (xy 100.738323 -396.687062)
			(xy 100.70755 -396.733575) (xy 100.670333 -396.775112) (xy 100.627465 -396.810787) (xy 100.579859 -396.839841)
			(xy 100.52853 -396.861653) (xy 100.474573 -396.875759) (xy 100.419136 -396.881859) (xy 100.363402 -396.879822)
			(xy 100.308559 -396.869692) (xy 100.255775 -396.851685) (xy 100.206175 -396.826184) (xy 100.160817 -396.793733)
			(xy 100.120668 -396.755024) (xy 100.086582 -396.710881) (xy 100.059286 -396.662246) (xy 100.039363 -396.610155)
			(xy 100.027237 -396.555718) (xy 100.023166 -396.500096) (xy 97.212644 -396.500096) (xy 97.206993 -396.503545)
			(xy 97.155664 -396.525357) (xy 97.101707 -396.539463) (xy 97.04627 -396.545563) (xy 96.990536 -396.543526)
			(xy 96.935693 -396.533396) (xy 96.882909 -396.515389) (xy 96.833309 -396.489888) (xy 96.787951 -396.457437)
			(xy 96.747802 -396.418728) (xy 96.713716 -396.374585) (xy 96.68642 -396.32595) (xy 96.666497 -396.273859)
			(xy 96.654371 -396.219422) (xy 96.6503 -396.1638) (xy 89.919556 -396.1638) (xy 89.919556 -396.21968)
			(xy 89.92235 -396.227808) (xy 89.92616 -396.239238) (xy 89.926922 -396.240762) (xy 89.928954 -396.244064)
			(xy 89.944815 -396.272135) (xy 89.969804 -396.331571) (xy 89.986714 -396.39379) (xy 89.995248 -396.457698)
			(xy 89.995756 -396.489936) (xy 89.995756 -396.49019) (xy 89.99524 -396.522068) (xy 89.986867 -396.585273)
			(xy 89.970291 -396.646838) (xy 89.945797 -396.705702) (xy 89.930224 -396.733522) (xy 89.929462 -396.734792)
			(xy 89.929208 -396.7353) (xy 89.926668 -396.739872) (xy 89.922096 -396.753842) (xy 89.920968 -396.757554)
			(xy 89.919691 -396.765205) (xy 89.919556 -396.769082) (xy 89.919556 -397.519652) (xy 89.92235 -397.52778)
			(xy 89.92616 -397.53921) (xy 89.926922 -397.540734) (xy 89.928954 -397.544036) (xy 89.936441 -397.557291)
			(xy 91.224968 -397.557291) (xy 91.233749 -397.492447) (xy 91.251154 -397.429369) (xy 91.276868 -397.369198)
			(xy 91.293188 -397.340836) (xy 91.296489 -397.334805) (xy 91.300104 -397.321546) (xy 91.3003 -397.314674)
			(xy 91.3003 -397.028924) (xy 91.300741 -397.018771) (xy 91.308529 -397.000019) (xy 91.32292 -396.985695)
			(xy 91.341708 -396.977995) (xy 91.351862 -396.977616) (xy 92.068142 -396.977616) (xy 92.078268 -396.978091)
			(xy 92.096986 -396.985829) (xy 92.11134 -397.000118) (xy 92.119162 -397.0188) (xy 92.119704 -397.028924)
			(xy 92.119704 -397.314674) (xy 92.119906 -397.321547) (xy 92.123507 -397.334809) (xy 92.126816 -397.340836)
			(xy 92.143148 -397.369192) (xy 92.168867 -397.429364) (xy 92.186276 -397.492444) (xy 92.195059 -397.55729)
			(xy 92.195058 -397.622728) (xy 92.186273 -397.687573) (xy 92.168862 -397.750652) (xy 92.14314 -397.810823)
			(xy 92.126816 -397.839184) (xy 92.123508 -397.845212) (xy 92.119898 -397.858473) (xy 92.119704 -397.865346)
			(xy 92.119704 -398.6149) (xy 92.119895 -398.621773) (xy 92.123504 -398.635036) (xy 92.126816 -398.641062)
			(xy 92.142497 -398.66824) (xy 100.573076 -398.66824) (xy 100.577147 -398.612618) (xy 100.589273 -398.558181)
			(xy 100.609196 -398.50609) (xy 100.636492 -398.457455) (xy 100.670578 -398.413312) (xy 100.710727 -398.374603)
			(xy 100.756085 -398.342152) (xy 100.805685 -398.316651) (xy 100.858469 -398.298644) (xy 100.913312 -398.288514)
			(xy 100.969046 -398.286477) (xy 101.024483 -398.292577) (xy 101.07844 -398.306683) (xy 101.129769 -398.328495)
			(xy 101.177375 -398.357549) (xy 101.220243 -398.393224) (xy 101.25746 -398.434761) (xy 101.288233 -398.481274)
			(xy 101.311905 -398.531771) (xy 101.327973 -398.585178) (xy 101.336093 -398.640354) (xy 101.336602 -398.66824)
			(xy 101.589076 -398.66824) (xy 101.593147 -398.612618) (xy 101.605273 -398.558181) (xy 101.625196 -398.50609)
			(xy 101.652492 -398.457455) (xy 101.686578 -398.413312) (xy 101.726727 -398.374603) (xy 101.772085 -398.342152)
			(xy 101.821685 -398.316651) (xy 101.874469 -398.298644) (xy 101.929312 -398.288514) (xy 101.985046 -398.286477)
			(xy 102.040483 -398.292577) (xy 102.09444 -398.306683) (xy 102.145769 -398.328495) (xy 102.193375 -398.357549)
			(xy 102.236243 -398.393224) (xy 102.27346 -398.434761) (xy 102.304233 -398.481274) (xy 102.327905 -398.531771)
			(xy 102.343973 -398.585178) (xy 102.352093 -398.640354) (xy 102.352602 -398.66824) (xy 102.352491 -398.674336)
			(xy 105.653076 -398.674336) (xy 105.657147 -398.618714) (xy 105.669273 -398.564277) (xy 105.689196 -398.512186)
			(xy 105.716492 -398.463551) (xy 105.750578 -398.419408) (xy 105.790727 -398.380699) (xy 105.836085 -398.348248)
			(xy 105.885685 -398.322747) (xy 105.938469 -398.30474) (xy 105.993312 -398.29461) (xy 106.049046 -398.292573)
			(xy 106.104483 -398.298673) (xy 106.15844 -398.312779) (xy 106.209769 -398.334591) (xy 106.257375 -398.363645)
			(xy 106.300243 -398.39932) (xy 106.33746 -398.440857) (xy 106.368233 -398.48737) (xy 106.391905 -398.537867)
			(xy 106.407973 -398.591274) (xy 106.416093 -398.64645) (xy 106.416602 -398.674336) (xy 106.416093 -398.702222)
			(xy 106.407973 -398.757398) (xy 106.391905 -398.810805) (xy 106.368233 -398.861302) (xy 106.33746 -398.907815)
			(xy 106.300243 -398.949352) (xy 106.257375 -398.985027) (xy 106.209769 -399.014081) (xy 106.15844 -399.035893)
			(xy 106.104483 -399.049999) (xy 106.049046 -399.056099) (xy 105.993312 -399.054062) (xy 105.938469 -399.043932)
			(xy 105.885685 -399.025925) (xy 105.836085 -399.000424) (xy 105.790727 -398.967973) (xy 105.750578 -398.929264)
			(xy 105.716492 -398.885121) (xy 105.689196 -398.836486) (xy 105.669273 -398.784395) (xy 105.657147 -398.729958)
			(xy 105.653076 -398.674336) (xy 102.352491 -398.674336) (xy 102.352093 -398.696126) (xy 102.343973 -398.751302)
			(xy 102.327905 -398.804709) (xy 102.304233 -398.855206) (xy 102.27346 -398.901719) (xy 102.236243 -398.943256)
			(xy 102.193375 -398.978931) (xy 102.145769 -399.007985) (xy 102.09444 -399.029797) (xy 102.040483 -399.043903)
			(xy 101.985046 -399.050003) (xy 101.929312 -399.047966) (xy 101.874469 -399.037836) (xy 101.821685 -399.019829)
			(xy 101.772085 -398.994328) (xy 101.726727 -398.961877) (xy 101.686578 -398.923168) (xy 101.652492 -398.879025)
			(xy 101.625196 -398.83039) (xy 101.605273 -398.778299) (xy 101.593147 -398.723862) (xy 101.589076 -398.66824)
			(xy 101.336602 -398.66824) (xy 101.336093 -398.696126) (xy 101.327973 -398.751302) (xy 101.311905 -398.804709)
			(xy 101.288233 -398.855206) (xy 101.25746 -398.901719) (xy 101.220243 -398.943256) (xy 101.177375 -398.978931)
			(xy 101.129769 -399.007985) (xy 101.07844 -399.029797) (xy 101.024483 -399.043903) (xy 100.969046 -399.050003)
			(xy 100.913312 -399.047966) (xy 100.858469 -399.037836) (xy 100.805685 -399.019829) (xy 100.756085 -398.994328)
			(xy 100.710727 -398.961877) (xy 100.670578 -398.923168) (xy 100.636492 -398.879025) (xy 100.609196 -398.83039)
			(xy 100.589273 -398.778299) (xy 100.577147 -398.723862) (xy 100.573076 -398.66824) (xy 92.142497 -398.66824)
			(xy 92.14317 -398.669406) (xy 92.168887 -398.729581) (xy 92.186294 -398.792663) (xy 92.195074 -398.857511)
			(xy 92.19507 -398.922951) (xy 92.186281 -398.987798) (xy 92.168867 -399.050878) (xy 92.143142 -399.111049)
			(xy 92.126816 -399.13941) (xy 92.123499 -399.145433) (xy 92.119894 -399.158698) (xy 92.119704 -399.165572)
			(xy 92.119704 -399.451576) (xy 92.119259 -399.461728) (xy 92.111472 -399.480479) (xy 92.097082 -399.494803)
			(xy 92.078296 -399.502505) (xy 92.068142 -399.502884) (xy 91.351862 -399.502884) (xy 91.341736 -399.502405)
			(xy 91.323018 -399.494669) (xy 91.308664 -399.480381) (xy 91.300842 -399.4617) (xy 91.3003 -399.451576)
			(xy 91.3003 -399.165572) (xy 91.300119 -399.158698) (xy 91.296503 -399.145435) (xy 91.293188 -399.13941)
			(xy 91.276898 -399.111031) (xy 91.25118 -399.050864) (xy 91.23377 -398.987789) (xy 91.224984 -398.922948)
			(xy 91.22498 -398.857514) (xy 91.233758 -398.792672) (xy 91.25116 -398.729595) (xy 91.27687 -398.669424)
			(xy 91.293188 -398.641062) (xy 91.296515 -398.635044) (xy 91.300113 -398.621775) (xy 91.3003 -398.6149)
			(xy 91.3003 -397.865346) (xy 91.30009 -397.858474) (xy 91.296494 -397.845211) (xy 91.293188 -397.839184)
			(xy 91.276876 -397.810818) (xy 91.25116 -397.750647) (xy 91.233753 -397.687569) (xy 91.224969 -397.622726)
			(xy 91.224968 -397.557291) (xy 89.936441 -397.557291) (xy 89.944811 -397.572108) (xy 89.969791 -397.631545)
			(xy 89.986692 -397.693764) (xy 89.995217 -397.757671) (xy 89.995756 -397.789908) (xy 89.995756 -397.790162)
			(xy 89.995241 -397.822041) (xy 89.986872 -397.885247) (xy 89.970299 -397.946813) (xy 89.945808 -398.00568)
			(xy 89.930224 -398.033494) (xy 89.929462 -398.034764) (xy 89.929208 -398.035272) (xy 89.926668 -398.039844)
			(xy 89.922096 -398.053814) (xy 89.920966 -398.057525) (xy 89.919685 -398.065177) (xy 89.919556 -398.069054)
			(xy 89.919556 -398.351502) (xy 89.91913 -398.361673) (xy 89.911344 -398.380466) (xy 89.896959 -398.394849)
			(xy 89.878165 -398.402631) (xy 89.867994 -398.403064) (xy 89.50706 -398.403064) (xy 89.501726 -398.403318)
			(xy 89.496451 -398.404047) (xy 89.486342 -398.407384) (xy 89.48166 -398.409922) (xy 89.48166 -399.833592)
			(xy 89.482095 -399.843288) (xy 89.489281 -399.861302) (xy 89.49563 -399.868644) (xy 89.516458 -399.890234)
			(xy 89.523086 -399.896727) (xy 89.539765 -399.904819) (xy 89.54897 -399.905982) (xy 89.58031 -399.909012)
			(xy 89.641888 -399.922145) (xy 89.701254 -399.943125) (xy 89.75741 -399.971601) (xy 89.809416 -400.007094)
			(xy 89.856399 -400.049011) (xy 89.897571 -400.096648) (xy 89.932242 -400.149206) (xy 89.959831 -400.205803)
			(xy 89.979874 -400.265491) (xy 89.992036 -400.327269) (xy 89.996113 -400.3901) (xy 89.992036 -400.452932)
			(xy 89.979874 -400.51471) (xy 89.95983 -400.574398) (xy 89.932242 -400.630995) (xy 89.897571 -400.683553)
			(xy 89.856398 -400.73119) (xy 89.809415 -400.773106) (xy 89.757409 -400.8086) (xy 89.701253 -400.837076)
			(xy 89.641887 -400.858056) (xy 89.580309 -400.871188) (xy 89.54897 -400.87423) (xy 89.539793 -400.875481)
			(xy 89.523145 -400.883567) (xy 89.516458 -400.889978) (xy 89.49563 -400.911568) (xy 89.489256 -400.918892)
			(xy 89.482091 -400.936919) (xy 89.48166 -400.94662) (xy 89.48166 -401.133564) (xy 89.48209 -401.143262)
			(xy 89.489269 -401.161283) (xy 89.49563 -401.168616) (xy 89.516458 -401.190206) (xy 89.52309 -401.196692)
			(xy 89.539769 -401.204772) (xy 89.54897 -401.205954) (xy 89.580311 -401.208984) (xy 89.641894 -401.222117)
			(xy 89.701263 -401.243098) (xy 89.757422 -401.271575) (xy 89.809431 -401.307071) (xy 89.856417 -401.34899)
			(xy 89.897592 -401.396629) (xy 89.932265 -401.44919) (xy 89.952247 -401.49018) (xy 91.223854 -401.49018)
			(xy 91.227845 -401.428013) (xy 91.239754 -401.366866) (xy 91.259383 -401.307745) (xy 91.286412 -401.251619)
			(xy 91.320396 -401.19941) (xy 91.360778 -401.151975) (xy 91.406894 -401.110094) (xy 91.457986 -401.074454)
			(xy 91.513217 -401.04564) (xy 91.571679 -401.024126) (xy 91.632413 -401.010264) (xy 91.69442 -401.004282)
			(xy 91.756683 -401.006278) (xy 91.81818 -401.016221) (xy 91.877901 -401.033945) (xy 91.934864 -401.059162)
			(xy 91.988135 -401.091455) (xy 92.03684 -401.130295) (xy 92.080177 -401.175045) (xy 92.117437 -401.224969)
			(xy 92.148006 -401.279248) (xy 92.171384 -401.336991) (xy 92.187185 -401.397249) (xy 92.195151 -401.459032)
			(xy 92.19565 -401.49018) (xy 92.195151 -401.521328) (xy 92.187185 -401.583111) (xy 92.171384 -401.643369)
			(xy 92.148006 -401.701112) (xy 92.117437 -401.755391) (xy 92.080177 -401.805315) (xy 92.03684 -401.850065)
			(xy 91.988135 -401.888905) (xy 91.934864 -401.921198) (xy 91.877901 -401.946415) (xy 91.81818 -401.964139)
			(xy 91.756683 -401.974082) (xy 91.69442 -401.976078) (xy 91.632413 -401.970096) (xy 91.571679 -401.956234)
			(xy 91.513217 -401.93472) (xy 91.457986 -401.905906) (xy 91.406894 -401.870266) (xy 91.360778 -401.828385)
			(xy 91.320396 -401.78095) (xy 91.286412 -401.728741) (xy 91.259383 -401.672615) (xy 91.239754 -401.613494)
			(xy 91.227845 -401.552347) (xy 91.223854 -401.49018) (xy 89.952247 -401.49018) (xy 89.959856 -401.50579)
			(xy 89.979901 -401.565482) (xy 89.992064 -401.627263) (xy 89.996141 -401.690098) (xy 89.992064 -401.752933)
			(xy 89.979901 -401.814715) (xy 89.959857 -401.874406) (xy 89.932267 -401.931007) (xy 89.897594 -401.983568)
			(xy 89.85642 -402.031208) (xy 89.809434 -402.073127) (xy 89.757425 -402.108623) (xy 89.701266 -402.1371)
			(xy 89.641897 -402.158082) (xy 89.580315 -402.171215) (xy 89.54897 -402.174202) (xy 89.539792 -402.175452)
			(xy 89.523142 -402.183535) (xy 89.516458 -402.18995) (xy 89.49563 -402.21154) (xy 89.489252 -402.218863)
			(xy 89.482076 -402.236889) (xy 89.48166 -402.246592) (xy 89.48166 -402.790152) (xy 91.223854 -402.790152)
			(xy 91.227845 -402.727985) (xy 91.239754 -402.666838) (xy 91.259383 -402.607717) (xy 91.286412 -402.551591)
			(xy 91.320396 -402.499382) (xy 91.360778 -402.451947) (xy 91.406894 -402.410066) (xy 91.457986 -402.374426)
			(xy 91.513217 -402.345612) (xy 91.571679 -402.324098) (xy 91.632413 -402.310236) (xy 91.69442 -402.304254)
			(xy 91.756683 -402.30625) (xy 91.81818 -402.316193) (xy 91.877901 -402.333917) (xy 91.934864 -402.359134)
			(xy 91.988135 -402.391427) (xy 92.03684 -402.430267) (xy 92.080177 -402.475017) (xy 92.117437 -402.524941)
			(xy 92.148006 -402.57922) (xy 92.171384 -402.636963) (xy 92.187185 -402.697221) (xy 92.195151 -402.759004)
			(xy 92.19565 -402.790152) (xy 92.195151 -402.8213) (xy 92.187185 -402.883083) (xy 92.171384 -402.943341)
			(xy 92.148006 -403.001084) (xy 92.117437 -403.055363) (xy 92.080177 -403.105287) (xy 92.03684 -403.150037)
			(xy 91.988135 -403.188877) (xy 91.934864 -403.22117) (xy 91.877901 -403.246387) (xy 91.81818 -403.264111)
			(xy 91.756683 -403.274054) (xy 91.69442 -403.27605) (xy 91.632413 -403.270068) (xy 91.571679 -403.256206)
			(xy 91.513217 -403.234692) (xy 91.457986 -403.205878) (xy 91.406894 -403.170238) (xy 91.360778 -403.128357)
			(xy 91.320396 -403.080922) (xy 91.286412 -403.028713) (xy 91.259383 -402.972587) (xy 91.239754 -402.913466)
			(xy 91.227845 -402.852319) (xy 91.223854 -402.790152) (xy 89.48166 -402.790152) (xy 89.48166 -403.733508)
			(xy 89.48208 -403.743211) (xy 89.489245 -403.761245) (xy 89.49563 -403.76856) (xy 89.516458 -403.79015)
			(xy 89.523087 -403.796642) (xy 89.539766 -403.804731) (xy 89.54897 -403.805898) (xy 89.580309 -403.808928)
			(xy 89.641885 -403.82206) (xy 89.701249 -403.84304) (xy 89.757403 -403.871515) (xy 89.809407 -403.907008)
			(xy 89.856388 -403.948923) (xy 89.897559 -403.996558) (xy 89.932229 -404.049115) (xy 89.959817 -404.10571)
			(xy 89.979859 -404.165397) (xy 89.992021 -404.227172) (xy 89.996097 -404.290002) (xy 89.99202 -404.352831)
			(xy 89.979858 -404.414607) (xy 89.959815 -404.474293) (xy 89.932227 -404.530888) (xy 89.897557 -404.583444)
			(xy 89.856386 -404.631079) (xy 89.809404 -404.672994) (xy 89.7574 -404.708487) (xy 89.701245 -404.736961)
			(xy 89.641882 -404.757941) (xy 89.580305 -404.771072) (xy 89.54897 -404.774146) (xy 89.539791 -404.775394)
			(xy 89.523134 -404.783471) (xy 89.516458 -404.789894) (xy 89.49563 -404.811484) (xy 89.489243 -404.818804)
			(xy 89.482048 -404.83683) (xy 89.48166 -404.846536) (xy 89.48166 -405.03348) (xy 89.482093 -405.043177)
			(xy 89.489276 -405.061193) (xy 89.49563 -405.068532) (xy 89.516458 -405.090122) (xy 89.523091 -405.096606)
			(xy 89.53977 -405.104683) (xy 89.54897 -405.10587) (xy 89.579011 -405.108741) (xy 89.638105 -405.120989)
			(xy 89.695225 -405.140466) (xy 89.749491 -405.16687) (xy 89.800067 -405.199796) (xy 89.846174 -405.238735)
			(xy 89.887099 -405.283088) (xy 89.922213 -405.33217) (xy 89.950974 -405.385225) (xy 89.972939 -405.441435)
			(xy 89.98777 -405.499934) (xy 89.995237 -405.559819) (xy 89.995756 -405.589994) (xy 89.995258 -405.621808)
			(xy 89.986953 -405.684892) (xy 89.970485 -405.746353) (xy 89.946134 -405.805137) (xy 89.914319 -405.86024)
			(xy 89.875583 -405.910719) (xy 89.830589 -405.955709) (xy 89.780107 -405.994441) (xy 89.725001 -406.026252)
			(xy 89.666215 -406.050598) (xy 89.604753 -406.067061) (xy 89.541668 -406.075361) (xy 89.509854 -406.075896)
			(xy 89.496681 -406.07576) (xy 89.470377 -406.074236) (xy 89.457276 -406.072848) (xy 89.445592 -406.071578)
			(xy 89.434924 -406.075388) (xy 89.429613 -406.077394) (xy 89.419995 -406.083422) (xy 89.415874 -406.087326)
			(xy 89.358724 -406.144476) (xy 89.355168 -406.150826) (xy 89.330022 -406.193752) (xy 89.323164 -406.211532)
			(xy 89.317176 -406.240724) (xy 89.29735 -406.296917) (xy 89.269027 -406.349343) (xy 89.232896 -406.396728)
			(xy 89.189836 -406.437917) (xy 89.165684 -406.455372) (xy 89.140518 -406.472162) (xy 89.08603 -406.498445)
			(xy 89.057226 -406.507696) (xy 89.049606 -406.509982) (xy 88.836652 -406.722792) (xy 91.224945 -406.722792)
			(xy 91.224949 -406.657353) (xy 91.233736 -406.592508) (xy 91.251146 -406.529428) (xy 91.276865 -406.469256)
			(xy 91.293188 -406.440894) (xy 91.296504 -406.43487) (xy 91.300109 -406.421606) (xy 91.3003 -406.414732)
			(xy 91.3003 -405.665432) (xy 91.300096 -405.65856) (xy 91.296496 -405.645297) (xy 91.293188 -405.63927)
			(xy 91.276864 -405.61091) (xy 91.251149 -405.550738) (xy 91.233743 -405.487659) (xy 91.224961 -405.422815)
			(xy 91.224962 -405.357378) (xy 91.233745 -405.292534) (xy 91.251152 -405.229455) (xy 91.276867 -405.169284)
			(xy 91.293188 -405.140922) (xy 91.296494 -405.134893) (xy 91.300105 -405.121633) (xy 91.3003 -405.11476)
			(xy 91.3003 -404.828756) (xy 91.300686 -404.818599) (xy 91.308496 -404.799846) (xy 91.322903 -404.785524)
			(xy 91.341703 -404.777826) (xy 91.351862 -404.777448) (xy 92.068142 -404.777448) (xy 92.078272 -404.777892)
			(xy 92.096996 -404.785635) (xy 92.111351 -404.799934) (xy 92.119167 -404.818628) (xy 92.119704 -404.828756)
			(xy 92.119704 -405.11476) (xy 92.119911 -405.121632) (xy 92.123509 -405.134895) (xy 92.126816 -405.140922)
			(xy 92.143136 -405.169285) (xy 92.168857 -405.229455) (xy 92.186267 -405.292533) (xy 92.195051 -405.357378)
			(xy 92.195052 -405.422815) (xy 92.186268 -405.48766) (xy 92.168859 -405.550739) (xy 92.143139 -405.610909)
			(xy 92.126816 -405.63927) (xy 92.123513 -405.6453) (xy 92.1199 -405.65856) (xy 92.119704 -405.665432)
			(xy 92.119704 -406.414732) (xy 92.119883 -406.421606) (xy 92.1235 -406.434869) (xy 92.126816 -406.440894)
			(xy 92.143113 -406.46927) (xy 92.168835 -406.529437) (xy 92.186248 -406.592513) (xy 92.195036 -406.657355)
			(xy 92.195039 -406.72279) (xy 92.186259 -406.787633) (xy 92.168853 -406.850711) (xy 92.143137 -406.910881)
			(xy 92.126816 -406.939242) (xy 92.123487 -406.94526) (xy 92.11989 -406.958529) (xy 92.119704 -406.965404)
			(xy 92.119704 -407.251408) (xy 92.119285 -407.261562) (xy 92.111487 -407.280314) (xy 92.09709 -407.294637)
			(xy 92.078298 -407.302337) (xy 92.068142 -407.302716) (xy 91.351862 -407.302716) (xy 91.341727 -407.302303)
			(xy 91.322997 -407.294555) (xy 91.308641 -407.280246) (xy 91.30083 -407.261541) (xy 91.3003 -407.251408)
			(xy 91.3003 -406.965404) (xy 91.300107 -406.958531) (xy 91.2965 -406.945268) (xy 91.293188 -406.939242)
			(xy 91.27684 -406.910895) (xy 91.251128 -406.85072) (xy 91.233725 -406.787638) (xy 91.224945 -406.722792)
			(xy 88.836652 -406.722792) (xy 88.673178 -406.886156) (xy 88.640394 -406.918248) (xy 88.569875 -406.976942)
			(xy 88.494264 -407.02891) (xy 88.454484 -407.051764) (xy 88.448134 -407.05532) (xy 88.352122 -407.151332)
			(xy 88.348566 -407.154634) (xy 88.34628 -407.156412) (xy 88.33739 -407.165302) (xy 88.324182 -407.165302)
			(xy 88.321642 -407.165556) (xy 88.316562 -407.16581) (xy 88.246204 -407.16581) (xy 88.239897 -407.1669)
			(xy 88.228068 -407.171776) (xy 88.222836 -407.175462) (xy 88.101424 -407.297128) (xy 88.099392 -407.299668)
			(xy 88.073094 -407.332993) (xy 88.015673 -407.395527) (xy 87.953142 -407.452953) (xy 87.919814 -407.479246)
			(xy 87.917782 -407.48077) (xy 87.73414 -407.664412) (xy 87.730584 -407.667714) (xy 87.728298 -407.669492)
			(xy 87.719408 -407.678382) (xy 87.7062 -407.678382) (xy 87.70366 -407.678636) (xy 87.69858 -407.67889)
			(xy 87.440008 -407.67889) (xy 87.436706 -407.679398) (xy 87.405153 -407.683132) (xy 87.341732 -407.687073)
			(xy 87.30996 -407.687272) (xy 87.278188 -407.687079) (xy 87.214766 -407.683137) (xy 87.183214 -407.679398)
			(xy 87.179912 -407.67889) (xy 86.92134 -407.67889) (xy 86.91626 -407.678636) (xy 86.91372 -407.678382)
			(xy 86.900512 -407.678382) (xy 86.891622 -407.669492) (xy 86.889336 -407.667714) (xy 86.88578 -407.664412)
			(xy 86.854538 -407.63317) (xy 86.850805 -407.629652) (xy 86.842227 -407.624032) (xy 86.83752 -407.621994)
			(xy 86.828884 -407.618438) (xy 86.810088 -407.618438) (xy 86.806278 -407.618946) (xy 86.7791 -407.622248)
			(xy 86.758526 -407.623518) (xy 86.74481 -407.623518) (xy 86.721568 -407.623003) (xy 86.675464 -407.61702)
			(xy 86.652862 -407.61158) (xy 86.628623 -407.604941) (xy 86.58201 -407.58615) (xy 86.538273 -407.561393)
			(xy 86.517988 -407.546556) (xy 86.491064 -407.524204) (xy 86.487 -407.520394) (xy 86.466426 -407.508456)
			(xy 86.459822 -407.506678) (xy 86.431882 -407.498804) (xy 86.42223 -407.49982) (xy 86.411572 -407.500348)
			(xy 86.39132 -407.493706) (xy 86.37551 -407.479413) (xy 86.366866 -407.459931) (xy 86.36635 -407.449274)
			(xy 86.36635 -407.240994) (xy 86.366538 -407.225683) (xy 86.36908 -407.195165) (xy 86.37143 -407.180034)
			(xy 86.371684 -407.178002) (xy 86.371938 -407.175208) (xy 86.372194 -407.164302) (xy 86.36457 -407.143885)
			(xy 86.357206 -407.135838) (xy 86.335616 -407.114248) (xy 86.332314 -407.110692) (xy 86.330536 -407.108406)
			(xy 86.321646 -407.099516) (xy 86.321646 -407.086308) (xy 86.321392 -407.083768) (xy 86.321138 -407.078688)
			(xy 86.321138 -406.820116) (xy 86.32063 -406.816814) (xy 86.316896 -406.785261) (xy 86.312954 -406.72184)
			(xy 86.312756 -406.690068) (xy 86.312756 -406.308052) (xy 86.312949 -406.27628) (xy 86.316892 -406.212858)
			(xy 86.32063 -406.181306) (xy 86.321138 -406.178004) (xy 86.321138 -406.043892) (xy 86.320767 -406.035103)
			(xy 86.314812 -406.018566) (xy 86.303607 -406.005022) (xy 86.296246 -406.000204) (xy 86.209124 -405.948642)
			(xy 86.182454 -405.948134) (xy 86.170516 -405.954738) (xy 86.156377 -405.96251) (xy 86.127669 -405.977244)
			(xy 86.113112 -405.984202) (xy 86.091014 -406.004014) (xy 86.08314 -406.014174) (xy 85.903054 -406.194514)
			(xy 85.901022 -406.197054) (xy 85.874018 -406.231476) (xy 85.814879 -406.295959) (xy 85.750314 -406.355008)
			(xy 85.715856 -406.381966) (xy 85.713316 -406.383998) (xy 85.533992 -406.563322) (xy 85.52665 -406.57014)
			(xy 85.508187 -406.577881) (xy 85.498178 -406.578308) (xy 85.24367 -406.578308) (xy 85.240368 -406.578816)
			(xy 85.197033 -406.584095) (xy 85.109812 -406.587939) (xy 85.022591 -406.584095) (xy 84.979256 -406.578816)
			(xy 84.975954 -406.578308) (xy 84.721446 -406.578308) (xy 84.711455 -406.577779) (xy 84.69301 -406.570078)
			(xy 84.685632 -406.563322) (xy 84.657692 -406.535382) (xy 84.657438 -406.535382) (xy 84.645754 -406.523698)
			(xy 84.638134 -406.521412) (xy 84.273136 -406.886156) (xy 84.239483 -406.919064) (xy 84.166968 -406.979083)
			(xy 84.089118 -407.031999) (xy 84.006626 -407.07734) (xy 83.920227 -407.114702) (xy 83.875626 -407.129742)
			(xy 83.869965 -407.131789) (xy 83.859704 -407.138077) (xy 83.855306 -407.142188) (xy 83.745324 -407.252424)
			(xy 83.70316 -407.294588) (xy 83.701128 -407.297128) (xy 83.674125 -407.331551) (xy 83.614987 -407.396035)
			(xy 83.550424 -407.455086) (xy 83.515962 -407.48204) (xy 83.513422 -407.484072) (xy 83.334098 -407.663396)
			(xy 83.326753 -407.670207) (xy 83.308291 -407.677939) (xy 83.298284 -407.678382) (xy 83.043776 -407.678382)
			(xy 83.040474 -407.67889) (xy 83.007982 -407.682864) (xy 82.942651 -407.687061) (xy 82.909918 -407.687272)
			(xy 82.877185 -407.687058) (xy 82.811854 -407.682864) (xy 82.779362 -407.67889) (xy 82.77606 -407.678382)
			(xy 82.521552 -407.678382) (xy 82.511561 -407.677854) (xy 82.493117 -407.670151) (xy 82.485738 -407.663396)
			(xy 82.454496 -407.632408) (xy 82.450146 -407.628234) (xy 82.439874 -407.62193) (xy 82.434176 -407.619962)
			(xy 82.422746 -407.616406) (xy 82.410554 -407.618438) (xy 82.410046 -407.618438) (xy 82.406236 -407.618946)
			(xy 82.382106 -407.621994) (xy 82.358484 -407.623518) (xy 82.344768 -407.623518) (xy 82.317658 -407.622827)
			(xy 82.264038 -407.614721) (xy 82.212105 -407.599105) (xy 82.162907 -407.576293) (xy 82.117435 -407.546745)
			(xy 82.076605 -407.511055) (xy 82.04124 -407.469944) (xy 82.012053 -407.424239) (xy 81.989631 -407.374862)
			(xy 81.974427 -407.322808) (xy 81.966747 -407.269125) (xy 81.966308 -407.24201) (xy 81.966308 -407.236422)
			(xy 81.966609 -407.222838) (xy 81.968897 -407.195762) (xy 81.97088 -407.18232) (xy 81.971134 -407.180796)
			(xy 81.971388 -407.178002) (xy 81.971642 -407.173176) (xy 81.971651 -407.162634) (xy 81.964177 -407.142946)
			(xy 81.957164 -407.135076) (xy 81.936844 -407.114502) (xy 81.93659 -407.114248) (xy 81.929789 -407.106899)
			(xy 81.922077 -407.088437) (xy 81.921604 -407.078434) (xy 81.921604 -406.823926) (xy 81.921096 -406.820624)
			(xy 81.917052 -406.788137) (xy 81.912732 -406.722805) (xy 81.91246 -406.690068) (xy 81.91246 -406.308052)
			(xy 81.912728 -406.275315) (xy 81.917047 -406.209983) (xy 81.921096 -406.177496) (xy 81.921604 -406.174194)
			(xy 81.921604 -406.043638) (xy 81.921242 -406.034843) (xy 81.915301 -406.018288) (xy 81.904108 -406.00472)
			(xy 81.896712 -405.99995) (xy 81.821274 -405.9555) (xy 81.815307 -405.952212) (xy 81.802175 -405.948602)
			(xy 81.795366 -405.948388) (xy 81.770982 -405.954738) (xy 81.756779 -405.962511) (xy 81.727945 -405.977246)
			(xy 81.713324 -405.984202) (xy 81.706597 -405.987628) (xy 81.695361 -405.997698) (xy 81.691226 -406.004014)
			(xy 81.683352 -406.014174) (xy 81.503266 -406.194514) (xy 81.501234 -406.197054) (xy 81.474231 -406.231477)
			(xy 81.415092 -406.29596) (xy 81.350528 -406.35501) (xy 81.316068 -406.381966) (xy 81.313528 -406.383998)
			(xy 81.134204 -406.563322) (xy 81.126863 -406.570141) (xy 81.1084 -406.577888) (xy 81.09839 -406.578308)
			(xy 80.843882 -406.578308) (xy 80.84058 -406.578816) (xy 80.797245 -406.584095) (xy 80.710024 -406.587939)
			(xy 80.622803 -406.584095) (xy 80.579468 -406.578816) (xy 80.576166 -406.578308) (xy 80.321658 -406.578308)
			(xy 80.311674 -406.577763) (xy 80.293252 -406.57004) (xy 80.285844 -406.563322) (xy 80.257904 -406.535382)
			(xy 80.25765 -406.535382) (xy 80.245966 -406.523698) (xy 80.238092 -406.521158) (xy 79.873094 -406.886156)
			(xy 79.83944 -406.919063) (xy 79.766924 -406.979079) (xy 79.689073 -407.031992) (xy 79.60658 -407.077329)
			(xy 79.52018 -407.114688) (xy 79.475584 -407.129742) (xy 79.46992 -407.131784) (xy 79.45965 -407.138064)
			(xy 79.455264 -407.142188) (xy 79.345282 -407.252424) (xy 79.303118 -407.294588) (xy 79.301086 -407.297128)
			(xy 79.274082 -407.33155) (xy 79.214943 -407.396033) (xy 79.150378 -407.455081) (xy 79.11592 -407.48204)
			(xy 79.11338 -407.484072) (xy 78.934056 -407.663396) (xy 78.926709 -407.6702) (xy 78.908246 -407.677917)
			(xy 78.898242 -407.678382) (xy 78.643734 -407.678382) (xy 78.640432 -407.67889) (xy 78.60794 -407.682863)
			(xy 78.542609 -407.687057) (xy 78.509876 -407.687272) (xy 78.477143 -407.687056) (xy 78.411812 -407.682859)
			(xy 78.37932 -407.67889) (xy 78.376018 -407.678382) (xy 78.12151 -407.678382) (xy 78.111522 -407.677846)
			(xy 78.093089 -407.670133) (xy 78.085696 -407.663396) (xy 78.054454 -407.632408) (xy 78.050102 -407.628237)
			(xy 78.039827 -407.621941) (xy 78.034134 -407.619962) (xy 78.022704 -407.616406) (xy 78.010512 -407.618438)
			(xy 78.010004 -407.618438) (xy 78.006194 -407.618946) (xy 77.982064 -407.621994) (xy 77.958442 -407.623518)
			(xy 77.944726 -407.623518) (xy 77.921484 -407.623004) (xy 77.87538 -407.617022) (xy 77.852778 -407.61158)
			(xy 77.828541 -407.604936) (xy 77.781934 -407.586137) (xy 77.738203 -407.561372) (xy 77.717904 -407.546556)
			(xy 77.69098 -407.524204) (xy 77.686916 -407.520394) (xy 77.666342 -407.508456) (xy 77.659738 -407.506678)
			(xy 77.631798 -407.498804) (xy 77.622146 -407.49982) (xy 77.6115 -407.500332) (xy 77.591279 -407.493672)
			(xy 77.575498 -407.479382) (xy 77.566872 -407.459919) (xy 77.566266 -407.449274) (xy 77.566266 -407.240994)
			(xy 77.566429 -407.225492) (xy 77.568975 -407.194593) (xy 77.571346 -407.179272) (xy 77.572108 -407.174954)
			(xy 77.572108 -407.170128) (xy 77.571679 -407.162605) (xy 77.567029 -407.148279) (xy 77.562964 -407.141934)
			(xy 77.557122 -407.134822) (xy 77.536548 -407.114248) (xy 77.52974 -407.106902) (xy 77.522019 -407.088439)
			(xy 77.521562 -407.078434) (xy 77.521562 -406.823926) (xy 77.521054 -406.820624) (xy 77.517081 -406.788132)
			(xy 77.512888 -406.722801) (xy 77.512672 -406.690068) (xy 77.512672 -406.308052) (xy 77.512885 -406.275319)
			(xy 77.517077 -406.209987) (xy 77.521054 -406.177496) (xy 77.521562 -406.174194) (xy 77.521562 -406.043638)
			(xy 77.521199 -406.034845) (xy 77.515255 -406.018293) (xy 77.504057 -406.004733) (xy 77.49667 -405.99995)
			(xy 77.421232 -405.9555) (xy 77.415264 -405.952217) (xy 77.402132 -405.948618) (xy 77.395324 -405.948388)
			(xy 77.37094 -405.954738) (xy 77.356737 -405.96251) (xy 77.327902 -405.977245) (xy 77.313282 -405.984202)
			(xy 77.30655 -405.987622) (xy 77.295303 -405.997686) (xy 77.291184 -406.004014) (xy 77.28331 -406.014174)
			(xy 77.103478 -406.19426) (xy 77.101446 -406.1968) (xy 77.074512 -406.231162) (xy 77.015532 -406.295544)
			(xy 76.951149 -406.354523) (xy 76.916788 -406.381458) (xy 76.914248 -406.38349) (xy 76.734162 -406.563322)
			(xy 76.726819 -406.570135) (xy 76.708355 -406.577866) (xy 76.698348 -406.578308) (xy 76.44384 -406.578308)
			(xy 76.440538 -406.578816) (xy 76.397203 -406.584095) (xy 76.309982 -406.587939) (xy 76.222761 -406.584095)
			(xy 76.179426 -406.578816) (xy 76.176124 -406.578308) (xy 75.921616 -406.578308) (xy 75.911627 -406.577773)
			(xy 75.89319 -406.570065) (xy 75.885802 -406.563322) (xy 75.845924 -406.523698) (xy 75.838304 -406.521158)
			(xy 75.473052 -406.886156) (xy 75.439399 -406.919065) (xy 75.366885 -406.979085) (xy 75.289035 -407.032002)
			(xy 75.206544 -407.077344) (xy 75.120145 -407.114707) (xy 75.075542 -407.129742) (xy 75.06988 -407.131787)
			(xy 75.059617 -407.138073) (xy 75.055222 -407.142188) (xy 74.903838 -407.293572) (xy 74.901806 -407.296112)
			(xy 74.87482 -407.330625) (xy 74.815693 -407.395283) (xy 74.751112 -407.454493) (xy 74.71664 -407.481532)
			(xy 74.7141 -407.483564) (xy 74.534014 -407.663396) (xy 74.52667 -407.670209) (xy 74.508207 -407.677947)
			(xy 74.4982 -407.678382) (xy 74.243692 -407.678382) (xy 74.24039 -407.67889) (xy 74.207898 -407.682861)
			(xy 74.142567 -407.687052) (xy 74.109834 -407.687272) (xy 74.077101 -407.687058) (xy 74.01177 -407.682865)
			(xy 73.979278 -407.67889) (xy 73.975976 -407.678382) (xy 73.721468 -407.678382) (xy 73.711484 -407.677838)
			(xy 73.693062 -407.670115) (xy 73.685654 -407.663396) (xy 73.654412 -407.632408) (xy 73.650058 -407.628241)
			(xy 73.639781 -407.621953) (xy 73.634092 -407.619962) (xy 73.622662 -407.616406) (xy 73.61047 -407.618438)
			(xy 73.597603 -407.620479) (xy 73.571672 -407.623022) (xy 73.558654 -407.623518) (xy 73.544684 -407.623518)
			(xy 73.517573 -407.622828) (xy 73.463951 -407.614724) (xy 73.412017 -407.59911) (xy 73.362817 -407.576299)
			(xy 73.317343 -407.54675) (xy 73.276511 -407.511061) (xy 73.241144 -407.469949) (xy 73.211955 -407.424244)
			(xy 73.189532 -407.374865) (xy 73.174327 -407.32281) (xy 73.166647 -407.269125) (xy 73.166224 -407.24201)
			(xy 73.166224 -407.236422) (xy 73.166541 -407.222002) (xy 73.169081 -407.193269) (xy 73.171304 -407.179018)
			(xy 73.172066 -407.17089) (xy 73.17164 -407.160821) (xy 73.16392 -407.142223) (xy 73.15708 -407.134822)
			(xy 73.136506 -407.114248) (xy 73.129703 -407.1069) (xy 73.121988 -407.088438) (xy 73.12152 -407.078434)
			(xy 73.12152 -406.823926) (xy 73.121012 -406.820624) (xy 73.116968 -406.788137) (xy 73.112648 -406.722805)
			(xy 73.112376 -406.690068) (xy 73.112376 -406.308052) (xy 73.112644 -406.275315) (xy 73.116963 -406.209983)
			(xy 73.121012 -406.177496) (xy 73.12152 -406.174194) (xy 73.12152 -406.043638) (xy 73.121156 -406.034846)
			(xy 73.115209 -406.018298) (xy 73.104006 -406.004745) (xy 73.096628 -405.99995) (xy 73.02119 -405.9555)
			(xy 73.015223 -405.95221) (xy 73.002092 -405.948596) (xy 72.995282 -405.948388) (xy 72.970898 -405.954738)
			(xy 72.956694 -405.962509) (xy 72.927859 -405.977243) (xy 72.91324 -405.984202) (xy 72.906512 -405.987626)
			(xy 72.895272 -405.997695) (xy 72.891142 -406.004014) (xy 72.883268 -406.014174) (xy 72.703182 -406.194514)
			(xy 72.70115 -406.197054) (xy 72.674147 -406.231477) (xy 72.615009 -406.295961) (xy 72.550445 -406.355012)
			(xy 72.515984 -406.381966) (xy 72.513444 -406.383998) (xy 72.33412 -406.563322) (xy 72.326774 -406.570128)
			(xy 72.308311 -406.577844) (xy 72.298306 -406.578308) (xy 72.043798 -406.578308) (xy 72.040496 -406.578816)
			(xy 71.997161 -406.584095) (xy 71.90994 -406.587939) (xy 71.822719 -406.584095) (xy 71.779384 -406.578816)
			(xy 71.776082 -406.578308) (xy 71.521574 -406.578308) (xy 71.511589 -406.577766) (xy 71.493163 -406.570047)
			(xy 71.48576 -406.563322) (xy 71.45782 -406.535382) (xy 71.457566 -406.535382) (xy 71.454518 -406.532334)
			(xy 71.450165 -406.528165) (xy 71.439889 -406.521873) (xy 71.434198 -406.519888) (xy 71.422768 -406.516332)
			(xy 71.410576 -406.518364) (xy 71.394878 -406.520785) (xy 71.363214 -406.523332) (xy 71.34733 -406.523444)
			(xy 71.3201 -406.522926) (xy 71.266201 -406.515116) (xy 71.213961 -406.49972) (xy 71.16444 -406.477053)
			(xy 71.118646 -406.447574) (xy 71.077509 -406.411884) (xy 71.041865 -406.370706) (xy 71.012439 -406.324878)
			(xy 70.989828 -406.275332) (xy 70.974492 -406.223074) (xy 70.966743 -406.169167) (xy 70.96633 -406.141936)
			(xy 70.966438 -406.126889) (xy 70.96873 -406.096882) (xy 70.970902 -406.081992) (xy 70.971156 -406.07996)
			(xy 70.97141 -406.079198) (xy 70.971664 -406.07488) (xy 70.972068 -406.063872) (xy 70.964555 -406.043191)
			(xy 70.957186 -406.035002) (xy 70.936866 -406.014428) (xy 70.936612 -406.014174) (xy 70.929804 -406.006828)
			(xy 70.922079 -405.988365) (xy 70.921626 -405.97836) (xy 70.921626 -405.723852) (xy 70.921118 -405.72055)
			(xy 70.917145 -405.688058) (xy 70.91295 -405.622727) (xy 70.912736 -405.589994) (xy 70.912736 -405.207978)
			(xy 70.912952 -405.175245) (xy 70.917148 -405.109914) (xy 70.921118 -405.077422) (xy 70.921626 -405.07412)
			(xy 70.921626 -404.805896) (xy 70.921118 -404.802594) (xy 70.917146 -404.770102) (xy 70.912955 -404.704771)
			(xy 70.912736 -404.672038) (xy 70.912736 -404.290022) (xy 70.91295 -404.257289) (xy 70.917144 -404.191958)
			(xy 70.921118 -404.159466) (xy 70.921626 -404.156164) (xy 70.921626 -403.901656) (xy 70.922154 -403.891664)
			(xy 70.929856 -403.87322) (xy 70.936612 -403.865842) (xy 70.956932 -403.845522) (xy 70.964771 -403.836852)
			(xy 70.972317 -403.814757) (xy 70.97141 -403.803104) (xy 70.971156 -403.801326) (xy 70.968872 -403.786126)
			(xy 70.966452 -403.755482) (xy 70.96633 -403.740112) (xy 70.96633 -403.72792) (xy 70.967516 -403.701603)
			(xy 70.976229 -403.649648) (xy 70.992001 -403.599384) (xy 71.014533 -403.551766) (xy 71.043398 -403.507698)
			(xy 71.078048 -403.468016) (xy 71.117823 -403.433474) (xy 71.161969 -403.404729) (xy 71.209649 -403.382325)
			(xy 71.259955 -403.366689) (xy 71.285862 -403.361906) (xy 71.296784 -403.360128) (xy 71.31685 -403.34692)
			(xy 71.323454 -403.341332) (xy 71.335392 -403.329394) (xy 71.34352 -403.318726) (xy 71.35368 -403.300946)
			(xy 71.35368 -403.300438) (xy 71.374 -403.26437) (xy 71.376629 -403.258824) (xy 71.379456 -403.246884)
			(xy 71.379588 -403.240748) (xy 71.379334 -403.232366) (xy 71.377048 -403.221698) (xy 71.375524 -403.217634)
			(xy 71.375016 -403.216618) (xy 71.366126 -403.194266) (xy 71.360186 -403.177968) (xy 71.350021 -403.144799)
			(xy 71.345806 -403.127972) (xy 71.338374 -403.095577) (xy 71.3301 -403.029627) (xy 71.329296 -402.9964)
			(xy 71.329296 -402.987256) (xy 71.329915 -402.954069) (xy 71.337805 -402.88816) (xy 71.353158 -402.823581)
			(xy 71.375773 -402.761173) (xy 71.405355 -402.70175) (xy 71.441519 -402.646087) (xy 71.483793 -402.59491)
			(xy 71.531625 -402.548886) (xy 71.584393 -402.508615) (xy 71.641408 -402.474622) (xy 71.701926 -402.447351)
			(xy 71.73341 -402.436838) (xy 71.733664 -402.436838) (xy 71.741268 -402.434115) (xy 71.754357 -402.424669)
			(xy 71.759318 -402.418296) (xy 71.76389 -402.4122) (xy 71.768716 -402.39696) (xy 71.768716 -402.35378)
			(xy 71.768225 -402.343774) (xy 71.760562 -402.325286) (xy 71.746411 -402.311135) (xy 71.727922 -402.303474)
			(xy 71.717916 -402.30298) (xy 71.5518 -402.30298) (xy 71.542313 -402.302554) (xy 71.524601 -402.295751)
			(xy 71.510507 -402.283049) (xy 71.505826 -402.274786) (xy 71.505064 -402.273262) (xy 71.504302 -402.270976)
			(xy 71.502555 -402.266341) (xy 71.500642 -402.256623) (xy 71.500492 -402.251672) (xy 71.500492 -401.969986)
			(xy 71.498968 -401.958048) (xy 71.494904 -401.942808) (xy 71.491094 -401.936458) (xy 71.47517 -401.90834)
			(xy 71.450078 -401.848791) (xy 71.433101 -401.786441) (xy 71.424538 -401.722391) (xy 71.42454 -401.657771)
			(xy 71.433108 -401.593722) (xy 71.45009 -401.531373) (xy 71.475187 -401.471826) (xy 71.491094 -401.443698)
			(xy 71.494904 -401.437348) (xy 71.498968 -401.422108) (xy 71.500492 -401.41017) (xy 71.500492 -400.670014)
			(xy 71.498968 -400.658076) (xy 71.496682 -400.649694) (xy 71.492618 -400.639788) (xy 71.48957 -400.633438)
			(xy 71.474025 -400.605604) (xy 71.449546 -400.546738) (xy 71.432964 -400.485179) (xy 71.424561 -400.421982)
			(xy 71.424038 -400.390106) (xy 71.424556 -400.357569) (xy 71.433244 -400.293078) (xy 71.450478 -400.230328)
			(xy 71.475948 -400.170446) (xy 71.49211 -400.142202) (xy 71.494396 -400.138392) (xy 71.497444 -400.130518)
			(xy 71.49973 -400.12239) (xy 71.500492 -400.113246) (xy 71.500492 -399.972022) (xy 71.500238 -399.828766)
			(xy 71.500733 -399.818644) (xy 71.508466 -399.799935) (xy 71.522751 -399.78559) (xy 71.541427 -399.777777)
			(xy 71.551546 -399.777204) (xy 71.717916 -399.777204) (xy 71.727922 -399.776713) (xy 71.746409 -399.769051)
			(xy 71.760558 -399.754899) (xy 71.768215 -399.73641) (xy 71.768716 -399.726404) (xy 71.768716 -399.691352)
			(xy 71.768352 -399.683316) (xy 71.763304 -399.668052) (xy 71.75881 -399.66138) (xy 71.754238 -399.655284)
			(xy 71.741538 -399.645886) (xy 71.73341 -399.643346) (xy 71.701806 -399.632777) (xy 71.641052 -399.605388)
			(xy 71.583832 -399.571225) (xy 71.5309 -399.530736) (xy 71.48295 -399.484454) (xy 71.440613 -399.432987)
			(xy 71.404447 -399.377012) (xy 71.374926 -399.317265) (xy 71.352438 -399.254531) (xy 71.33728 -399.189636)
			(xy 71.32965 -399.123432) (xy 71.329648 -399.056789) (xy 71.337276 -398.990585) (xy 71.352432 -398.925689)
			(xy 71.374918 -398.862954) (xy 71.404437 -398.803206) (xy 71.440601 -398.74723) (xy 71.482936 -398.695761)
			(xy 71.530884 -398.649477) (xy 71.583815 -398.608987) (xy 71.641033 -398.574821) (xy 71.701787 -398.54743)
			(xy 71.73341 -398.536922) (xy 71.733664 -398.536922) (xy 71.741267 -398.534199) (xy 71.754354 -398.52475)
			(xy 71.759318 -398.51838) (xy 71.76389 -398.512284) (xy 71.768716 -398.497044) (xy 71.768716 -398.453864)
			(xy 71.768222 -398.44386) (xy 71.760557 -398.425378) (xy 71.746406 -398.411232) (xy 71.72792 -398.403574)
			(xy 71.717916 -398.403064) (xy 71.5518 -398.403064) (xy 71.542314 -398.402638) (xy 71.524604 -398.395833)
			(xy 71.510512 -398.383129) (xy 71.505826 -398.37487) (xy 71.505064 -398.373346) (xy 71.504302 -398.37106)
			(xy 71.502557 -398.366425) (xy 71.500646 -398.356707) (xy 71.500492 -398.351756) (xy 71.500492 -398.07007)
			(xy 71.498968 -398.058132) (xy 71.494904 -398.042892) (xy 71.491094 -398.036542) (xy 71.475171 -398.008424)
			(xy 71.450081 -397.948875) (xy 71.433106 -397.886526) (xy 71.424545 -397.822477) (xy 71.424549 -397.757858)
			(xy 71.433119 -397.69381) (xy 71.450102 -397.631463) (xy 71.4752 -397.571917) (xy 71.491094 -397.543782)
			(xy 71.494904 -397.537432) (xy 71.498968 -397.522192) (xy 71.500492 -397.510254) (xy 71.500492 -396.770098)
			(xy 71.498968 -396.75816) (xy 71.496682 -396.749778) (xy 71.492618 -396.739872) (xy 71.48957 -396.733522)
			(xy 71.474026 -396.705688) (xy 71.449549 -396.646821) (xy 71.432968 -396.585262) (xy 71.424568 -396.522066)
			(xy 71.424038 -396.49019) (xy 71.424557 -396.457653) (xy 71.433247 -396.393163) (xy 71.450482 -396.330414)
			(xy 71.475954 -396.270534) (xy 71.49211 -396.242286) (xy 71.494396 -396.238476) (xy 71.497444 -396.230602)
			(xy 71.49973 -396.222474) (xy 71.500492 -396.21333) (xy 71.500492 -396.072106) (xy 71.500238 -395.92885)
			(xy 71.500719 -395.918717) (xy 71.508437 -395.899979) (xy 71.522724 -395.885608) (xy 71.541416 -395.877779)
			(xy 71.551546 -395.877288) (xy 71.717916 -395.877288) (xy 71.727921 -395.876797) (xy 71.746405 -395.869134)
			(xy 71.76055 -395.854981) (xy 71.768203 -395.836493) (xy 71.768716 -395.826488) (xy 71.768716 -395.791436)
			(xy 71.76835 -395.783401) (xy 71.763298 -395.76814) (xy 71.75881 -395.761464) (xy 71.754238 -395.755368)
			(xy 71.741538 -395.74597) (xy 71.73341 -395.74343) (xy 71.70181 -395.73286) (xy 71.641065 -395.70547)
			(xy 71.583854 -395.671306) (xy 71.530931 -395.630817) (xy 71.482991 -395.584536) (xy 71.440665 -395.53307)
			(xy 71.404509 -395.477098) (xy 71.374998 -395.417354) (xy 71.352522 -395.354624) (xy 71.337374 -395.289733)
			(xy 71.329755 -395.223536) (xy 71.329296 -395.190218) (xy 71.329296 -395.185392) (xy 71.330312 -395.157198)
			(xy 71.330312 -395.15161) (xy 71.330156 -395.145744) (xy 71.327451 -395.134327) (xy 71.324978 -395.129004)
			(xy 71.320914 -395.120876) (xy 71.307198 -395.101826) (xy 71.30542 -395.099286) (xy 71.302417 -395.095824)
			(xy 71.295389 -395.089945) (xy 71.29145 -395.087602) (xy 71.28002 -395.080998) (xy 71.275956 -395.079474)
			(xy 71.254366 -395.071092) (xy 70.84568 -394.901928) (xy 70.823075 -394.892416) (xy 70.77873 -394.871454)
			(xy 70.757034 -394.860018) (xy 70.754748 -394.858748) (xy 70.731888 -394.84935) (xy 70.73138 -394.849096)
			(xy 70.698868 -394.835888) (xy 70.696582 -394.834872) (xy 70.55231 -394.774928) (xy 70.552056 -394.774928)
			(xy 70.318884 -394.678408) (xy 70.297548 -394.669518) (xy 70.294754 -394.668502) (xy 70.292214 -394.66774)
			(xy 70.269665 -394.660668) (xy 70.225196 -394.644659) (xy 70.203314 -394.635736) (xy 69.794628 -394.466572)
			(xy 69.75021 -394.447529) (xy 69.664967 -394.40198) (xy 69.624448 -394.37564) (xy 69.596298 -394.356583)
			(xy 69.542403 -394.315144) (xy 69.516752 -394.292836) (xy 69.510148 -394.286994) (xy 69.478906 -394.27404)
			(xy 69.47027 -394.273532) (xy 69.429386 -394.270653) (xy 69.348258 -394.258961) (xy 69.268379 -394.240582)
			(xy 69.190299 -394.215644) (xy 69.152262 -394.20038) (xy 68.743576 -394.031216) (xy 68.705763 -394.015114)
			(xy 68.632688 -393.977489) (xy 68.562989 -393.933927) (xy 68.497148 -393.884728) (xy 68.435619 -393.830232)
			(xy 68.378827 -393.770816) (xy 68.35267 -393.739116) (xy 68.348352 -393.733782) (xy 68.34378 -393.73048)
			(xy 68.333366 -393.724638) (xy 67.715638 -393.467844) (xy 67.6756 -393.450785) (xy 67.5984 -393.410592)
			(xy 67.56146 -393.38758) (xy 67.516703 -393.358166) (xy 67.433204 -393.291088) (xy 67.394836 -393.253722)
			(xy 67.343528 -393.202414) (xy 67.335654 -393.197334) (xy 67.32905 -393.193016) (xy 67.32143 -393.19073)
			(xy 67.282214 -393.178679) (xy 67.205746 -393.148938) (xy 67.132006 -393.11296) (xy 67.061502 -393.070995)
			(xy 66.994719 -393.023331) (xy 66.932116 -392.970295) (xy 66.902838 -392.941556) (xy 66.590164 -392.628882)
			(xy 66.561656 -392.599804) (xy 66.508977 -392.5377) (xy 66.461572 -392.471482) (xy 66.419763 -392.401597)
			(xy 66.401442 -392.36523) (xy 66.399918 -392.361674) (xy 66.391282 -392.34872) (xy 66.387472 -392.345164)
			(xy 66.372994 -392.330686) (xy 66.36893 -392.328654) (xy 66.36512 -392.326876) (xy 66.328353 -392.308501)
			(xy 66.257693 -392.266496) (xy 66.190764 -392.218772) (xy 66.128028 -392.165656) (xy 66.098674 -392.136884)
			(xy 65.786 -391.82421) (xy 65.757385 -391.794889) (xy 65.704573 -391.732244) (xy 65.657129 -391.665442)
			(xy 65.615379 -391.594941) (xy 65.579609 -391.521225) (xy 65.550066 -391.444801) (xy 65.538096 -391.405618)
			(xy 65.536064 -391.399268) (xy 65.53327 -391.394442) (xy 65.525396 -391.384282) (xy 65.337944 -391.19683)
			(xy 65.302105 -391.160067) (xy 65.23742 -391.080328) (xy 65.181357 -390.99431) (xy 65.15735 -390.948926)
			(xy 64.901318 -390.450578) (xy 64.896284 -390.441902) (xy 64.880991 -390.428955) (xy 64.8716 -390.425432)
			(xy 64.812926 -390.406636) (xy 64.728598 -390.379458) (xy 64.727582 -390.378442) (xy 64.618362 -390.16559)
			(xy 64.55029 -390.032748) (xy 64.549528 -390.031224) (xy 64.548512 -390.029192) (xy 64.545464 -390.023604)
			(xy 64.492378 -389.970264) (xy 64.45816 -389.935244) (xy 64.395989 -389.859598) (xy 64.341529 -389.778224)
			(xy 64.295303 -389.691905) (xy 64.27597 -389.646922) (xy 64.177926 -389.40994) (xy 64.16696 -389.409268)
			(xy 64.145176 -389.412078) (xy 64.134746 -389.415528) (xy 64.125856 -389.419084) (xy 64.114625 -389.424769)
			(xy 64.095151 -389.440706) (xy 64.080163 -389.46092) (xy 64.075056 -389.472424) (xy 64.063846 -389.498215)
			(xy 64.034957 -389.546463) (xy 63.999298 -389.589948) (xy 63.957642 -389.627726) (xy 63.910892 -389.658981)
			(xy 63.86006 -389.683035) (xy 63.806248 -389.699367) (xy 63.750622 -389.707622) (xy 63.722504 -389.708136)
			(xy 63.695252 -389.707651) (xy 63.641302 -389.699895) (xy 63.589005 -389.68454) (xy 63.539426 -389.6619)
			(xy 63.493573 -389.632434) (xy 63.45238 -389.596743) (xy 63.416685 -389.555553) (xy 63.387216 -389.509702)
			(xy 63.364571 -389.460125) (xy 63.349212 -389.407829) (xy 63.341452 -389.35388) (xy 63.340996 -389.326628)
			(xy 63.341475 -389.299445) (xy 63.349189 -389.245628) (xy 63.364465 -389.193452) (xy 63.386993 -389.143973)
			(xy 63.416317 -389.098193) (xy 63.451844 -389.05704) (xy 63.492853 -389.021347) (xy 63.538513 -388.991837)
			(xy 63.5879 -388.969108) (xy 63.640014 -388.953621) (xy 63.693799 -388.945688) (xy 63.72098 -388.94512)
			(xy 63.723012 -388.94512) (xy 63.747743 -388.945522) (xy 63.796787 -388.951941) (xy 63.844586 -388.964656)
			(xy 63.890337 -388.983454) (xy 63.911988 -388.995412) (xy 63.913766 -388.996174) (xy 63.917322 -388.997952)
			(xy 63.921201 -388.999675) (xy 63.929369 -389.00198) (xy 63.933578 -389.002524) (xy 63.978282 -388.983982)
			(xy 63.983014 -388.977716) (xy 63.988717 -388.963096) (xy 63.989458 -388.95528) (xy 63.955422 -388.87273)
			(xy 63.954406 -388.870952) (xy 63.94323 -388.848854) (xy 63.942722 -388.847838) (xy 63.942468 -388.847584)
			(xy 63.932054 -388.827772) (xy 63.932054 -388.827518) (xy 63.893192 -388.751826) (xy 63.73495 -388.443216)
			(xy 63.729108 -388.431786) (xy 63.7286 -388.430262) (xy 63.723012 -388.419848) (xy 63.723012 -388.419594)
			(xy 63.722758 -388.419086) (xy 63.557912 -388.097522) (xy 63.557658 -388.097014) (xy 63.556896 -388.095236)
			(xy 63.55334 -388.088378) (xy 63.552578 -388.078218) (xy 63.552322 -388.073329) (xy 63.553473 -388.063608)
			(xy 63.554864 -388.058914) (xy 63.576962 -387.99008) (xy 63.579367 -387.981412) (xy 63.578592 -387.963452)
			(xy 63.575438 -387.955028) (xy 63.38189 -387.488176) (xy 63.380112 -387.48462) (xy 62.63894 -386.039106)
			(xy 62.620973 -386.003205) (xy 62.590235 -385.929034) (xy 62.565615 -385.852615) (xy 62.547275 -385.77445)
			(xy 62.540896 -385.734814) (xy 62.540642 -385.732782) (xy 62.538864 -385.724908) (xy 62.537848 -385.722114)
			(xy 62.534282 -385.712846) (xy 62.521334 -385.697815) (xy 62.512702 -385.692904) (xy 62.503558 -385.688332)
			(xy 62.484 -385.686808) (xy 62.474348 -385.689856) (xy 62.446132 -385.698262) (xy 62.38796 -385.707311)
			(xy 62.358524 -385.70789) (xy 62.357 -385.70789) (xy 62.329748 -385.707427) (xy 62.275798 -385.69967)
			(xy 62.223501 -385.684313) (xy 62.173922 -385.661671) (xy 62.12807 -385.632202) (xy 62.086879 -385.596508)
			(xy 62.051187 -385.555316) (xy 62.021721 -385.509462) (xy 61.99908 -385.459882) (xy 61.983727 -385.407585)
			(xy 61.975972 -385.353634) (xy 61.975492 -385.326382) (xy 61.975995 -385.298598) (xy 61.984061 -385.24362)
			(xy 62.00002 -385.190393) (xy 62.023533 -385.140046) (xy 62.054103 -385.093644) (xy 62.091084 -385.052168)
			(xy 62.133691 -385.016498) (xy 62.181023 -384.987389) (xy 62.232079 -384.965455) (xy 62.285776 -384.951163)
			(xy 62.313312 -384.947414) (xy 62.31382 -384.947414) (xy 62.316868 -384.946906) (xy 62.3248 -384.945161)
			(xy 62.339053 -384.937395) (xy 62.344808 -384.931666) (xy 62.34811 -384.927856) (xy 62.385194 -384.879342)
			(xy 62.388496 -384.875532) (xy 62.395608 -384.868166) (xy 62.399926 -384.857498) (xy 62.402115 -384.851202)
			(xy 62.403525 -384.837953) (xy 62.40272 -384.831336) (xy 62.324742 -384.321558) (xy 62.310264 -384.227324)
			(xy 62.309756 -384.225546) (xy 62.308486 -384.220974) (xy 62.304226 -384.210002) (xy 62.287676 -384.193308)
			(xy 62.276736 -384.18897) (xy 62.25159 -384.181096) (xy 62.251336 -384.181096) (xy 62.192408 -384.162554)
			(xy 62.184364 -384.158227) (xy 62.171857 -384.144937) (xy 62.168024 -384.136646) (xy 62.150177 -384.160514)
			(xy 62.108315 -384.202928) (xy 62.060369 -384.23832) (xy 62.007505 -384.265831) (xy 61.951008 -384.284792)
			(xy 61.89225 -384.294741) (xy 61.862462 -384.29565) (xy 61.854588 -384.29565) (xy 61.827493 -384.294939)
			(xy 61.773906 -384.286802) (xy 61.722011 -384.271161) (xy 61.672853 -384.248332) (xy 61.62742 -384.218775)
			(xy 61.586629 -384.183085) (xy 61.551301 -384.14198) (xy 61.522146 -384.096288) (xy 61.499752 -384.04693)
			(xy 61.484571 -383.994899) (xy 61.476907 -383.941242) (xy 61.476382 -383.914142) (xy 61.476859 -383.887066)
			(xy 61.484525 -383.83346) (xy 61.499693 -383.781475) (xy 61.522059 -383.732158) (xy 61.551174 -383.686499)
			(xy 61.586453 -383.645416) (xy 61.627187 -383.609734) (xy 61.672556 -383.58017) (xy 61.72165 -383.557319)
			(xy 61.773482 -383.541639) (xy 61.827011 -383.533445) (xy 61.85408 -383.532634) (xy 61.858398 -383.532634)
			(xy 61.889484 -383.533274) (xy 61.950827 -383.543391) (xy 62.009728 -383.563294) (xy 62.037468 -383.577338)
			(xy 62.037722 -383.577592) (xy 62.038738 -383.5781) (xy 62.040262 -383.578862) (xy 62.05093 -383.583688)
			(xy 62.056518 -383.584958) (xy 62.0649 -383.587244) (xy 62.079124 -383.58699) (xy 62.085474 -383.585212)
			(xy 62.093856 -383.582926) (xy 62.146942 -383.546096) (xy 62.151514 -383.546096) (xy 62.165738 -383.53365)
			(xy 62.170056 -383.530348) (xy 62.17285 -383.52857) (xy 62.180887 -383.522912) (xy 62.192259 -383.506905)
			(xy 62.196771 -383.487795) (xy 62.19571 -383.478024) (xy 60.052458 -369.474496) (xy 58.900314 -361.947968)
			(xy 58.90006 -361.945936) (xy 58.90006 -361.940348) (xy 58.899806 -361.939078) (xy 58.899806 -345.667584)
			(xy 58.898028 -345.660726) (xy 58.887004 -345.619339) (xy 58.871234 -345.535149) (xy 58.866532 -345.492578)
			(xy 58.461402 -341.37854) (xy 58.460158 -341.369849) (xy 58.452624 -341.354004) (xy 58.44667 -341.347552)
			(xy 57.510426 -340.411308) (xy 57.503576 -340.403911) (xy 57.495834 -340.385313) (xy 57.49544 -340.37524)
			(xy 57.49544 -338.879434) (xy 56.625236 -321.179698) (xy 56.62422 -321.14871) (xy 56.62422 -321.138296)
			(xy 56.62422 -321.131184) (xy 56.62422 -320.201544) (xy 56.624643 -320.161331) (xy 56.631216 -320.081174)
			(xy 56.644291 -320.001817) (xy 56.663781 -319.923788) (xy 56.67629 -319.885568) (xy 56.679084 -319.877694)
			(xy 56.68899 -319.85204) (xy 56.689752 -319.849754) (xy 56.692546 -319.839848) (xy 56.694324 -319.831466)
			(xy 56.69534 -319.821052) (xy 56.69534 -319.048384) (xy 56.694892 -319.038574) (xy 56.687539 -319.020382)
			(xy 56.673909 -319.006267) (xy 56.665114 -319.001902) (xy 56.642121 -318.991126) (xy 56.599467 -318.963576)
			(xy 56.561525 -318.92983) (xy 56.529186 -318.890683) (xy 56.50321 -318.847053) (xy 56.484207 -318.799965)
			(xy 56.472624 -318.750526) (xy 56.468733 -318.699898) (xy 56.472625 -318.64927) (xy 56.484208 -318.599832)
			(xy 56.503212 -318.552745) (xy 56.529188 -318.509115) (xy 56.561528 -318.469967) (xy 56.59947 -318.436223)
			(xy 56.642124 -318.408673) (xy 56.665114 -318.39789) (xy 56.673903 -318.39351) (xy 56.687547 -318.379412)
			(xy 56.69489 -318.361218) (xy 56.69534 -318.351408) (xy 56.69534 -318.098424) (xy 56.694881 -318.08862)
			(xy 56.687516 -318.070446) (xy 56.673884 -318.05635) (xy 56.665114 -318.051942) (xy 56.640502 -318.040347)
			(xy 56.59513 -318.010331) (xy 56.555285 -317.973291) (xy 56.522043 -317.930228) (xy 56.4963 -317.882303)
			(xy 56.478751 -317.830809) (xy 56.46987 -317.777137) (xy 56.46928 -317.749936) (xy 56.46928 -317.749428)
			(xy 56.471058 -317.715392) (xy 56.472328 -317.703962) (xy 56.464708 -317.682372) (xy 56.400446 -317.618364)
			(xy 56.393037 -317.611677) (xy 56.374602 -317.604083) (xy 56.364632 -317.603632) (xy 56.359298 -317.603886)
			(xy 56.333299 -317.606115) (xy 56.281191 -317.603351) (xy 56.230158 -317.592467) (xy 56.205628 -317.583566)
			(xy 56.20512 -317.583566) (xy 56.201564 -317.582042) (xy 56.192402 -317.579325) (xy 56.173325 -317.580172)
			(xy 56.15588 -317.587938) (xy 56.142484 -317.601547) (xy 56.134993 -317.619112) (xy 56.134446 -317.6382)
			(xy 56.137302 -317.64732) (xy 56.145602 -317.672158) (xy 56.154548 -317.723753) (xy 56.155082 -317.749936)
			(xy 56.154593 -317.774754) (xy 56.146558 -317.823734) (xy 56.130704 -317.87077) (xy 56.10745 -317.914621)
			(xy 56.077409 -317.954133) (xy 56.041371 -317.988264) (xy 56.000286 -318.016115) (xy 55.955237 -318.036954)
			(xy 55.90741 -318.050229) (xy 55.858065 -318.055593) (xy 55.808503 -318.052904) (xy 55.760028 -318.042232)
			(xy 55.713919 -318.023858) (xy 55.671389 -317.998267) (xy 55.63356 -317.966133) (xy 55.601427 -317.928303)
			(xy 55.575837 -317.885772) (xy 55.557465 -317.839662) (xy 55.546795 -317.791187) (xy 55.544107 -317.741625)
			(xy 55.549472 -317.69228) (xy 55.56275 -317.644454) (xy 55.58359 -317.599405) (xy 55.611443 -317.558321)
			(xy 55.645575 -317.522284) (xy 55.685088 -317.492244) (xy 55.72894 -317.468992) (xy 55.775976 -317.45314)
			(xy 55.824956 -317.445106) (xy 55.849774 -317.444628) (xy 55.858875 -317.444667) (xy 55.877048 -317.445682)
			(xy 55.886096 -317.44666) (xy 55.898034 -317.448184) (xy 55.920386 -317.440056) (xy 55.993284 -317.363856)
			(xy 56.000142 -317.34125) (xy 55.99938 -317.335916) (xy 55.996772 -317.320939) (xy 55.993973 -317.290665)
			(xy 55.993792 -317.275464) (xy 55.993792 -316.799976) (xy 55.993538 -316.324742) (xy 55.994044 -316.298745)
			(xy 56.002168 -316.247391) (xy 56.018222 -316.197938) (xy 56.041812 -316.151605) (xy 56.072356 -316.10953)
			(xy 56.109104 -316.072749) (xy 56.151152 -316.042167) (xy 56.197465 -316.018536) (xy 56.246903 -316.002437)
			(xy 56.29825 -315.994268) (xy 56.324246 -315.99378) (xy 56.3245 -315.99378) (xy 56.338928 -315.99394)
			(xy 56.367673 -315.99648) (xy 56.381904 -315.99886) (xy 56.382666 -315.99886) (xy 56.391302 -316.000384)
			(xy 56.413908 -315.993272) (xy 56.481472 -315.928502) (xy 56.489553 -315.920012) (xy 56.497636 -315.898039)
			(xy 56.496966 -315.886338) (xy 56.496966 -315.886084) (xy 56.495919 -315.87704) (xy 56.494777 -315.858866)
			(xy 56.49468 -315.849762) (xy 56.495155 -315.825353) (xy 56.502918 -315.777156) (xy 56.518257 -315.730809)
			(xy 56.540779 -315.687497) (xy 56.569911 -315.648323) (xy 56.604909 -315.614288) (xy 56.644879 -315.586259)
			(xy 56.666638 -315.575188) (xy 56.666892 -315.575188) (xy 56.675221 -315.570695) (xy 56.688038 -315.556791)
			(xy 56.694922 -315.539177) (xy 56.69534 -315.529722) (xy 56.69534 -315.24829) (xy 56.694893 -315.238479)
			(xy 56.687541 -315.220286) (xy 56.673912 -315.206169) (xy 56.665114 -315.201808) (xy 56.642121 -315.191032)
			(xy 56.599466 -315.163481) (xy 56.561523 -315.129736) (xy 56.529183 -315.090588) (xy 56.503206 -315.046957)
			(xy 56.484203 -314.999869) (xy 56.472619 -314.95043) (xy 56.468727 -314.899801) (xy 56.472619 -314.849172)
			(xy 56.484202 -314.799733) (xy 56.503206 -314.752644) (xy 56.529182 -314.709014) (xy 56.561522 -314.669865)
			(xy 56.599465 -314.63612) (xy 56.642119 -314.608569) (xy 56.665114 -314.597796) (xy 56.673904 -314.593416)
			(xy 56.687549 -314.579318) (xy 56.694894 -314.561125) (xy 56.69534 -314.551314) (xy 56.69534 -314.29833)
			(xy 56.694882 -314.288525) (xy 56.687518 -314.27035) (xy 56.673887 -314.256251) (xy 56.665114 -314.251848)
			(xy 56.642118 -314.241071) (xy 56.599457 -314.21352) (xy 56.561508 -314.179773) (xy 56.529163 -314.140622)
			(xy 56.503181 -314.096988) (xy 56.484173 -314.049896) (xy 56.472585 -314.000451) (xy 56.468691 -313.949817)
			(xy 56.47258 -313.899182) (xy 56.484163 -313.849737) (xy 56.503166 -313.802643) (xy 56.529143 -313.759006)
			(xy 56.561484 -313.719852) (xy 56.59943 -313.6861) (xy 56.642088 -313.658545) (xy 56.665114 -313.647836)
			(xy 56.673908 -313.643458) (xy 56.687565 -313.629362) (xy 56.694924 -313.611168) (xy 56.69534 -313.601354)
			(xy 56.69534 -313.34837) (xy 56.694889 -313.338561) (xy 56.687534 -313.320374) (xy 56.673904 -313.306263)
			(xy 56.665114 -313.301888) (xy 56.642122 -313.291112) (xy 56.599471 -313.263562) (xy 56.561531 -313.229817)
			(xy 56.529193 -313.190671) (xy 56.503219 -313.147042) (xy 56.484218 -313.099956) (xy 56.472636 -313.050519)
			(xy 56.468745 -312.999893) (xy 56.472638 -312.949267) (xy 56.484222 -312.89983) (xy 56.503226 -312.852745)
			(xy 56.529202 -312.809117) (xy 56.561541 -312.769972) (xy 56.599482 -312.736229) (xy 56.642135 -312.708681)
			(xy 56.665114 -312.697876) (xy 56.673901 -312.693495) (xy 56.687541 -312.679396) (xy 56.694879 -312.661203)
			(xy 56.69534 -312.651394) (xy 56.69534 -312.369962) (xy 56.69485 -312.360525) (xy 56.68794 -312.342955)
			(xy 56.675171 -312.329048) (xy 56.666892 -312.324496) (xy 56.666638 -312.324496) (xy 56.644896 -312.313401)
			(xy 56.604944 -312.285359) (xy 56.569962 -312.25132) (xy 56.540839 -312.21215) (xy 56.518317 -312.168847)
			(xy 56.502969 -312.122512) (xy 56.495186 -312.074327) (xy 56.49468 -312.049922) (xy 56.494772 -312.040754)
			(xy 56.495914 -312.022454) (xy 56.496966 -312.013346) (xy 56.49849 -312.001408) (xy 56.490362 -311.979056)
			(xy 56.414162 -311.905904) (xy 56.391556 -311.898792) (xy 56.386984 -311.899554) (xy 56.371763 -311.902281)
			(xy 56.340978 -311.905205) (xy 56.325516 -311.905396) (xy 56.324754 -311.905396) (xy 56.31561 -311.90565)
			(xy 56.290088 -311.904474) (xy 56.239842 -311.895237) (xy 56.191612 -311.878387) (xy 56.146545 -311.854324)
			(xy 56.105713 -311.82362) (xy 56.070085 -311.787004) (xy 56.040509 -311.745347) (xy 56.017687 -311.699639)
			(xy 56.002162 -311.650967) (xy 55.994303 -311.600486) (xy 55.993792 -311.574942) (xy 55.993792 -310.62422)
			(xy 55.994248 -310.600648) (xy 56.001011 -310.553991) (xy 56.007254 -310.531256) (xy 56.007508 -310.529986)
			(xy 56.009881 -310.520785) (xy 56.008382 -310.501856) (xy 56.000096 -310.48477) (xy 55.986161 -310.471872)
			(xy 55.968487 -310.464929) (xy 55.958994 -310.464454) (xy 55.948326 -310.465978) (xy 55.941214 -310.467502)
			(xy 55.91884 -310.473556) (xy 55.872949 -310.480063) (xy 55.849774 -310.480456) (xy 55.822171 -310.479899)
			(xy 55.767732 -310.47072) (xy 55.715576 -310.452623) (xy 55.667153 -310.426109) (xy 55.623809 -310.391918)
			(xy 55.586749 -310.350999) (xy 55.57139 -310.328056) (xy 55.566535 -310.321097) (xy 55.55321 -310.310606)
			(xy 55.537196 -310.30502) (xy 55.528718 -310.304688) (xy 55.22087 -310.304688) (xy 55.212384 -310.304999)
			(xy 55.196349 -310.310556) (xy 55.183032 -310.321075) (xy 55.178198 -310.328056) (xy 55.162857 -310.351012)
			(xy 55.125794 -310.391932) (xy 55.082447 -310.426125) (xy 55.03402 -310.452638) (xy 54.98186 -310.470735)
			(xy 54.927419 -310.479912) (xy 54.899814 -310.480456) (xy 54.899306 -310.480456) (xy 54.86527 -310.478678)
			(xy 54.859936 -310.478424) (xy 54.849974 -310.47891) (xy 54.831551 -310.4865) (xy 54.824122 -310.493156)
			(xy 54.75986 -310.557164) (xy 54.75224 -310.578754) (xy 54.75351 -310.590184) (xy 54.755288 -310.62422)
			(xy 54.755288 -310.695594) (xy 54.755893 -310.706219) (xy 54.764552 -310.725635) (xy 54.772052 -310.733186)
			(xy 54.836568 -310.790844) (xy 54.856888 -310.797448) (xy 54.867556 -310.796432) (xy 54.899814 -310.794654)
			(xy 54.925072 -310.795177) (xy 54.974898 -310.803493) (xy 55.022676 -310.819897) (xy 55.067102 -310.843942)
			(xy 55.106965 -310.87497) (xy 55.141177 -310.912136) (xy 55.168806 -310.954426) (xy 55.189097 -311.000687)
			(xy 55.201498 -311.049657) (xy 55.205669 -311.1) (xy 55.201498 -311.150343) (xy 55.189097 -311.199313)
			(xy 55.168806 -311.245574) (xy 55.141177 -311.287864) (xy 55.106965 -311.32503) (xy 55.067102 -311.356058)
			(xy 55.022676 -311.380103) (xy 54.974898 -311.396507) (xy 54.925072 -311.404823) (xy 54.899814 -311.40527)
			(xy 54.86781 -311.403492) (xy 54.867302 -311.403492) (xy 54.856888 -311.402476) (xy 54.836568 -311.40908)
			(xy 54.772052 -311.466738) (xy 54.764435 -311.474205) (xy 54.755765 -311.493673) (xy 54.755288 -311.50433)
			(xy 54.755288 -311.574942) (xy 54.755126 -311.58937) (xy 54.752585 -311.618114) (xy 54.750208 -311.632346)
			(xy 54.750208 -311.632854) (xy 54.748684 -311.641236) (xy 54.755796 -311.663842) (xy 54.820312 -311.731406)
			(xy 54.827786 -311.73857) (xy 54.8468 -311.746709) (xy 54.857142 -311.747154) (xy 54.863238 -311.7469)
			(xy 54.872346 -311.745847) (xy 54.890646 -311.744705) (xy 54.899814 -311.744614) (xy 54.924632 -311.745101)
			(xy 54.973615 -311.753133) (xy 55.020653 -311.768984) (xy 55.064507 -311.792236) (xy 55.104022 -311.822276)
			(xy 55.138156 -311.858313) (xy 55.166011 -311.899398) (xy 55.186852 -311.944447) (xy 55.200131 -311.992275)
			(xy 55.205497 -312.041621) (xy 55.202809 -312.091185) (xy 55.192139 -312.139662) (xy 55.173766 -312.185773)
			(xy 55.148176 -312.228305) (xy 55.116042 -312.266137) (xy 55.078212 -312.298272) (xy 55.03568 -312.323863)
			(xy 54.989569 -312.342236) (xy 54.941093 -312.352908) (xy 54.891529 -312.355597) (xy 54.842183 -312.350232)
			(xy 54.794355 -312.336955) (xy 54.749305 -312.316115) (xy 54.708219 -312.288261) (xy 54.672182 -312.254128)
			(xy 54.64214 -312.214614) (xy 54.618887 -312.17076) (xy 54.603035 -312.123723) (xy 54.595002 -312.07474)
			(xy 54.594506 -312.049922) (xy 54.594598 -312.040754) (xy 54.59574 -312.022454) (xy 54.596792 -312.013346)
			(xy 54.597046 -312.00725) (xy 54.596561 -311.996916) (xy 54.588433 -311.977912) (xy 54.581298 -311.97042)
			(xy 54.513734 -311.905904) (xy 54.491128 -311.898792) (xy 54.482492 -311.900316) (xy 54.468195 -311.902684)
			(xy 54.439325 -311.905227) (xy 54.424834 -311.905396) (xy 54.42458 -311.905396) (xy 54.398594 -311.904885)
			(xy 54.347263 -311.896752) (xy 54.297836 -311.880689) (xy 54.25153 -311.857092) (xy 54.209485 -311.826541)
			(xy 54.172738 -311.78979) (xy 54.142191 -311.747743) (xy 54.118599 -311.701435) (xy 54.102541 -311.652006)
			(xy 54.094413 -311.600674) (xy 54.093872 -311.574688) (xy 54.093872 -310.62422) (xy 54.09565 -310.590438)
			(xy 54.095904 -310.585104) (xy 54.09543 -310.575136) (xy 54.087861 -310.556693) (xy 54.081172 -310.54929)
			(xy 54.017164 -310.485028) (xy 53.995574 -310.477408) (xy 53.984144 -310.478678) (xy 53.949854 -310.480456)
			(xy 53.922252 -310.479897) (xy 53.867815 -310.470716) (xy 53.815661 -310.452616) (xy 53.767241 -310.426101)
			(xy 53.723899 -310.391909) (xy 53.686842 -310.35099) (xy 53.67147 -310.328056) (xy 53.666614 -310.321099)
			(xy 53.653288 -310.310613) (xy 53.637275 -310.305034) (xy 53.628798 -310.304688) (xy 53.32095 -310.304688)
			(xy 53.312466 -310.305002) (xy 53.296436 -310.310563) (xy 53.283124 -310.321084) (xy 53.278278 -310.328056)
			(xy 53.262936 -310.351011) (xy 53.225873 -310.391929) (xy 53.182525 -310.426119) (xy 53.134098 -310.452629)
			(xy 53.081939 -310.470723) (xy 53.027498 -310.479897) (xy 52.999894 -310.480456) (xy 52.999386 -310.480456)
			(xy 52.96535 -310.478678) (xy 52.960016 -310.478424) (xy 52.950056 -310.478914) (xy 52.931638 -310.486509)
			(xy 52.924202 -310.493156) (xy 52.85994 -310.557164) (xy 52.85232 -310.578754) (xy 52.85359 -310.590184)
			(xy 52.855368 -310.62422) (xy 52.855368 -310.695594) (xy 52.855976 -310.706217) (xy 52.864644 -310.725624)
			(xy 52.872132 -310.733186) (xy 52.936648 -310.790844) (xy 52.956968 -310.797448) (xy 52.967636 -310.796432)
			(xy 52.999894 -310.794654) (xy 53.025155 -310.795146) (xy 53.074989 -310.803461) (xy 53.122774 -310.819865)
			(xy 53.167207 -310.84391) (xy 53.207077 -310.874941) (xy 53.241295 -310.912112) (xy 53.268928 -310.954407)
			(xy 53.289223 -311.000674) (xy 53.301626 -311.04965) (xy 53.305798 -311.1) (xy 53.301626 -311.15035)
			(xy 53.289223 -311.199326) (xy 53.268928 -311.245593) (xy 53.241295 -311.287888) (xy 53.207077 -311.325059)
			(xy 53.167207 -311.35609) (xy 53.122774 -311.380135) (xy 53.074989 -311.396539) (xy 53.025155 -311.404854)
			(xy 52.999894 -311.40527) (xy 52.96789 -311.403492) (xy 52.967382 -311.403492) (xy 52.956968 -311.402476)
			(xy 52.936648 -311.40908) (xy 52.872132 -311.466738) (xy 52.864517 -311.474206) (xy 52.855851 -311.493674)
			(xy 52.855368 -311.50433) (xy 52.855368 -311.574942) (xy 52.855206 -311.58937) (xy 52.852665 -311.618114)
			(xy 52.850288 -311.632346) (xy 52.850288 -311.632854) (xy 52.848764 -311.641236) (xy 52.855876 -311.663842)
			(xy 52.920392 -311.731406) (xy 52.927865 -311.738573) (xy 52.946878 -311.746719) (xy 52.957222 -311.747154)
			(xy 52.963318 -311.7469) (xy 52.972426 -311.745846) (xy 52.990726 -311.744704) (xy 52.999894 -311.744614)
			(xy 53.024713 -311.745099) (xy 53.073697 -311.753129) (xy 53.120736 -311.768977) (xy 53.164592 -311.792227)
			(xy 53.204109 -311.822265) (xy 53.238246 -311.858301) (xy 53.266103 -311.899384) (xy 53.286947 -311.944433)
			(xy 53.300228 -311.992261) (xy 53.305597 -312.041608) (xy 53.302911 -312.091173) (xy 53.292242 -312.13965)
			(xy 53.273872 -312.185763) (xy 53.248283 -312.228296) (xy 53.21615 -312.26613) (xy 53.178319 -312.298266)
			(xy 53.135788 -312.323859) (xy 53.089677 -312.342234) (xy 53.0412 -312.352907) (xy 52.991636 -312.355597)
			(xy 52.942289 -312.350233) (xy 52.89446 -312.336957) (xy 52.849409 -312.316117) (xy 52.808322 -312.288264)
			(xy 52.772284 -312.25413) (xy 52.742242 -312.214616) (xy 52.718988 -312.170762) (xy 52.703135 -312.123724)
			(xy 52.695102 -312.074741) (xy 52.694586 -312.049922) (xy 52.694678 -312.040754) (xy 52.69582 -312.022454)
			(xy 52.696872 -312.013346) (xy 52.697126 -312.00725) (xy 52.69664 -311.996916) (xy 52.68851 -311.977914)
			(xy 52.681378 -311.97042) (xy 52.613814 -311.905904) (xy 52.591208 -311.898792) (xy 52.582572 -311.900316)
			(xy 52.568275 -311.902683) (xy 52.539405 -311.905225) (xy 52.524914 -311.905396) (xy 52.52466 -311.905396)
			(xy 52.498675 -311.904883) (xy 52.447346 -311.896748) (xy 52.397922 -311.880683) (xy 52.351619 -311.857085)
			(xy 52.309577 -311.826534) (xy 52.272832 -311.789783) (xy 52.242288 -311.747737) (xy 52.218697 -311.70143)
			(xy 52.20264 -311.652003) (xy 52.194512 -311.600673) (xy 52.193952 -311.574688) (xy 52.193952 -310.62422)
			(xy 52.19573 -310.590438) (xy 52.195984 -310.585104) (xy 52.19551 -310.575136) (xy 52.187939 -310.556695)
			(xy 52.181252 -310.54929) (xy 52.117244 -310.485028) (xy 52.095654 -310.477408) (xy 52.084224 -310.478678)
			(xy 52.049934 -310.480456) (xy 52.022328 -310.479903) (xy 51.967884 -310.470733) (xy 51.915721 -310.452642)
			(xy 51.867289 -310.426134) (xy 51.823937 -310.391945) (xy 51.78687 -310.351027) (xy 51.77155 -310.328056)
			(xy 51.766693 -310.321101) (xy 51.753366 -310.31062) (xy 51.737354 -310.305047) (xy 51.728878 -310.304688)
			(xy 51.42103 -310.304688) (xy 51.412548 -310.305005) (xy 51.396522 -310.31057) (xy 51.383215 -310.321093)
			(xy 51.378358 -310.328056) (xy 51.363016 -310.35101) (xy 51.325952 -310.391926) (xy 51.282604 -310.426113)
			(xy 51.234177 -310.45262) (xy 51.182018 -310.470711) (xy 51.127578 -310.479882) (xy 51.099974 -310.480456)
			(xy 51.099466 -310.480456) (xy 51.06543 -310.478678) (xy 51.060096 -310.478424) (xy 51.050129 -310.478899)
			(xy 51.031691 -310.486474) (xy 51.024282 -310.493156) (xy 50.96002 -310.557164) (xy 50.9524 -310.578754)
			(xy 50.95367 -310.590184) (xy 50.955448 -310.62422) (xy 50.955448 -310.695594) (xy 50.956055 -310.706218)
			(xy 50.964721 -310.725627) (xy 50.972212 -310.733186) (xy 51.036728 -310.790844) (xy 51.057048 -310.797448)
			(xy 51.067716 -310.796432) (xy 51.099974 -310.794654) (xy 51.125236 -310.795145) (xy 51.175072 -310.803457)
			(xy 51.22286 -310.819859) (xy 51.267297 -310.843903) (xy 51.307169 -310.874934) (xy 51.34139 -310.912105)
			(xy 51.369025 -310.954401) (xy 51.389322 -311.00067) (xy 51.401726 -311.049648) (xy 51.405898 -311.1)
			(xy 51.401725 -311.150352) (xy 51.389322 -311.19933) (xy 51.369025 -311.245599) (xy 51.34139 -311.287895)
			(xy 51.307169 -311.325066) (xy 51.267297 -311.356097) (xy 51.22286 -311.380141) (xy 51.175072 -311.396543)
			(xy 51.125236 -311.404855) (xy 51.099974 -311.40527) (xy 51.06797 -311.403492) (xy 51.067462 -311.403492)
			(xy 51.057048 -311.402476) (xy 51.036728 -311.40908) (xy 50.972212 -311.466738) (xy 50.964599 -311.474207)
			(xy 50.955937 -311.493675) (xy 50.955448 -311.50433) (xy 50.955448 -311.574942) (xy 50.955286 -311.58937)
			(xy 50.952745 -311.618114) (xy 50.950368 -311.632346) (xy 50.950368 -311.632854) (xy 50.948844 -311.641236)
			(xy 50.955956 -311.663842) (xy 51.020472 -311.731406) (xy 51.027949 -311.73856) (xy 51.046963 -311.746677)
			(xy 51.057302 -311.747154) (xy 51.063398 -311.7469) (xy 51.072506 -311.745846) (xy 51.090806 -311.744702)
			(xy 51.099974 -311.744614) (xy 51.124793 -311.745098) (xy 51.173778 -311.753124) (xy 51.220819 -311.76897)
			(xy 51.264677 -311.792217) (xy 51.304197 -311.822254) (xy 51.338336 -311.858288) (xy 51.366196 -311.899371)
			(xy 51.387042 -311.944419) (xy 51.400325 -311.992247) (xy 51.405696 -312.041594) (xy 51.403013 -312.09116)
			(xy 51.392346 -312.139638) (xy 51.373977 -312.185753) (xy 51.348389 -312.228288) (xy 51.316257 -312.266123)
			(xy 51.278427 -312.298261) (xy 51.235896 -312.323855) (xy 51.189784 -312.342232) (xy 51.141307 -312.352906)
			(xy 51.091742 -312.355597) (xy 51.042395 -312.350234) (xy 50.994565 -312.336958) (xy 50.949513 -312.316119)
			(xy 50.908425 -312.288266) (xy 50.872386 -312.254132) (xy 50.842343 -312.214618) (xy 50.819089 -312.170764)
			(xy 50.803236 -312.123725) (xy 50.795202 -312.074741) (xy 50.794666 -312.049922) (xy 50.794758 -312.040754)
			(xy 50.7959 -312.022454) (xy 50.796952 -312.013346) (xy 50.797206 -312.00725) (xy 50.796723 -311.996914)
			(xy 50.788602 -311.977904) (xy 50.781458 -311.97042) (xy 50.713894 -311.905904) (xy 50.691288 -311.898792)
			(xy 50.682652 -311.900316) (xy 50.668355 -311.902682) (xy 50.639485 -311.905222) (xy 50.624994 -311.905396)
			(xy 50.62474 -311.905396) (xy 50.598749 -311.904916) (xy 50.547406 -311.89679) (xy 50.497967 -311.880731)
			(xy 50.451649 -311.857135) (xy 50.409593 -311.826583) (xy 50.372835 -311.789828) (xy 50.34228 -311.747775)
			(xy 50.31868 -311.701459) (xy 50.302617 -311.652021) (xy 50.294486 -311.600679) (xy 50.294032 -311.574688)
			(xy 50.294032 -310.62422) (xy 50.29581 -310.590184) (xy 50.29708 -310.579008) (xy 50.28946 -310.557418)
			(xy 50.21707 -310.485028) (xy 50.19548 -310.477408) (xy 50.184304 -310.478678) (xy 50.150268 -310.480456)
			(xy 50.14976 -310.480456) (xy 50.122157 -310.479897) (xy 50.06772 -310.470717) (xy 50.015566 -310.452618)
			(xy 49.967144 -310.426104) (xy 49.923802 -310.391912) (xy 49.886744 -310.350993) (xy 49.871376 -310.328056)
			(xy 49.86652 -310.321098) (xy 49.853195 -310.310611) (xy 49.837182 -310.30503) (xy 49.828704 -310.304688)
			(xy 49.520856 -310.304688) (xy 49.512371 -310.305001) (xy 49.49634 -310.310561) (xy 49.483026 -310.321081)
			(xy 49.478184 -310.328056) (xy 49.462842 -310.351011) (xy 49.425779 -310.39193) (xy 49.382432 -310.42612)
			(xy 49.334005 -310.452632) (xy 49.281845 -310.470726) (xy 49.227404 -310.479901) (xy 49.1998 -310.480456)
			(xy 49.199292 -310.480456) (xy 49.165256 -310.478678) (xy 49.15408 -310.477408) (xy 49.13249 -310.485028)
			(xy 49.0601 -310.557164) (xy 49.05248 -310.578754) (xy 49.05375 -310.590184) (xy 49.055528 -310.621172)
			(xy 49.055528 -310.695594) (xy 49.056134 -310.706218) (xy 49.064798 -310.72563) (xy 49.072292 -310.733186)
			(xy 49.128426 -310.783732) (xy 49.136645 -310.790524) (xy 49.156903 -310.797114) (xy 49.167542 -310.796432)
			(xy 49.167796 -310.796432) (xy 49.1998 -310.794654) (xy 49.225058 -310.795176) (xy 49.274886 -310.803491)
			(xy 49.322666 -310.819893) (xy 49.367094 -310.843937) (xy 49.406959 -310.874965) (xy 49.441174 -310.912131)
			(xy 49.468804 -310.954422) (xy 49.489096 -311.000684) (xy 49.501497 -311.049656) (xy 49.505669 -311.1)
			(xy 49.501497 -311.150344) (xy 49.489096 -311.199316) (xy 49.468804 -311.245578) (xy 49.441174 -311.287869)
			(xy 49.406959 -311.325035) (xy 49.367094 -311.356063) (xy 49.322666 -311.380107) (xy 49.274886 -311.396509)
			(xy 49.225058 -311.404824) (xy 49.1998 -311.40527) (xy 49.16805 -311.403492) (xy 49.167542 -311.403492)
			(xy 49.15692 -311.402971) (xy 49.136712 -311.409526) (xy 49.128426 -311.416192) (xy 49.072292 -311.466738)
			(xy 49.064682 -311.474208) (xy 49.056023 -311.493676) (xy 49.055528 -311.50433) (xy 49.055528 -311.57545)
			(xy 49.05536 -311.589815) (xy 49.05282 -311.618432) (xy 49.050448 -311.6326) (xy 49.050448 -311.633108)
			(xy 49.049178 -311.641236) (xy 49.056036 -311.663842) (xy 49.12868 -311.740296) (xy 49.15154 -311.748424)
			(xy 49.163224 -311.7469) (xy 49.172332 -311.745846) (xy 49.190632 -311.744704) (xy 49.1998 -311.744614)
			(xy 49.224619 -311.7451) (xy 49.273602 -311.75313) (xy 49.320641 -311.768979) (xy 49.364497 -311.792229)
			(xy 49.404013 -311.822268) (xy 49.438149 -311.858304) (xy 49.466005 -311.899388) (xy 49.486848 -311.944438)
			(xy 49.500129 -311.992265) (xy 49.505497 -312.041612) (xy 49.502811 -312.091176) (xy 49.492141 -312.139653)
			(xy 49.47377 -312.185766) (xy 49.448181 -312.228299) (xy 49.416047 -312.266132) (xy 49.378217 -312.298268)
			(xy 49.335686 -312.32386) (xy 49.289575 -312.342235) (xy 49.241098 -312.352908) (xy 49.191534 -312.355597)
			(xy 49.142187 -312.350233) (xy 49.094358 -312.336956) (xy 49.049307 -312.316116) (xy 49.008222 -312.288263)
			(xy 48.972183 -312.254129) (xy 48.942141 -312.214615) (xy 48.918888 -312.170762) (xy 48.903035 -312.123724)
			(xy 48.895002 -312.074741) (xy 48.894492 -312.049922) (xy 48.894584 -312.040754) (xy 48.895726 -312.022454)
			(xy 48.896778 -312.013346) (xy 48.898302 -312.001662) (xy 48.890174 -311.978802) (xy 48.81372 -311.906158)
			(xy 48.791114 -311.8993) (xy 48.782732 -311.90057) (xy 48.768498 -311.902929) (xy 48.739755 -311.905476)
			(xy 48.725328 -311.90565) (xy 48.724566 -311.90565) (xy 48.698561 -311.905137) (xy 48.647192 -311.896996)
			(xy 48.597729 -311.88092) (xy 48.551389 -311.857304) (xy 48.509315 -311.82673) (xy 48.47254 -311.78995)
			(xy 48.441972 -311.747871) (xy 48.418363 -311.701529) (xy 48.402293 -311.652063) (xy 48.394159 -311.600693)
			(xy 48.393604 -311.574688) (xy 48.393604 -310.62422) (xy 48.39406 -310.600648) (xy 48.400821 -310.55399)
			(xy 48.407066 -310.531256) (xy 48.40732 -310.529986) (xy 48.409652 -310.520799) (xy 48.408098 -310.501923)
			(xy 48.399803 -310.484895) (xy 48.385898 -310.472035) (xy 48.368275 -310.465094) (xy 48.358806 -310.464708)
			(xy 48.347884 -310.466232) (xy 48.341026 -310.467756) (xy 48.318824 -310.473674) (xy 48.273321 -310.480045)
			(xy 48.250348 -310.480456) (xy 48.24984 -310.480456) (xy 48.222234 -310.479904) (xy 48.167789 -310.470735)
			(xy 48.115625 -310.452644) (xy 48.067193 -310.426136) (xy 48.02384 -310.391947) (xy 47.986772 -310.351029)
			(xy 47.971456 -310.328056) (xy 47.9666 -310.3211) (xy 47.953273 -310.310618) (xy 47.93726 -310.305043)
			(xy 47.928784 -310.304688) (xy 47.620936 -310.304688) (xy 47.612453 -310.305004) (xy 47.596426 -310.310568)
			(xy 47.583118 -310.32109) (xy 47.578264 -310.328056) (xy 47.562922 -310.35101) (xy 47.525858 -310.391927)
			(xy 47.48251 -310.426114) (xy 47.434083 -310.452623) (xy 47.381924 -310.470714) (xy 47.327484 -310.479886)
			(xy 47.29988 -310.480456) (xy 47.299372 -310.480456) (xy 47.265336 -310.478678) (xy 47.25416 -310.477408)
			(xy 47.23257 -310.485028) (xy 47.16018 -310.557164) (xy 47.15256 -310.578754) (xy 47.15383 -310.590184)
			(xy 47.155608 -310.621172) (xy 47.155608 -310.695594) (xy 47.156214 -310.706219) (xy 47.164875 -310.725632)
			(xy 47.172372 -310.733186) (xy 47.228506 -310.783732) (xy 47.236729 -310.790509) (xy 47.256984 -310.797067)
			(xy 47.267622 -310.796432) (xy 47.267876 -310.796432) (xy 47.29988 -310.794654) (xy 47.325142 -310.795145)
			(xy 47.374977 -310.803458) (xy 47.422764 -310.819861) (xy 47.4672 -310.843906) (xy 47.507071 -310.874936)
			(xy 47.541291 -310.912107) (xy 47.568926 -310.954403) (xy 47.589222 -311.000671) (xy 47.601626 -311.049649)
			(xy 47.605798 -311.1) (xy 47.601626 -311.150351) (xy 47.589222 -311.199329) (xy 47.568926 -311.245597)
			(xy 47.541291 -311.287893) (xy 47.507071 -311.325064) (xy 47.4672 -311.356094) (xy 47.422764 -311.380139)
			(xy 47.374977 -311.396542) (xy 47.325142 -311.404855) (xy 47.29988 -311.40527) (xy 47.26813 -311.403492)
			(xy 47.267622 -311.403492) (xy 47.257001 -311.402975) (xy 47.236799 -311.409536) (xy 47.228506 -311.416192)
			(xy 47.172372 -311.466738) (xy 47.164752 -311.474203) (xy 47.156079 -311.493672) (xy 47.155608 -311.50433)
			(xy 47.155608 -311.57545) (xy 47.15544 -311.589815) (xy 47.1529 -311.618432) (xy 47.150528 -311.6326)
			(xy 47.150528 -311.633108) (xy 47.149258 -311.641236) (xy 47.156116 -311.663842) (xy 47.22876 -311.740296)
			(xy 47.25162 -311.748424) (xy 47.263304 -311.7469) (xy 47.272412 -311.745846) (xy 47.290712 -311.744702)
			(xy 47.29988 -311.744614) (xy 47.324699 -311.745098) (xy 47.373684 -311.753126) (xy 47.420724 -311.768972)
			(xy 47.464582 -311.79222) (xy 47.5041 -311.822257) (xy 47.538239 -311.858292) (xy 47.566098 -311.899375)
			(xy 47.586943 -311.944424) (xy 47.600226 -311.992251) (xy 47.605596 -312.041598) (xy 47.602912 -312.091164)
			(xy 47.592245 -312.139642) (xy 47.573875 -312.185756) (xy 47.548287 -312.22829) (xy 47.516154 -312.266125)
			(xy 47.478324 -312.298262) (xy 47.435793 -312.323856) (xy 47.389682 -312.342233) (xy 47.341205 -312.352907)
			(xy 47.29164 -312.355597) (xy 47.242293 -312.350234) (xy 47.194463 -312.336958) (xy 47.149411 -312.316119)
			(xy 47.108324 -312.288265) (xy 47.072285 -312.254132) (xy 47.042243 -312.214617) (xy 47.018989 -312.170763)
			(xy 47.003136 -312.123725) (xy 46.995102 -312.074741) (xy 46.994572 -312.049922) (xy 46.994664 -312.040754)
			(xy 46.995806 -312.022454) (xy 46.996858 -312.013346) (xy 46.998382 -312.001662) (xy 46.990254 -311.978802)
			(xy 46.9138 -311.906158) (xy 46.891194 -311.8993) (xy 46.882812 -311.90057) (xy 46.868578 -311.902929)
			(xy 46.839835 -311.905474) (xy 46.825408 -311.90565) (xy 46.824646 -311.90565) (xy 46.798635 -311.90517)
			(xy 46.747252 -311.897038) (xy 46.697774 -311.880968) (xy 46.65142 -311.857354) (xy 46.609331 -311.826779)
			(xy 46.572543 -311.789995) (xy 46.541964 -311.747909) (xy 46.518346 -311.701557) (xy 46.50227 -311.652081)
			(xy 46.494133 -311.600699) (xy 46.493684 -311.574688) (xy 46.493684 -310.62422) (xy 46.49414 -310.600648)
			(xy 46.500903 -310.553991) (xy 46.507146 -310.531256) (xy 46.5074 -310.529986) (xy 46.509732 -310.5208)
			(xy 46.508178 -310.501926) (xy 46.499883 -310.484901) (xy 46.485977 -310.472045) (xy 46.468354 -310.46511)
			(xy 46.458886 -310.464708) (xy 46.447964 -310.466232) (xy 46.441106 -310.467756) (xy 46.418904 -310.473673)
			(xy 46.373401 -310.480041) (xy 46.350428 -310.480456) (xy 46.34992 -310.480456) (xy 46.322315 -310.479902)
			(xy 46.267872 -310.47073) (xy 46.21571 -310.452638) (xy 46.167281 -310.426128) (xy 46.123931 -310.391939)
			(xy 46.086865 -310.35102) (xy 46.071536 -310.328056) (xy 46.066678 -310.321103) (xy 46.053351 -310.310626)
			(xy 46.037339 -310.305057) (xy 46.028864 -310.304688) (xy 45.721016 -310.304688) (xy 45.712526 -310.304992)
			(xy 45.69648 -310.310538) (xy 45.683151 -310.321053) (xy 45.678344 -310.328056) (xy 45.663002 -310.351009)
			(xy 45.625937 -310.391923) (xy 45.582589 -310.426109) (xy 45.534162 -310.452614) (xy 45.482003 -310.470702)
			(xy 45.427563 -310.479871) (xy 45.39996 -310.480456) (xy 45.399452 -310.480456) (xy 45.365416 -310.478678)
			(xy 45.35424 -310.477408) (xy 45.33265 -310.485028) (xy 45.26026 -310.557164) (xy 45.25264 -310.578754)
			(xy 45.25391 -310.590184) (xy 45.255688 -310.621172) (xy 45.255688 -310.695594) (xy 45.256293 -310.706219)
			(xy 45.264952 -310.725635) (xy 45.272452 -310.733186) (xy 45.328586 -310.783732) (xy 45.336808 -310.790513)
			(xy 45.357063 -310.797079) (xy 45.367702 -310.796432) (xy 45.367956 -310.796432) (xy 45.39996 -310.794654)
			(xy 45.425223 -310.795144) (xy 45.475061 -310.803454) (xy 45.522851 -310.819855) (xy 45.567289 -310.843899)
			(xy 45.607164 -310.874929) (xy 45.641386 -310.9121) (xy 45.669023 -310.954398) (xy 45.689321 -311.000667)
			(xy 45.701725 -311.049647) (xy 45.705898 -311.1) (xy 45.701725 -311.150353) (xy 45.689321 -311.199333)
			(xy 45.669023 -311.245602) (xy 45.641386 -311.2879) (xy 45.607164 -311.325071) (xy 45.567289 -311.356101)
			(xy 45.522851 -311.380145) (xy 45.475061 -311.396546) (xy 45.425223 -311.404856) (xy 45.39996 -311.40527)
			(xy 45.36821 -311.403492) (xy 45.367702 -311.403492) (xy 45.357083 -311.402979) (xy 45.336885 -311.409546)
			(xy 45.328586 -311.416192) (xy 45.272452 -311.466738) (xy 45.264835 -311.474205) (xy 45.256165 -311.493673)
			(xy 45.255688 -311.50433) (xy 45.255688 -311.57545) (xy 45.25552 -311.589815) (xy 45.25298 -311.618432)
			(xy 45.250608 -311.6326) (xy 45.250608 -311.633108) (xy 45.249338 -311.641236) (xy 45.256196 -311.663842)
			(xy 45.32884 -311.740296) (xy 45.3517 -311.748424) (xy 45.363384 -311.7469) (xy 45.372492 -311.745845)
			(xy 45.390792 -311.744701) (xy 45.39996 -311.744614) (xy 45.424779 -311.745097) (xy 45.473765 -311.753121)
			(xy 45.520808 -311.768965) (xy 45.564667 -311.79221) (xy 45.604188 -311.822246) (xy 45.638329 -311.858279)
			(xy 45.66619 -311.899361) (xy 45.687038 -311.94441) (xy 45.700323 -311.992238) (xy 45.705696 -312.041585)
			(xy 45.703014 -312.091151) (xy 45.692348 -312.13963) (xy 45.67398 -312.185746) (xy 45.648393 -312.228282)
			(xy 45.616262 -312.266118) (xy 45.578432 -312.298257) (xy 45.535901 -312.323853) (xy 45.48979 -312.34223)
			(xy 45.441313 -312.352906) (xy 45.391747 -312.355598) (xy 45.342399 -312.350235) (xy 45.294568 -312.33696)
			(xy 45.249515 -312.316121) (xy 45.208427 -312.288268) (xy 45.172387 -312.254134) (xy 45.142344 -312.214619)
			(xy 45.119089 -312.170765) (xy 45.103236 -312.123726) (xy 45.095202 -312.074741) (xy 45.094652 -312.049922)
			(xy 45.094744 -312.040754) (xy 45.095886 -312.022454) (xy 45.096938 -312.013346) (xy 45.098462 -312.001662)
			(xy 45.090334 -311.978802) (xy 45.01388 -311.906158) (xy 44.991274 -311.8993) (xy 44.982892 -311.90057)
			(xy 44.968658 -311.902928) (xy 44.939915 -311.905471) (xy 44.925488 -311.90565) (xy 44.924726 -311.90565)
			(xy 44.898716 -311.905169) (xy 44.847335 -311.897034) (xy 44.79786 -311.880962) (xy 44.751509 -311.857347)
			(xy 44.709422 -311.826772) (xy 44.672637 -311.789988) (xy 44.64206 -311.747903) (xy 44.618444 -311.701553)
			(xy 44.602369 -311.652078) (xy 44.594233 -311.600698) (xy 44.593764 -311.574688) (xy 44.593764 -310.62422)
			(xy 44.59422 -310.600648) (xy 44.600982 -310.553991) (xy 44.607226 -310.531256) (xy 44.60748 -310.529986)
			(xy 44.609852 -310.520781) (xy 44.608351 -310.501844) (xy 44.600067 -310.48475) (xy 44.586136 -310.471837)
			(xy 44.568463 -310.464872) (xy 44.558966 -310.464454) (xy 44.548298 -310.465978) (xy 44.541186 -310.467502)
			(xy 44.518812 -310.473554) (xy 44.472921 -310.480057) (xy 44.449746 -310.480456) (xy 44.42214 -310.479904)
			(xy 44.367694 -310.470736) (xy 44.31553 -310.452646) (xy 44.267097 -310.426139) (xy 44.223743 -310.39195)
			(xy 44.186674 -310.351032) (xy 44.171362 -310.328056) (xy 44.166506 -310.3211) (xy 44.153179 -310.310616)
			(xy 44.137167 -310.305039) (xy 44.12869 -310.304688) (xy 43.820842 -310.304688) (xy 43.812359 -310.305003)
			(xy 43.79633 -310.310566) (xy 43.78302 -310.321088) (xy 43.77817 -310.328056) (xy 43.762828 -310.351011)
			(xy 43.725765 -310.391928) (xy 43.682417 -310.426116) (xy 43.63399 -310.452625) (xy 43.581831 -310.470718)
			(xy 43.52739 -310.479891) (xy 43.499786 -310.480456) (xy 43.499278 -310.480456) (xy 43.465242 -310.478678)
			(xy 43.459908 -310.478424) (xy 43.44994 -310.478897) (xy 43.431499 -310.486469) (xy 43.424094 -310.493156)
			(xy 43.359832 -310.557164) (xy 43.352212 -310.578754) (xy 43.353482 -310.590184) (xy 43.35526 -310.62422)
			(xy 43.35526 -310.695594) (xy 43.355868 -310.706217) (xy 43.364535 -310.725625) (xy 43.372024 -310.733186)
			(xy 43.43654 -310.790844) (xy 43.45686 -310.797448) (xy 43.467528 -310.796432) (xy 43.499786 -310.794654)
			(xy 43.525048 -310.795146) (xy 43.574882 -310.803459) (xy 43.622668 -310.819863) (xy 43.667103 -310.843908)
			(xy 43.706974 -310.874939) (xy 43.741193 -310.912109) (xy 43.768827 -310.954405) (xy 43.789123 -311.000672)
			(xy 43.801526 -311.049649) (xy 43.805698 -311.1) (xy 43.801526 -311.150351) (xy 43.789123 -311.199328)
			(xy 43.768827 -311.245595) (xy 43.741193 -311.287891) (xy 43.706974 -311.325061) (xy 43.667103 -311.356092)
			(xy 43.622668 -311.380137) (xy 43.574882 -311.396541) (xy 43.525048 -311.404854) (xy 43.499786 -311.40527)
			(xy 43.467782 -311.403492) (xy 43.467274 -311.403492) (xy 43.45686 -311.402476) (xy 43.43654 -311.40908)
			(xy 43.372024 -311.466738) (xy 43.36441 -311.474206) (xy 43.355745 -311.493674) (xy 43.35526 -311.50433)
			(xy 43.35526 -311.574942) (xy 43.355098 -311.58937) (xy 43.352557 -311.618114) (xy 43.35018 -311.632346)
			(xy 43.35018 -311.632854) (xy 43.348656 -311.641236) (xy 43.355768 -311.663842) (xy 43.420284 -311.731406)
			(xy 43.427757 -311.738574) (xy 43.44677 -311.746723) (xy 43.457114 -311.747154) (xy 43.46321 -311.7469)
			(xy 43.472318 -311.745846) (xy 43.490618 -311.744703) (xy 43.499786 -311.744614) (xy 43.525043 -311.745105)
			(xy 43.574867 -311.753418) (xy 43.622644 -311.769818) (xy 43.66707 -311.793858) (xy 43.706933 -311.824883)
			(xy 43.741146 -311.862046) (xy 43.768774 -311.904333) (xy 43.789066 -311.950592) (xy 43.801467 -311.999559)
			(xy 43.805638 -312.0499) (xy 43.801467 -312.100241) (xy 43.789066 -312.149208) (xy 43.768774 -312.195467)
			(xy 43.741146 -312.237754) (xy 43.706933 -312.274917) (xy 43.66707 -312.305942) (xy 43.622644 -312.329982)
			(xy 43.574867 -312.346382) (xy 43.525043 -312.354695) (xy 43.499786 -312.35523) (xy 43.481498 -312.354722)
			(xy 43.481244 -312.354722) (xy 43.472075 -312.354546) (xy 43.454571 -312.359963) (xy 43.440127 -312.371237)
			(xy 43.435016 -312.378852) (xy 43.38828 -312.455306) (xy 43.38478 -312.461412) (xy 43.380919 -312.474942)
			(xy 43.38066 -312.481976) (xy 43.387772 -312.50763) (xy 43.405871 -312.539002) (xy 43.437909 -312.603967)
			(xy 43.45178 -312.637424) (xy 43.49877 -312.669174) (xy 43.499786 -312.669174) (xy 43.525774 -312.669682)
			(xy 43.577112 -312.677811) (xy 43.626545 -312.693871) (xy 43.672858 -312.717466) (xy 43.71491 -312.748015)
			(xy 43.751664 -312.784766) (xy 43.782218 -312.826815) (xy 43.805817 -312.873125) (xy 43.821881 -312.922557)
			(xy 43.830015 -312.973894) (xy 43.830494 -312.999882) (xy 44.143942 -312.999882) (xy 44.147902 -312.950828)
			(xy 44.159679 -312.903044) (xy 44.17897 -312.857768) (xy 44.205273 -312.816172) (xy 44.237908 -312.779335)
			(xy 44.276029 -312.74821) (xy 44.31865 -312.723603) (xy 44.364666 -312.706151) (xy 44.412885 -312.696307)
			(xy 44.46206 -312.694326) (xy 44.510915 -312.700258) (xy 44.558186 -312.71395) (xy 44.602648 -312.735048)
			(xy 44.643151 -312.763004) (xy 44.678644 -312.797096) (xy 44.708209 -312.83644) (xy 44.73108 -312.880017)
			(xy 44.746664 -312.926698) (xy 44.754559 -312.975275) (xy 44.755054 -312.999882) (xy 46.044116 -312.999882)
			(xy 46.048076 -312.950828) (xy 46.059853 -312.903044) (xy 46.079144 -312.857768) (xy 46.105447 -312.816172)
			(xy 46.138082 -312.779335) (xy 46.176203 -312.74821) (xy 46.218824 -312.723603) (xy 46.26484 -312.706151)
			(xy 46.313059 -312.696307) (xy 46.362234 -312.694326) (xy 46.411089 -312.700258) (xy 46.45836 -312.71395)
			(xy 46.502822 -312.735048) (xy 46.543325 -312.763004) (xy 46.578818 -312.797096) (xy 46.608383 -312.83644)
			(xy 46.631254 -312.880017) (xy 46.646838 -312.926698) (xy 46.654733 -312.975275) (xy 46.655228 -312.999882)
			(xy 47.944036 -312.999882) (xy 47.947996 -312.950828) (xy 47.959773 -312.903044) (xy 47.979064 -312.857768)
			(xy 48.005367 -312.816172) (xy 48.038002 -312.779335) (xy 48.076123 -312.74821) (xy 48.118744 -312.723603)
			(xy 48.16476 -312.706151) (xy 48.212979 -312.696307) (xy 48.262154 -312.694326) (xy 48.311009 -312.700258)
			(xy 48.35828 -312.71395) (xy 48.402742 -312.735048) (xy 48.443245 -312.763004) (xy 48.478738 -312.797096)
			(xy 48.508303 -312.83644) (xy 48.531174 -312.880017) (xy 48.546758 -312.926698) (xy 48.554653 -312.975275)
			(xy 48.555148 -312.999882) (xy 49.843956 -312.999882) (xy 49.847916 -312.950828) (xy 49.859693 -312.903044)
			(xy 49.878984 -312.857768) (xy 49.905287 -312.816172) (xy 49.937922 -312.779335) (xy 49.976043 -312.74821)
			(xy 50.018664 -312.723603) (xy 50.06468 -312.706151) (xy 50.112899 -312.696307) (xy 50.162074 -312.694326)
			(xy 50.210929 -312.700258) (xy 50.2582 -312.71395) (xy 50.302662 -312.735048) (xy 50.343165 -312.763004)
			(xy 50.378658 -312.797096) (xy 50.408223 -312.83644) (xy 50.431094 -312.880017) (xy 50.446678 -312.926698)
			(xy 50.454573 -312.975275) (xy 50.455068 -312.999882) (xy 51.74413 -312.999882) (xy 51.74809 -312.950828)
			(xy 51.759867 -312.903044) (xy 51.779158 -312.857768) (xy 51.805461 -312.816172) (xy 51.838096 -312.779335)
			(xy 51.876217 -312.74821) (xy 51.918838 -312.723603) (xy 51.964854 -312.706151) (xy 52.013073 -312.696307)
			(xy 52.062248 -312.694326) (xy 52.111103 -312.700258) (xy 52.158374 -312.71395) (xy 52.202836 -312.735048)
			(xy 52.243339 -312.763004) (xy 52.278832 -312.797096) (xy 52.308397 -312.83644) (xy 52.331268 -312.880017)
			(xy 52.346852 -312.926698) (xy 52.354747 -312.975275) (xy 52.355242 -312.999882) (xy 53.64405 -312.999882)
			(xy 53.64801 -312.950828) (xy 53.659787 -312.903044) (xy 53.679078 -312.857768) (xy 53.705381 -312.816172)
			(xy 53.738016 -312.779335) (xy 53.776137 -312.74821) (xy 53.818758 -312.723603) (xy 53.864774 -312.706151)
			(xy 53.912993 -312.696307) (xy 53.962168 -312.694326) (xy 54.011023 -312.700258) (xy 54.058294 -312.71395)
			(xy 54.102756 -312.735048) (xy 54.143259 -312.763004) (xy 54.178752 -312.797096) (xy 54.208317 -312.83644)
			(xy 54.231188 -312.880017) (xy 54.246772 -312.926698) (xy 54.254667 -312.975275) (xy 54.255162 -312.999882)
			(xy 55.54397 -312.999882) (xy 55.54793 -312.950828) (xy 55.559707 -312.903044) (xy 55.578998 -312.857768)
			(xy 55.605301 -312.816172) (xy 55.637936 -312.779335) (xy 55.676057 -312.74821) (xy 55.718678 -312.723603)
			(xy 55.764694 -312.706151) (xy 55.812913 -312.696307) (xy 55.862088 -312.694326) (xy 55.910943 -312.700258)
			(xy 55.958214 -312.71395) (xy 56.002676 -312.735048) (xy 56.043179 -312.763004) (xy 56.078672 -312.797096)
			(xy 56.108237 -312.83644) (xy 56.131108 -312.880017) (xy 56.146692 -312.926698) (xy 56.154587 -312.975275)
			(xy 56.155082 -312.999882) (xy 56.154587 -313.024489) (xy 56.146692 -313.073066) (xy 56.131108 -313.119747)
			(xy 56.108237 -313.163324) (xy 56.078672 -313.202668) (xy 56.043179 -313.23676) (xy 56.002676 -313.264716)
			(xy 55.958214 -313.285814) (xy 55.910943 -313.299506) (xy 55.862088 -313.305438) (xy 55.812913 -313.303457)
			(xy 55.764694 -313.293613) (xy 55.718678 -313.276161) (xy 55.676057 -313.251554) (xy 55.637936 -313.220429)
			(xy 55.605301 -313.183592) (xy 55.578998 -313.141996) (xy 55.559707 -313.09672) (xy 55.54793 -313.048936)
			(xy 55.54397 -312.999882) (xy 54.255162 -312.999882) (xy 54.254667 -313.024489) (xy 54.246772 -313.073066)
			(xy 54.231188 -313.119747) (xy 54.208317 -313.163324) (xy 54.178752 -313.202668) (xy 54.143259 -313.23676)
			(xy 54.102756 -313.264716) (xy 54.058294 -313.285814) (xy 54.011023 -313.299506) (xy 53.962168 -313.305438)
			(xy 53.912993 -313.303457) (xy 53.864774 -313.293613) (xy 53.818758 -313.276161) (xy 53.776137 -313.251554)
			(xy 53.738016 -313.220429) (xy 53.705381 -313.183592) (xy 53.679078 -313.141996) (xy 53.659787 -313.09672)
			(xy 53.64801 -313.048936) (xy 53.64405 -312.999882) (xy 52.355242 -312.999882) (xy 52.354747 -313.024489)
			(xy 52.346852 -313.073066) (xy 52.331268 -313.119747) (xy 52.308397 -313.163324) (xy 52.278832 -313.202668)
			(xy 52.243339 -313.23676) (xy 52.202836 -313.264716) (xy 52.158374 -313.285814) (xy 52.111103 -313.299506)
			(xy 52.062248 -313.305438) (xy 52.013073 -313.303457) (xy 51.964854 -313.293613) (xy 51.918838 -313.276161)
			(xy 51.876217 -313.251554) (xy 51.838096 -313.220429) (xy 51.805461 -313.183592) (xy 51.779158 -313.141996)
			(xy 51.759867 -313.09672) (xy 51.74809 -313.048936) (xy 51.74413 -312.999882) (xy 50.455068 -312.999882)
			(xy 50.454573 -313.024489) (xy 50.446678 -313.073066) (xy 50.431094 -313.119747) (xy 50.408223 -313.163324)
			(xy 50.378658 -313.202668) (xy 50.343165 -313.23676) (xy 50.302662 -313.264716) (xy 50.2582 -313.285814)
			(xy 50.210929 -313.299506) (xy 50.162074 -313.305438) (xy 50.112899 -313.303457) (xy 50.06468 -313.293613)
			(xy 50.018664 -313.276161) (xy 49.976043 -313.251554) (xy 49.937922 -313.220429) (xy 49.905287 -313.183592)
			(xy 49.878984 -313.141996) (xy 49.859693 -313.09672) (xy 49.847916 -313.048936) (xy 49.843956 -312.999882)
			(xy 48.555148 -312.999882) (xy 48.554653 -313.024489) (xy 48.546758 -313.073066) (xy 48.531174 -313.119747)
			(xy 48.508303 -313.163324) (xy 48.478738 -313.202668) (xy 48.443245 -313.23676) (xy 48.402742 -313.264716)
			(xy 48.35828 -313.285814) (xy 48.311009 -313.299506) (xy 48.262154 -313.305438) (xy 48.212979 -313.303457)
			(xy 48.16476 -313.293613) (xy 48.118744 -313.276161) (xy 48.076123 -313.251554) (xy 48.038002 -313.220429)
			(xy 48.005367 -313.183592) (xy 47.979064 -313.141996) (xy 47.959773 -313.09672) (xy 47.947996 -313.048936)
			(xy 47.944036 -312.999882) (xy 46.655228 -312.999882) (xy 46.654733 -313.024489) (xy 46.646838 -313.073066)
			(xy 46.631254 -313.119747) (xy 46.608383 -313.163324) (xy 46.578818 -313.202668) (xy 46.543325 -313.23676)
			(xy 46.502822 -313.264716) (xy 46.45836 -313.285814) (xy 46.411089 -313.299506) (xy 46.362234 -313.305438)
			(xy 46.313059 -313.303457) (xy 46.26484 -313.293613) (xy 46.218824 -313.276161) (xy 46.176203 -313.251554)
			(xy 46.138082 -313.220429) (xy 46.105447 -313.183592) (xy 46.079144 -313.141996) (xy 46.059853 -313.09672)
			(xy 46.048076 -313.048936) (xy 46.044116 -312.999882) (xy 44.755054 -312.999882) (xy 44.754559 -313.024489)
			(xy 44.746664 -313.073066) (xy 44.73108 -313.119747) (xy 44.708209 -313.163324) (xy 44.678644 -313.202668)
			(xy 44.643151 -313.23676) (xy 44.602648 -313.264716) (xy 44.558186 -313.285814) (xy 44.510915 -313.299506)
			(xy 44.46206 -313.305438) (xy 44.412885 -313.303457) (xy 44.364666 -313.293613) (xy 44.31865 -313.276161)
			(xy 44.276029 -313.251554) (xy 44.237908 -313.220429) (xy 44.205273 -313.183592) (xy 44.17897 -313.141996)
			(xy 44.159679 -313.09672) (xy 44.147902 -313.048936) (xy 44.143942 -312.999882) (xy 43.830494 -312.999882)
			(xy 43.830007 -313.025508) (xy 43.822092 -313.076147) (xy 43.806463 -313.124959) (xy 43.783495 -313.170778)
			(xy 43.753737 -313.212507) (xy 43.7179 -313.249149) (xy 43.676842 -313.279827) (xy 43.631545 -313.303807)
			(xy 43.583092 -313.320516) (xy 43.557952 -313.32551) (xy 43.547277 -313.327945) (xy 43.529279 -313.340376)
			(xy 43.518058 -313.359152) (xy 43.516296 -313.36996) (xy 43.513566 -313.393732) (xy 43.506071 -313.440998)
			(xy 43.50131 -313.464448) (xy 43.500294 -313.474862) (xy 43.50131 -313.485276) (xy 43.506078 -313.508725)
			(xy 43.513575 -313.55599) (xy 43.516296 -313.579764) (xy 43.518015 -313.590587) (xy 43.52924 -313.609381)
			(xy 43.547262 -313.62181) (xy 43.557952 -313.624214) (xy 43.583101 -313.62919) (xy 43.631575 -313.645873)
			(xy 43.676893 -313.669838) (xy 43.717969 -313.70051) (xy 43.753818 -313.737156) (xy 43.783581 -313.778895)
			(xy 43.806545 -313.824728) (xy 43.82216 -313.873556) (xy 43.830051 -313.92421) (xy 43.830494 -313.949842)
			(xy 44.143942 -313.949842) (xy 44.147902 -313.900788) (xy 44.159679 -313.853004) (xy 44.17897 -313.807728)
			(xy 44.205273 -313.766132) (xy 44.237908 -313.729295) (xy 44.276029 -313.69817) (xy 44.31865 -313.673563)
			(xy 44.364666 -313.656111) (xy 44.412885 -313.646267) (xy 44.46206 -313.644286) (xy 44.510915 -313.650218)
			(xy 44.558186 -313.66391) (xy 44.602648 -313.685008) (xy 44.643151 -313.712964) (xy 44.678644 -313.747056)
			(xy 44.708209 -313.7864) (xy 44.73108 -313.829977) (xy 44.746664 -313.876658) (xy 44.754559 -313.925235)
			(xy 44.755054 -313.949842) (xy 46.044116 -313.949842) (xy 46.048076 -313.900788) (xy 46.059853 -313.853004)
			(xy 46.079144 -313.807728) (xy 46.105447 -313.766132) (xy 46.138082 -313.729295) (xy 46.176203 -313.69817)
			(xy 46.218824 -313.673563) (xy 46.26484 -313.656111) (xy 46.313059 -313.646267) (xy 46.362234 -313.644286)
			(xy 46.411089 -313.650218) (xy 46.45836 -313.66391) (xy 46.502822 -313.685008) (xy 46.543325 -313.712964)
			(xy 46.578818 -313.747056) (xy 46.608383 -313.7864) (xy 46.631254 -313.829977) (xy 46.646838 -313.876658)
			(xy 46.654733 -313.925235) (xy 46.655228 -313.949842) (xy 47.944036 -313.949842) (xy 47.947996 -313.900788)
			(xy 47.959773 -313.853004) (xy 47.979064 -313.807728) (xy 48.005367 -313.766132) (xy 48.038002 -313.729295)
			(xy 48.076123 -313.69817) (xy 48.118744 -313.673563) (xy 48.16476 -313.656111) (xy 48.212979 -313.646267)
			(xy 48.262154 -313.644286) (xy 48.311009 -313.650218) (xy 48.35828 -313.66391) (xy 48.402742 -313.685008)
			(xy 48.443245 -313.712964) (xy 48.478738 -313.747056) (xy 48.508303 -313.7864) (xy 48.531174 -313.829977)
			(xy 48.546758 -313.876658) (xy 48.554653 -313.925235) (xy 48.555148 -313.949842) (xy 49.843956 -313.949842)
			(xy 49.847916 -313.900788) (xy 49.859693 -313.853004) (xy 49.878984 -313.807728) (xy 49.905287 -313.766132)
			(xy 49.937922 -313.729295) (xy 49.976043 -313.69817) (xy 50.018664 -313.673563) (xy 50.06468 -313.656111)
			(xy 50.112899 -313.646267) (xy 50.162074 -313.644286) (xy 50.210929 -313.650218) (xy 50.2582 -313.66391)
			(xy 50.302662 -313.685008) (xy 50.343165 -313.712964) (xy 50.378658 -313.747056) (xy 50.408223 -313.7864)
			(xy 50.431094 -313.829977) (xy 50.446678 -313.876658) (xy 50.454573 -313.925235) (xy 50.455068 -313.949842)
			(xy 51.74413 -313.949842) (xy 51.74809 -313.900788) (xy 51.759867 -313.853004) (xy 51.779158 -313.807728)
			(xy 51.805461 -313.766132) (xy 51.838096 -313.729295) (xy 51.876217 -313.69817) (xy 51.918838 -313.673563)
			(xy 51.964854 -313.656111) (xy 52.013073 -313.646267) (xy 52.062248 -313.644286) (xy 52.111103 -313.650218)
			(xy 52.158374 -313.66391) (xy 52.202836 -313.685008) (xy 52.243339 -313.712964) (xy 52.278832 -313.747056)
			(xy 52.308397 -313.7864) (xy 52.331268 -313.829977) (xy 52.346852 -313.876658) (xy 52.354747 -313.925235)
			(xy 52.355242 -313.949842) (xy 53.64405 -313.949842) (xy 53.64801 -313.900788) (xy 53.659787 -313.853004)
			(xy 53.679078 -313.807728) (xy 53.705381 -313.766132) (xy 53.738016 -313.729295) (xy 53.776137 -313.69817)
			(xy 53.818758 -313.673563) (xy 53.864774 -313.656111) (xy 53.912993 -313.646267) (xy 53.962168 -313.644286)
			(xy 54.011023 -313.650218) (xy 54.058294 -313.66391) (xy 54.102756 -313.685008) (xy 54.143259 -313.712964)
			(xy 54.178752 -313.747056) (xy 54.208317 -313.7864) (xy 54.231188 -313.829977) (xy 54.246772 -313.876658)
			(xy 54.254667 -313.925235) (xy 54.255162 -313.949842) (xy 55.54397 -313.949842) (xy 55.54793 -313.900788)
			(xy 55.559707 -313.853004) (xy 55.578998 -313.807728) (xy 55.605301 -313.766132) (xy 55.637936 -313.729295)
			(xy 55.676057 -313.69817) (xy 55.718678 -313.673563) (xy 55.764694 -313.656111) (xy 55.812913 -313.646267)
			(xy 55.862088 -313.644286) (xy 55.910943 -313.650218) (xy 55.958214 -313.66391) (xy 56.002676 -313.685008)
			(xy 56.043179 -313.712964) (xy 56.078672 -313.747056) (xy 56.108237 -313.7864) (xy 56.131108 -313.829977)
			(xy 56.146692 -313.876658) (xy 56.154587 -313.925235) (xy 56.155082 -313.949842) (xy 56.154587 -313.974449)
			(xy 56.146692 -314.023026) (xy 56.131108 -314.069707) (xy 56.108237 -314.113284) (xy 56.078672 -314.152628)
			(xy 56.043179 -314.18672) (xy 56.002676 -314.214676) (xy 55.958214 -314.235774) (xy 55.910943 -314.249466)
			(xy 55.862088 -314.255398) (xy 55.812913 -314.253417) (xy 55.764694 -314.243573) (xy 55.718678 -314.226121)
			(xy 55.676057 -314.201514) (xy 55.637936 -314.170389) (xy 55.605301 -314.133552) (xy 55.578998 -314.091956)
			(xy 55.559707 -314.04668) (xy 55.54793 -313.998896) (xy 55.54397 -313.949842) (xy 54.255162 -313.949842)
			(xy 54.254667 -313.974449) (xy 54.246772 -314.023026) (xy 54.231188 -314.069707) (xy 54.208317 -314.113284)
			(xy 54.178752 -314.152628) (xy 54.143259 -314.18672) (xy 54.102756 -314.214676) (xy 54.058294 -314.235774)
			(xy 54.011023 -314.249466) (xy 53.962168 -314.255398) (xy 53.912993 -314.253417) (xy 53.864774 -314.243573)
			(xy 53.818758 -314.226121) (xy 53.776137 -314.201514) (xy 53.738016 -314.170389) (xy 53.705381 -314.133552)
			(xy 53.679078 -314.091956) (xy 53.659787 -314.04668) (xy 53.64801 -313.998896) (xy 53.64405 -313.949842)
			(xy 52.355242 -313.949842) (xy 52.354747 -313.974449) (xy 52.346852 -314.023026) (xy 52.331268 -314.069707)
			(xy 52.308397 -314.113284) (xy 52.278832 -314.152628) (xy 52.243339 -314.18672) (xy 52.202836 -314.214676)
			(xy 52.158374 -314.235774) (xy 52.111103 -314.249466) (xy 52.062248 -314.255398) (xy 52.013073 -314.253417)
			(xy 51.964854 -314.243573) (xy 51.918838 -314.226121) (xy 51.876217 -314.201514) (xy 51.838096 -314.170389)
			(xy 51.805461 -314.133552) (xy 51.779158 -314.091956) (xy 51.759867 -314.04668) (xy 51.74809 -313.998896)
			(xy 51.74413 -313.949842) (xy 50.455068 -313.949842) (xy 50.454573 -313.974449) (xy 50.446678 -314.023026)
			(xy 50.431094 -314.069707) (xy 50.408223 -314.113284) (xy 50.378658 -314.152628) (xy 50.343165 -314.18672)
			(xy 50.302662 -314.214676) (xy 50.2582 -314.235774) (xy 50.210929 -314.249466) (xy 50.162074 -314.255398)
			(xy 50.112899 -314.253417) (xy 50.06468 -314.243573) (xy 50.018664 -314.226121) (xy 49.976043 -314.201514)
			(xy 49.937922 -314.170389) (xy 49.905287 -314.133552) (xy 49.878984 -314.091956) (xy 49.859693 -314.04668)
			(xy 49.847916 -313.998896) (xy 49.843956 -313.949842) (xy 48.555148 -313.949842) (xy 48.554653 -313.974449)
			(xy 48.546758 -314.023026) (xy 48.531174 -314.069707) (xy 48.508303 -314.113284) (xy 48.478738 -314.152628)
			(xy 48.443245 -314.18672) (xy 48.402742 -314.214676) (xy 48.35828 -314.235774) (xy 48.311009 -314.249466)
			(xy 48.262154 -314.255398) (xy 48.212979 -314.253417) (xy 48.16476 -314.243573) (xy 48.118744 -314.226121)
			(xy 48.076123 -314.201514) (xy 48.038002 -314.170389) (xy 48.005367 -314.133552) (xy 47.979064 -314.091956)
			(xy 47.959773 -314.04668) (xy 47.947996 -313.998896) (xy 47.944036 -313.949842) (xy 46.655228 -313.949842)
			(xy 46.654733 -313.974449) (xy 46.646838 -314.023026) (xy 46.631254 -314.069707) (xy 46.608383 -314.113284)
			(xy 46.578818 -314.152628) (xy 46.543325 -314.18672) (xy 46.502822 -314.214676) (xy 46.45836 -314.235774)
			(xy 46.411089 -314.249466) (xy 46.362234 -314.255398) (xy 46.313059 -314.253417) (xy 46.26484 -314.243573)
			(xy 46.218824 -314.226121) (xy 46.176203 -314.201514) (xy 46.138082 -314.170389) (xy 46.105447 -314.133552)
			(xy 46.079144 -314.091956) (xy 46.059853 -314.04668) (xy 46.048076 -313.998896) (xy 46.044116 -313.949842)
			(xy 44.755054 -313.949842) (xy 44.754559 -313.974449) (xy 44.746664 -314.023026) (xy 44.73108 -314.069707)
			(xy 44.708209 -314.113284) (xy 44.678644 -314.152628) (xy 44.643151 -314.18672) (xy 44.602648 -314.214676)
			(xy 44.558186 -314.235774) (xy 44.510915 -314.249466) (xy 44.46206 -314.255398) (xy 44.412885 -314.253417)
			(xy 44.364666 -314.243573) (xy 44.31865 -314.226121) (xy 44.276029 -314.201514) (xy 44.237908 -314.170389)
			(xy 44.205273 -314.133552) (xy 44.17897 -314.091956) (xy 44.159679 -314.04668) (xy 44.147902 -313.998896)
			(xy 44.143942 -313.949842) (xy 43.830494 -313.949842) (xy 43.829981 -313.975827) (xy 43.821845 -314.027155)
			(xy 43.805781 -314.076579) (xy 43.782182 -314.122882) (xy 43.751632 -314.164923) (xy 43.714881 -314.201668)
			(xy 43.672834 -314.232212) (xy 43.626527 -314.255802) (xy 43.577101 -314.271859) (xy 43.525771 -314.279986)
			(xy 43.499786 -314.28055) (xy 43.49877 -314.28055) (xy 43.45178 -314.3123) (xy 43.430893 -314.362249)
			(xy 43.379592 -314.457594) (xy 43.349418 -314.502546) (xy 43.34256 -314.517278) (xy 43.335403 -314.540308)
			(xy 43.315341 -314.58416) (xy 43.289115 -314.62463) (xy 43.257284 -314.660856) (xy 43.239182 -314.67679)
			(xy 43.222527 -314.690425) (xy 43.186343 -314.713737) (xy 43.167046 -314.723272) (xy 43.16603 -314.72378)
			(xy 43.15714 -314.728098) (xy 43.1419 -314.752736) (xy 43.1419 -315.5061) (xy 43.142367 -315.515445)
			(xy 43.149138 -315.532872) (xy 43.16168 -315.546736) (xy 43.16984 -315.551312) (xy 43.251374 -315.592206)
			(xy 43.259939 -315.596043) (xy 43.278601 -315.597881) (xy 43.296672 -315.592873) (xy 43.30446 -315.587634)
			(xy 43.325764 -315.572404) (xy 43.372205 -315.54821) (xy 43.421908 -315.531728) (xy 43.473603 -315.523379)
			(xy 43.499786 -315.522864) (xy 43.52548 -315.52334) (xy 43.576234 -315.531377) (xy 43.625107 -315.547255)
			(xy 43.670894 -315.570583) (xy 43.712468 -315.600786) (xy 43.748805 -315.637122) (xy 43.77901 -315.678694)
			(xy 43.80234 -315.72448) (xy 43.81822 -315.773352) (xy 43.826258 -315.824106) (xy 43.826258 -315.87547)
			(xy 45.073312 -315.87547) (xy 45.073312 -315.824054) (xy 45.081355 -315.773272) (xy 45.097243 -315.724373)
			(xy 45.120586 -315.678561) (xy 45.150807 -315.636965) (xy 45.187163 -315.600609) (xy 45.228759 -315.570388)
			(xy 45.274571 -315.547045) (xy 45.32347 -315.531157) (xy 45.374252 -315.523114) (xy 45.425668 -315.523114)
			(xy 45.47645 -315.531157) (xy 45.525349 -315.547045) (xy 45.571161 -315.570388) (xy 45.612757 -315.600609)
			(xy 45.649113 -315.636965) (xy 45.679334 -315.678561) (xy 45.702677 -315.724373) (xy 45.718565 -315.773272)
			(xy 45.726608 -315.824054) (xy 45.727112 -315.849762) (xy 45.726608 -315.87547) (xy 46.973232 -315.87547)
			(xy 46.973232 -315.824054) (xy 46.981275 -315.773272) (xy 46.997163 -315.724373) (xy 47.020506 -315.678561)
			(xy 47.050727 -315.636965) (xy 47.087083 -315.600609) (xy 47.128679 -315.570388) (xy 47.174491 -315.547045)
			(xy 47.22339 -315.531157) (xy 47.274172 -315.523114) (xy 47.325588 -315.523114) (xy 47.37637 -315.531157)
			(xy 47.425269 -315.547045) (xy 47.471081 -315.570388) (xy 47.512677 -315.600609) (xy 47.549033 -315.636965)
			(xy 47.579254 -315.678561) (xy 47.602597 -315.724373) (xy 47.618485 -315.773272) (xy 47.626528 -315.824054)
			(xy 47.627032 -315.849762) (xy 47.626528 -315.87547) (xy 48.873152 -315.87547) (xy 48.873152 -315.824054)
			(xy 48.881195 -315.773272) (xy 48.897083 -315.724373) (xy 48.920426 -315.678561) (xy 48.950647 -315.636965)
			(xy 48.987003 -315.600609) (xy 49.028599 -315.570388) (xy 49.074411 -315.547045) (xy 49.12331 -315.531157)
			(xy 49.174092 -315.523114) (xy 49.225508 -315.523114) (xy 49.27629 -315.531157) (xy 49.325189 -315.547045)
			(xy 49.371001 -315.570388) (xy 49.412597 -315.600609) (xy 49.448953 -315.636965) (xy 49.479174 -315.678561)
			(xy 49.502517 -315.724373) (xy 49.518405 -315.773272) (xy 49.526448 -315.824054) (xy 49.526952 -315.849762)
			(xy 50.79417 -315.849762) (xy 50.79813 -315.800708) (xy 50.809907 -315.752924) (xy 50.829198 -315.707648)
			(xy 50.855501 -315.666052) (xy 50.888136 -315.629215) (xy 50.926257 -315.59809) (xy 50.968878 -315.573483)
			(xy 51.014894 -315.556031) (xy 51.063113 -315.546187) (xy 51.112288 -315.544206) (xy 51.161143 -315.550138)
			(xy 51.208414 -315.56383) (xy 51.252876 -315.584928) (xy 51.293379 -315.612884) (xy 51.328872 -315.646976)
			(xy 51.358437 -315.68632) (xy 51.381308 -315.729897) (xy 51.396892 -315.776578) (xy 51.404787 -315.825155)
			(xy 51.405282 -315.849762) (xy 52.69409 -315.849762) (xy 52.69805 -315.800708) (xy 52.709827 -315.752924)
			(xy 52.729118 -315.707648) (xy 52.755421 -315.666052) (xy 52.788056 -315.629215) (xy 52.826177 -315.59809)
			(xy 52.868798 -315.573483) (xy 52.914814 -315.556031) (xy 52.963033 -315.546187) (xy 53.012208 -315.544206)
			(xy 53.061063 -315.550138) (xy 53.108334 -315.56383) (xy 53.152796 -315.584928) (xy 53.193299 -315.612884)
			(xy 53.228792 -315.646976) (xy 53.258357 -315.68632) (xy 53.281228 -315.729897) (xy 53.296812 -315.776578)
			(xy 53.304707 -315.825155) (xy 53.305202 -315.849762) (xy 54.59401 -315.849762) (xy 54.59797 -315.800708)
			(xy 54.609747 -315.752924) (xy 54.629038 -315.707648) (xy 54.655341 -315.666052) (xy 54.687976 -315.629215)
			(xy 54.726097 -315.59809) (xy 54.768718 -315.573483) (xy 54.814734 -315.556031) (xy 54.862953 -315.546187)
			(xy 54.912128 -315.544206) (xy 54.960983 -315.550138) (xy 55.008254 -315.56383) (xy 55.052716 -315.584928)
			(xy 55.093219 -315.612884) (xy 55.128712 -315.646976) (xy 55.158277 -315.68632) (xy 55.181148 -315.729897)
			(xy 55.196732 -315.776578) (xy 55.204627 -315.825155) (xy 55.205122 -315.849762) (xy 55.204627 -315.874369)
			(xy 55.196732 -315.922946) (xy 55.181148 -315.969627) (xy 55.158277 -316.013204) (xy 55.128712 -316.052548)
			(xy 55.093219 -316.08664) (xy 55.052716 -316.114596) (xy 55.008254 -316.135694) (xy 54.960983 -316.149386)
			(xy 54.912128 -316.155318) (xy 54.862953 -316.153337) (xy 54.814734 -316.143493) (xy 54.768718 -316.126041)
			(xy 54.726097 -316.101434) (xy 54.687976 -316.070309) (xy 54.655341 -316.033472) (xy 54.629038 -315.991876)
			(xy 54.609747 -315.9466) (xy 54.59797 -315.898816) (xy 54.59401 -315.849762) (xy 53.305202 -315.849762)
			(xy 53.304707 -315.874369) (xy 53.296812 -315.922946) (xy 53.281228 -315.969627) (xy 53.258357 -316.013204)
			(xy 53.228792 -316.052548) (xy 53.193299 -316.08664) (xy 53.152796 -316.114596) (xy 53.108334 -316.135694)
			(xy 53.061063 -316.149386) (xy 53.012208 -316.155318) (xy 52.963033 -316.153337) (xy 52.914814 -316.143493)
			(xy 52.868798 -316.126041) (xy 52.826177 -316.101434) (xy 52.788056 -316.070309) (xy 52.755421 -316.033472)
			(xy 52.729118 -315.991876) (xy 52.709827 -315.9466) (xy 52.69805 -315.898816) (xy 52.69409 -315.849762)
			(xy 51.405282 -315.849762) (xy 51.404787 -315.874369) (xy 51.396892 -315.922946) (xy 51.381308 -315.969627)
			(xy 51.358437 -316.013204) (xy 51.328872 -316.052548) (xy 51.293379 -316.08664) (xy 51.252876 -316.114596)
			(xy 51.208414 -316.135694) (xy 51.161143 -316.149386) (xy 51.112288 -316.155318) (xy 51.063113 -316.153337)
			(xy 51.014894 -316.143493) (xy 50.968878 -316.126041) (xy 50.926257 -316.101434) (xy 50.888136 -316.070309)
			(xy 50.855501 -316.033472) (xy 50.829198 -315.991876) (xy 50.809907 -315.9466) (xy 50.79813 -315.898816)
			(xy 50.79417 -315.849762) (xy 49.526952 -315.849762) (xy 49.526448 -315.87547) (xy 49.518405 -315.926252)
			(xy 49.502517 -315.975151) (xy 49.479174 -316.020963) (xy 49.448953 -316.062559) (xy 49.412597 -316.098915)
			(xy 49.371001 -316.129136) (xy 49.325189 -316.152479) (xy 49.27629 -316.168367) (xy 49.225508 -316.17641)
			(xy 49.174092 -316.17641) (xy 49.12331 -316.168367) (xy 49.074411 -316.152479) (xy 49.028599 -316.129136)
			(xy 48.987003 -316.098915) (xy 48.950647 -316.062559) (xy 48.920426 -316.020963) (xy 48.897083 -315.975151)
			(xy 48.881195 -315.926252) (xy 48.873152 -315.87547) (xy 47.626528 -315.87547) (xy 47.618485 -315.926252)
			(xy 47.602597 -315.975151) (xy 47.579254 -316.020963) (xy 47.549033 -316.062559) (xy 47.512677 -316.098915)
			(xy 47.471081 -316.129136) (xy 47.425269 -316.152479) (xy 47.37637 -316.168367) (xy 47.325588 -316.17641)
			(xy 47.274172 -316.17641) (xy 47.22339 -316.168367) (xy 47.174491 -316.152479) (xy 47.128679 -316.129136)
			(xy 47.087083 -316.098915) (xy 47.050727 -316.062559) (xy 47.020506 -316.020963) (xy 46.997163 -315.975151)
			(xy 46.981275 -315.926252) (xy 46.973232 -315.87547) (xy 45.726608 -315.87547) (xy 45.718565 -315.926252)
			(xy 45.702677 -315.975151) (xy 45.679334 -316.020963) (xy 45.649113 -316.062559) (xy 45.612757 -316.098915)
			(xy 45.571161 -316.129136) (xy 45.525349 -316.152479) (xy 45.47645 -316.168367) (xy 45.425668 -316.17641)
			(xy 45.374252 -316.17641) (xy 45.32347 -316.168367) (xy 45.274571 -316.152479) (xy 45.228759 -316.129136)
			(xy 45.187163 -316.098915) (xy 45.150807 -316.062559) (xy 45.120586 -316.020963) (xy 45.097243 -315.975151)
			(xy 45.081355 -315.926252) (xy 45.073312 -315.87547) (xy 43.826258 -315.87547) (xy 43.826258 -315.875494)
			(xy 43.81822 -315.926248) (xy 43.80234 -315.97512) (xy 43.77901 -316.020906) (xy 43.748805 -316.062478)
			(xy 43.712468 -316.098814) (xy 43.670894 -316.129017) (xy 43.625107 -316.152345) (xy 43.576234 -316.168223)
			(xy 43.52548 -316.17626) (xy 43.499786 -316.17666) (xy 43.464988 -316.174882) (xy 43.464734 -316.174882)
			(xy 43.453387 -316.174365) (xy 43.432032 -316.182018) (xy 43.423586 -316.189614) (xy 43.359324 -316.25413)
			(xy 43.351958 -316.275974) (xy 43.353228 -316.287404) (xy 43.354195 -316.296708) (xy 43.355211 -316.315388)
			(xy 43.35526 -316.324742) (xy 43.35526 -316.37351) (xy 43.355871 -316.384132) (xy 43.364542 -316.403535)
			(xy 43.372024 -316.411102) (xy 43.436032 -316.46876) (xy 43.456352 -316.475364) (xy 43.46702 -316.474348)
			(xy 43.499786 -316.472824) (xy 43.525475 -316.473301) (xy 43.57622 -316.481336) (xy 43.625084 -316.497211)
			(xy 43.670862 -316.520534) (xy 43.712428 -316.550732) (xy 43.748759 -316.587061) (xy 43.778958 -316.628626)
			(xy 43.802284 -316.674403) (xy 43.818161 -316.723266) (xy 43.826198 -316.774011) (xy 43.826198 -316.825389)
			(xy 43.826192 -316.82543) (xy 45.073312 -316.82543) (xy 45.073312 -316.774014) (xy 45.081355 -316.723232)
			(xy 45.097243 -316.674333) (xy 45.120586 -316.628521) (xy 45.150807 -316.586925) (xy 45.187163 -316.550569)
			(xy 45.228759 -316.520348) (xy 45.274571 -316.497005) (xy 45.32347 -316.481117) (xy 45.374252 -316.473074)
			(xy 45.425668 -316.473074) (xy 45.47645 -316.481117) (xy 45.525349 -316.497005) (xy 45.571161 -316.520348)
			(xy 45.612757 -316.550569) (xy 45.649113 -316.586925) (xy 45.679334 -316.628521) (xy 45.702677 -316.674333)
			(xy 45.718565 -316.723232) (xy 45.726608 -316.774014) (xy 45.727112 -316.799722) (xy 45.726608 -316.82543)
			(xy 46.973232 -316.82543) (xy 46.973232 -316.774014) (xy 46.981275 -316.723232) (xy 46.997163 -316.674333)
			(xy 47.020506 -316.628521) (xy 47.050727 -316.586925) (xy 47.087083 -316.550569) (xy 47.128679 -316.520348)
			(xy 47.174491 -316.497005) (xy 47.22339 -316.481117) (xy 47.274172 -316.473074) (xy 47.325588 -316.473074)
			(xy 47.37637 -316.481117) (xy 47.425269 -316.497005) (xy 47.471081 -316.520348) (xy 47.512677 -316.550569)
			(xy 47.549033 -316.586925) (xy 47.579254 -316.628521) (xy 47.602597 -316.674333) (xy 47.618485 -316.723232)
			(xy 47.626528 -316.774014) (xy 47.627032 -316.799722) (xy 47.626528 -316.82543) (xy 48.873152 -316.82543)
			(xy 48.873152 -316.774014) (xy 48.881195 -316.723232) (xy 48.897083 -316.674333) (xy 48.920426 -316.628521)
			(xy 48.950647 -316.586925) (xy 48.987003 -316.550569) (xy 49.028599 -316.520348) (xy 49.074411 -316.497005)
			(xy 49.12331 -316.481117) (xy 49.174092 -316.473074) (xy 49.225508 -316.473074) (xy 49.27629 -316.481117)
			(xy 49.325189 -316.497005) (xy 49.371001 -316.520348) (xy 49.412597 -316.550569) (xy 49.448953 -316.586925)
			(xy 49.479174 -316.628521) (xy 49.502517 -316.674333) (xy 49.518405 -316.723232) (xy 49.526448 -316.774014)
			(xy 49.526952 -316.799722) (xy 50.79417 -316.799722) (xy 50.79813 -316.750668) (xy 50.809907 -316.702884)
			(xy 50.829198 -316.657608) (xy 50.855501 -316.616012) (xy 50.888136 -316.579175) (xy 50.926257 -316.54805)
			(xy 50.968878 -316.523443) (xy 51.014894 -316.505991) (xy 51.063113 -316.496147) (xy 51.112288 -316.494166)
			(xy 51.161143 -316.500098) (xy 51.208414 -316.51379) (xy 51.252876 -316.534888) (xy 51.293379 -316.562844)
			(xy 51.328872 -316.596936) (xy 51.358437 -316.63628) (xy 51.381308 -316.679857) (xy 51.396892 -316.726538)
			(xy 51.404787 -316.775115) (xy 51.405282 -316.799722) (xy 52.69409 -316.799722) (xy 52.69805 -316.750668)
			(xy 52.709827 -316.702884) (xy 52.729118 -316.657608) (xy 52.755421 -316.616012) (xy 52.788056 -316.579175)
			(xy 52.826177 -316.54805) (xy 52.868798 -316.523443) (xy 52.914814 -316.505991) (xy 52.963033 -316.496147)
			(xy 53.012208 -316.494166) (xy 53.061063 -316.500098) (xy 53.108334 -316.51379) (xy 53.152796 -316.534888)
			(xy 53.193299 -316.562844) (xy 53.228792 -316.596936) (xy 53.258357 -316.63628) (xy 53.281228 -316.679857)
			(xy 53.296812 -316.726538) (xy 53.304707 -316.775115) (xy 53.305202 -316.799722) (xy 54.59401 -316.799722)
			(xy 54.59797 -316.750668) (xy 54.609747 -316.702884) (xy 54.629038 -316.657608) (xy 54.655341 -316.616012)
			(xy 54.687976 -316.579175) (xy 54.726097 -316.54805) (xy 54.768718 -316.523443) (xy 54.814734 -316.505991)
			(xy 54.862953 -316.496147) (xy 54.912128 -316.494166) (xy 54.960983 -316.500098) (xy 55.008254 -316.51379)
			(xy 55.052716 -316.534888) (xy 55.093219 -316.562844) (xy 55.128712 -316.596936) (xy 55.158277 -316.63628)
			(xy 55.181148 -316.679857) (xy 55.196732 -316.726538) (xy 55.204627 -316.775115) (xy 55.205122 -316.799722)
			(xy 55.204627 -316.824329) (xy 55.196732 -316.872906) (xy 55.181148 -316.919587) (xy 55.158277 -316.963164)
			(xy 55.128712 -317.002508) (xy 55.093219 -317.0366) (xy 55.052716 -317.064556) (xy 55.008254 -317.085654)
			(xy 54.960983 -317.099346) (xy 54.912128 -317.105278) (xy 54.862953 -317.103297) (xy 54.814734 -317.093453)
			(xy 54.768718 -317.076001) (xy 54.726097 -317.051394) (xy 54.687976 -317.020269) (xy 54.655341 -316.983432)
			(xy 54.629038 -316.941836) (xy 54.609747 -316.89656) (xy 54.59797 -316.848776) (xy 54.59401 -316.799722)
			(xy 53.305202 -316.799722) (xy 53.304707 -316.824329) (xy 53.296812 -316.872906) (xy 53.281228 -316.919587)
			(xy 53.258357 -316.963164) (xy 53.228792 -317.002508) (xy 53.193299 -317.0366) (xy 53.152796 -317.064556)
			(xy 53.108334 -317.085654) (xy 53.061063 -317.099346) (xy 53.012208 -317.105278) (xy 52.963033 -317.103297)
			(xy 52.914814 -317.093453) (xy 52.868798 -317.076001) (xy 52.826177 -317.051394) (xy 52.788056 -317.020269)
			(xy 52.755421 -316.983432) (xy 52.729118 -316.941836) (xy 52.709827 -316.89656) (xy 52.69805 -316.848776)
			(xy 52.69409 -316.799722) (xy 51.405282 -316.799722) (xy 51.404787 -316.824329) (xy 51.396892 -316.872906)
			(xy 51.381308 -316.919587) (xy 51.358437 -316.963164) (xy 51.328872 -317.002508) (xy 51.293379 -317.0366)
			(xy 51.252876 -317.064556) (xy 51.208414 -317.085654) (xy 51.161143 -317.099346) (xy 51.112288 -317.105278)
			(xy 51.063113 -317.103297) (xy 51.014894 -317.093453) (xy 50.968878 -317.076001) (xy 50.926257 -317.051394)
			(xy 50.888136 -317.020269) (xy 50.855501 -316.983432) (xy 50.829198 -316.941836) (xy 50.809907 -316.89656)
			(xy 50.79813 -316.848776) (xy 50.79417 -316.799722) (xy 49.526952 -316.799722) (xy 49.526448 -316.82543)
			(xy 49.518405 -316.876212) (xy 49.502517 -316.925111) (xy 49.479174 -316.970923) (xy 49.448953 -317.012519)
			(xy 49.412597 -317.048875) (xy 49.371001 -317.079096) (xy 49.325189 -317.102439) (xy 49.27629 -317.118327)
			(xy 49.225508 -317.12637) (xy 49.174092 -317.12637) (xy 49.12331 -317.118327) (xy 49.074411 -317.102439)
			(xy 49.028599 -317.079096) (xy 48.987003 -317.048875) (xy 48.950647 -317.012519) (xy 48.920426 -316.970923)
			(xy 48.897083 -316.925111) (xy 48.881195 -316.876212) (xy 48.873152 -316.82543) (xy 47.626528 -316.82543)
			(xy 47.618485 -316.876212) (xy 47.602597 -316.925111) (xy 47.579254 -316.970923) (xy 47.549033 -317.012519)
			(xy 47.512677 -317.048875) (xy 47.471081 -317.079096) (xy 47.425269 -317.102439) (xy 47.37637 -317.118327)
			(xy 47.325588 -317.12637) (xy 47.274172 -317.12637) (xy 47.22339 -317.118327) (xy 47.174491 -317.102439)
			(xy 47.128679 -317.079096) (xy 47.087083 -317.048875) (xy 47.050727 -317.012519) (xy 47.020506 -316.970923)
			(xy 46.997163 -316.925111) (xy 46.981275 -316.876212) (xy 46.973232 -316.82543) (xy 45.726608 -316.82543)
			(xy 45.718565 -316.876212) (xy 45.702677 -316.925111) (xy 45.679334 -316.970923) (xy 45.649113 -317.012519)
			(xy 45.612757 -317.048875) (xy 45.571161 -317.079096) (xy 45.525349 -317.102439) (xy 45.47645 -317.118327)
			(xy 45.425668 -317.12637) (xy 45.374252 -317.12637) (xy 45.32347 -317.118327) (xy 45.274571 -317.102439)
			(xy 45.228759 -317.079096) (xy 45.187163 -317.048875) (xy 45.150807 -317.012519) (xy 45.120586 -316.970923)
			(xy 45.097243 -316.925111) (xy 45.081355 -316.876212) (xy 45.073312 -316.82543) (xy 43.826192 -316.82543)
			(xy 43.818161 -316.876134) (xy 43.802284 -316.924997) (xy 43.778958 -316.970774) (xy 43.748759 -317.012339)
			(xy 43.712428 -317.048668) (xy 43.670862 -317.078866) (xy 43.625084 -317.102189) (xy 43.57622 -317.118064)
			(xy 43.525475 -317.126099) (xy 43.499786 -317.12662) (xy 43.46702 -317.125096) (xy 43.456352 -317.12408)
			(xy 43.436032 -317.130684) (xy 43.372024 -317.188342) (xy 43.36441 -317.19581) (xy 43.355748 -317.215278)
			(xy 43.35526 -317.225934) (xy 43.35526 -317.274702) (xy 43.354835 -317.29897) (xy 43.34775 -317.346986)
			(xy 43.333733 -317.393454) (xy 43.313082 -317.437378) (xy 43.286242 -317.477817) (xy 43.253786 -317.513905)
			(xy 43.235372 -317.529718) (xy 43.218801 -317.543013) (xy 43.182872 -317.565685) (xy 43.163744 -317.57493)
			(xy 43.15714 -317.578232) (xy 43.1419 -317.602616) (xy 43.1419 -317.775644) (xy 44.123098 -317.775644)
			(xy 44.123098 -317.724228) (xy 44.131141 -317.673446) (xy 44.147029 -317.624547) (xy 44.170372 -317.578735)
			(xy 44.200593 -317.537139) (xy 44.236949 -317.500783) (xy 44.278545 -317.470562) (xy 44.324357 -317.447219)
			(xy 44.373256 -317.431331) (xy 44.424038 -317.423288) (xy 44.475454 -317.423288) (xy 44.526236 -317.431331)
			(xy 44.575135 -317.447219) (xy 44.620947 -317.470562) (xy 44.662543 -317.500783) (xy 44.698899 -317.537139)
			(xy 44.72912 -317.578735) (xy 44.752463 -317.624547) (xy 44.768351 -317.673446) (xy 44.776394 -317.724228)
			(xy 44.776898 -317.749936) (xy 44.776394 -317.775644) (xy 46.023272 -317.775644) (xy 46.023272 -317.724228)
			(xy 46.031315 -317.673446) (xy 46.047203 -317.624547) (xy 46.070546 -317.578735) (xy 46.100767 -317.537139)
			(xy 46.137123 -317.500783) (xy 46.178719 -317.470562) (xy 46.224531 -317.447219) (xy 46.27343 -317.431331)
			(xy 46.324212 -317.423288) (xy 46.375628 -317.423288) (xy 46.42641 -317.431331) (xy 46.475309 -317.447219)
			(xy 46.521121 -317.470562) (xy 46.562717 -317.500783) (xy 46.599073 -317.537139) (xy 46.629294 -317.578735)
			(xy 46.652637 -317.624547) (xy 46.668525 -317.673446) (xy 46.676568 -317.724228) (xy 46.677072 -317.749936)
			(xy 46.676568 -317.775644) (xy 47.923192 -317.775644) (xy 47.923192 -317.724228) (xy 47.931235 -317.673446)
			(xy 47.947123 -317.624547) (xy 47.970466 -317.578735) (xy 48.000687 -317.537139) (xy 48.037043 -317.500783)
			(xy 48.078639 -317.470562) (xy 48.124451 -317.447219) (xy 48.17335 -317.431331) (xy 48.224132 -317.423288)
			(xy 48.275548 -317.423288) (xy 48.32633 -317.431331) (xy 48.375229 -317.447219) (xy 48.421041 -317.470562)
			(xy 48.462637 -317.500783) (xy 48.498993 -317.537139) (xy 48.529214 -317.578735) (xy 48.552557 -317.624547)
			(xy 48.568445 -317.673446) (xy 48.576488 -317.724228) (xy 48.576992 -317.749936) (xy 48.576488 -317.775644)
			(xy 49.823112 -317.775644) (xy 49.823112 -317.724228) (xy 49.831155 -317.673446) (xy 49.847043 -317.624547)
			(xy 49.870386 -317.578735) (xy 49.900607 -317.537139) (xy 49.936963 -317.500783) (xy 49.978559 -317.470562)
			(xy 50.024371 -317.447219) (xy 50.07327 -317.431331) (xy 50.124052 -317.423288) (xy 50.175468 -317.423288)
			(xy 50.22625 -317.431331) (xy 50.275149 -317.447219) (xy 50.320961 -317.470562) (xy 50.362557 -317.500783)
			(xy 50.398913 -317.537139) (xy 50.429134 -317.578735) (xy 50.452477 -317.624547) (xy 50.468365 -317.673446)
			(xy 50.476408 -317.724228) (xy 50.476912 -317.749936) (xy 51.74413 -317.749936) (xy 51.74809 -317.700882)
			(xy 51.759867 -317.653098) (xy 51.779158 -317.607822) (xy 51.805461 -317.566226) (xy 51.838096 -317.529389)
			(xy 51.876217 -317.498264) (xy 51.918838 -317.473657) (xy 51.964854 -317.456205) (xy 52.013073 -317.446361)
			(xy 52.062248 -317.44438) (xy 52.111103 -317.450312) (xy 52.158374 -317.464004) (xy 52.202836 -317.485102)
			(xy 52.243339 -317.513058) (xy 52.278832 -317.54715) (xy 52.308397 -317.586494) (xy 52.331268 -317.630071)
			(xy 52.346852 -317.676752) (xy 52.354747 -317.725329) (xy 52.355242 -317.749936) (xy 53.64405 -317.749936)
			(xy 53.64801 -317.700882) (xy 53.659787 -317.653098) (xy 53.679078 -317.607822) (xy 53.705381 -317.566226)
			(xy 53.738016 -317.529389) (xy 53.776137 -317.498264) (xy 53.818758 -317.473657) (xy 53.864774 -317.456205)
			(xy 53.912993 -317.446361) (xy 53.962168 -317.44438) (xy 54.011023 -317.450312) (xy 54.058294 -317.464004)
			(xy 54.102756 -317.485102) (xy 54.143259 -317.513058) (xy 54.178752 -317.54715) (xy 54.208317 -317.586494)
			(xy 54.231188 -317.630071) (xy 54.246772 -317.676752) (xy 54.254667 -317.725329) (xy 54.255162 -317.749936)
			(xy 54.254667 -317.774543) (xy 54.246772 -317.82312) (xy 54.231188 -317.869801) (xy 54.208317 -317.913378)
			(xy 54.178752 -317.952722) (xy 54.143259 -317.986814) (xy 54.102756 -318.01477) (xy 54.058294 -318.035868)
			(xy 54.011023 -318.04956) (xy 53.962168 -318.055492) (xy 53.912993 -318.053511) (xy 53.864774 -318.043667)
			(xy 53.818758 -318.026215) (xy 53.776137 -318.001608) (xy 53.738016 -317.970483) (xy 53.705381 -317.933646)
			(xy 53.679078 -317.89205) (xy 53.659787 -317.846774) (xy 53.64801 -317.79899) (xy 53.64405 -317.749936)
			(xy 52.355242 -317.749936) (xy 52.354747 -317.774543) (xy 52.346852 -317.82312) (xy 52.331268 -317.869801)
			(xy 52.308397 -317.913378) (xy 52.278832 -317.952722) (xy 52.243339 -317.986814) (xy 52.202836 -318.01477)
			(xy 52.158374 -318.035868) (xy 52.111103 -318.04956) (xy 52.062248 -318.055492) (xy 52.013073 -318.053511)
			(xy 51.964854 -318.043667) (xy 51.918838 -318.026215) (xy 51.876217 -318.001608) (xy 51.838096 -317.970483)
			(xy 51.805461 -317.933646) (xy 51.779158 -317.89205) (xy 51.759867 -317.846774) (xy 51.74809 -317.79899)
			(xy 51.74413 -317.749936) (xy 50.476912 -317.749936) (xy 50.476408 -317.775644) (xy 50.468365 -317.826426)
			(xy 50.452477 -317.875325) (xy 50.429134 -317.921137) (xy 50.398913 -317.962733) (xy 50.362557 -317.999089)
			(xy 50.320961 -318.02931) (xy 50.275149 -318.052653) (xy 50.22625 -318.068541) (xy 50.175468 -318.076584)
			(xy 50.124052 -318.076584) (xy 50.07327 -318.068541) (xy 50.024371 -318.052653) (xy 49.978559 -318.02931)
			(xy 49.936963 -317.999089) (xy 49.900607 -317.962733) (xy 49.870386 -317.921137) (xy 49.847043 -317.875325)
			(xy 49.831155 -317.826426) (xy 49.823112 -317.775644) (xy 48.576488 -317.775644) (xy 48.568445 -317.826426)
			(xy 48.552557 -317.875325) (xy 48.529214 -317.921137) (xy 48.498993 -317.962733) (xy 48.462637 -317.999089)
			(xy 48.421041 -318.02931) (xy 48.375229 -318.052653) (xy 48.32633 -318.068541) (xy 48.275548 -318.076584)
			(xy 48.224132 -318.076584) (xy 48.17335 -318.068541) (xy 48.124451 -318.052653) (xy 48.078639 -318.02931)
			(xy 48.037043 -317.999089) (xy 48.000687 -317.962733) (xy 47.970466 -317.921137) (xy 47.947123 -317.875325)
			(xy 47.931235 -317.826426) (xy 47.923192 -317.775644) (xy 46.676568 -317.775644) (xy 46.668525 -317.826426)
			(xy 46.652637 -317.875325) (xy 46.629294 -317.921137) (xy 46.599073 -317.962733) (xy 46.562717 -317.999089)
			(xy 46.521121 -318.02931) (xy 46.475309 -318.052653) (xy 46.42641 -318.068541) (xy 46.375628 -318.076584)
			(xy 46.324212 -318.076584) (xy 46.27343 -318.068541) (xy 46.224531 -318.052653) (xy 46.178719 -318.02931)
			(xy 46.137123 -317.999089) (xy 46.100767 -317.962733) (xy 46.070546 -317.921137) (xy 46.047203 -317.875325)
			(xy 46.031315 -317.826426) (xy 46.023272 -317.775644) (xy 44.776394 -317.775644) (xy 44.768351 -317.826426)
			(xy 44.752463 -317.875325) (xy 44.72912 -317.921137) (xy 44.698899 -317.962733) (xy 44.662543 -317.999089)
			(xy 44.620947 -318.02931) (xy 44.575135 -318.052653) (xy 44.526236 -318.068541) (xy 44.475454 -318.076584)
			(xy 44.424038 -318.076584) (xy 44.373256 -318.068541) (xy 44.324357 -318.052653) (xy 44.278545 -318.02931)
			(xy 44.236949 -317.999089) (xy 44.200593 -317.962733) (xy 44.170372 -317.921137) (xy 44.147029 -317.875325)
			(xy 44.131141 -317.826426) (xy 44.123098 -317.775644) (xy 43.1419 -317.775644) (xy 43.1419 -318.725604)
			(xy 44.123098 -318.725604) (xy 44.123098 -318.674188) (xy 44.131141 -318.623406) (xy 44.147029 -318.574507)
			(xy 44.170372 -318.528695) (xy 44.200593 -318.487099) (xy 44.236949 -318.450743) (xy 44.278545 -318.420522)
			(xy 44.324357 -318.397179) (xy 44.373256 -318.381291) (xy 44.424038 -318.373248) (xy 44.475454 -318.373248)
			(xy 44.526236 -318.381291) (xy 44.575135 -318.397179) (xy 44.620947 -318.420522) (xy 44.662543 -318.450743)
			(xy 44.698899 -318.487099) (xy 44.72912 -318.528695) (xy 44.752463 -318.574507) (xy 44.768351 -318.623406)
			(xy 44.776394 -318.674188) (xy 44.776898 -318.699896) (xy 44.776394 -318.725604) (xy 46.023272 -318.725604)
			(xy 46.023272 -318.674188) (xy 46.031315 -318.623406) (xy 46.047203 -318.574507) (xy 46.070546 -318.528695)
			(xy 46.100767 -318.487099) (xy 46.137123 -318.450743) (xy 46.178719 -318.420522) (xy 46.224531 -318.397179)
			(xy 46.27343 -318.381291) (xy 46.324212 -318.373248) (xy 46.375628 -318.373248) (xy 46.42641 -318.381291)
			(xy 46.475309 -318.397179) (xy 46.521121 -318.420522) (xy 46.562717 -318.450743) (xy 46.599073 -318.487099)
			(xy 46.629294 -318.528695) (xy 46.652637 -318.574507) (xy 46.668525 -318.623406) (xy 46.676568 -318.674188)
			(xy 46.677072 -318.699896) (xy 46.676568 -318.725604) (xy 47.923192 -318.725604) (xy 47.923192 -318.674188)
			(xy 47.931235 -318.623406) (xy 47.947123 -318.574507) (xy 47.970466 -318.528695) (xy 48.000687 -318.487099)
			(xy 48.037043 -318.450743) (xy 48.078639 -318.420522) (xy 48.124451 -318.397179) (xy 48.17335 -318.381291)
			(xy 48.224132 -318.373248) (xy 48.275548 -318.373248) (xy 48.32633 -318.381291) (xy 48.375229 -318.397179)
			(xy 48.421041 -318.420522) (xy 48.462637 -318.450743) (xy 48.498993 -318.487099) (xy 48.529214 -318.528695)
			(xy 48.552557 -318.574507) (xy 48.568445 -318.623406) (xy 48.576488 -318.674188) (xy 48.576992 -318.699896)
			(xy 48.576488 -318.725604) (xy 49.823112 -318.725604) (xy 49.823112 -318.674188) (xy 49.831155 -318.623406)
			(xy 49.847043 -318.574507) (xy 49.870386 -318.528695) (xy 49.900607 -318.487099) (xy 49.936963 -318.450743)
			(xy 49.978559 -318.420522) (xy 50.024371 -318.397179) (xy 50.07327 -318.381291) (xy 50.124052 -318.373248)
			(xy 50.175468 -318.373248) (xy 50.22625 -318.381291) (xy 50.275149 -318.397179) (xy 50.320961 -318.420522)
			(xy 50.362557 -318.450743) (xy 50.398913 -318.487099) (xy 50.429134 -318.528695) (xy 50.452477 -318.574507)
			(xy 50.468365 -318.623406) (xy 50.476408 -318.674188) (xy 50.476912 -318.699896) (xy 51.74413 -318.699896)
			(xy 51.74809 -318.650842) (xy 51.759867 -318.603058) (xy 51.779158 -318.557782) (xy 51.805461 -318.516186)
			(xy 51.838096 -318.479349) (xy 51.876217 -318.448224) (xy 51.918838 -318.423617) (xy 51.964854 -318.406165)
			(xy 52.013073 -318.396321) (xy 52.062248 -318.39434) (xy 52.111103 -318.400272) (xy 52.158374 -318.413964)
			(xy 52.202836 -318.435062) (xy 52.243339 -318.463018) (xy 52.278832 -318.49711) (xy 52.308397 -318.536454)
			(xy 52.331268 -318.580031) (xy 52.346852 -318.626712) (xy 52.354747 -318.675289) (xy 52.355242 -318.699896)
			(xy 53.64405 -318.699896) (xy 53.64801 -318.650842) (xy 53.659787 -318.603058) (xy 53.679078 -318.557782)
			(xy 53.705381 -318.516186) (xy 53.738016 -318.479349) (xy 53.776137 -318.448224) (xy 53.818758 -318.423617)
			(xy 53.864774 -318.406165) (xy 53.912993 -318.396321) (xy 53.962168 -318.39434) (xy 54.011023 -318.400272)
			(xy 54.058294 -318.413964) (xy 54.102756 -318.435062) (xy 54.143259 -318.463018) (xy 54.178752 -318.49711)
			(xy 54.208317 -318.536454) (xy 54.231188 -318.580031) (xy 54.246772 -318.626712) (xy 54.254667 -318.675289)
			(xy 54.255162 -318.699896) (xy 55.54397 -318.699896) (xy 55.54793 -318.650842) (xy 55.559707 -318.603058)
			(xy 55.578998 -318.557782) (xy 55.605301 -318.516186) (xy 55.637936 -318.479349) (xy 55.676057 -318.448224)
			(xy 55.718678 -318.423617) (xy 55.764694 -318.406165) (xy 55.812913 -318.396321) (xy 55.862088 -318.39434)
			(xy 55.910943 -318.400272) (xy 55.958214 -318.413964) (xy 56.002676 -318.435062) (xy 56.043179 -318.463018)
			(xy 56.078672 -318.49711) (xy 56.108237 -318.536454) (xy 56.131108 -318.580031) (xy 56.146692 -318.626712)
			(xy 56.154587 -318.675289) (xy 56.155082 -318.699896) (xy 56.154587 -318.724503) (xy 56.146692 -318.77308)
			(xy 56.131108 -318.819761) (xy 56.108237 -318.863338) (xy 56.078672 -318.902682) (xy 56.043179 -318.936774)
			(xy 56.002676 -318.96473) (xy 55.958214 -318.985828) (xy 55.910943 -318.99952) (xy 55.862088 -319.005452)
			(xy 55.812913 -319.003471) (xy 55.764694 -318.993627) (xy 55.718678 -318.976175) (xy 55.676057 -318.951568)
			(xy 55.637936 -318.920443) (xy 55.605301 -318.883606) (xy 55.578998 -318.84201) (xy 55.559707 -318.796734)
			(xy 55.54793 -318.74895) (xy 55.54397 -318.699896) (xy 54.255162 -318.699896) (xy 54.254667 -318.724503)
			(xy 54.246772 -318.77308) (xy 54.231188 -318.819761) (xy 54.208317 -318.863338) (xy 54.178752 -318.902682)
			(xy 54.143259 -318.936774) (xy 54.102756 -318.96473) (xy 54.058294 -318.985828) (xy 54.011023 -318.99952)
			(xy 53.962168 -319.005452) (xy 53.912993 -319.003471) (xy 53.864774 -318.993627) (xy 53.818758 -318.976175)
			(xy 53.776137 -318.951568) (xy 53.738016 -318.920443) (xy 53.705381 -318.883606) (xy 53.679078 -318.84201)
			(xy 53.659787 -318.796734) (xy 53.64801 -318.74895) (xy 53.64405 -318.699896) (xy 52.355242 -318.699896)
			(xy 52.354747 -318.724503) (xy 52.346852 -318.77308) (xy 52.331268 -318.819761) (xy 52.308397 -318.863338)
			(xy 52.278832 -318.902682) (xy 52.243339 -318.936774) (xy 52.202836 -318.96473) (xy 52.158374 -318.985828)
			(xy 52.111103 -318.99952) (xy 52.062248 -319.005452) (xy 52.013073 -319.003471) (xy 51.964854 -318.993627)
			(xy 51.918838 -318.976175) (xy 51.876217 -318.951568) (xy 51.838096 -318.920443) (xy 51.805461 -318.883606)
			(xy 51.779158 -318.84201) (xy 51.759867 -318.796734) (xy 51.74809 -318.74895) (xy 51.74413 -318.699896)
			(xy 50.476912 -318.699896) (xy 50.476408 -318.725604) (xy 50.468365 -318.776386) (xy 50.452477 -318.825285)
			(xy 50.429134 -318.871097) (xy 50.398913 -318.912693) (xy 50.362557 -318.949049) (xy 50.320961 -318.97927)
			(xy 50.275149 -319.002613) (xy 50.22625 -319.018501) (xy 50.175468 -319.026544) (xy 50.124052 -319.026544)
			(xy 50.07327 -319.018501) (xy 50.024371 -319.002613) (xy 49.978559 -318.97927) (xy 49.936963 -318.949049)
			(xy 49.900607 -318.912693) (xy 49.870386 -318.871097) (xy 49.847043 -318.825285) (xy 49.831155 -318.776386)
			(xy 49.823112 -318.725604) (xy 48.576488 -318.725604) (xy 48.568445 -318.776386) (xy 48.552557 -318.825285)
			(xy 48.529214 -318.871097) (xy 48.498993 -318.912693) (xy 48.462637 -318.949049) (xy 48.421041 -318.97927)
			(xy 48.375229 -319.002613) (xy 48.32633 -319.018501) (xy 48.275548 -319.026544) (xy 48.224132 -319.026544)
			(xy 48.17335 -319.018501) (xy 48.124451 -319.002613) (xy 48.078639 -318.97927) (xy 48.037043 -318.949049)
			(xy 48.000687 -318.912693) (xy 47.970466 -318.871097) (xy 47.947123 -318.825285) (xy 47.931235 -318.776386)
			(xy 47.923192 -318.725604) (xy 46.676568 -318.725604) (xy 46.668525 -318.776386) (xy 46.652637 -318.825285)
			(xy 46.629294 -318.871097) (xy 46.599073 -318.912693) (xy 46.562717 -318.949049) (xy 46.521121 -318.97927)
			(xy 46.475309 -319.002613) (xy 46.42641 -319.018501) (xy 46.375628 -319.026544) (xy 46.324212 -319.026544)
			(xy 46.27343 -319.018501) (xy 46.224531 -319.002613) (xy 46.178719 -318.97927) (xy 46.137123 -318.949049)
			(xy 46.100767 -318.912693) (xy 46.070546 -318.871097) (xy 46.047203 -318.825285) (xy 46.031315 -318.776386)
			(xy 46.023272 -318.725604) (xy 44.776394 -318.725604) (xy 44.768351 -318.776386) (xy 44.752463 -318.825285)
			(xy 44.72912 -318.871097) (xy 44.698899 -318.912693) (xy 44.662543 -318.949049) (xy 44.620947 -318.97927)
			(xy 44.575135 -319.002613) (xy 44.526236 -319.018501) (xy 44.475454 -319.026544) (xy 44.424038 -319.026544)
			(xy 44.373256 -319.018501) (xy 44.324357 -319.002613) (xy 44.278545 -318.97927) (xy 44.236949 -318.949049)
			(xy 44.200593 -318.912693) (xy 44.170372 -318.871097) (xy 44.147029 -318.825285) (xy 44.131141 -318.776386)
			(xy 44.123098 -318.725604) (xy 43.1419 -318.725604) (xy 43.1419 -319.536572) (xy 43.145456 -319.55486)
			(xy 43.161631 -319.59804) (xy 43.186902 -319.686725) (xy 43.203889 -319.777362) (xy 43.212447 -319.869179)
			(xy 43.21302 -319.915286) (xy 43.21302 -321.350894) (xy 43.213213 -321.357562) (xy 43.216682 -321.370439)
			(xy 43.219878 -321.376294) (xy 47.902368 -329.411838) (xy 47.91305 -329.430377) (xy 47.932998 -329.468236)
			(xy 47.942246 -329.48753) (xy 52.86629 -339.898482) (xy 52.881625 -339.931827) (xy 52.907939 -340.00035)
			(xy 52.918868 -340.035388) (xy 53.151786 -340.803738) (xy 53.155596 -340.812882) (xy 53.159406 -340.819994)
			(xy 53.17758 -340.855422) (xy 53.208823 -340.928667) (xy 53.234067 -341.004191) (xy 53.243988 -341.042752)
			(xy 53.328824 -341.385906) (xy 53.329586 -341.388446) (xy 53.503576 -341.962994) (xy 53.517277 -342.010024)
			(xy 53.536468 -342.106089) (xy 53.546146 -342.203573) (xy 53.546756 -342.252554) (xy 53.546756 -346.103702)
			(xy 53.546286 -346.147226) (xy 53.538678 -346.233942) (xy 53.52354 -346.319664) (xy 53.500984 -346.40374)
			(xy 53.471185 -346.485529) (xy 53.434367 -346.564408) (xy 53.390813 -346.639777) (xy 53.340853 -346.711062)
			(xy 53.284868 -346.777719) (xy 53.254402 -346.808806) (xy 53.142896 -346.920312) (xy 53.136121 -346.927737)
			(xy 53.128532 -346.946334) (xy 53.128164 -346.95638) (xy 53.128164 -354.456492) (xy 53.12796 -354.46258)
			(xy 53.125014 -354.474396) (xy 53.122322 -354.47986) (xy 51.825144 -356.974902) (xy 51.820986 -356.983982)
			(xy 51.819284 -357.003857) (xy 51.821842 -357.01351) (xy 51.821842 -357.013764) (xy 51.829978 -357.040531)
			(xy 51.838781 -357.095776) (xy 51.839368 -357.123746) (xy 51.838878 -357.150676) (xy 51.830779 -357.203924)
			(xy 51.814757 -357.255346) (xy 51.791177 -357.30377) (xy 51.760576 -357.348093) (xy 51.723653 -357.387305)
			(xy 51.681247 -357.420512) (xy 51.658012 -357.434134) (xy 51.649376 -357.43896) (xy 51.636676 -357.454708)
			(xy 51.611784 -357.543354) (xy 51.61407 -357.563166) (xy 51.61915 -357.572056) (xy 51.634215 -357.600526)
			(xy 51.655601 -357.661279) (xy 51.666452 -357.724765) (xy 51.667156 -357.756968) (xy 51.667156 -357.75773)
			(xy 51.666668 -357.784986) (xy 51.65891 -357.838944) (xy 51.643555 -357.891249) (xy 51.620915 -357.940838)
			(xy 51.591452 -357.986703) (xy 51.555764 -358.02791) (xy 51.514578 -358.063621) (xy 51.46873 -358.093111)
			(xy 51.419154 -358.115778) (xy 51.366857 -358.131163) (xy 51.312904 -358.138953) (xy 51.285648 -358.139492)
			(xy 51.251866 -358.139492) (xy 51.243993 -358.139787) (xy 51.228991 -358.14457) (xy 51.222402 -358.14889)
			(xy 51.216052 -358.153462) (xy 51.208432 -358.162606) (xy 51.205638 -358.16794) (xy 48.518365 -363.334808)
			(xy 54.890416 -363.334808) (xy 54.890416 -362.471208) (xy 54.890906 -362.441224) (xy 54.898734 -362.381768)
			(xy 54.914255 -362.323843) (xy 54.937204 -362.268439) (xy 54.967188 -362.216505) (xy 55.003694 -362.168929)
			(xy 55.046099 -362.126524) (xy 55.093675 -362.090018) (xy 55.145609 -362.060034) (xy 55.201013 -362.037085)
			(xy 55.258938 -362.021564) (xy 55.318394 -362.013736) (xy 55.378362 -362.013736) (xy 55.437818 -362.021564)
			(xy 55.495743 -362.037085) (xy 55.551147 -362.060034) (xy 55.603081 -362.090018) (xy 55.650657 -362.126524)
			(xy 55.693062 -362.168929) (xy 55.729568 -362.216505) (xy 55.759552 -362.268439) (xy 55.782501 -362.323843)
			(xy 55.798022 -362.381768) (xy 55.80585 -362.441224) (xy 55.80634 -362.471208) (xy 55.80634 -363.334808)
			(xy 55.80585 -363.364792) (xy 55.798022 -363.424248) (xy 55.782501 -363.482173) (xy 55.759552 -363.537577)
			(xy 55.729568 -363.589511) (xy 55.693062 -363.637087) (xy 55.650657 -363.679492) (xy 55.603081 -363.715998)
			(xy 55.551147 -363.745982) (xy 55.495743 -363.768931) (xy 55.437818 -363.784452) (xy 55.378362 -363.79228)
			(xy 55.318394 -363.79228) (xy 55.258938 -363.784452) (xy 55.201013 -363.768931) (xy 55.145609 -363.745982)
			(xy 55.093675 -363.715998) (xy 55.046099 -363.679492) (xy 55.003694 -363.637087) (xy 54.967188 -363.589511)
			(xy 54.937204 -363.537577) (xy 54.914255 -363.482173) (xy 54.898734 -363.424248) (xy 54.890906 -363.364792)
			(xy 54.890416 -363.334808) (xy 48.518365 -363.334808) (xy 47.237586 -365.797384) (xy 54.438294 -365.797384)
			(xy 54.438294 -365.737416) (xy 54.446121 -365.67796) (xy 54.461641 -365.620034) (xy 54.484589 -365.564629)
			(xy 54.514571 -365.512694) (xy 54.551076 -365.465115) (xy 54.593478 -365.422709) (xy 54.641052 -365.386199)
			(xy 54.692984 -365.356211) (xy 54.748387 -365.333257) (xy 54.806311 -365.317731) (xy 54.865766 -365.309897)
			(xy 54.89575 -365.309404) (xy 55.75935 -365.309404) (xy 55.789336 -365.309938) (xy 55.848794 -365.31776)
			(xy 55.906723 -365.333276) (xy 55.962131 -365.356222) (xy 56.01407 -365.386203) (xy 56.06165 -365.422708)
			(xy 56.104059 -365.465112) (xy 56.140569 -365.512689) (xy 56.170556 -365.564624) (xy 56.193508 -365.620029)
			(xy 56.20903 -365.677957) (xy 56.216859 -365.737414) (xy 56.216859 -365.797386) (xy 56.20903 -365.856843)
			(xy 56.193508 -365.914771) (xy 56.170556 -365.970176) (xy 56.140569 -366.022112) (xy 56.104059 -366.069688)
			(xy 56.06165 -366.112092) (xy 56.01407 -366.148597) (xy 55.962131 -366.178578) (xy 55.906723 -366.201524)
			(xy 55.848794 -366.21704) (xy 55.789336 -366.224862) (xy 55.75935 -366.225328) (xy 54.89575 -366.225328)
			(xy 54.865766 -366.224903) (xy 54.806311 -366.217069) (xy 54.748386 -366.201543) (xy 54.692984 -366.178589)
			(xy 54.641052 -366.148601) (xy 54.593478 -366.112091) (xy 54.551076 -366.069685) (xy 54.514571 -366.022106)
			(xy 54.484589 -365.970171) (xy 54.461641 -365.914766) (xy 54.446121 -365.85684) (xy 54.438294 -365.797384)
			(xy 47.237586 -365.797384) (xy 47.071026 -366.117632) (xy 45.772832 -368.618262) (xy 45.770702 -368.62327)
			(xy 45.768394 -368.633903) (xy 45.76826 -368.639344) (xy 45.794168 -368.68354) (xy 45.823733 -368.700714)
			(xy 45.879004 -368.740965) (xy 45.929168 -368.787428) (xy 45.97353 -368.839458) (xy 46.011476 -368.896337)
			(xy 46.042483 -368.957277) (xy 46.054583 -368.990118) (xy 47.223942 -368.990118) (xy 47.227933 -368.927951)
			(xy 47.239842 -368.866804) (xy 47.259471 -368.807683) (xy 47.2865 -368.751557) (xy 47.320484 -368.699348)
			(xy 47.360866 -368.651913) (xy 47.406982 -368.610032) (xy 47.458074 -368.574392) (xy 47.513305 -368.545578)
			(xy 47.571767 -368.524064) (xy 47.632501 -368.510202) (xy 47.694508 -368.50422) (xy 47.756771 -368.506216)
			(xy 47.818268 -368.516159) (xy 47.819963 -368.516662) (xy 53.966364 -368.516662) (xy 53.966364 -367.653062)
			(xy 53.96685 -367.625793) (xy 53.974612 -367.571809) (xy 53.989977 -367.519479) (xy 54.012634 -367.469869)
			(xy 54.04212 -367.423988) (xy 54.077835 -367.382771) (xy 54.119052 -367.347056) (xy 54.164933 -367.31757)
			(xy 54.214543 -367.294913) (xy 54.266873 -367.279548) (xy 54.320857 -367.271786) (xy 54.375395 -367.271786)
			(xy 54.429379 -367.279548) (xy 54.481709 -367.294913) (xy 54.531319 -367.31757) (xy 54.5772 -367.347056)
			(xy 54.618417 -367.382771) (xy 54.654132 -367.423988) (xy 54.683618 -367.469869) (xy 54.706275 -367.519479)
			(xy 54.72164 -367.571809) (xy 54.729402 -367.625793) (xy 54.729888 -367.653062) (xy 54.729888 -368.516662)
			(xy 57.339484 -368.516662) (xy 57.339484 -367.653062) (xy 57.33997 -367.625793) (xy 57.347732 -367.571809)
			(xy 57.363097 -367.519479) (xy 57.385754 -367.469869) (xy 57.41524 -367.423988) (xy 57.450955 -367.382771)
			(xy 57.492172 -367.347056) (xy 57.538053 -367.31757) (xy 57.587663 -367.294913) (xy 57.639993 -367.279548)
			(xy 57.693977 -367.271786) (xy 57.748515 -367.271786) (xy 57.802499 -367.279548) (xy 57.854829 -367.294913)
			(xy 57.904439 -367.31757) (xy 57.95032 -367.347056) (xy 57.991537 -367.382771) (xy 58.027252 -367.423988)
			(xy 58.056738 -367.469869) (xy 58.079395 -367.519479) (xy 58.09476 -367.571809) (xy 58.102522 -367.625793)
			(xy 58.103008 -367.653062) (xy 58.103008 -368.516662) (xy 58.102522 -368.543931) (xy 58.09476 -368.597915)
			(xy 58.079395 -368.650245) (xy 58.056738 -368.699855) (xy 58.027252 -368.745736) (xy 57.991537 -368.786953)
			(xy 57.95032 -368.822668) (xy 57.904439 -368.852154) (xy 57.854829 -368.874811) (xy 57.802499 -368.890176)
			(xy 57.748515 -368.897938) (xy 57.693977 -368.897938) (xy 57.639993 -368.890176) (xy 57.587663 -368.874811)
			(xy 57.538053 -368.852154) (xy 57.492172 -368.822668) (xy 57.450955 -368.786953) (xy 57.41524 -368.745736)
			(xy 57.385754 -368.699855) (xy 57.363097 -368.650245) (xy 57.347732 -368.597915) (xy 57.33997 -368.543931)
			(xy 57.339484 -368.516662) (xy 54.729888 -368.516662) (xy 54.729402 -368.543931) (xy 54.72164 -368.597915)
			(xy 54.706275 -368.650245) (xy 54.683618 -368.699855) (xy 54.654132 -368.745736) (xy 54.618417 -368.786953)
			(xy 54.5772 -368.822668) (xy 54.531319 -368.852154) (xy 54.481709 -368.874811) (xy 54.429379 -368.890176)
			(xy 54.375395 -368.897938) (xy 54.320857 -368.897938) (xy 54.266873 -368.890176) (xy 54.214543 -368.874811)
			(xy 54.164933 -368.852154) (xy 54.119052 -368.822668) (xy 54.077835 -368.786953) (xy 54.04212 -368.745736)
			(xy 54.012634 -368.699855) (xy 53.989977 -368.650245) (xy 53.974612 -368.597915) (xy 53.96685 -368.543931)
			(xy 53.966364 -368.516662) (xy 47.819963 -368.516662) (xy 47.877989 -368.533883) (xy 47.934952 -368.5591)
			(xy 47.988223 -368.591393) (xy 48.036928 -368.630233) (xy 48.080265 -368.674983) (xy 48.117525 -368.724907)
			(xy 48.148094 -368.779186) (xy 48.171472 -368.836929) (xy 48.187273 -368.897187) (xy 48.195239 -368.95897)
			(xy 48.195738 -368.990118) (xy 48.195239 -369.021266) (xy 48.187273 -369.083049) (xy 48.171472 -369.143307)
			(xy 48.148094 -369.20105) (xy 48.117525 -369.255329) (xy 48.080265 -369.305253) (xy 48.036928 -369.350003)
			(xy 47.988223 -369.388843) (xy 47.934952 -369.421136) (xy 47.877989 -369.446353) (xy 47.818268 -369.464077)
			(xy 47.756771 -369.47402) (xy 47.694508 -369.476016) (xy 47.632501 -369.470034) (xy 47.571767 -369.456172)
			(xy 47.513305 -369.434658) (xy 47.458074 -369.405844) (xy 47.406982 -369.370204) (xy 47.360866 -369.328323)
			(xy 47.320484 -369.280888) (xy 47.2865 -369.228679) (xy 47.259471 -369.172553) (xy 47.239842 -369.113432)
			(xy 47.227933 -369.052285) (xy 47.223942 -368.990118) (xy 46.054583 -368.990118) (xy 46.066121 -369.021436)
			(xy 46.082062 -369.087926) (xy 46.090088 -369.155829) (xy 46.090586 -369.190016) (xy 46.090055 -369.225107)
			(xy 46.081594 -369.294776) (xy 46.064798 -369.362918) (xy 46.039911 -369.428539) (xy 46.007296 -369.490682)
			(xy 45.967429 -369.54844) (xy 45.920891 -369.600973) (xy 45.868361 -369.647513) (xy 45.810604 -369.687383)
			(xy 45.748463 -369.72) (xy 45.682843 -369.74489) (xy 45.614702 -369.76169) (xy 45.545033 -369.770154)
			(xy 45.509942 -369.77066) (xy 45.481748 -369.769898) (xy 45.481748 -369.870482) (xy 45.487613 -369.873654)
			(xy 45.500483 -369.877123) (xy 45.507148 -369.87734) (xy 45.868082 -369.87734) (xy 45.878256 -369.877763)
			(xy 45.897056 -369.885545) (xy 45.911446 -369.89993) (xy 45.919234 -369.918728) (xy 45.919644 -369.928902)
			(xy 45.919644 -370.219478) (xy 45.922438 -370.227606) (xy 45.92701 -370.241068) (xy 45.92955 -370.24564)
			(xy 45.94524 -370.273561) (xy 45.969946 -370.33265) (xy 45.98666 -370.394476) (xy 45.995091 -370.457965)
			(xy 45.99559 -370.489988) (xy 45.99559 -370.496338) (xy 45.995314 -370.510669) (xy 45.993283 -370.539263)
			(xy 45.991526 -370.553488) (xy 45.986822 -370.585215) (xy 45.97015 -370.64715) (xy 45.945487 -370.706358)
			(xy 45.929804 -370.734336) (xy 45.927518 -370.738146) (xy 45.925486 -370.74348) (xy 45.922184 -370.75364)
			(xy 45.921056 -370.757352) (xy 45.919779 -370.765003) (xy 45.919644 -370.76888) (xy 45.919644 -371.519704)
			(xy 45.922438 -371.527832) (xy 45.92701 -371.541294) (xy 45.92955 -371.545866) (xy 45.945238 -371.573787)
			(xy 45.965723 -371.622787) (xy 47.225018 -371.622787) (xy 47.225022 -371.557348) (xy 47.233811 -371.492501)
			(xy 47.251225 -371.42942) (xy 47.27695 -371.369249) (xy 47.293276 -371.340888) (xy 47.296593 -371.334865)
			(xy 47.300198 -371.3216) (xy 47.300388 -371.314726) (xy 47.300388 -371.028722) (xy 47.300783 -371.018546)
			(xy 47.30857 -370.999742) (xy 47.322966 -370.985355) (xy 47.341773 -370.977578) (xy 47.35195 -370.97716)
			(xy 48.06823 -370.97716) (xy 48.078392 -370.977609) (xy 48.097167 -370.985398) (xy 48.111532 -370.999777)
			(xy 48.119301 -371.018559) (xy 48.119792 -371.028722) (xy 48.119792 -371.310662) (xy 53.966364 -371.310662)
			(xy 53.966364 -370.447062) (xy 53.96685 -370.419793) (xy 53.974612 -370.365809) (xy 53.989977 -370.313479)
			(xy 54.012634 -370.263869) (xy 54.04212 -370.217988) (xy 54.077835 -370.176771) (xy 54.119052 -370.141056)
			(xy 54.164933 -370.11157) (xy 54.214543 -370.088913) (xy 54.266873 -370.073548) (xy 54.320857 -370.065786)
			(xy 54.375395 -370.065786) (xy 54.429379 -370.073548) (xy 54.481709 -370.088913) (xy 54.531319 -370.11157)
			(xy 54.5772 -370.141056) (xy 54.618417 -370.176771) (xy 54.654132 -370.217988) (xy 54.683618 -370.263869)
			(xy 54.706275 -370.313479) (xy 54.72164 -370.365809) (xy 54.729402 -370.419793) (xy 54.729888 -370.447062)
			(xy 54.729888 -371.310662) (xy 57.339484 -371.310662) (xy 57.339484 -370.447062) (xy 57.33997 -370.419793)
			(xy 57.347732 -370.365809) (xy 57.363097 -370.313479) (xy 57.385754 -370.263869) (xy 57.41524 -370.217988)
			(xy 57.450955 -370.176771) (xy 57.492172 -370.141056) (xy 57.538053 -370.11157) (xy 57.587663 -370.088913)
			(xy 57.639993 -370.073548) (xy 57.693977 -370.065786) (xy 57.748515 -370.065786) (xy 57.802499 -370.073548)
			(xy 57.854829 -370.088913) (xy 57.904439 -370.11157) (xy 57.95032 -370.141056) (xy 57.991537 -370.176771)
			(xy 58.027252 -370.217988) (xy 58.056738 -370.263869) (xy 58.079395 -370.313479) (xy 58.09476 -370.365809)
			(xy 58.102522 -370.419793) (xy 58.103008 -370.447062) (xy 58.103008 -371.310662) (xy 58.102522 -371.337931)
			(xy 58.09476 -371.391915) (xy 58.079395 -371.444245) (xy 58.056738 -371.493855) (xy 58.027252 -371.539736)
			(xy 57.991537 -371.580953) (xy 57.95032 -371.616668) (xy 57.904439 -371.646154) (xy 57.854829 -371.668811)
			(xy 57.802499 -371.684176) (xy 57.748515 -371.691938) (xy 57.693977 -371.691938) (xy 57.639993 -371.684176)
			(xy 57.587663 -371.668811) (xy 57.538053 -371.646154) (xy 57.492172 -371.616668) (xy 57.450955 -371.580953)
			(xy 57.41524 -371.539736) (xy 57.385754 -371.493855) (xy 57.363097 -371.444245) (xy 57.347732 -371.391915)
			(xy 57.33997 -371.337931) (xy 57.339484 -371.310662) (xy 54.729888 -371.310662) (xy 54.729402 -371.337931)
			(xy 54.72164 -371.391915) (xy 54.706275 -371.444245) (xy 54.683618 -371.493855) (xy 54.654132 -371.539736)
			(xy 54.618417 -371.580953) (xy 54.5772 -371.616668) (xy 54.531319 -371.646154) (xy 54.481709 -371.668811)
			(xy 54.429379 -371.684176) (xy 54.375395 -371.691938) (xy 54.320857 -371.691938) (xy 54.266873 -371.684176)
			(xy 54.214543 -371.668811) (xy 54.164933 -371.646154) (xy 54.119052 -371.616668) (xy 54.077835 -371.580953)
			(xy 54.04212 -371.539736) (xy 54.012634 -371.493855) (xy 53.989977 -371.444245) (xy 53.974612 -371.391915)
			(xy 53.96685 -371.337931) (xy 53.966364 -371.310662) (xy 48.119792 -371.310662) (xy 48.119792 -371.314726)
			(xy 48.119975 -371.3216) (xy 48.123589 -371.334863) (xy 48.126904 -371.340888) (xy 48.143193 -371.369267)
			(xy 48.168911 -371.429435) (xy 48.186321 -371.49251) (xy 48.195108 -371.557351) (xy 48.195112 -371.622784)
			(xy 48.186334 -371.687626) (xy 48.168933 -371.750703) (xy 48.143222 -371.810874) (xy 48.126904 -371.839236)
			(xy 48.123577 -371.845255) (xy 48.119979 -371.858523) (xy 48.119792 -371.865398) (xy 48.119792 -372.614698)
			(xy 48.119986 -372.621571) (xy 48.123593 -372.634834) (xy 48.126904 -372.64086) (xy 48.143254 -372.669206)
			(xy 48.168966 -372.729381) (xy 48.18637 -372.792463) (xy 48.195149 -372.85731) (xy 48.195145 -372.922748)
			(xy 48.186358 -372.987594) (xy 48.168947 -373.050674) (xy 48.143227 -373.110846) (xy 48.126904 -373.139208)
			(xy 48.123587 -373.145231) (xy 48.119983 -373.158496) (xy 48.119792 -373.16537) (xy 48.119792 -373.451374)
			(xy 48.119246 -373.461526) (xy 48.111486 -373.480289) (xy 48.097136 -373.494655) (xy 48.078382 -373.502435)
			(xy 48.06823 -373.502936) (xy 47.35195 -373.502936) (xy 47.341778 -373.502495) (xy 47.32298 -373.494721)
			(xy 47.308592 -373.48034) (xy 47.30081 -373.461545) (xy 47.300388 -373.451374) (xy 47.300388 -373.16537)
			(xy 47.300209 -373.158496) (xy 47.296592 -373.145233) (xy 47.293276 -373.139208) (xy 47.276981 -373.110831)
			(xy 47.251259 -373.050664) (xy 47.233847 -372.987589) (xy 47.225059 -372.922747) (xy 47.225055 -372.857312)
			(xy 47.233835 -372.792469) (xy 47.25124 -372.729391) (xy 47.276955 -372.669221) (xy 47.293276 -372.64086)
			(xy 47.296603 -372.634841) (xy 47.300201 -372.621573) (xy 47.300388 -372.614698) (xy 47.300388 -371.865398)
			(xy 47.300199 -371.858525) (xy 47.296589 -371.845262) (xy 47.293276 -371.839236) (xy 47.27692 -371.810893)
			(xy 47.251204 -371.750718) (xy 47.233798 -371.687635) (xy 47.225018 -371.622787) (xy 45.965723 -371.622787)
			(xy 45.969941 -371.632877) (xy 45.986652 -371.694703) (xy 45.995079 -371.758191) (xy 45.99559 -371.790214)
			(xy 45.99559 -371.796564) (xy 45.995313 -371.810895) (xy 45.99328 -371.839488) (xy 45.991526 -371.853714)
			(xy 45.98682 -371.88544) (xy 45.970145 -371.947374) (xy 45.945479 -372.00658) (xy 45.929804 -372.034562)
			(xy 45.927518 -372.038372) (xy 45.925486 -372.043706) (xy 45.922184 -372.053866) (xy 45.921058 -372.057578)
			(xy 45.919785 -372.065229) (xy 45.919644 -372.069106) (xy 45.919644 -372.351554) (xy 45.919226 -372.36173)
			(xy 45.911449 -372.380538) (xy 45.897061 -372.394933) (xy 45.878258 -372.402721) (xy 45.868082 -372.403116)
			(xy 45.507148 -372.403116) (xy 45.500481 -372.403314) (xy 45.487605 -372.406783) (xy 45.481748 -372.409974)
			(xy 45.481748 -373.770398) (xy 45.487612 -373.773574) (xy 45.500482 -373.777049) (xy 45.507148 -373.777256)
			(xy 45.868082 -373.777256) (xy 45.878255 -373.777679) (xy 45.897053 -373.785461) (xy 45.911439 -373.799847)
			(xy 45.919221 -373.818645) (xy 45.919644 -373.828818) (xy 45.919644 -373.88419) (xy 56.962292 -373.88419)
			(xy 56.966363 -373.828568) (xy 56.978489 -373.774131) (xy 56.998412 -373.72204) (xy 57.025708 -373.673405)
			(xy 57.059794 -373.629262) (xy 57.099943 -373.590553) (xy 57.145301 -373.558102) (xy 57.194901 -373.532601)
			(xy 57.247685 -373.514594) (xy 57.302528 -373.504464) (xy 57.358262 -373.502427) (xy 57.413699 -373.508527)
			(xy 57.467656 -373.522633) (xy 57.518985 -373.544445) (xy 57.566591 -373.573499) (xy 57.609459 -373.609174)
			(xy 57.646676 -373.650711) (xy 57.677449 -373.697224) (xy 57.701121 -373.747721) (xy 57.717189 -373.801128)
			(xy 57.725309 -373.856304) (xy 57.725818 -373.88419) (xy 57.725309 -373.912076) (xy 57.717189 -373.967252)
			(xy 57.701121 -374.020659) (xy 57.677449 -374.071156) (xy 57.646676 -374.117669) (xy 57.609459 -374.159206)
			(xy 57.566591 -374.194881) (xy 57.518985 -374.223935) (xy 57.467656 -374.245747) (xy 57.413699 -374.259853)
			(xy 57.358262 -374.265953) (xy 57.302528 -374.263916) (xy 57.247685 -374.253786) (xy 57.194901 -374.235779)
			(xy 57.145301 -374.210278) (xy 57.099943 -374.177827) (xy 57.059794 -374.139118) (xy 57.025708 -374.094975)
			(xy 56.998412 -374.04634) (xy 56.978489 -373.994249) (xy 56.966363 -373.939812) (xy 56.962292 -373.88419)
			(xy 45.919644 -373.88419) (xy 45.919644 -374.119648) (xy 45.922438 -374.127776) (xy 45.92701 -374.141238)
			(xy 45.92955 -374.14581) (xy 45.945235 -374.173732) (xy 45.969933 -374.232822) (xy 45.986638 -374.294649)
			(xy 45.99506 -374.358136) (xy 45.99559 -374.390158) (xy 45.99559 -374.396508) (xy 45.995312 -374.410839)
			(xy 45.993277 -374.439432) (xy 45.991526 -374.453658) (xy 45.986818 -374.485383) (xy 45.970137 -374.547314)
			(xy 45.945467 -374.606518) (xy 45.929804 -374.634506) (xy 45.927518 -374.638316) (xy 45.925486 -374.64365)
			(xy 45.922184 -374.65381) (xy 45.921054 -374.657521) (xy 45.919773 -374.665173) (xy 45.919644 -374.66905)
			(xy 45.919644 -375.41962) (xy 45.922438 -375.427748) (xy 45.92701 -375.44121) (xy 45.92955 -375.445782)
			(xy 45.945237 -375.473703) (xy 45.969938 -375.532793) (xy 45.986647 -375.59462) (xy 45.995072 -375.658108)
			(xy 45.99559 -375.69013) (xy 45.99559 -375.69648) (xy 45.995313 -375.710811) (xy 45.993279 -375.739404)
			(xy 45.991526 -375.75363) (xy 45.986819 -375.785356) (xy 45.970142 -375.847288) (xy 45.945475 -375.906494)
			(xy 45.929804 -375.934478) (xy 45.927518 -375.938288) (xy 45.925486 -375.943622) (xy 45.922184 -375.953782)
			(xy 45.921059 -375.957494) (xy 45.919788 -375.965146) (xy 45.919644 -375.969022) (xy 45.919644 -376.25147)
			(xy 45.919223 -376.261644) (xy 45.911443 -376.280446) (xy 45.897056 -376.294836) (xy 45.878256 -376.302621)
			(xy 45.868082 -376.303032) (xy 45.458126 -376.303032) (xy 45.447987 -376.303484) (xy 45.42929 -376.311335)
			(xy 45.415068 -376.32579) (xy 45.410882 -376.335036) (xy 45.395507 -376.372587) (xy 45.359487 -376.445304)
			(xy 45.317672 -376.51485) (xy 45.270339 -376.580765) (xy 45.217802 -376.642613) (xy 45.189394 -376.671586)
			(xy 45.103495 -376.757485) (xy 47.225041 -376.757485) (xy 47.233825 -376.69264) (xy 47.251234 -376.629562)
			(xy 47.276953 -376.569391) (xy 47.293276 -376.54103) (xy 47.296578 -376.534999) (xy 47.300192 -376.52174)
			(xy 47.300388 -376.514868) (xy 47.300388 -375.765568) (xy 47.30021 -375.758694) (xy 47.296592 -375.745431)
			(xy 47.293276 -375.739406) (xy 47.27698 -375.71103) (xy 47.251258 -375.650863) (xy 47.233845 -375.587787)
			(xy 47.225058 -375.522945) (xy 47.225054 -375.45751) (xy 47.233834 -375.392667) (xy 47.251239 -375.329589)
			(xy 47.276955 -375.269419) (xy 47.293276 -375.241058) (xy 47.296604 -375.23504) (xy 47.300202 -375.221771)
			(xy 47.300388 -375.214896) (xy 47.300388 -374.928892) (xy 47.300815 -374.918739) (xy 47.308611 -374.899989)
			(xy 47.323006 -374.885666) (xy 47.341795 -374.877965) (xy 47.35195 -374.877584) (xy 48.06823 -374.877584)
			(xy 48.078364 -374.878003) (xy 48.097094 -374.885749) (xy 48.111451 -374.900056) (xy 48.119261 -374.91876)
			(xy 48.119792 -374.928892) (xy 48.119792 -375.214896) (xy 48.119986 -375.221769) (xy 48.123593 -375.235032)
			(xy 48.126904 -375.241058) (xy 48.143252 -375.269405) (xy 48.168965 -375.32958) (xy 48.186368 -375.392661)
			(xy 48.194111 -375.449846) (xy 56.712102 -375.449846) (xy 56.716173 -375.394224) (xy 56.728299 -375.339787)
			(xy 56.748222 -375.287696) (xy 56.775518 -375.239061) (xy 56.809604 -375.194918) (xy 56.849753 -375.156209)
			(xy 56.895111 -375.123758) (xy 56.944711 -375.098257) (xy 56.997495 -375.08025) (xy 57.052338 -375.07012)
			(xy 57.108072 -375.068083) (xy 57.163509 -375.074183) (xy 57.191673 -375.081546) (xy 58.879484 -375.081546)
			(xy 58.883555 -375.025924) (xy 58.895681 -374.971487) (xy 58.915604 -374.919396) (xy 58.9429 -374.870761)
			(xy 58.976986 -374.826618) (xy 59.017135 -374.787909) (xy 59.062493 -374.755458) (xy 59.112093 -374.729957)
			(xy 59.164877 -374.71195) (xy 59.21972 -374.70182) (xy 59.275454 -374.699783) (xy 59.330891 -374.705883)
			(xy 59.384848 -374.719989) (xy 59.436177 -374.741801) (xy 59.483783 -374.770855) (xy 59.526651 -374.80653)
			(xy 59.563868 -374.848067) (xy 59.594641 -374.89458) (xy 59.618313 -374.945077) (xy 59.634381 -374.998484)
			(xy 59.642501 -375.05366) (xy 59.64301 -375.081546) (xy 59.642501 -375.109432) (xy 59.634381 -375.164608)
			(xy 59.618313 -375.218015) (xy 59.594641 -375.268512) (xy 59.563868 -375.315025) (xy 59.526651 -375.356562)
			(xy 59.483783 -375.392237) (xy 59.436177 -375.421291) (xy 59.384848 -375.443103) (xy 59.330891 -375.457209)
			(xy 59.275454 -375.463309) (xy 59.21972 -375.461272) (xy 59.164877 -375.451142) (xy 59.112093 -375.433135)
			(xy 59.062493 -375.407634) (xy 59.017135 -375.375183) (xy 58.976986 -375.336474) (xy 58.9429 -375.292331)
			(xy 58.915604 -375.243696) (xy 58.895681 -375.191605) (xy 58.883555 -375.137168) (xy 58.879484 -375.081546)
			(xy 57.191673 -375.081546) (xy 57.217466 -375.088289) (xy 57.268795 -375.110101) (xy 57.316401 -375.139155)
			(xy 57.359269 -375.17483) (xy 57.396486 -375.216367) (xy 57.427259 -375.26288) (xy 57.450931 -375.313377)
			(xy 57.466999 -375.366784) (xy 57.475119 -375.42196) (xy 57.475628 -375.449846) (xy 57.475119 -375.477732)
			(xy 57.466999 -375.532908) (xy 57.450931 -375.586315) (xy 57.427259 -375.636812) (xy 57.396486 -375.683325)
			(xy 57.359269 -375.724862) (xy 57.316401 -375.760537) (xy 57.268795 -375.789591) (xy 57.217466 -375.811403)
			(xy 57.163509 -375.825509) (xy 57.108072 -375.831609) (xy 57.052338 -375.829572) (xy 56.997495 -375.819442)
			(xy 56.944711 -375.801435) (xy 56.895111 -375.775934) (xy 56.849753 -375.743483) (xy 56.809604 -375.704774)
			(xy 56.775518 -375.660631) (xy 56.748222 -375.611996) (xy 56.728299 -375.559905) (xy 56.716173 -375.505468)
			(xy 56.712102 -375.449846) (xy 48.194111 -375.449846) (xy 48.195148 -375.457508) (xy 48.195144 -375.522947)
			(xy 48.186357 -375.587792) (xy 48.168947 -375.650872) (xy 48.143227 -375.711044) (xy 48.126904 -375.739406)
			(xy 48.123587 -375.74543) (xy 48.119983 -375.758694) (xy 48.119792 -375.765568) (xy 48.119792 -376.514868)
			(xy 48.119997 -376.52174) (xy 48.123596 -376.535003) (xy 48.126904 -376.54103) (xy 48.143228 -376.56939)
			(xy 48.168943 -376.629562) (xy 48.186349 -376.692641) (xy 48.1868 -376.69597) (xy 54.986172 -376.69597)
			(xy 54.990243 -376.640348) (xy 55.002369 -376.585911) (xy 55.022292 -376.53382) (xy 55.049588 -376.485185)
			(xy 55.083674 -376.441042) (xy 55.123823 -376.402333) (xy 55.169181 -376.369882) (xy 55.218781 -376.344381)
			(xy 55.271565 -376.326374) (xy 55.326408 -376.316244) (xy 55.382142 -376.314207) (xy 55.437579 -376.320307)
			(xy 55.491536 -376.334413) (xy 55.518106 -376.345704) (xy 59.301886 -376.345704) (xy 59.305957 -376.290082)
			(xy 59.318083 -376.235645) (xy 59.338006 -376.183554) (xy 59.365302 -376.134919) (xy 59.399388 -376.090776)
			(xy 59.439537 -376.052067) (xy 59.484895 -376.019616) (xy 59.534495 -375.994115) (xy 59.587279 -375.976108)
			(xy 59.642122 -375.965978) (xy 59.697856 -375.963941) (xy 59.753293 -375.970041) (xy 59.80725 -375.984147)
			(xy 59.858579 -376.005959) (xy 59.906185 -376.035013) (xy 59.949053 -376.070688) (xy 59.98627 -376.112225)
			(xy 60.017043 -376.158738) (xy 60.040715 -376.209235) (xy 60.056783 -376.262642) (xy 60.064903 -376.317818)
			(xy 60.065412 -376.345704) (xy 60.064903 -376.37359) (xy 60.056783 -376.428766) (xy 60.040715 -376.482173)
			(xy 60.017043 -376.53267) (xy 59.98627 -376.579183) (xy 59.949053 -376.62072) (xy 59.906185 -376.656395)
			(xy 59.858579 -376.685449) (xy 59.80725 -376.707261) (xy 59.753293 -376.721367) (xy 59.697856 -376.727467)
			(xy 59.642122 -376.72543) (xy 59.587279 -376.7153) (xy 59.534495 -376.697293) (xy 59.484895 -376.671792)
			(xy 59.439537 -376.639341) (xy 59.399388 -376.600632) (xy 59.365302 -376.556489) (xy 59.338006 -376.507854)
			(xy 59.318083 -376.455763) (xy 59.305957 -376.401326) (xy 59.301886 -376.345704) (xy 55.518106 -376.345704)
			(xy 55.542865 -376.356225) (xy 55.590471 -376.385279) (xy 55.633339 -376.420954) (xy 55.670556 -376.462491)
			(xy 55.701329 -376.509004) (xy 55.725001 -376.559501) (xy 55.741069 -376.612908) (xy 55.749189 -376.668084)
			(xy 55.749698 -376.69597) (xy 55.749189 -376.723856) (xy 55.741069 -376.779032) (xy 55.725001 -376.832439)
			(xy 55.701329 -376.882936) (xy 55.670556 -376.929449) (xy 55.633339 -376.970986) (xy 55.590471 -377.006661)
			(xy 55.542865 -377.035715) (xy 55.491536 -377.057527) (xy 55.437579 -377.071633) (xy 55.382142 -377.077733)
			(xy 55.326408 -377.075696) (xy 55.271565 -377.065566) (xy 55.218781 -377.047559) (xy 55.169181 -377.022058)
			(xy 55.123823 -376.989607) (xy 55.083674 -376.950898) (xy 55.049588 -376.906755) (xy 55.022292 -376.85812)
			(xy 55.002369 -376.806029) (xy 54.990243 -376.751592) (xy 54.986172 -376.69597) (xy 48.1868 -376.69597)
			(xy 48.195132 -376.757485) (xy 48.195131 -376.822922) (xy 48.186348 -376.887766) (xy 48.168941 -376.950845)
			(xy 48.143225 -377.011016) (xy 48.126904 -377.039378) (xy 48.123597 -377.045407) (xy 48.119987 -377.058667)
			(xy 48.119792 -377.06554) (xy 48.119792 -377.351544) (xy 48.119414 -377.361702) (xy 48.111603 -377.380457)
			(xy 48.097193 -377.394779) (xy 48.07839 -377.402476) (xy 48.06823 -377.402852) (xy 47.35195 -377.402852)
			(xy 47.341825 -377.402332) (xy 47.323104 -377.394619) (xy 47.308746 -377.380343) (xy 47.300926 -377.361666)
			(xy 47.300388 -377.351544) (xy 47.300388 -377.06554) (xy 47.300182 -377.058668) (xy 47.296583 -377.045405)
			(xy 47.293276 -377.039378) (xy 47.276956 -377.011015) (xy 47.251236 -376.950845) (xy 47.233826 -376.887766)
			(xy 47.225042 -376.822922) (xy 47.225041 -376.757485) (xy 45.103495 -376.757485) (xy 44.874688 -376.986292)
			(xy 44.841361 -377.018855) (xy 44.769612 -377.07831) (xy 44.692628 -377.130811) (xy 44.611083 -377.175902)
			(xy 44.525686 -377.213188) (xy 44.437183 -377.242344) (xy 44.346346 -377.263116) (xy 44.253967 -377.275323)
			(xy 44.20743 -377.27763) (xy 44.194777 -377.278833) (xy 44.17293 -377.291763) (xy 44.165774 -377.302268)
			(xy 44.143369 -377.33882) (xy 44.093192 -377.408343) (xy 44.037231 -377.473302) (xy 43.975898 -377.533215)
			(xy 43.947837 -377.556268) (xy 58.845702 -377.556268) (xy 58.849773 -377.500646) (xy 58.861899 -377.446209)
			(xy 58.881822 -377.394118) (xy 58.909118 -377.345483) (xy 58.943204 -377.30134) (xy 58.983353 -377.262631)
			(xy 59.028711 -377.23018) (xy 59.078311 -377.204679) (xy 59.131095 -377.186672) (xy 59.185938 -377.176542)
			(xy 59.241672 -377.174505) (xy 59.297109 -377.180605) (xy 59.351066 -377.194711) (xy 59.402395 -377.216523)
			(xy 59.450001 -377.245577) (xy 59.492869 -377.281252) (xy 59.530086 -377.322789) (xy 59.560859 -377.369302)
			(xy 59.584531 -377.419799) (xy 59.600599 -377.473206) (xy 59.608719 -377.528382) (xy 59.609228 -377.556268)
			(xy 59.608719 -377.584154) (xy 59.600599 -377.63933) (xy 59.584531 -377.692737) (xy 59.560859 -377.743234)
			(xy 59.530086 -377.789747) (xy 59.492869 -377.831284) (xy 59.450001 -377.866959) (xy 59.402395 -377.896013)
			(xy 59.351066 -377.917825) (xy 59.297109 -377.931931) (xy 59.241672 -377.938031) (xy 59.185938 -377.935994)
			(xy 59.131095 -377.925864) (xy 59.078311 -377.907857) (xy 59.028711 -377.882356) (xy 58.983353 -377.849905)
			(xy 58.943204 -377.811196) (xy 58.909118 -377.767053) (xy 58.881822 -377.718418) (xy 58.861899 -377.666327)
			(xy 58.849773 -377.61189) (xy 58.845702 -377.556268) (xy 43.947837 -377.556268) (xy 43.909648 -377.587641)
			(xy 43.838969 -377.636177) (xy 43.764384 -377.678465) (xy 43.686443 -377.714192) (xy 43.605722 -377.743095)
			(xy 43.522817 -377.76496) (xy 43.438341 -377.779626) (xy 43.352918 -377.786983) (xy 43.310048 -377.787408)
			(xy 43.309286 -377.787408) (xy 43.266413 -377.786926) (xy 43.180986 -377.77952) (xy 43.096511 -377.764807)
			(xy 43.01361 -377.742894) (xy 42.932898 -377.713945) (xy 42.893742 -377.696476) (xy 42.890186 -377.697238)
			(xy 42.88282 -377.698762) (xy 42.869936 -377.703522) (xy 42.843621 -377.711404) (xy 42.830242 -377.71451)
			(xy 42.807128 -377.718828) (xy 42.806874 -377.718828) (xy 42.803318 -377.719336) (xy 42.800778 -377.719844)
			(xy 42.796714 -377.720352) (xy 42.796206 -377.720352) (xy 42.794936 -377.720606) (xy 42.794682 -377.720606)
			(xy 42.79011 -377.721114) (xy 42.789602 -377.721114) (xy 42.763948 -377.723146) (xy 42.7609 -377.723146)
			(xy 42.757598 -377.7234) (xy 42.745914 -377.7234) (xy 42.718756 -377.722779) (xy 42.665023 -377.714794)
			(xy 42.612967 -377.699267) (xy 42.563639 -377.676514) (xy 42.518038 -377.646993) (xy 42.477085 -377.611303)
			(xy 42.441609 -377.570164) (xy 42.412328 -377.524409) (xy 42.389832 -377.474963) (xy 42.374578 -377.422827)
			(xy 42.366874 -377.369053) (xy 42.366438 -377.341892) (xy 42.366438 -377.340368) (xy 42.367169 -377.307497)
			(xy 42.378539 -377.242745) (xy 42.389044 -377.21159) (xy 42.39006 -377.20905) (xy 42.390568 -377.207018)
			(xy 42.392346 -377.201938) (xy 42.394886 -377.18746) (xy 42.394886 -377.186952) (xy 42.38879 -377.172474)
			(xy 42.370616 -377.127055) (xy 42.342196 -377.033442) (xy 42.323085 -376.937494) (xy 42.313468 -376.840136)
			(xy 42.312844 -376.79122) (xy 42.312844 -376.407426) (xy 42.313314 -376.364569) (xy 42.320693 -376.279174)
			(xy 42.335373 -376.194727) (xy 42.345864 -376.153172) (xy 42.347642 -376.140218) (xy 42.345864 -376.127264)
			(xy 42.34307 -376.116596) (xy 42.31386 -376.082306) (xy 42.229278 -376.04573) (xy 42.205656 -376.046746)
			(xy 42.195242 -376.052588) (xy 42.153707 -376.075066) (xy 42.067201 -376.112976) (xy 42.022522 -376.12828)
			(xy 42.013313 -376.131754) (xy 41.99827 -376.144418) (xy 41.993312 -376.152918) (xy 41.97188 -376.192754)
			(xy 41.922829 -376.268768) (xy 41.867095 -376.340027) (xy 41.805137 -376.405945) (xy 41.737463 -376.465981)
			(xy 41.664629 -376.519641) (xy 41.587235 -376.566483) (xy 41.505916 -376.606124) (xy 41.421342 -376.638236)
			(xy 41.334206 -376.662557) (xy 41.245226 -376.678885) (xy 41.155133 -376.687088) (xy 41.1099 -376.687588)
			(xy 41.067891 -376.687141) (xy 40.984172 -376.680053) (xy 40.901345 -376.665952) (xy 40.819997 -376.644937)
			(xy 40.780208 -376.631454) (xy 40.76319 -376.62866) (xy 40.753222 -376.629135) (xy 40.73478 -376.636704)
			(xy 40.727376 -376.643392) (xy 40.384222 -376.986292) (xy 40.350769 -377.018978) (xy 40.278736 -377.078643)
			(xy 40.201436 -377.131306) (xy 40.119546 -377.176503) (xy 40.033786 -377.213838) (xy 39.944908 -377.242984)
			(xy 39.853693 -377.263683) (xy 39.807388 -377.270264) (xy 39.77005 -377.294902) (xy 39.747775 -377.331947)
			(xy 39.697733 -377.402438) (xy 39.641776 -377.468331) (xy 39.580324 -377.529134) (xy 39.51384 -377.584388)
			(xy 39.442823 -377.63368) (xy 39.367805 -377.676638) (xy 39.289349 -377.712941) (xy 39.208046 -377.742317)
			(xy 39.124504 -377.764544) (xy 39.039353 -377.779455) (xy 38.95323 -377.786939) (xy 38.910006 -377.787408)
			(xy 38.909752 -377.787408) (xy 38.868637 -377.786988) (xy 38.786685 -377.780216) (xy 38.70557 -377.766714)
			(xy 38.625844 -377.746573) (xy 38.548049 -377.719931) (xy 38.51021 -377.703842) (xy 38.493446 -377.696476)
			(xy 38.485064 -377.698254) (xy 38.477952 -377.700794) (xy 38.471856 -377.702826) (xy 38.46322 -377.705874)
			(xy 38.462712 -377.705874) (xy 38.43473 -377.714138) (xy 38.377075 -377.723066) (xy 38.347904 -377.723654)
			(xy 38.319723 -377.723149) (xy 38.263973 -377.714858) (xy 38.21005 -377.698456) (xy 38.159126 -377.674299)
			(xy 38.11231 -377.642915) (xy 38.09111 -377.62434) (xy 38.090602 -377.623578) (xy 38.087808 -377.621038)
			(xy 38.086792 -377.620022) (xy 38.081966 -377.61545) (xy 38.07079 -377.609354) (xy 38.061646 -377.607068)
			(xy 38.031928 -377.598686) (xy 38.022276 -377.599702) (xy 38.011627 -377.60022) (xy 37.991398 -377.593566)
			(xy 37.975611 -377.579274) (xy 37.966984 -377.559804) (xy 37.966396 -377.549156) (xy 37.966396 -377.340622)
			(xy 37.966769 -377.316364) (xy 37.972919 -377.268239) (xy 37.985135 -377.221286) (xy 37.993828 -377.198636)
			(xy 37.995606 -377.18873) (xy 37.979609 -377.151001) (xy 37.953135 -377.073439) (xy 37.933121 -376.993965)
			(xy 37.919705 -376.913115) (xy 37.912975 -376.831436) (xy 37.912548 -376.790458) (xy 37.912548 -376.408188)
			(xy 37.91302 -376.365198) (xy 37.92046 -376.279541) (xy 37.93524 -376.194841) (xy 37.945822 -376.153172)
			(xy 37.9476 -376.140218) (xy 37.945822 -376.127264) (xy 37.943028 -376.116596) (xy 37.93998 -376.104912)
			(xy 37.924994 -376.087386) (xy 37.829236 -376.045984) (xy 37.805614 -376.047) (xy 37.7952 -376.052842)
			(xy 37.753719 -376.075242) (xy 37.667339 -376.113021) (xy 37.622734 -376.12828) (xy 37.593524 -376.153172)
			(xy 37.572077 -376.192991) (xy 37.523002 -376.268968) (xy 37.46725 -376.340191) (xy 37.405279 -376.406075)
			(xy 37.337599 -376.466077) (xy 37.264764 -376.519706) (xy 37.187373 -376.566522) (xy 37.106062 -376.606139)
			(xy 37.021499 -376.638232) (xy 36.934377 -376.662538) (xy 36.845413 -376.678857) (xy 36.755336 -376.687056)
			(xy 36.710112 -376.687588) (xy 36.665457 -376.687079) (xy 36.576507 -376.679074) (xy 36.488627 -376.663153)
			(xy 36.445444 -376.651774) (xy 36.436686 -376.649738) (xy 36.418781 -376.651257) (xy 36.4025 -376.65886)
			(xy 36.395914 -376.664982) (xy 36.389564 -376.671332) (xy 36.074604 -376.986292) (xy 36.041278 -377.018855)
			(xy 35.969528 -377.078311) (xy 35.892545 -377.130814) (xy 35.811 -377.175906) (xy 35.725603 -377.213193)
			(xy 35.6371 -377.242351) (xy 35.546263 -377.263124) (xy 35.453884 -377.275333) (xy 35.407346 -377.27763)
			(xy 35.394691 -377.278829) (xy 35.372838 -377.291756) (xy 35.36569 -377.302268) (xy 35.343285 -377.33882)
			(xy 35.293108 -377.408345) (xy 35.237147 -377.473304) (xy 35.175815 -377.533219) (xy 35.109565 -377.587645)
			(xy 35.038887 -377.636183) (xy 34.964301 -377.678472) (xy 34.88636 -377.7142) (xy 34.805639 -377.743104)
			(xy 34.722734 -377.76497) (xy 34.638258 -377.779637) (xy 34.552834 -377.786996) (xy 34.509964 -377.787408)
			(xy 34.509202 -377.787408) (xy 34.466386 -377.786926) (xy 34.381072 -377.779535) (xy 34.296706 -377.764859)
			(xy 34.213908 -377.743006) (xy 34.133288 -377.714137) (xy 34.094166 -377.69673) (xy 34.089594 -377.697492)
			(xy 34.08299 -377.698762) (xy 34.078926 -377.700286) (xy 34.060892 -377.706382) (xy 34.049716 -377.709684)
			(xy 34.018982 -377.716796) (xy 34.006634 -377.719034) (xy 33.981721 -377.722084) (xy 33.969198 -377.722892)
			(xy 33.955736 -377.7234) (xy 33.945576 -377.7234) (xy 33.918433 -377.722756) (xy 33.864738 -377.714732)
			(xy 33.812722 -377.699177) (xy 33.763436 -377.676404) (xy 33.717877 -377.646874) (xy 33.676965 -377.611184)
			(xy 33.641525 -377.570054) (xy 33.612275 -377.524316) (xy 33.589804 -377.474892) (xy 33.574566 -377.422782)
			(xy 33.566871 -377.369038) (xy 33.566354 -377.341892) (xy 33.566354 -377.340876) (xy 33.566898 -377.312105)
			(xy 33.57557 -377.255218) (xy 33.583626 -377.227592) (xy 33.58388 -377.227084) (xy 33.58642 -377.219464)
			(xy 33.586928 -377.21794) (xy 33.587182 -377.217178) (xy 33.588198 -377.214384) (xy 33.593786 -377.199652)
			(xy 33.595818 -377.19381) (xy 33.596326 -377.189746) (xy 33.580257 -377.151954) (xy 33.55365 -377.074254)
			(xy 33.533521 -376.994631) (xy 33.520005 -376.913622) (xy 33.513195 -376.831776) (xy 33.51276 -376.790712)
			(xy 33.51276 -376.407426) (xy 33.51323 -376.364569) (xy 33.520609 -376.279174) (xy 33.535287 -376.194727)
			(xy 33.54578 -376.153172) (xy 33.547558 -376.140218) (xy 33.54578 -376.127264) (xy 33.542986 -376.116596)
			(xy 33.539938 -376.104912) (xy 33.524952 -376.087386) (xy 33.429194 -376.045984) (xy 33.405572 -376.047)
			(xy 33.395158 -376.052842) (xy 33.353678 -376.075245) (xy 33.2673 -376.113028) (xy 33.222692 -376.12828)
			(xy 33.193482 -376.153172) (xy 33.172035 -376.192992) (xy 33.122961 -376.268973) (xy 33.06721 -376.340199)
			(xy 33.005241 -376.406086) (xy 32.937561 -376.466093) (xy 32.864727 -376.519726) (xy 32.787336 -376.566546)
			(xy 32.706025 -376.606168) (xy 32.621461 -376.638266) (xy 32.534339 -376.662577) (xy 32.445373 -376.678901)
			(xy 32.355295 -376.687105) (xy 32.31007 -376.687588) (xy 32.265415 -376.687077) (xy 32.176466 -376.679068)
			(xy 32.088588 -376.663144) (xy 32.045402 -376.651774) (xy 32.036641 -376.649728) (xy 32.018724 -376.651229)
			(xy 32.002427 -376.658822) (xy 31.995872 -376.664982) (xy 31.989522 -376.671332) (xy 31.674562 -376.986292)
			(xy 31.641235 -377.018854) (xy 31.569485 -377.078307) (xy 31.492501 -377.130806) (xy 31.410955 -377.175895)
			(xy 31.325558 -377.213179) (xy 31.237055 -377.242332) (xy 31.146218 -377.263102) (xy 31.05384 -377.275307)
			(xy 31.007304 -377.27763) (xy 30.994641 -377.278817) (xy 30.972767 -377.291731) (xy 30.965648 -377.302268)
			(xy 30.943243 -377.338819) (xy 30.893065 -377.408341) (xy 30.837104 -377.473298) (xy 30.775771 -377.53321)
			(xy 30.70952 -377.587634) (xy 30.638841 -377.636168) (xy 30.564256 -377.678454) (xy 30.486315 -377.71418)
			(xy 30.405594 -377.74308) (xy 30.322689 -377.764943) (xy 30.238214 -377.779607) (xy 30.152791 -377.786962)
			(xy 30.109922 -377.787408) (xy 30.109668 -377.787408) (xy 30.068552 -377.786989) (xy 29.986601 -377.780218)
			(xy 29.905485 -377.766717) (xy 29.825759 -377.746578) (xy 29.747963 -377.719937) (xy 29.710126 -377.703842)
			(xy 29.693362 -377.696476) (xy 29.68498 -377.698254) (xy 29.677868 -377.700794) (xy 29.671772 -377.702826)
			(xy 29.663136 -377.705874) (xy 29.662628 -377.705874) (xy 29.634646 -377.714139) (xy 29.576991 -377.723069)
			(xy 29.54782 -377.723654) (xy 29.519638 -377.72315) (xy 29.463888 -377.714861) (xy 29.409963 -377.698461)
			(xy 29.359038 -377.674306) (xy 29.31222 -377.642922) (xy 29.291026 -377.62434) (xy 29.290518 -377.623578)
			(xy 29.287724 -377.621038) (xy 29.286708 -377.620022) (xy 29.281882 -377.61545) (xy 29.270706 -377.609354)
			(xy 29.261562 -377.607068) (xy 29.231844 -377.598686) (xy 29.222192 -377.599702) (xy 29.211541 -377.600223)
			(xy 29.191306 -377.593572) (xy 29.175513 -377.57928) (xy 29.166883 -377.559806) (xy 29.166312 -377.549156)
			(xy 29.166312 -377.340622) (xy 29.166685 -377.316364) (xy 29.172836 -377.268239) (xy 29.185052 -377.221286)
			(xy 29.193744 -377.198636) (xy 29.195522 -377.18873) (xy 29.179527 -377.151001) (xy 29.153054 -377.073439)
			(xy 29.133042 -376.993964) (xy 29.119627 -376.913114) (xy 29.112898 -376.831436) (xy 29.112464 -376.790458)
			(xy 29.112464 -376.408188) (xy 29.112936 -376.365198) (xy 29.120376 -376.279541) (xy 29.135157 -376.194842)
			(xy 29.145738 -376.153172) (xy 29.147516 -376.140218) (xy 29.145738 -376.127264) (xy 29.142944 -376.116596)
			(xy 29.139896 -376.104912) (xy 29.12491 -376.087386) (xy 29.029152 -376.045984) (xy 29.00553 -376.047)
			(xy 28.995116 -376.052842) (xy 28.953635 -376.075243) (xy 28.867256 -376.113023) (xy 28.82265 -376.12828)
			(xy 28.81345 -376.131763) (xy 28.798426 -376.144437) (xy 28.79344 -376.152918) (xy 28.772154 -376.192491)
			(xy 28.723464 -376.268021) (xy 28.668175 -376.338863) (xy 28.606735 -376.404442) (xy 28.539642 -376.464226)
			(xy 28.467442 -376.51773) (xy 28.39072 -376.564519) (xy 28.310099 -376.604215) (xy 28.226233 -376.636494)
			(xy 28.139802 -376.661095) (xy 28.051508 -376.677818) (xy 27.962067 -376.686528) (xy 27.91714 -376.687334)
			(xy 27.916886 -376.687334) (xy 27.90703 -376.687946) (xy 27.888871 -376.695659) (xy 27.88158 -376.70232)
			(xy 27.869388 -376.714512) (xy 27.866685 -376.717365) (xy 27.862097 -376.723746) (xy 27.860244 -376.727212)
			(xy 27.857656 -376.732638) (xy 27.854822 -376.744317) (xy 27.854656 -376.750326) (xy 27.854656 -377.626372)
			(xy 27.855139 -377.636387) (xy 27.862792 -377.654896) (xy 27.876944 -377.669068) (xy 27.895442 -377.676747)
			(xy 27.905456 -377.677172) (xy 28.268168 -377.677172) (xy 28.27766 -377.677591) (xy 28.295386 -377.684384)
			(xy 28.309499 -377.697079) (xy 28.314142 -377.705366) (xy 28.314904 -377.70689) (xy 28.315666 -377.709176)
			(xy 28.317418 -377.71381) (xy 28.319341 -377.723528) (xy 28.319476 -377.72848) (xy 28.319476 -378.010166)
			(xy 28.321 -378.022104) (xy 28.325064 -378.037344) (xy 28.328874 -378.043694) (xy 28.3448 -378.071813)
			(xy 28.369895 -378.131363) (xy 28.386876 -378.193715) (xy 28.395443 -378.257766) (xy 28.395446 -378.322389)
			(xy 28.395391 -378.322797) (xy 31.825007 -378.322797) (xy 31.82501 -378.257358) (xy 31.833797 -378.192512)
			(xy 31.85121 -378.129433) (xy 31.876931 -378.069261) (xy 31.893256 -378.0409) (xy 31.896567 -378.034874)
			(xy 31.900176 -378.021611) (xy 31.900368 -378.014738) (xy 31.900368 -377.728734) (xy 31.900793 -377.718561)
			(xy 31.908572 -377.699761) (xy 31.922958 -377.685374) (xy 31.941757 -377.677593) (xy 31.95193 -377.677172)
			(xy 32.66821 -377.677172) (xy 32.678386 -377.677557) (xy 32.697188 -377.685351) (xy 32.711574 -377.699749)
			(xy 32.719352 -377.718557) (xy 32.719772 -377.728734) (xy 32.719772 -378.014738) (xy 32.719991 -378.021609)
			(xy 32.723581 -378.034872) (xy 32.726884 -378.0409) (xy 32.743183 -378.069274) (xy 32.768902 -378.129442)
			(xy 32.786312 -378.192518) (xy 32.795097 -378.25736) (xy 32.7951 -378.322795) (xy 32.786321 -378.387638)
			(xy 32.768917 -378.450716) (xy 32.743204 -378.510887) (xy 32.726884 -378.539248) (xy 32.723551 -378.545264)
			(xy 32.719957 -378.558534) (xy 32.719772 -378.56541) (xy 32.719772 -379.31471) (xy 32.719964 -379.321583)
			(xy 32.723572 -379.334846) (xy 32.726884 -379.340872) (xy 32.743244 -379.369212) (xy 32.768957 -379.429388)
			(xy 32.78636 -379.492471) (xy 32.795138 -379.55732) (xy 32.795133 -379.622759) (xy 32.786344 -379.687606)
			(xy 32.768931 -379.750686) (xy 32.743209 -379.810858) (xy 32.726884 -379.83922) (xy 32.723561 -379.845241)
			(xy 32.719961 -379.858507) (xy 32.719772 -379.865382) (xy 32.719772 -380.151386) (xy 32.719325 -380.161556)
			(xy 32.711547 -380.180348) (xy 32.697168 -380.194733) (xy 32.678379 -380.20252) (xy 32.66821 -380.202948)
			(xy 31.95193 -380.202948) (xy 31.941759 -380.202511) (xy 31.922962 -380.194733) (xy 31.908576 -380.180351)
			(xy 31.900792 -380.161557) (xy 31.900368 -380.151386) (xy 31.900368 -379.865382) (xy 31.900187 -379.858508)
			(xy 31.896572 -379.845245) (xy 31.893256 -379.83922) (xy 31.876972 -379.810837) (xy 31.85125 -379.750671)
			(xy 31.833837 -379.687597) (xy 31.825048 -379.622756) (xy 31.825043 -379.557323) (xy 31.833821 -379.49248)
			(xy 31.851224 -379.429403) (xy 31.876936 -379.369233) (xy 31.893256 -379.340872) (xy 31.896577 -379.33485)
			(xy 31.900179 -379.321584) (xy 31.900368 -379.31471) (xy 31.900368 -378.56541) (xy 31.900176 -378.558537)
			(xy 31.896568 -378.545274) (xy 31.893256 -378.539248) (xy 31.876911 -378.510899) (xy 31.851195 -378.450725)
			(xy 31.833788 -378.387644) (xy 31.825007 -378.322797) (xy 28.395391 -378.322797) (xy 28.386884 -378.386441)
			(xy 28.369909 -378.448794) (xy 28.34482 -378.508347) (xy 28.328874 -378.536454) (xy 28.325064 -378.542804)
			(xy 28.321 -378.558044) (xy 28.319476 -378.569982) (xy 28.319476 -379.30963) (xy 28.321254 -379.322584)
			(xy 28.325064 -379.33757) (xy 28.328874 -379.34392) (xy 28.33116 -379.347984) (xy 28.331414 -379.348492)
			(xy 28.335986 -379.356366) (xy 28.350131 -379.383122) (xy 28.372423 -379.43939) (xy 28.387569 -379.497987)
			(xy 28.395334 -379.558009) (xy 28.39593 -379.588268) (xy 28.395676 -379.595888) (xy 28.395676 -379.596396)
			(xy 28.395422 -379.608842) (xy 28.395422 -379.60935) (xy 28.39362 -379.64111) (xy 28.382789 -379.703794)
			(xy 28.373832 -379.734318) (xy 28.365154 -379.760991) (xy 28.342491 -379.812301) (xy 28.32862 -379.83668)
			(xy 28.327858 -379.83795) (xy 28.325064 -379.843284) (xy 28.322524 -379.850142) (xy 28.321137 -379.854261)
			(xy 28.319605 -379.862816) (xy 28.319476 -379.86716) (xy 28.319476 -380.00813) (xy 28.31973 -380.151386)
			(xy 28.319243 -380.161512) (xy 28.311517 -380.180232) (xy 28.29723 -380.194585) (xy 28.278546 -380.202396)
			(xy 28.268422 -380.202948) (xy 27.905456 -380.202948) (xy 27.895444 -380.203376) (xy 27.87695 -380.211055)
			(xy 27.862804 -380.225228) (xy 27.855158 -380.243735) (xy 27.854656 -380.253748) (xy 27.854656 -380.6574)
			(xy 29.62489 -380.6574) (xy 29.63367 -380.592557) (xy 29.651075 -380.529479) (xy 29.676788 -380.469308)
			(xy 29.693108 -380.440946) (xy 29.696407 -380.434914) (xy 29.700022 -380.421656) (xy 29.70022 -380.414784)
			(xy 29.70022 -379.665484) (xy 29.700032 -379.658611) (xy 29.696421 -379.645348) (xy 29.693108 -379.639322)
			(xy 29.676827 -379.610938) (xy 29.651108 -379.550772) (xy 29.633696 -379.487698) (xy 29.624908 -379.422858)
			(xy 29.624903 -379.357425) (xy 29.63368 -379.292583) (xy 29.65108 -379.229506) (xy 29.67679 -379.169336)
			(xy 29.693108 -379.140974) (xy 29.696433 -379.134954) (xy 29.700032 -379.121687) (xy 29.70022 -379.114812)
			(xy 29.70022 -378.828554) (xy 29.700695 -378.818396) (xy 29.708482 -378.799629) (xy 29.722852 -378.785266)
			(xy 29.741623 -378.77749) (xy 29.751782 -378.776992) (xy 30.468062 -378.776992) (xy 30.478212 -378.777564)
			(xy 30.496971 -378.785317) (xy 30.511336 -378.799658) (xy 30.51912 -378.818405) (xy 30.519624 -378.828554)
			(xy 30.519624 -379.114812) (xy 30.519809 -379.121686) (xy 30.523422 -379.134949) (xy 30.526736 -379.140974)
			(xy 30.5431 -379.169313) (xy 30.568815 -379.229489) (xy 30.586219 -379.292572) (xy 30.594998 -379.357421)
			(xy 30.594993 -379.422861) (xy 30.586203 -379.487709) (xy 30.568788 -379.550789) (xy 30.543062 -379.610961)
			(xy 30.526736 -379.639322) (xy 30.523416 -379.645344) (xy 30.519814 -379.65861) (xy 30.519624 -379.665484)
			(xy 30.519624 -380.414784) (xy 30.519819 -380.421657) (xy 30.523425 -380.43492) (xy 30.526736 -380.440946)
			(xy 30.543076 -380.469298) (xy 30.568793 -380.529471) (xy 30.5862 -380.592551) (xy 30.594982 -380.657398)
			(xy 30.594981 -380.69012) (xy 34.024316 -380.69012) (xy 34.024866 -380.65739) (xy 34.033726 -380.592531)
			(xy 34.051221 -380.529451) (xy 34.077033 -380.469293) (xy 34.093404 -380.440946) (xy 34.096703 -380.434914)
			(xy 34.100318 -380.421656) (xy 34.100516 -380.414784) (xy 34.100516 -379.665484) (xy 34.100328 -379.65861)
			(xy 34.096717 -379.645348) (xy 34.093404 -379.639322) (xy 34.077048 -379.610968) (xy 34.051243 -379.55081)
			(xy 34.033751 -379.487732) (xy 34.024888 -379.422877) (xy 34.024316 -379.390148) (xy 34.024879 -379.357418)
			(xy 34.033735 -379.29256) (xy 34.051226 -379.22948) (xy 34.077035 -379.169322) (xy 34.093404 -379.140974)
			(xy 34.096728 -379.134954) (xy 34.100328 -379.121687) (xy 34.100516 -379.114812) (xy 34.100516 -378.828554)
			(xy 34.100988 -378.818427) (xy 34.108727 -378.79971) (xy 34.123017 -378.785356) (xy 34.1417 -378.777534)
			(xy 34.151824 -378.776992) (xy 34.868104 -378.776992) (xy 34.878257 -378.777418) (xy 34.897008 -378.785214)
			(xy 34.911331 -378.799609) (xy 34.919032 -378.818399) (xy 34.919412 -378.828554) (xy 34.919412 -379.114812)
			(xy 34.919598 -379.121686) (xy 34.92321 -379.134949) (xy 34.926524 -379.140974) (xy 34.942882 -379.169328)
			(xy 34.968685 -379.229486) (xy 34.986177 -379.292564) (xy 34.99504 -379.357419) (xy 34.995612 -379.390148)
			(xy 34.995044 -379.422877) (xy 34.986188 -379.487735) (xy 34.968699 -379.550816) (xy 34.95187 -379.590046)
			(xy 36.224464 -379.590046) (xy 36.225033 -379.557317) (xy 36.233888 -379.492459) (xy 36.251378 -379.429379)
			(xy 36.277184 -379.36922) (xy 36.293552 -379.340872) (xy 36.296873 -379.33485) (xy 36.300475 -379.321584)
			(xy 36.300664 -379.31471) (xy 36.300664 -378.56541) (xy 36.300473 -378.558537) (xy 36.296864 -378.545274)
			(xy 36.293552 -378.539248) (xy 36.277171 -378.510907) (xy 36.251371 -378.450745) (xy 36.233886 -378.387663)
			(xy 36.225031 -378.322804) (xy 36.224464 -378.290074) (xy 36.225045 -378.257345) (xy 36.233897 -378.192488)
			(xy 36.251383 -378.129407) (xy 36.277186 -378.069249) (xy 36.293552 -378.0409) (xy 36.296863 -378.034873)
			(xy 36.300472 -378.021611) (xy 36.300664 -378.014738) (xy 36.300664 -377.728734) (xy 36.301155 -377.718607)
			(xy 36.308876 -377.699882) (xy 36.323162 -377.685523) (xy 36.341847 -377.677707) (xy 36.351972 -377.677172)
			(xy 37.068252 -377.677172) (xy 37.0784 -377.67766) (xy 37.097145 -377.685435) (xy 37.11147 -377.699811)
			(xy 37.119176 -377.718585) (xy 37.11956 -377.728734) (xy 37.11956 -378.014738) (xy 37.119781 -378.021609)
			(xy 37.12337 -378.034872) (xy 37.126672 -378.0409) (xy 37.143035 -378.069251) (xy 37.168838 -378.12941)
			(xy 37.186329 -378.192489) (xy 37.195189 -378.257345) (xy 37.19576 -378.290074) (xy 37.195197 -378.322804)
			(xy 37.186339 -378.387662) (xy 37.168848 -378.450742) (xy 37.14304 -378.5109) (xy 37.126672 -378.539248)
			(xy 37.123338 -378.545263) (xy 37.119745 -378.558534) (xy 37.11956 -378.56541) (xy 37.11956 -379.31471)
			(xy 37.119753 -379.321583) (xy 37.123361 -379.334846) (xy 37.126672 -379.340872) (xy 37.143024 -379.369229)
			(xy 37.16883 -379.429385) (xy 37.186323 -379.492463) (xy 37.195188 -379.557318) (xy 37.19576 -379.590046)
			(xy 37.195184 -379.622775) (xy 37.18633 -379.687633) (xy 37.168843 -379.750713) (xy 37.143039 -379.810871)
			(xy 37.126672 -379.83922) (xy 37.123348 -379.84524) (xy 37.119749 -379.858507) (xy 37.11956 -379.865382)
			(xy 37.11956 -380.151386) (xy 37.119062 -380.161512) (xy 37.111339 -380.180233) (xy 37.097056 -380.194589)
			(xy 37.078375 -380.202409) (xy 37.068252 -380.202948) (xy 36.351972 -380.202948) (xy 36.341822 -380.202502)
			(xy 36.323078 -380.194707) (xy 36.308758 -380.180318) (xy 36.30105 -380.161538) (xy 36.300664 -380.151386)
			(xy 36.300664 -379.865382) (xy 36.300483 -379.858508) (xy 36.296868 -379.845245) (xy 36.293552 -379.83922)
			(xy 36.277199 -379.810864) (xy 36.251393 -379.750707) (xy 36.2339 -379.68763) (xy 36.225036 -379.622774)
			(xy 36.224464 -379.590046) (xy 34.95187 -379.590046) (xy 34.942892 -379.610974) (xy 34.926524 -379.639322)
			(xy 34.923203 -379.645344) (xy 34.919601 -379.65861) (xy 34.919412 -379.665484) (xy 34.919412 -380.414784)
			(xy 34.919609 -380.421657) (xy 34.923214 -380.43492) (xy 34.926524 -380.440946) (xy 34.94291 -380.469284)
			(xy 34.968707 -380.529448) (xy 34.98619 -380.592531) (xy 34.995045 -380.65739) (xy 34.995045 -380.6574)
			(xy 38.424976 -380.6574) (xy 38.433756 -380.592557) (xy 38.45116 -380.529479) (xy 38.476873 -380.469308)
			(xy 38.493192 -380.440946) (xy 38.49649 -380.434913) (xy 38.500106 -380.421656) (xy 38.500304 -380.414784)
			(xy 38.500304 -379.665484) (xy 38.500118 -379.65861) (xy 38.496506 -379.645348) (xy 38.493192 -379.639322)
			(xy 38.476912 -379.610938) (xy 38.451193 -379.550771) (xy 38.433782 -379.487698) (xy 38.424994 -379.422858)
			(xy 38.424989 -379.357425) (xy 38.433766 -379.292583) (xy 38.451166 -379.229506) (xy 38.476874 -379.169336)
			(xy 38.493192 -379.140974) (xy 38.496515 -379.134954) (xy 38.500116 -379.121687) (xy 38.500304 -379.114812)
			(xy 38.500304 -378.828554) (xy 38.500795 -378.818397) (xy 38.508578 -378.799634) (xy 38.522944 -378.785271)
			(xy 38.541709 -378.777493) (xy 38.551866 -378.776992) (xy 39.268146 -378.776992) (xy 39.278301 -378.777495)
			(xy 39.297062 -378.785276) (xy 39.311424 -378.799638) (xy 39.319205 -378.818399) (xy 39.319708 -378.828554)
			(xy 39.319708 -379.114812) (xy 39.319894 -379.121686) (xy 39.323506 -379.134949) (xy 39.32682 -379.140974)
			(xy 39.343184 -379.169312) (xy 39.3689 -379.229488) (xy 39.386305 -379.292572) (xy 39.395085 -379.357421)
			(xy 39.395079 -379.422861) (xy 39.386289 -379.487709) (xy 39.368873 -379.550789) (xy 39.352089 -379.590046)
			(xy 40.624252 -379.590046) (xy 40.624822 -379.557317) (xy 40.633678 -379.492459) (xy 40.651167 -379.429379)
			(xy 40.676972 -379.36922) (xy 40.69334 -379.340872) (xy 40.69666 -379.33485) (xy 40.700263 -379.321584)
			(xy 40.700452 -379.31471) (xy 40.700452 -378.56541) (xy 40.700262 -378.558537) (xy 40.696653 -378.545274)
			(xy 40.69334 -378.539248) (xy 40.676958 -378.510908) (xy 40.651159 -378.450745) (xy 40.633674 -378.387663)
			(xy 40.624819 -378.322804) (xy 40.624252 -378.290074) (xy 40.624835 -378.257345) (xy 40.633686 -378.192488)
			(xy 40.651172 -378.129408) (xy 40.676974 -378.069249) (xy 40.69334 -378.0409) (xy 40.69665 -378.034873)
			(xy 40.700259 -378.021611) (xy 40.700452 -378.014738) (xy 40.700452 -377.728734) (xy 40.700955 -377.718608)
			(xy 40.708674 -377.699885) (xy 40.722955 -377.685528) (xy 40.741637 -377.677709) (xy 40.75176 -377.677172)
			(xy 41.46804 -377.677172) (xy 41.478193 -377.677588) (xy 41.496941 -377.685392) (xy 41.511262 -377.699789)
			(xy 41.518965 -377.718579) (xy 41.519348 -377.728734) (xy 41.519348 -378.014738) (xy 41.519558 -378.02161)
			(xy 41.523153 -378.034873) (xy 41.52646 -378.0409) (xy 41.542822 -378.069251) (xy 41.568625 -378.12941)
			(xy 41.586116 -378.192489) (xy 41.594977 -378.257345) (xy 41.595548 -378.290074) (xy 45.023794 -378.290074)
			(xy 45.027785 -378.227907) (xy 45.039694 -378.16676) (xy 45.059323 -378.107639) (xy 45.086352 -378.051513)
			(xy 45.120336 -377.999304) (xy 45.160718 -377.951869) (xy 45.206834 -377.909988) (xy 45.257926 -377.874348)
			(xy 45.313157 -377.845534) (xy 45.371619 -377.82402) (xy 45.432353 -377.810158) (xy 45.49436 -377.804176)
			(xy 45.556623 -377.806172) (xy 45.61812 -377.816115) (xy 45.677841 -377.833839) (xy 45.734804 -377.859056)
			(xy 45.788075 -377.891349) (xy 45.83678 -377.930189) (xy 45.880117 -377.974939) (xy 45.917377 -378.024863)
			(xy 45.947946 -378.079142) (xy 45.971324 -378.136885) (xy 45.987125 -378.197143) (xy 45.995091 -378.258926)
			(xy 45.99559 -378.290074) (xy 45.995091 -378.321222) (xy 45.987972 -378.376434) (xy 54.891938 -378.376434)
			(xy 54.896009 -378.320812) (xy 54.908135 -378.266375) (xy 54.928058 -378.214284) (xy 54.955354 -378.165649)
			(xy 54.98944 -378.121506) (xy 55.029589 -378.082797) (xy 55.074947 -378.050346) (xy 55.124547 -378.024845)
			(xy 55.177331 -378.006838) (xy 55.232174 -377.996708) (xy 55.287908 -377.994671) (xy 55.343345 -378.000771)
			(xy 55.397302 -378.014877) (xy 55.448631 -378.036689) (xy 55.496237 -378.065743) (xy 55.539105 -378.101418)
			(xy 55.576322 -378.142955) (xy 55.584423 -378.1552) (xy 55.980328 -378.1552) (xy 55.984399 -378.099578)
			(xy 55.996525 -378.045141) (xy 56.016448 -377.99305) (xy 56.043744 -377.944415) (xy 56.07783 -377.900272)
			(xy 56.117979 -377.861563) (xy 56.163337 -377.829112) (xy 56.212937 -377.803611) (xy 56.265721 -377.785604)
			(xy 56.320564 -377.775474) (xy 56.376298 -377.773437) (xy 56.431735 -377.779537) (xy 56.485692 -377.793643)
			(xy 56.537021 -377.815455) (xy 56.584627 -377.844509) (xy 56.627495 -377.880184) (xy 56.664712 -377.921721)
			(xy 56.695485 -377.968234) (xy 56.719157 -378.018731) (xy 56.735225 -378.072138) (xy 56.743345 -378.127314)
			(xy 56.743854 -378.1552) (xy 56.743345 -378.183086) (xy 56.735225 -378.238262) (xy 56.719157 -378.291669)
			(xy 56.695485 -378.342166) (xy 56.664712 -378.388679) (xy 56.627495 -378.430216) (xy 56.584627 -378.465891)
			(xy 56.537021 -378.494945) (xy 56.485692 -378.516757) (xy 56.431735 -378.530863) (xy 56.376298 -378.536963)
			(xy 56.320564 -378.534926) (xy 56.265721 -378.524796) (xy 56.212937 -378.506789) (xy 56.163337 -378.481288)
			(xy 56.117979 -378.448837) (xy 56.07783 -378.410128) (xy 56.043744 -378.365985) (xy 56.016448 -378.31735)
			(xy 55.996525 -378.265259) (xy 55.984399 -378.210822) (xy 55.980328 -378.1552) (xy 55.584423 -378.1552)
			(xy 55.607095 -378.189468) (xy 55.630767 -378.239965) (xy 55.646835 -378.293372) (xy 55.654955 -378.348548)
			(xy 55.655464 -378.376434) (xy 55.654955 -378.40432) (xy 55.646835 -378.459496) (xy 55.630767 -378.512903)
			(xy 55.607095 -378.5634) (xy 55.576322 -378.609913) (xy 55.539105 -378.65145) (xy 55.496237 -378.687125)
			(xy 55.448631 -378.716179) (xy 55.397302 -378.737991) (xy 55.343345 -378.752097) (xy 55.287908 -378.758197)
			(xy 55.232174 -378.75616) (xy 55.177331 -378.74603) (xy 55.124547 -378.728023) (xy 55.074947 -378.702522)
			(xy 55.029589 -378.670071) (xy 54.98944 -378.631362) (xy 54.955354 -378.587219) (xy 54.928058 -378.538584)
			(xy 54.908135 -378.486493) (xy 54.896009 -378.432056) (xy 54.891938 -378.376434) (xy 45.987972 -378.376434)
			(xy 45.987125 -378.383005) (xy 45.971324 -378.443263) (xy 45.947946 -378.501006) (xy 45.917377 -378.555285)
			(xy 45.880117 -378.605209) (xy 45.83678 -378.649959) (xy 45.788075 -378.688799) (xy 45.734804 -378.721092)
			(xy 45.677841 -378.746309) (xy 45.61812 -378.764033) (xy 45.556623 -378.773976) (xy 45.49436 -378.775972)
			(xy 45.432353 -378.76999) (xy 45.371619 -378.756128) (xy 45.313157 -378.734614) (xy 45.257926 -378.7058)
			(xy 45.206834 -378.67016) (xy 45.160718 -378.628279) (xy 45.120336 -378.580844) (xy 45.086352 -378.528635)
			(xy 45.059323 -378.472509) (xy 45.039694 -378.413388) (xy 45.027785 -378.352241) (xy 45.023794 -378.290074)
			(xy 41.595548 -378.290074) (xy 41.594987 -378.322804) (xy 41.586129 -378.387662) (xy 41.568637 -378.450742)
			(xy 41.542829 -378.5109) (xy 41.52646 -378.539248) (xy 41.523133 -378.545267) (xy 41.519534 -378.558535)
			(xy 41.519348 -378.56541) (xy 41.519348 -379.31471) (xy 41.51953 -379.321584) (xy 41.523144 -379.334847)
			(xy 41.52646 -379.340872) (xy 41.542811 -379.36923) (xy 41.568617 -379.429386) (xy 41.586111 -379.492463)
			(xy 41.594976 -379.557318) (xy 41.595548 -379.590046) (xy 41.594974 -379.622775) (xy 41.58612 -379.687633)
			(xy 41.568632 -379.750713) (xy 41.542827 -379.810872) (xy 41.52646 -379.83922) (xy 41.523143 -379.845244)
			(xy 41.519538 -379.858508) (xy 41.519348 -379.865382) (xy 41.519348 -380.151386) (xy 41.518862 -380.161513)
			(xy 41.511136 -380.180236) (xy 41.49685 -380.194594) (xy 41.478165 -380.202411) (xy 41.46804 -380.202948)
			(xy 40.75176 -380.202948) (xy 40.741609 -380.202512) (xy 40.722865 -380.194712) (xy 40.708545 -380.180321)
			(xy 40.700838 -380.161539) (xy 40.700452 -380.151386) (xy 40.700452 -379.865382) (xy 40.700273 -379.858508)
			(xy 40.696656 -379.845245) (xy 40.69334 -379.83922) (xy 40.676986 -379.810864) (xy 40.651181 -379.750707)
			(xy 40.633687 -379.68763) (xy 40.624824 -379.622774) (xy 40.624252 -379.590046) (xy 39.352089 -379.590046)
			(xy 39.343147 -379.610961) (xy 39.32682 -379.639322) (xy 39.323499 -379.645344) (xy 39.319897 -379.65861)
			(xy 39.319708 -379.665484) (xy 39.319708 -380.414784) (xy 39.319905 -380.421657) (xy 39.32351 -380.43492)
			(xy 39.32682 -380.440946) (xy 39.34316 -380.469297) (xy 39.368879 -380.52947) (xy 39.386286 -380.592551)
			(xy 39.395069 -380.657398) (xy 39.395067 -380.69012) (xy 42.8244 -380.69012) (xy 42.824953 -380.65739)
			(xy 42.833812 -380.592531) (xy 42.851306 -380.529451) (xy 42.877118 -380.469294) (xy 42.893488 -380.440946)
			(xy 42.896786 -380.434913) (xy 42.900402 -380.421656) (xy 42.9006 -380.414784) (xy 42.9006 -379.665484)
			(xy 42.900414 -379.65861) (xy 42.896802 -379.645347) (xy 42.893488 -379.639322) (xy 42.87713 -379.610969)
			(xy 42.851327 -379.55081) (xy 42.833835 -379.487732) (xy 42.824972 -379.422877) (xy 42.8244 -379.390148)
			(xy 42.824965 -379.357418) (xy 42.833821 -379.29256) (xy 42.851312 -379.22948) (xy 42.877119 -379.169322)
			(xy 42.893488 -379.140974) (xy 42.896811 -379.134953) (xy 42.900412 -379.121687) (xy 42.9006 -379.114812)
			(xy 42.9006 -378.828554) (xy 42.901088 -378.818429) (xy 42.908823 -378.799715) (xy 42.923108 -378.785361)
			(xy 42.941786 -378.777537) (xy 42.951908 -378.776992) (xy 43.668188 -378.776992) (xy 43.67834 -378.777431)
			(xy 43.697091 -378.785221) (xy 43.711414 -378.799613) (xy 43.719116 -378.8184) (xy 43.719496 -378.828554)
			(xy 43.719496 -378.829316) (xy 58.842146 -378.829316) (xy 58.846217 -378.773694) (xy 58.858343 -378.719257)
			(xy 58.878266 -378.667166) (xy 58.905562 -378.618531) (xy 58.939648 -378.574388) (xy 58.979797 -378.535679)
			(xy 59.025155 -378.503228) (xy 59.074755 -378.477727) (xy 59.127539 -378.45972) (xy 59.182382 -378.44959)
			(xy 59.238116 -378.447553) (xy 59.293553 -378.453653) (xy 59.34751 -378.467759) (xy 59.398839 -378.489571)
			(xy 59.446445 -378.518625) (xy 59.489313 -378.5543) (xy 59.52653 -378.595837) (xy 59.557303 -378.64235)
			(xy 59.580975 -378.692847) (xy 59.597043 -378.746254) (xy 59.605163 -378.80143) (xy 59.605672 -378.829316)
			(xy 59.605163 -378.857202) (xy 59.597043 -378.912378) (xy 59.580975 -378.965785) (xy 59.557303 -379.016282)
			(xy 59.52653 -379.062795) (xy 59.489313 -379.104332) (xy 59.446445 -379.140007) (xy 59.398839 -379.169061)
			(xy 59.34751 -379.190873) (xy 59.293553 -379.204979) (xy 59.238116 -379.211079) (xy 59.182382 -379.209042)
			(xy 59.127539 -379.198912) (xy 59.074755 -379.180905) (xy 59.025155 -379.155404) (xy 58.979797 -379.122953)
			(xy 58.939648 -379.084244) (xy 58.905562 -379.040101) (xy 58.878266 -378.991466) (xy 58.858343 -378.939375)
			(xy 58.846217 -378.884938) (xy 58.842146 -378.829316) (xy 43.719496 -378.829316) (xy 43.719496 -379.114812)
			(xy 43.719684 -379.121686) (xy 43.723295 -379.134948) (xy 43.726608 -379.140974) (xy 43.742964 -379.169329)
			(xy 43.768768 -379.229486) (xy 43.78626 -379.292564) (xy 43.795124 -379.357419) (xy 43.795696 -379.390148)
			(xy 43.79513 -379.422878) (xy 43.786274 -379.487736) (xy 43.768784 -379.550816) (xy 43.751954 -379.590046)
			(xy 45.023794 -379.590046) (xy 45.027785 -379.527879) (xy 45.039694 -379.466732) (xy 45.059323 -379.407611)
			(xy 45.086352 -379.351485) (xy 45.120336 -379.299276) (xy 45.160718 -379.251841) (xy 45.206834 -379.20996)
			(xy 45.257926 -379.17432) (xy 45.313157 -379.145506) (xy 45.371619 -379.123992) (xy 45.432353 -379.11013)
			(xy 45.49436 -379.104148) (xy 45.556623 -379.106144) (xy 45.61812 -379.116087) (xy 45.677841 -379.133811)
			(xy 45.734804 -379.159028) (xy 45.788075 -379.191321) (xy 45.83678 -379.230161) (xy 45.880117 -379.274911)
			(xy 45.917377 -379.324835) (xy 45.947946 -379.379114) (xy 45.952413 -379.390148) (xy 47.223942 -379.390148)
			(xy 47.227933 -379.327981) (xy 47.239842 -379.266834) (xy 47.259471 -379.207713) (xy 47.2865 -379.151587)
			(xy 47.320484 -379.099378) (xy 47.360866 -379.051943) (xy 47.406982 -379.010062) (xy 47.458074 -378.974422)
			(xy 47.513305 -378.945608) (xy 47.571767 -378.924094) (xy 47.632501 -378.910232) (xy 47.694508 -378.90425)
			(xy 47.756771 -378.906246) (xy 47.818268 -378.916189) (xy 47.877989 -378.933913) (xy 47.934952 -378.95913)
			(xy 47.988223 -378.991423) (xy 48.036928 -379.030263) (xy 48.080265 -379.075013) (xy 48.117525 -379.124937)
			(xy 48.148094 -379.179216) (xy 48.171472 -379.236959) (xy 48.187273 -379.297217) (xy 48.195239 -379.359)
			(xy 48.195738 -379.390148) (xy 48.195239 -379.421296) (xy 48.187273 -379.483079) (xy 48.171472 -379.543337)
			(xy 48.148094 -379.60108) (xy 48.117525 -379.655359) (xy 48.114139 -379.659896) (xy 54.995316 -379.659896)
			(xy 54.999387 -379.604274) (xy 55.011513 -379.549837) (xy 55.031436 -379.497746) (xy 55.058732 -379.449111)
			(xy 55.092818 -379.404968) (xy 55.132967 -379.366259) (xy 55.178325 -379.333808) (xy 55.227925 -379.308307)
			(xy 55.280709 -379.2903) (xy 55.335552 -379.28017) (xy 55.391286 -379.278133) (xy 55.446723 -379.284233)
			(xy 55.50068 -379.298339) (xy 55.552009 -379.320151) (xy 55.599615 -379.349205) (xy 55.642483 -379.38488)
			(xy 55.6797 -379.426417) (xy 55.710473 -379.47293) (xy 55.734145 -379.523427) (xy 55.750213 -379.576834)
			(xy 55.758333 -379.63201) (xy 55.758842 -379.659896) (xy 55.758333 -379.687782) (xy 55.750213 -379.742958)
			(xy 55.734145 -379.796365) (xy 55.710473 -379.846862) (xy 55.6797 -379.893375) (xy 55.642483 -379.934912)
			(xy 55.599615 -379.970587) (xy 55.552009 -379.999641) (xy 55.50068 -380.021453) (xy 55.446723 -380.035559)
			(xy 55.391286 -380.041659) (xy 55.335552 -380.039622) (xy 55.280709 -380.029492) (xy 55.227925 -380.011485)
			(xy 55.178325 -379.985984) (xy 55.132967 -379.953533) (xy 55.092818 -379.914824) (xy 55.058732 -379.870681)
			(xy 55.031436 -379.822046) (xy 55.011513 -379.769955) (xy 54.999387 -379.715518) (xy 54.995316 -379.659896)
			(xy 48.114139 -379.659896) (xy 48.080265 -379.705283) (xy 48.036928 -379.750033) (xy 47.988223 -379.788873)
			(xy 47.934952 -379.821166) (xy 47.877989 -379.846383) (xy 47.818268 -379.864107) (xy 47.756771 -379.87405)
			(xy 47.694508 -379.876046) (xy 47.632501 -379.870064) (xy 47.571767 -379.856202) (xy 47.513305 -379.834688)
			(xy 47.458074 -379.805874) (xy 47.406982 -379.770234) (xy 47.360866 -379.728353) (xy 47.320484 -379.680918)
			(xy 47.2865 -379.628709) (xy 47.259471 -379.572583) (xy 47.239842 -379.513462) (xy 47.227933 -379.452315)
			(xy 47.223942 -379.390148) (xy 45.952413 -379.390148) (xy 45.971324 -379.436857) (xy 45.987125 -379.497115)
			(xy 45.995091 -379.558898) (xy 45.99559 -379.590046) (xy 45.995091 -379.621194) (xy 45.987125 -379.682977)
			(xy 45.971324 -379.743235) (xy 45.947946 -379.800978) (xy 45.917377 -379.855257) (xy 45.880117 -379.905181)
			(xy 45.83678 -379.949931) (xy 45.788075 -379.988771) (xy 45.734804 -380.021064) (xy 45.677841 -380.046281)
			(xy 45.61812 -380.064005) (xy 45.556623 -380.073948) (xy 45.49436 -380.075944) (xy 45.432353 -380.069962)
			(xy 45.371619 -380.0561) (xy 45.313157 -380.034586) (xy 45.257926 -380.005772) (xy 45.206834 -379.970132)
			(xy 45.160718 -379.928251) (xy 45.120336 -379.880816) (xy 45.086352 -379.828607) (xy 45.059323 -379.772481)
			(xy 45.039694 -379.71336) (xy 45.027785 -379.652213) (xy 45.023794 -379.590046) (xy 43.751954 -379.590046)
			(xy 43.742976 -379.610974) (xy 43.726608 -379.639322) (xy 43.723286 -379.645343) (xy 43.719685 -379.65861)
			(xy 43.719496 -379.665484) (xy 43.719496 -380.414784) (xy 43.719694 -380.421657) (xy 43.723298 -380.43492)
			(xy 43.726608 -380.440946) (xy 43.742993 -380.469285) (xy 43.76879 -380.529448) (xy 43.786274 -380.592531)
			(xy 43.795129 -380.65739) (xy 43.795696 -380.69012) (xy 47.223942 -380.69012) (xy 47.227933 -380.627953)
			(xy 47.239842 -380.566806) (xy 47.259471 -380.507685) (xy 47.2865 -380.451559) (xy 47.320484 -380.39935)
			(xy 47.360866 -380.351915) (xy 47.406982 -380.310034) (xy 47.458074 -380.274394) (xy 47.513305 -380.24558)
			(xy 47.571767 -380.224066) (xy 47.632501 -380.210204) (xy 47.694508 -380.204222) (xy 47.756771 -380.206218)
			(xy 47.818268 -380.216161) (xy 47.877989 -380.233885) (xy 47.934952 -380.259102) (xy 47.988223 -380.291395)
			(xy 48.036928 -380.330235) (xy 48.080265 -380.374985) (xy 48.117525 -380.424909) (xy 48.148094 -380.479188)
			(xy 48.171472 -380.536931) (xy 48.187273 -380.597189) (xy 48.188186 -380.604268) (xy 56.220104 -380.604268)
			(xy 56.224175 -380.548646) (xy 56.236301 -380.494209) (xy 56.256224 -380.442118) (xy 56.28352 -380.393483)
			(xy 56.317606 -380.34934) (xy 56.357755 -380.310631) (xy 56.403113 -380.27818) (xy 56.452713 -380.252679)
			(xy 56.505497 -380.234672) (xy 56.56034 -380.224542) (xy 56.616074 -380.222505) (xy 56.671511 -380.228605)
			(xy 56.725468 -380.242711) (xy 56.776797 -380.264523) (xy 56.824403 -380.293577) (xy 56.867271 -380.329252)
			(xy 56.904488 -380.370789) (xy 56.935261 -380.417302) (xy 56.958933 -380.467799) (xy 56.975001 -380.521206)
			(xy 56.983121 -380.576382) (xy 56.98363 -380.604268) (xy 56.983121 -380.632154) (xy 56.975001 -380.68733)
			(xy 56.958933 -380.740737) (xy 56.935261 -380.791234) (xy 56.904488 -380.837747) (xy 56.867271 -380.879284)
			(xy 56.824403 -380.914959) (xy 56.776797 -380.944013) (xy 56.725468 -380.965825) (xy 56.671511 -380.979931)
			(xy 56.616074 -380.986031) (xy 56.56034 -380.983994) (xy 56.505497 -380.973864) (xy 56.452713 -380.955857)
			(xy 56.403113 -380.930356) (xy 56.357755 -380.897905) (xy 56.317606 -380.859196) (xy 56.28352 -380.815053)
			(xy 56.256224 -380.766418) (xy 56.236301 -380.714327) (xy 56.224175 -380.65989) (xy 56.220104 -380.604268)
			(xy 48.188186 -380.604268) (xy 48.195239 -380.658972) (xy 48.195738 -380.69012) (xy 48.195239 -380.721268)
			(xy 48.187273 -380.783051) (xy 48.171472 -380.843309) (xy 48.148094 -380.901052) (xy 48.117525 -380.955331)
			(xy 48.080265 -381.005255) (xy 48.036928 -381.050005) (xy 47.988223 -381.088845) (xy 47.934952 -381.121138)
			(xy 47.877989 -381.146355) (xy 47.818268 -381.164079) (xy 47.756771 -381.174022) (xy 47.694508 -381.176018)
			(xy 47.632501 -381.170036) (xy 47.571767 -381.156174) (xy 47.513305 -381.13466) (xy 47.458074 -381.105846)
			(xy 47.406982 -381.070206) (xy 47.360866 -381.028325) (xy 47.320484 -380.98089) (xy 47.2865 -380.928681)
			(xy 47.259471 -380.872555) (xy 47.239842 -380.813434) (xy 47.227933 -380.752287) (xy 47.223942 -380.69012)
			(xy 43.795696 -380.69012) (xy 43.795117 -380.722849) (xy 43.786265 -380.787707) (xy 43.768779 -380.850787)
			(xy 43.742975 -380.910946) (xy 43.726608 -380.939294) (xy 43.723296 -380.94532) (xy 43.719688 -380.958583)
			(xy 43.719496 -380.965456) (xy 43.719496 -381.251206) (xy 43.718979 -381.261329) (xy 43.711256 -381.280043)
			(xy 43.69698 -381.294398) (xy 43.678308 -381.302223) (xy 43.668188 -381.302768) (xy 42.951908 -381.302768)
			(xy 42.94175 -381.302371) (xy 42.922992 -381.294572) (xy 42.908667 -381.280167) (xy 42.900973 -381.261366)
			(xy 42.9006 -381.251206) (xy 42.9006 -380.965456) (xy 42.900386 -380.958584) (xy 42.896793 -380.945322)
			(xy 42.893488 -380.939294) (xy 42.877119 -380.910947) (xy 42.851318 -380.850786) (xy 42.83383 -380.787706)
			(xy 42.82497 -380.722849) (xy 42.8244 -380.69012) (xy 39.395067 -380.69012) (xy 39.395066 -380.722836)
			(xy 39.386279 -380.787682) (xy 39.368867 -380.850762) (xy 39.343145 -380.910933) (xy 39.32682 -380.939294)
			(xy 39.323509 -380.94532) (xy 39.319901 -380.958583) (xy 39.319708 -380.965456) (xy 39.319708 -381.251206)
			(xy 39.319173 -381.261358) (xy 39.311405 -381.280119) (xy 39.297052 -381.294482) (xy 39.278298 -381.302265)
			(xy 39.268146 -381.302768) (xy 38.551866 -381.302768) (xy 38.541707 -381.302295) (xy 38.522938 -381.29451)
			(xy 38.508574 -381.280138) (xy 38.5008 -381.261365) (xy 38.500304 -381.251206) (xy 38.500304 -380.965456)
			(xy 38.50009 -380.958584) (xy 38.496497 -380.945322) (xy 38.493192 -380.939294) (xy 38.476888 -380.910923)
			(xy 38.451171 -380.850754) (xy 38.433763 -380.787677) (xy 38.424978 -380.722835) (xy 38.424976 -380.6574)
			(xy 34.995045 -380.6574) (xy 34.995612 -380.69012) (xy 34.995031 -380.722849) (xy 34.98618 -380.787707)
			(xy 34.968694 -380.850787) (xy 34.94289 -380.910945) (xy 34.926524 -380.939294) (xy 34.923213 -380.945321)
			(xy 34.919605 -380.958583) (xy 34.919412 -380.965456) (xy 34.919412 -381.251206) (xy 34.91888 -381.261327)
			(xy 34.91116 -381.280038) (xy 34.896888 -381.294392) (xy 34.878222 -381.30222) (xy 34.868104 -381.302768)
			(xy 34.151824 -381.302768) (xy 34.141667 -381.302358) (xy 34.122909 -381.294565) (xy 34.108584 -381.280164)
			(xy 34.100889 -381.261365) (xy 34.100516 -381.251206) (xy 34.100516 -380.965456) (xy 34.1003 -380.958585)
			(xy 34.096708 -380.945322) (xy 34.093404 -380.939294) (xy 34.077036 -380.910946) (xy 34.051235 -380.850786)
			(xy 34.033746 -380.787706) (xy 34.024886 -380.722849) (xy 34.024316 -380.69012) (xy 30.594981 -380.69012)
			(xy 30.59498 -380.722836) (xy 30.586194 -380.787682) (xy 30.568782 -380.850762) (xy 30.54306 -380.910933)
			(xy 30.526736 -380.939294) (xy 30.523426 -380.945321) (xy 30.519817 -380.958583) (xy 30.519624 -380.965456)
			(xy 30.519624 -381.251206) (xy 30.51924 -381.261383) (xy 30.511446 -381.280185) (xy 30.497048 -381.294571)
			(xy 30.478239 -381.302349) (xy 30.468062 -381.302768) (xy 29.751782 -381.302768) (xy 29.741624 -381.302282)
			(xy 29.722855 -381.294502) (xy 29.708491 -381.280135) (xy 29.700716 -381.261364) (xy 29.70022 -381.251206)
			(xy 29.70022 -380.965456) (xy 29.700004 -380.958585) (xy 29.696412 -380.945322) (xy 29.693108 -380.939294)
			(xy 29.676804 -380.910923) (xy 29.651086 -380.850754) (xy 29.633677 -380.787677) (xy 29.624892 -380.722835)
			(xy 29.62489 -380.6574) (xy 27.854656 -380.6574) (xy 27.854656 -381.526796) (xy 27.855143 -381.536807)
			(xy 27.8628 -381.555308) (xy 27.876952 -381.569473) (xy 27.895445 -381.577148) (xy 27.905456 -381.577596)
			(xy 28.268168 -381.577596) (xy 28.278293 -381.578014) (xy 28.297006 -381.585755) (xy 28.311329 -381.600071)
			(xy 28.31908 -381.618779) (xy 28.319476 -381.628904) (xy 28.319476 -381.910082) (xy 28.321 -381.92202)
			(xy 28.325064 -381.93726) (xy 28.328874 -381.94361) (xy 28.344799 -381.971729) (xy 28.369891 -382.031279)
			(xy 28.38687 -382.09363) (xy 28.395436 -382.157681) (xy 28.395437 -382.222302) (xy 28.395382 -382.22271)
			(xy 31.825016 -382.22271) (xy 31.825018 -382.157273) (xy 31.833803 -382.092427) (xy 31.851213 -382.029348)
			(xy 31.876933 -381.969177) (xy 31.893256 -381.940816) (xy 31.896561 -381.934787) (xy 31.900173 -381.921527)
			(xy 31.900368 -381.914654) (xy 31.900368 -381.628904) (xy 31.900824 -381.618754) (xy 31.908613 -381.600008)
			(xy 31.922998 -381.585686) (xy 31.941778 -381.57798) (xy 31.95193 -381.577596) (xy 32.66821 -381.577596)
			(xy 32.678332 -381.578117) (xy 32.697045 -381.58584) (xy 32.711399 -381.600115) (xy 32.719226 -381.618785)
			(xy 32.719772 -381.628904) (xy 32.719772 -381.914654) (xy 32.719985 -381.921526) (xy 32.723579 -381.934788)
			(xy 32.726884 -381.940816) (xy 32.743197 -381.969182) (xy 32.768914 -382.029352) (xy 32.786322 -382.09243)
			(xy 32.795107 -382.157274) (xy 32.795108 -382.222709) (xy 32.786326 -382.287553) (xy 32.76892 -382.350631)
			(xy 32.743205 -382.410803) (xy 32.726884 -382.439164) (xy 32.723581 -382.445194) (xy 32.719968 -382.458454)
			(xy 32.719772 -382.465326) (xy 32.719772 -383.21488) (xy 32.719975 -383.221752) (xy 32.723576 -383.235015)
			(xy 32.726884 -383.241042) (xy 32.743219 -383.269396) (xy 32.768934 -383.329569) (xy 32.78634 -383.392649)
			(xy 32.795121 -383.457495) (xy 32.79512 -383.522932) (xy 32.786334 -383.587778) (xy 32.768925 -383.650857)
			(xy 32.743207 -383.711028) (xy 32.726884 -383.73939) (xy 32.723572 -383.745416) (xy 32.719965 -383.758679)
			(xy 32.719772 -383.765552) (xy 32.719772 -384.051556) (xy 32.719342 -384.061711) (xy 32.711555 -384.080468)
			(xy 32.697161 -384.094793) (xy 32.678367 -384.10249) (xy 32.66821 -384.102864) (xy 31.95193 -384.102864)
			(xy 31.941806 -384.102349) (xy 31.923086 -384.094632) (xy 31.908729 -384.080354) (xy 31.900908 -384.061678)
			(xy 31.900368 -384.051556) (xy 31.900368 -383.765552) (xy 31.90016 -383.75868) (xy 31.896563 -383.745417)
			(xy 31.893256 -383.73939) (xy 31.876947 -383.711021) (xy 31.851227 -383.650852) (xy 31.833817 -383.587775)
			(xy 31.825031 -383.522932) (xy 31.825029 -383.457496) (xy 31.833811 -383.392652) (xy 31.851218 -383.329574)
			(xy 31.876934 -383.269403) (xy 31.893256 -383.241042) (xy 31.896552 -383.235008) (xy 31.90017 -383.221752)
			(xy 31.900368 -383.21488) (xy 31.900368 -382.465326) (xy 31.90017 -382.458453) (xy 31.896566 -382.44519)
			(xy 31.893256 -382.439164) (xy 31.876925 -382.410808) (xy 31.851207 -382.350635) (xy 31.833799 -382.287556)
			(xy 31.825016 -382.22271) (xy 28.395382 -382.22271) (xy 28.386874 -382.286353) (xy 28.369897 -382.348705)
			(xy 28.344807 -382.408256) (xy 28.328874 -382.43637) (xy 28.325064 -382.44272) (xy 28.321 -382.45796)
			(xy 28.319476 -382.469898) (xy 28.319476 -383.210308) (xy 28.321 -383.222246) (xy 28.325064 -383.237486)
			(xy 28.328874 -383.243836) (xy 28.344797 -383.271955) (xy 28.366214 -383.322789) (xy 29.62486 -383.322789)
			(xy 29.624864 -383.25735) (xy 29.633652 -383.192504) (xy 29.651064 -383.129424) (xy 29.676784 -383.069252)
			(xy 29.693108 -383.04089) (xy 29.696427 -383.034867) (xy 29.70003 -383.021602) (xy 29.70022 -383.014728)
			(xy 29.70022 -382.728724) (xy 29.700641 -382.718569) (xy 29.708433 -382.699813) (xy 29.72283 -382.685488)
			(xy 29.741625 -382.677791) (xy 29.751782 -382.677416) (xy 30.468062 -382.677416) (xy 30.478183 -382.677957)
			(xy 30.496899 -382.685668) (xy 30.511256 -382.699938) (xy 30.51908 -382.718606) (xy 30.519624 -382.728724)
			(xy 30.519624 -383.014728) (xy 30.519802 -383.021602) (xy 30.523419 -383.034865) (xy 30.526736 -383.04089)
			(xy 30.543029 -383.069268) (xy 30.56875 -383.129435) (xy 30.586163 -383.19251) (xy 30.59495 -383.257352)
			(xy 30.594955 -383.322786) (xy 30.586175 -383.387629) (xy 30.568771 -383.450707) (xy 30.543057 -383.510877)
			(xy 30.526736 -383.539238) (xy 30.523411 -383.545258) (xy 30.519811 -383.558525) (xy 30.519624 -383.5654)
			(xy 30.519624 -384.3147) (xy 30.519813 -384.321573) (xy 30.523423 -384.334836) (xy 30.526736 -384.340862)
			(xy 30.54309 -384.369206) (xy 30.568806 -384.429381) (xy 30.586211 -384.492463) (xy 30.594991 -384.557311)
			(xy 30.594989 -384.590036) (xy 34.024316 -384.590036) (xy 34.024873 -384.557306) (xy 34.033731 -384.492448)
			(xy 34.051224 -384.429367) (xy 34.077034 -384.36921) (xy 34.093404 -384.340862) (xy 34.096733 -384.334844)
			(xy 34.100329 -384.321575) (xy 34.100516 -384.3147) (xy 34.100516 -383.5654) (xy 34.100322 -383.558527)
			(xy 34.096715 -383.545264) (xy 34.093404 -383.539238) (xy 34.077054 -383.51088) (xy 34.051248 -383.450724)
			(xy 34.033754 -383.387647) (xy 34.024889 -383.322792) (xy 34.024316 -383.290064) (xy 34.024886 -383.257335)
			(xy 34.03374 -383.192476) (xy 34.051229 -383.129396) (xy 34.077036 -383.069238) (xy 34.093404 -383.04089)
			(xy 34.096723 -383.034867) (xy 34.100326 -383.021602) (xy 34.100516 -383.014728) (xy 34.100516 -382.728724)
			(xy 34.100936 -382.718601) (xy 34.108679 -382.699895) (xy 34.122995 -382.685579) (xy 34.141701 -382.677836)
			(xy 34.151824 -382.677416) (xy 34.868104 -382.677416) (xy 34.878229 -382.677813) (xy 34.896935 -382.685566)
			(xy 34.91125 -382.699888) (xy 34.918992 -382.718599) (xy 34.919412 -382.728724) (xy 34.919412 -383.014728)
			(xy 34.919592 -383.021602) (xy 34.923208 -383.034865) (xy 34.926524 -383.04089) (xy 34.942888 -383.06924)
			(xy 34.96869 -383.1294) (xy 34.98618 -383.192479) (xy 34.995041 -383.257335) (xy 34.995612 -383.290064)
			(xy 34.995051 -383.322794) (xy 34.986193 -383.387652) (xy 34.968702 -383.450732) (xy 34.951763 -383.490216)
			(xy 36.224464 -383.490216) (xy 36.225019 -383.457486) (xy 36.233879 -383.392628) (xy 36.251372 -383.329548)
			(xy 36.277182 -383.26939) (xy 36.293552 -383.241042) (xy 36.296848 -383.235008) (xy 36.300466 -383.221752)
			(xy 36.300664 -383.21488) (xy 36.300664 -382.465326) (xy 36.300467 -382.458453) (xy 36.296863 -382.44519)
			(xy 36.293552 -382.439164) (xy 36.277177 -382.41082) (xy 36.251376 -382.350659) (xy 36.233889 -382.287578)
			(xy 36.225032 -382.22272) (xy 36.224464 -382.18999) (xy 36.225053 -382.157261) (xy 36.233903 -382.092404)
			(xy 36.251386 -382.029324) (xy 36.277187 -381.969165) (xy 36.293552 -381.940816) (xy 36.296857 -381.934787)
			(xy 36.300469 -381.921527) (xy 36.300664 -381.914654) (xy 36.300664 -381.628904) (xy 36.301188 -381.6188)
			(xy 36.308917 -381.600129) (xy 36.323202 -381.585835) (xy 36.341868 -381.578094) (xy 36.351972 -381.577596)
			(xy 37.068252 -381.577596) (xy 37.078371 -381.578055) (xy 37.097073 -381.585787) (xy 37.111388 -381.60009)
			(xy 37.119136 -381.618786) (xy 37.11956 -381.628904) (xy 37.11956 -381.914654) (xy 37.119774 -381.921526)
			(xy 37.123368 -381.934788) (xy 37.126672 -381.940816) (xy 37.143041 -381.969163) (xy 37.168843 -382.029323)
			(xy 37.186332 -382.092403) (xy 37.195191 -382.157261) (xy 37.19576 -382.18999) (xy 37.195204 -382.22272)
			(xy 37.186344 -382.287578) (xy 37.168851 -382.350658) (xy 37.143041 -382.410816) (xy 37.126672 -382.439164)
			(xy 37.123368 -382.445194) (xy 37.119756 -382.458454) (xy 37.11956 -382.465326) (xy 37.11956 -383.21488)
			(xy 37.119765 -383.221752) (xy 37.123365 -383.235015) (xy 37.126672 -383.241042) (xy 37.143052 -383.269384)
			(xy 37.165953 -383.322788) (xy 38.424947 -383.322788) (xy 38.424951 -383.25735) (xy 38.433738 -383.192504)
			(xy 38.451149 -383.129424) (xy 38.476869 -383.069252) (xy 38.493192 -383.04089) (xy 38.49651 -383.034867)
			(xy 38.500114 -383.021602) (xy 38.500304 -383.014728) (xy 38.500304 -382.728724) (xy 38.500741 -382.718571)
			(xy 38.50853 -382.699818) (xy 38.522922 -382.685494) (xy 38.541711 -382.677794) (xy 38.551866 -382.677416)
			(xy 39.268146 -382.677416) (xy 39.278273 -382.677888) (xy 39.29699 -382.685627) (xy 39.311344 -382.699917)
			(xy 39.319166 -382.7186) (xy 39.319708 -382.728724) (xy 39.319708 -383.014728) (xy 39.319888 -383.021602)
			(xy 39.323504 -383.034865) (xy 39.32682 -383.04089) (xy 39.343113 -383.069268) (xy 39.368836 -383.129435)
			(xy 39.386249 -383.19251) (xy 39.395037 -383.257352) (xy 39.395041 -383.322787) (xy 39.386261 -383.38763)
			(xy 39.368856 -383.450707) (xy 39.351971 -383.490216) (xy 40.624252 -383.490216) (xy 40.624809 -383.457486)
			(xy 40.633668 -383.392628) (xy 40.651161 -383.329548) (xy 40.676971 -383.26939) (xy 40.69334 -383.241042)
			(xy 40.696635 -383.235008) (xy 40.700254 -383.221752) (xy 40.700452 -383.21488) (xy 40.700452 -382.465326)
			(xy 40.700256 -382.458453) (xy 40.696651 -382.44519) (xy 40.69334 -382.439164) (xy 40.676964 -382.41082)
			(xy 40.651164 -382.350659) (xy 40.633677 -382.287578) (xy 40.62482 -382.22272) (xy 40.624252 -382.18999)
			(xy 40.624842 -382.157261) (xy 40.633691 -382.092404) (xy 40.651175 -382.029324) (xy 40.676975 -381.969165)
			(xy 40.69334 -381.940816) (xy 40.696644 -381.934786) (xy 40.700257 -381.921527) (xy 40.700452 -381.914654)
			(xy 40.700452 -381.628904) (xy 40.700987 -381.618801) (xy 40.708715 -381.600133) (xy 40.722996 -381.585839)
			(xy 40.741658 -381.578096) (xy 40.75176 -381.577596) (xy 41.46804 -381.577596) (xy 41.478151 -381.578052)
			(xy 41.496829 -381.585802) (xy 41.511122 -381.600108) (xy 41.518856 -381.618793) (xy 41.519348 -381.628904)
			(xy 41.519348 -381.914654) (xy 41.519551 -381.921526) (xy 41.523151 -381.93479) (xy 41.52646 -381.940816)
			(xy 41.542828 -381.969164) (xy 41.56863 -382.029324) (xy 41.586119 -382.092404) (xy 41.594979 -382.157261)
			(xy 41.595548 -382.18999) (xy 41.594994 -382.22271) (xy 45.024892 -382.22271) (xy 45.024893 -382.157273)
			(xy 45.033678 -382.092428) (xy 45.051087 -382.029349) (xy 45.076805 -381.969177) (xy 45.093128 -381.940816)
			(xy 45.096439 -381.93479) (xy 45.100047 -381.921527) (xy 45.10024 -381.914654) (xy 45.10024 -381.628904)
			(xy 45.100626 -381.618745) (xy 45.108427 -381.599985) (xy 45.122836 -381.58566) (xy 45.141641 -381.577968)
			(xy 45.151802 -381.577596) (xy 45.868082 -381.577596) (xy 45.878202 -381.57814) (xy 45.896915 -381.585854)
			(xy 45.91127 -381.600122) (xy 45.919098 -381.618787) (xy 45.919178 -381.620268) (xy 57.056272 -381.620268)
			(xy 57.060343 -381.564646) (xy 57.072469 -381.510209) (xy 57.092392 -381.458118) (xy 57.119688 -381.409483)
			(xy 57.153774 -381.36534) (xy 57.193923 -381.326631) (xy 57.239281 -381.29418) (xy 57.288881 -381.268679)
			(xy 57.341665 -381.250672) (xy 57.396508 -381.240542) (xy 57.452242 -381.238505) (xy 57.507679 -381.244605)
			(xy 57.561636 -381.258711) (xy 57.612965 -381.280523) (xy 57.660571 -381.309577) (xy 57.703439 -381.345252)
			(xy 57.740656 -381.386789) (xy 57.771429 -381.433302) (xy 57.795101 -381.483799) (xy 57.811169 -381.537206)
			(xy 57.819289 -381.592382) (xy 57.819798 -381.620268) (xy 57.819289 -381.648154) (xy 57.811169 -381.70333)
			(xy 57.795101 -381.756737) (xy 57.771429 -381.807234) (xy 57.740656 -381.853747) (xy 57.703439 -381.895284)
			(xy 57.660571 -381.930959) (xy 57.612965 -381.960013) (xy 57.561636 -381.981825) (xy 57.507679 -381.995931)
			(xy 57.452242 -382.002031) (xy 57.396508 -381.999994) (xy 57.341665 -381.989864) (xy 57.288881 -381.971857)
			(xy 57.239281 -381.946356) (xy 57.193923 -381.913905) (xy 57.153774 -381.875196) (xy 57.119688 -381.831053)
			(xy 57.092392 -381.782418) (xy 57.072469 -381.730327) (xy 57.060343 -381.67589) (xy 57.056272 -381.620268)
			(xy 45.919178 -381.620268) (xy 45.919644 -381.628904) (xy 45.919644 -381.914654) (xy 45.919848 -381.921526)
			(xy 45.923447 -381.934789) (xy 45.926756 -381.940816) (xy 45.94307 -381.969182) (xy 45.968789 -382.029352)
			(xy 45.986198 -382.09243) (xy 45.994982 -382.157273) (xy 45.994984 -382.222709) (xy 45.986996 -382.281684)
			(xy 58.230514 -382.281684) (xy 58.234585 -382.226062) (xy 58.246711 -382.171625) (xy 58.266634 -382.119534)
			(xy 58.29393 -382.070899) (xy 58.328016 -382.026756) (xy 58.368165 -381.988047) (xy 58.413523 -381.955596)
			(xy 58.463123 -381.930095) (xy 58.515907 -381.912088) (xy 58.57075 -381.901958) (xy 58.626484 -381.899921)
			(xy 58.681921 -381.906021) (xy 58.735878 -381.920127) (xy 58.787207 -381.941939) (xy 58.834813 -381.970993)
			(xy 58.877681 -382.006668) (xy 58.914898 -382.048205) (xy 58.945671 -382.094718) (xy 58.969343 -382.145215)
			(xy 58.985411 -382.198622) (xy 58.993531 -382.253798) (xy 58.99404 -382.281684) (xy 58.993531 -382.30957)
			(xy 58.985411 -382.364746) (xy 58.969343 -382.418153) (xy 58.945671 -382.46865) (xy 58.914898 -382.515163)
			(xy 58.877681 -382.5567) (xy 58.834813 -382.592375) (xy 58.787207 -382.621429) (xy 58.735878 -382.643241)
			(xy 58.681921 -382.657347) (xy 58.626484 -382.663447) (xy 58.57075 -382.66141) (xy 58.515907 -382.65128)
			(xy 58.463123 -382.633273) (xy 58.413523 -382.607772) (xy 58.368165 -382.575321) (xy 58.328016 -382.536612)
			(xy 58.29393 -382.492469) (xy 58.266634 -382.443834) (xy 58.246711 -382.391743) (xy 58.234585 -382.337306)
			(xy 58.230514 -382.281684) (xy 45.986996 -382.281684) (xy 45.986201 -382.287554) (xy 45.968794 -382.350632)
			(xy 45.943078 -382.410803) (xy 45.926756 -382.439164) (xy 45.923458 -382.445197) (xy 45.919841 -382.458454)
			(xy 45.919644 -382.465326) (xy 45.919644 -383.21488) (xy 45.919838 -383.221753) (xy 45.923444 -383.235016)
			(xy 45.926756 -383.241042) (xy 45.943092 -383.269396) (xy 45.965911 -383.322789) (xy 47.225019 -383.322789)
			(xy 47.225023 -383.257349) (xy 47.233812 -383.192502) (xy 47.251226 -383.129422) (xy 47.27695 -383.069251)
			(xy 47.293276 -383.04089) (xy 47.296593 -383.034866) (xy 47.300198 -383.021602) (xy 47.300388 -383.014728)
			(xy 47.300388 -382.728724) (xy 47.300841 -382.718573) (xy 47.308626 -382.699823) (xy 47.323013 -382.685499)
			(xy 47.341797 -382.677797) (xy 47.35195 -382.677416) (xy 48.06823 -382.677416) (xy 48.078356 -382.677901)
			(xy 48.097073 -382.685634) (xy 48.111427 -382.699921) (xy 48.11925 -382.718601) (xy 48.119792 -382.728724)
			(xy 48.119792 -383.014728) (xy 48.119974 -383.021602) (xy 48.123589 -383.034865) (xy 48.126904 -383.04089)
			(xy 48.143194 -383.069269) (xy 48.168913 -383.129436) (xy 48.186322 -383.192511) (xy 48.195109 -383.257352)
			(xy 48.195113 -383.322786) (xy 48.186335 -383.387628) (xy 48.168933 -383.450705) (xy 48.143222 -383.510876)
			(xy 48.126904 -383.539238) (xy 48.123576 -383.545256) (xy 48.119979 -383.558525) (xy 48.119792 -383.5654)
			(xy 48.119792 -384.024886) (xy 59.976764 -384.024886) (xy 59.980835 -383.969264) (xy 59.992961 -383.914827)
			(xy 60.012884 -383.862736) (xy 60.04018 -383.814101) (xy 60.074266 -383.769958) (xy 60.114415 -383.731249)
			(xy 60.159773 -383.698798) (xy 60.209373 -383.673297) (xy 60.262157 -383.65529) (xy 60.317 -383.64516)
			(xy 60.372734 -383.643123) (xy 60.428171 -383.649223) (xy 60.482128 -383.663329) (xy 60.533457 -383.685141)
			(xy 60.581063 -383.714195) (xy 60.623931 -383.74987) (xy 60.661148 -383.791407) (xy 60.691921 -383.83792)
			(xy 60.715593 -383.888417) (xy 60.731661 -383.941824) (xy 60.739781 -383.997) (xy 60.74029 -384.024886)
			(xy 60.739781 -384.052772) (xy 60.731661 -384.107948) (xy 60.715593 -384.161355) (xy 60.691921 -384.211852)
			(xy 60.661148 -384.258365) (xy 60.623931 -384.299902) (xy 60.581063 -384.335577) (xy 60.533457 -384.364631)
			(xy 60.482128 -384.386443) (xy 60.428171 -384.400549) (xy 60.372734 -384.406649) (xy 60.317 -384.404612)
			(xy 60.262157 -384.394482) (xy 60.209373 -384.376475) (xy 60.159773 -384.350974) (xy 60.114415 -384.318523)
			(xy 60.074266 -384.279814) (xy 60.04018 -384.235671) (xy 60.012884 -384.187036) (xy 59.992961 -384.134945)
			(xy 59.980835 -384.080508) (xy 59.976764 -384.024886) (xy 48.119792 -384.024886) (xy 48.119792 -384.3147)
			(xy 48.119985 -384.321573) (xy 48.123592 -384.334836) (xy 48.126904 -384.340862) (xy 48.143255 -384.369207)
			(xy 48.168968 -384.429382) (xy 48.186371 -384.492464) (xy 48.19515 -384.557312) (xy 48.195146 -384.62275)
			(xy 48.186359 -384.687596) (xy 48.182159 -384.702812) (xy 57.268616 -384.702812) (xy 57.272687 -384.64719)
			(xy 57.284813 -384.592753) (xy 57.304736 -384.540662) (xy 57.332032 -384.492027) (xy 57.366118 -384.447884)
			(xy 57.406267 -384.409175) (xy 57.451625 -384.376724) (xy 57.501225 -384.351223) (xy 57.554009 -384.333216)
			(xy 57.608852 -384.323086) (xy 57.664586 -384.321049) (xy 57.720023 -384.327149) (xy 57.77398 -384.341255)
			(xy 57.825309 -384.363067) (xy 57.872915 -384.392121) (xy 57.915783 -384.427796) (xy 57.953 -384.469333)
			(xy 57.983773 -384.515846) (xy 58.007445 -384.566343) (xy 58.023513 -384.61975) (xy 58.031633 -384.674926)
			(xy 58.032142 -384.702812) (xy 58.031633 -384.730698) (xy 58.023513 -384.785874) (xy 58.007445 -384.839281)
			(xy 57.983773 -384.889778) (xy 57.953 -384.936291) (xy 57.915783 -384.977828) (xy 57.872915 -385.013503)
			(xy 57.825309 -385.042557) (xy 57.77398 -385.064369) (xy 57.720023 -385.078475) (xy 57.664586 -385.084575)
			(xy 57.608852 -385.082538) (xy 57.554009 -385.072408) (xy 57.501225 -385.054401) (xy 57.451625 -385.0289)
			(xy 57.406267 -384.996449) (xy 57.366118 -384.95774) (xy 57.332032 -384.913597) (xy 57.304736 -384.864962)
			(xy 57.284813 -384.812871) (xy 57.272687 -384.758434) (xy 57.268616 -384.702812) (xy 48.182159 -384.702812)
			(xy 48.168947 -384.750676) (xy 48.143227 -384.810848) (xy 48.126904 -384.83921) (xy 48.123586 -384.845233)
			(xy 48.119982 -384.858498) (xy 48.119792 -384.865372) (xy 48.119792 -385.151376) (xy 48.119359 -385.16153)
			(xy 48.11157 -385.180283) (xy 48.097176 -385.194608) (xy 48.078386 -385.202307) (xy 48.06823 -385.202684)
			(xy 47.35195 -385.202684) (xy 47.341829 -385.202133) (xy 47.323114 -385.194426) (xy 47.308757 -385.18016)
			(xy 47.300932 -385.161493) (xy 47.300388 -385.151376) (xy 47.300388 -384.865372) (xy 47.300208 -384.858498)
			(xy 47.296592 -384.845235) (xy 47.293276 -384.83921) (xy 47.276983 -384.810832) (xy 47.251261 -384.750665)
			(xy 47.233848 -384.68759) (xy 47.22506 -384.622748) (xy 47.225056 -384.557314) (xy 47.233835 -384.492471)
			(xy 47.25124 -384.429393) (xy 47.276955 -384.369223) (xy 47.293276 -384.340862) (xy 47.296603 -384.334843)
			(xy 47.300201 -384.321575) (xy 47.300388 -384.3147) (xy 47.300388 -383.5654) (xy 47.300197 -383.558527)
			(xy 47.296588 -383.545264) (xy 47.293276 -383.539238) (xy 47.276922 -383.510894) (xy 47.251205 -383.450719)
			(xy 47.233799 -383.387637) (xy 47.225019 -383.322789) (xy 45.965911 -383.322789) (xy 45.968809 -383.329569)
			(xy 45.986215 -383.392649) (xy 45.994997 -383.457495) (xy 45.994995 -383.522933) (xy 45.98621 -383.587778)
			(xy 45.968799 -383.650857) (xy 45.943079 -383.711029) (xy 45.926756 -383.73939) (xy 45.923449 -383.745419)
			(xy 45.919838 -383.758679) (xy 45.919644 -383.765552) (xy 45.919644 -384.051556) (xy 45.919143 -384.061702)
			(xy 45.91137 -384.080445) (xy 45.896998 -384.094768) (xy 45.878229 -384.102477) (xy 45.868082 -384.102864)
			(xy 45.151802 -384.102864) (xy 45.141676 -384.102372) (xy 45.122956 -384.094645) (xy 45.108599 -384.080361)
			(xy 45.100779 -384.06168) (xy 45.10024 -384.051556) (xy 45.10024 -383.765552) (xy 45.100023 -383.758681)
			(xy 45.096431 -383.745418) (xy 45.093128 -383.73939) (xy 45.07682 -383.711021) (xy 45.051101 -383.650852)
			(xy 45.033692 -383.587775) (xy 45.024907 -383.522931) (xy 45.024905 -383.457496) (xy 45.033687 -383.392652)
			(xy 45.051092 -383.329574) (xy 45.076807 -383.269403) (xy 45.093128 -383.241042) (xy 45.09643 -383.235011)
			(xy 45.100043 -383.221752) (xy 45.10024 -383.21488) (xy 45.10024 -382.465326) (xy 45.100033 -382.458454)
			(xy 45.096435 -382.445191) (xy 45.093128 -382.439164) (xy 45.076798 -382.410807) (xy 45.051081 -382.350635)
			(xy 45.033675 -382.287555) (xy 45.024892 -382.22271) (xy 41.594994 -382.22271) (xy 41.594994 -382.22272)
			(xy 41.586134 -382.287578) (xy 41.56864 -382.350658) (xy 41.54283 -382.410816) (xy 41.52646 -382.439164)
			(xy 41.523163 -382.445197) (xy 41.519545 -382.458454) (xy 41.519348 -382.465326) (xy 41.519348 -383.21488)
			(xy 41.519542 -383.221753) (xy 41.523148 -383.235016) (xy 41.52646 -383.241042) (xy 41.542838 -383.269384)
			(xy 41.568638 -383.329546) (xy 41.586124 -383.392628) (xy 41.59498 -383.457486) (xy 41.595548 -383.490216)
			(xy 41.594961 -383.522945) (xy 41.58611 -383.587802) (xy 41.568626 -383.650882) (xy 41.542825 -383.711041)
			(xy 41.52646 -383.73939) (xy 41.523154 -383.745419) (xy 41.519542 -383.758679) (xy 41.519348 -383.765552)
			(xy 41.519348 -384.051556) (xy 41.518849 -384.06167) (xy 41.511124 -384.080363) (xy 41.496834 -384.094677)
			(xy 41.478153 -384.102432) (xy 41.46804 -384.102864) (xy 40.75176 -384.102864) (xy 40.74163 -384.102516)
			(xy 40.722919 -384.094748) (xy 40.708605 -384.08041) (xy 40.700868 -384.061686) (xy 40.700452 -384.051556)
			(xy 40.700452 -383.765552) (xy 40.700246 -383.75868) (xy 40.696648 -383.745417) (xy 40.69334 -383.73939)
			(xy 40.676974 -383.711041) (xy 40.651172 -383.650882) (xy 40.633682 -383.587802) (xy 40.624822 -383.522945)
			(xy 40.624252 -383.490216) (xy 39.351971 -383.490216) (xy 39.343141 -383.510877) (xy 39.32682 -383.539238)
			(xy 39.323493 -383.545257) (xy 39.319895 -383.558525) (xy 39.319708 -383.5654) (xy 39.319708 -384.3147)
			(xy 39.319899 -384.321573) (xy 39.323508 -384.334836) (xy 39.32682 -384.340862) (xy 39.343174 -384.369206)
			(xy 39.368891 -384.429381) (xy 39.386297 -384.492463) (xy 39.395078 -384.557311) (xy 39.395076 -384.590036)
			(xy 42.8244 -384.590036) (xy 42.82496 -384.557306) (xy 42.833817 -384.492448) (xy 42.851309 -384.429368)
			(xy 42.877119 -384.36921) (xy 42.893488 -384.340862) (xy 42.896815 -384.334844) (xy 42.900413 -384.321575)
			(xy 42.9006 -384.3147) (xy 42.9006 -383.5654) (xy 42.900408 -383.558527) (xy 42.8968 -383.545264)
			(xy 42.893488 -383.539238) (xy 42.877136 -383.510881) (xy 42.851331 -383.450724) (xy 42.833838 -383.387647)
			(xy 42.824973 -383.322792) (xy 42.8244 -383.290064) (xy 42.824972 -383.257335) (xy 42.833826 -383.192477)
			(xy 42.851315 -383.129397) (xy 42.87712 -383.069238) (xy 42.893488 -383.04089) (xy 42.896805 -383.034867)
			(xy 42.90041 -383.021602) (xy 42.9006 -383.014728) (xy 42.9006 -382.728724) (xy 42.901035 -382.718603)
			(xy 42.908776 -382.6999) (xy 42.923086 -382.685585) (xy 42.941787 -382.677839) (xy 42.951908 -382.677416)
			(xy 43.668188 -382.677416) (xy 43.678312 -382.677826) (xy 43.697018 -382.685573) (xy 43.711333 -382.699892)
			(xy 43.719076 -382.7186) (xy 43.719496 -382.728724) (xy 43.719496 -383.014728) (xy 43.719678 -383.021602)
			(xy 43.723293 -383.034865) (xy 43.726608 -383.04089) (xy 43.74297 -383.069241) (xy 43.768773 -383.1294)
			(xy 43.786263 -383.192479) (xy 43.795125 -383.257335) (xy 43.795696 -383.290064) (xy 43.795137 -383.322794)
			(xy 43.786279 -383.387652) (xy 43.768787 -383.450732) (xy 43.742977 -383.51089) (xy 43.726608 -383.539238)
			(xy 43.72328 -383.545256) (xy 43.719683 -383.558525) (xy 43.719496 -383.5654) (xy 43.719496 -384.3147)
			(xy 43.719688 -384.321573) (xy 43.723296 -384.334836) (xy 43.726608 -384.340862) (xy 43.742959 -384.369219)
			(xy 43.768764 -384.429376) (xy 43.786258 -384.492453) (xy 43.795123 -384.557308) (xy 43.795696 -384.590036)
			(xy 43.795124 -384.622765) (xy 43.78627 -384.687623) (xy 43.768782 -384.750704) (xy 43.742976 -384.810862)
			(xy 43.726608 -384.83921) (xy 43.72329 -384.845233) (xy 43.719686 -384.858498) (xy 43.719496 -384.865372)
			(xy 43.719496 -385.151376) (xy 43.719064 -385.161497) (xy 43.711323 -385.180201) (xy 43.697011 -385.194517)
			(xy 43.678309 -385.202262) (xy 43.668188 -385.202684) (xy 42.951908 -385.202684) (xy 42.941784 -385.202277)
			(xy 42.923078 -385.194529) (xy 42.908762 -385.180209) (xy 42.90102 -385.1615) (xy 42.9006 -385.151376)
			(xy 42.9006 -384.865372) (xy 42.900419 -384.858498) (xy 42.896803 -384.845235) (xy 42.893488 -384.83921)
			(xy 42.877125 -384.810859) (xy 42.851323 -384.7507) (xy 42.833833 -384.687621) (xy 42.824971 -384.622765)
			(xy 42.8244 -384.590036) (xy 39.395076 -384.590036) (xy 39.395074 -384.622751) (xy 39.386285 -384.687598)
			(xy 39.36887 -384.750678) (xy 39.343146 -384.810849) (xy 39.32682 -384.83921) (xy 39.323503 -384.845234)
			(xy 39.319898 -384.858498) (xy 39.319708 -384.865372) (xy 39.319708 -385.151376) (xy 39.319259 -385.161528)
			(xy 39.311473 -385.180278) (xy 39.297085 -385.194602) (xy 39.278299 -385.202304) (xy 39.268146 -385.202684)
			(xy 38.551866 -385.202684) (xy 38.54174 -385.202202) (xy 38.523023 -385.194468) (xy 38.508668 -385.18018)
			(xy 38.500846 -385.1615) (xy 38.500304 -385.151376) (xy 38.500304 -384.865372) (xy 38.500122 -384.858498)
			(xy 38.496507 -384.845235) (xy 38.493192 -384.83921) (xy 38.476902 -384.810831) (xy 38.451184 -384.750664)
			(xy 38.433774 -384.687589) (xy 38.424988 -384.622748) (xy 38.424983 -384.557314) (xy 38.433762 -384.492472)
			(xy 38.451163 -384.429395) (xy 38.476874 -384.369224) (xy 38.493192 -384.340862) (xy 38.49652 -384.334844)
			(xy 38.500117 -384.321575) (xy 38.500304 -384.3147) (xy 38.500304 -383.5654) (xy 38.500112 -383.558527)
			(xy 38.496504 -383.545264) (xy 38.493192 -383.539238) (xy 38.476841 -383.510893) (xy 38.451128 -383.450718)
			(xy 38.433725 -383.387636) (xy 38.424947 -383.322788) (xy 37.165953 -383.322788) (xy 37.168851 -383.329546)
			(xy 37.186337 -383.392628) (xy 37.195192 -383.457486) (xy 37.19576 -383.490216) (xy 37.195171 -383.522945)
			(xy 37.186321 -383.587802) (xy 37.168837 -383.650882) (xy 37.143037 -383.711041) (xy 37.126672 -383.73939)
			(xy 37.123359 -383.745415) (xy 37.119753 -383.758679) (xy 37.11956 -383.765552) (xy 37.11956 -384.051556)
			(xy 37.119147 -384.061681) (xy 37.111406 -384.080391) (xy 37.097087 -384.094708) (xy 37.078377 -384.102448)
			(xy 37.068252 -384.102864) (xy 36.351972 -384.102864) (xy 36.341843 -384.102506) (xy 36.323132 -384.094742)
			(xy 36.308817 -384.080407) (xy 36.30108 -384.061685) (xy 36.300664 -384.051556) (xy 36.300664 -383.765552)
			(xy 36.300457 -383.75868) (xy 36.296859 -383.745417) (xy 36.293552 -383.73939) (xy 36.277187 -383.71104)
			(xy 36.251384 -383.650881) (xy 36.233894 -383.587802) (xy 36.225034 -383.522945) (xy 36.224464 -383.490216)
			(xy 34.951763 -383.490216) (xy 34.942893 -383.51089) (xy 34.926524 -383.539238) (xy 34.923197 -383.545257)
			(xy 34.919599 -383.558525) (xy 34.919412 -383.5654) (xy 34.919412 -384.3147) (xy 34.919603 -384.321573)
			(xy 34.923212 -384.334836) (xy 34.926524 -384.340862) (xy 34.942877 -384.369218) (xy 34.968681 -384.429375)
			(xy 34.986174 -384.492453) (xy 34.995039 -384.557308) (xy 34.995612 -384.590036) (xy 34.995038 -384.622765)
			(xy 34.986185 -384.687623) (xy 34.968696 -384.750703) (xy 34.942891 -384.810862) (xy 34.926524 -384.83921)
			(xy 34.923207 -384.845234) (xy 34.919602 -384.858498) (xy 34.919412 -384.865372) (xy 34.919412 -385.151376)
			(xy 34.918965 -385.161495) (xy 34.911227 -385.180196) (xy 34.89692 -385.194511) (xy 34.878223 -385.202259)
			(xy 34.868104 -385.202684) (xy 34.151824 -385.202684) (xy 34.141701 -385.202264) (xy 34.122995 -385.194521)
			(xy 34.108679 -385.180205) (xy 34.100936 -385.161499) (xy 34.100516 -385.151376) (xy 34.100516 -384.865372)
			(xy 34.100333 -384.858498) (xy 34.096718 -384.845235) (xy 34.093404 -384.83921) (xy 34.077043 -384.810858)
			(xy 34.05124 -384.7507) (xy 34.033749 -384.687621) (xy 34.024887 -384.622765) (xy 34.024316 -384.590036)
			(xy 30.594989 -384.590036) (xy 30.594987 -384.622751) (xy 30.586199 -384.687597) (xy 30.568785 -384.750677)
			(xy 30.543061 -384.810849) (xy 30.526736 -384.83921) (xy 30.523421 -384.845234) (xy 30.519815 -384.858498)
			(xy 30.519624 -384.865372) (xy 30.519624 -385.151376) (xy 30.519159 -385.161526) (xy 30.511376 -385.180273)
			(xy 30.496993 -385.194596) (xy 30.478213 -385.202301) (xy 30.468062 -385.202684) (xy 29.751782 -385.202684)
			(xy 29.741657 -385.202189) (xy 29.72294 -385.19446) (xy 29.708585 -385.180177) (xy 29.700762 -385.161498)
			(xy 29.70022 -385.151376) (xy 29.70022 -384.865372) (xy 29.700036 -384.858498) (xy 29.696422 -384.845236)
			(xy 29.693108 -384.83921) (xy 29.676817 -384.810832) (xy 29.651098 -384.750664) (xy 29.633688 -384.687589)
			(xy 29.624901 -384.622748) (xy 29.624897 -384.557314) (xy 29.633676 -384.492472) (xy 29.651078 -384.429394)
			(xy 29.676789 -384.369224) (xy 29.693108 -384.340862) (xy 29.696437 -384.334844) (xy 29.700033 -384.321575)
			(xy 29.70022 -384.3147) (xy 29.70022 -383.5654) (xy 29.700026 -383.558527) (xy 29.696419 -383.545264)
			(xy 29.693108 -383.539238) (xy 29.676756 -383.510893) (xy 29.651043 -383.450718) (xy 29.633639 -383.387636)
			(xy 29.62486 -383.322789) (xy 28.366214 -383.322789) (xy 28.369886 -383.331505) (xy 28.386862 -383.393854)
			(xy 28.395424 -383.457904) (xy 28.395422 -383.522523) (xy 28.386856 -383.586573) (xy 28.369877 -383.648922)
			(xy 28.344785 -383.70847) (xy 28.328874 -383.736596) (xy 28.325064 -383.742946) (xy 28.321 -383.758186)
			(xy 28.319476 -383.770124) (xy 28.319476 -384.051556) (xy 28.31906 -384.061681) (xy 28.31132 -384.080393)
			(xy 28.297003 -384.094713) (xy 28.278293 -384.102457) (xy 28.268168 -384.102864) (xy 28.038806 -384.102864)
			(xy 28.030317 -384.103169) (xy 28.014271 -384.108716) (xy 28.00094 -384.119229) (xy 27.996134 -384.126232)
			(xy 27.989022 -384.137154) (xy 27.98699 -384.162554) (xy 28.006802 -384.205988) (xy 28.02509 -384.22072)
			(xy 28.034996 -384.223006) (xy 28.07843 -384.234436) (xy 28.109344 -384.244276) (xy 28.168948 -384.269899)
			(xy 28.225327 -384.302) (xy 28.277781 -384.340181) (xy 28.325655 -384.383966) (xy 28.368356 -384.432811)
			(xy 28.405351 -384.486107) (xy 28.43618 -384.543192) (xy 28.46046 -384.603355) (xy 28.46959 -384.634486)
			(xy 28.478947 -384.670423) (xy 28.489525 -384.743927) (xy 28.490672 -384.781044) (xy 28.490672 -384.790696)
			(xy 28.489656 -384.828796) (xy 28.489656 -384.829304) (xy 28.489402 -384.83667) (xy 28.50642 -384.863594)
			(xy 29.775658 -385.389628) (xy 29.786597 -385.393513) (xy 29.809741 -385.392057) (xy 29.820108 -385.386834)
			(xy 29.820362 -385.38658) (xy 29.853501 -385.36824) (xy 29.923519 -385.339359) (xy 29.996699 -385.31983)
			(xy 30.071798 -385.309987) (xy 30.109668 -385.309364) (xy 30.109922 -385.309364) (xy 30.143671 -385.309854)
			(xy 30.210713 -385.317683) (xy 30.276395 -385.333233) (xy 30.339831 -385.356294) (xy 30.400165 -385.386556)
			(xy 30.456583 -385.423609) (xy 30.508324 -385.466954) (xy 30.55469 -385.516006) (xy 30.595056 -385.570104)
			(xy 30.628876 -385.628517) (xy 30.655695 -385.690458) (xy 30.664716 -385.718812) (xy 56.34177 -385.718812)
			(xy 56.345841 -385.66319) (xy 56.357967 -385.608753) (xy 56.37789 -385.556662) (xy 56.405186 -385.508027)
			(xy 56.439272 -385.463884) (xy 56.479421 -385.425175) (xy 56.524779 -385.392724) (xy 56.574379 -385.367223)
			(xy 56.627163 -385.349216) (xy 56.682006 -385.339086) (xy 56.73774 -385.337049) (xy 56.793177 -385.343149)
			(xy 56.847134 -385.357255) (xy 56.898463 -385.379067) (xy 56.946069 -385.408121) (xy 56.988937 -385.443796)
			(xy 57.026154 -385.485333) (xy 57.056927 -385.531846) (xy 57.080599 -385.582343) (xy 57.096667 -385.63575)
			(xy 57.104787 -385.690926) (xy 57.105296 -385.718812) (xy 57.104787 -385.746698) (xy 57.096667 -385.801874)
			(xy 57.080599 -385.855281) (xy 57.056927 -385.905778) (xy 57.026154 -385.952291) (xy 56.988937 -385.993828)
			(xy 56.946069 -386.029503) (xy 56.898463 -386.058557) (xy 56.88267 -386.065268) (xy 60.783214 -386.065268)
			(xy 60.787285 -386.009646) (xy 60.799411 -385.955209) (xy 60.819334 -385.903118) (xy 60.84663 -385.854483)
			(xy 60.880716 -385.81034) (xy 60.920865 -385.771631) (xy 60.966223 -385.73918) (xy 61.015823 -385.713679)
			(xy 61.068607 -385.695672) (xy 61.12345 -385.685542) (xy 61.179184 -385.683505) (xy 61.234621 -385.689605)
			(xy 61.288578 -385.703711) (xy 61.339907 -385.725523) (xy 61.387513 -385.754577) (xy 61.430381 -385.790252)
			(xy 61.467598 -385.831789) (xy 61.498371 -385.878302) (xy 61.522043 -385.928799) (xy 61.538111 -385.982206)
			(xy 61.546231 -386.037382) (xy 61.54674 -386.065268) (xy 61.546231 -386.093154) (xy 61.538111 -386.14833)
			(xy 61.522043 -386.201737) (xy 61.498371 -386.252234) (xy 61.467598 -386.298747) (xy 61.430381 -386.340284)
			(xy 61.387513 -386.375959) (xy 61.339907 -386.405013) (xy 61.288578 -386.426825) (xy 61.234621 -386.440931)
			(xy 61.179184 -386.447031) (xy 61.12345 -386.444994) (xy 61.068607 -386.434864) (xy 61.015823 -386.416857)
			(xy 60.966223 -386.391356) (xy 60.920865 -386.358905) (xy 60.880716 -386.320196) (xy 60.84663 -386.276053)
			(xy 60.819334 -386.227418) (xy 60.799411 -386.175327) (xy 60.787285 -386.12089) (xy 60.783214 -386.065268)
			(xy 56.88267 -386.065268) (xy 56.847134 -386.080369) (xy 56.793177 -386.094475) (xy 56.73774 -386.100575)
			(xy 56.682006 -386.098538) (xy 56.627163 -386.088408) (xy 56.574379 -386.070401) (xy 56.524779 -386.0449)
			(xy 56.479421 -386.012449) (xy 56.439272 -385.97374) (xy 56.405186 -385.929597) (xy 56.37789 -385.880962)
			(xy 56.357967 -385.828871) (xy 56.345841 -385.774434) (xy 56.34177 -385.718812) (xy 30.664716 -385.718812)
			(xy 30.665928 -385.722622) (xy 30.665928 -385.722876) (xy 30.669568 -385.733107) (xy 30.683861 -385.749428)
			(xy 30.703597 -385.758438) (xy 30.714442 -385.758944) (xy 30.978348 -385.758944) (xy 31.027328 -385.759528)
			(xy 31.124815 -385.769136) (xy 31.220891 -385.788254) (xy 31.31463 -385.816698) (xy 31.36011 -385.83489)
			(xy 33.532146 -386.734812) (xy 57.268616 -386.734812) (xy 57.272687 -386.67919) (xy 57.284813 -386.624753)
			(xy 57.304736 -386.572662) (xy 57.332032 -386.524027) (xy 57.366118 -386.479884) (xy 57.406267 -386.441175)
			(xy 57.451625 -386.408724) (xy 57.501225 -386.383223) (xy 57.554009 -386.365216) (xy 57.608852 -386.355086)
			(xy 57.664586 -386.353049) (xy 57.720023 -386.359149) (xy 57.77398 -386.373255) (xy 57.825309 -386.395067)
			(xy 57.872915 -386.424121) (xy 57.915783 -386.459796) (xy 57.953 -386.501333) (xy 57.983773 -386.547846)
			(xy 58.007445 -386.598343) (xy 58.023513 -386.65175) (xy 58.031633 -386.706926) (xy 58.032142 -386.734812)
			(xy 59.48248 -386.734812) (xy 59.486551 -386.67919) (xy 59.498677 -386.624753) (xy 59.5186 -386.572662)
			(xy 59.545896 -386.524027) (xy 59.579982 -386.479884) (xy 59.620131 -386.441175) (xy 59.665489 -386.408724)
			(xy 59.715089 -386.383223) (xy 59.767873 -386.365216) (xy 59.822716 -386.355086) (xy 59.87845 -386.353049)
			(xy 59.933887 -386.359149) (xy 59.987844 -386.373255) (xy 60.039173 -386.395067) (xy 60.086779 -386.424121)
			(xy 60.129647 -386.459796) (xy 60.166864 -386.501333) (xy 60.197637 -386.547846) (xy 60.221309 -386.598343)
			(xy 60.237377 -386.65175) (xy 60.245497 -386.706926) (xy 60.246006 -386.734812) (xy 60.245497 -386.762698)
			(xy 60.237377 -386.817874) (xy 60.221309 -386.871281) (xy 60.197637 -386.921778) (xy 60.166864 -386.968291)
			(xy 60.129647 -387.009828) (xy 60.086779 -387.045503) (xy 60.039173 -387.074557) (xy 59.987844 -387.096369)
			(xy 59.933887 -387.110475) (xy 59.87845 -387.116575) (xy 59.822716 -387.114538) (xy 59.767873 -387.104408)
			(xy 59.715089 -387.086401) (xy 59.665489 -387.0609) (xy 59.620131 -387.028449) (xy 59.579982 -386.98974)
			(xy 59.545896 -386.945597) (xy 59.5186 -386.896962) (xy 59.498677 -386.844871) (xy 59.486551 -386.790434)
			(xy 59.48248 -386.734812) (xy 58.032142 -386.734812) (xy 58.031633 -386.762698) (xy 58.023513 -386.817874)
			(xy 58.007445 -386.871281) (xy 57.983773 -386.921778) (xy 57.953 -386.968291) (xy 57.915783 -387.009828)
			(xy 57.872915 -387.045503) (xy 57.825309 -387.074557) (xy 57.77398 -387.096369) (xy 57.720023 -387.110475)
			(xy 57.664586 -387.116575) (xy 57.608852 -387.114538) (xy 57.554009 -387.104408) (xy 57.501225 -387.086401)
			(xy 57.451625 -387.0609) (xy 57.406267 -387.028449) (xy 57.366118 -386.98974) (xy 57.332032 -386.945597)
			(xy 57.304736 -386.896962) (xy 57.284813 -386.844871) (xy 57.272687 -386.790434) (xy 57.268616 -386.734812)
			(xy 33.532146 -386.734812) (xy 34.549196 -387.156198) (xy 62.08598 -387.156198) (xy 62.090051 -387.100576)
			(xy 62.102177 -387.046139) (xy 62.1221 -386.994048) (xy 62.149396 -386.945413) (xy 62.183482 -386.90127)
			(xy 62.223631 -386.862561) (xy 62.268989 -386.83011) (xy 62.318589 -386.804609) (xy 62.371373 -386.786602)
			(xy 62.426216 -386.776472) (xy 62.48195 -386.774435) (xy 62.537387 -386.780535) (xy 62.591344 -386.794641)
			(xy 62.642673 -386.816453) (xy 62.690279 -386.845507) (xy 62.733147 -386.881182) (xy 62.770364 -386.922719)
			(xy 62.801137 -386.969232) (xy 62.824809 -387.019729) (xy 62.840877 -387.073136) (xy 62.848997 -387.128312)
			(xy 62.849506 -387.156198) (xy 62.848997 -387.184084) (xy 62.840877 -387.23926) (xy 62.824809 -387.292667)
			(xy 62.801137 -387.343164) (xy 62.770364 -387.389677) (xy 62.733147 -387.431214) (xy 62.690279 -387.466889)
			(xy 62.642673 -387.495943) (xy 62.591344 -387.517755) (xy 62.537387 -387.531861) (xy 62.48195 -387.537961)
			(xy 62.426216 -387.535924) (xy 62.371373 -387.525794) (xy 62.318589 -387.507787) (xy 62.268989 -387.482286)
			(xy 62.223631 -387.449835) (xy 62.183482 -387.411126) (xy 62.149396 -387.366983) (xy 62.1221 -387.318348)
			(xy 62.102177 -387.266257) (xy 62.090051 -387.21182) (xy 62.08598 -387.156198) (xy 34.549196 -387.156198)
			(xy 37.226386 -388.265416) (xy 59.963302 -388.265416) (xy 59.967373 -388.209794) (xy 59.979499 -388.155357)
			(xy 59.999422 -388.103266) (xy 60.026718 -388.054631) (xy 60.060804 -388.010488) (xy 60.100953 -387.971779)
			(xy 60.146311 -387.939328) (xy 60.195911 -387.913827) (xy 60.248695 -387.89582) (xy 60.303538 -387.88569)
			(xy 60.359272 -387.883653) (xy 60.414709 -387.889753) (xy 60.468666 -387.903859) (xy 60.519995 -387.925671)
			(xy 60.567601 -387.954725) (xy 60.610469 -387.9904) (xy 60.647686 -388.031937) (xy 60.678459 -388.07845)
			(xy 60.702131 -388.128947) (xy 60.718199 -388.182354) (xy 60.726319 -388.23753) (xy 60.726828 -388.265416)
			(xy 60.726319 -388.293302) (xy 60.718199 -388.348478) (xy 60.702131 -388.401885) (xy 60.678459 -388.452382)
			(xy 60.647686 -388.498895) (xy 60.610469 -388.540432) (xy 60.567601 -388.576107) (xy 60.519995 -388.605161)
			(xy 60.468666 -388.626973) (xy 60.414709 -388.641079) (xy 60.359272 -388.647179) (xy 60.303538 -388.645142)
			(xy 60.248695 -388.635012) (xy 60.195911 -388.617005) (xy 60.146311 -388.591504) (xy 60.100953 -388.559053)
			(xy 60.060804 -388.520344) (xy 60.026718 -388.476201) (xy 59.999422 -388.427566) (xy 59.979499 -388.375475)
			(xy 59.967373 -388.321038) (xy 59.963302 -388.265416) (xy 37.226386 -388.265416) (xy 38.570805 -388.822438)
			(xy 55.493156 -388.822438) (xy 55.497227 -388.766816) (xy 55.509353 -388.712379) (xy 55.529276 -388.660288)
			(xy 55.556572 -388.611653) (xy 55.590658 -388.56751) (xy 55.630807 -388.528801) (xy 55.676165 -388.49635)
			(xy 55.725765 -388.470849) (xy 55.778549 -388.452842) (xy 55.833392 -388.442712) (xy 55.889126 -388.440675)
			(xy 55.944563 -388.446775) (xy 55.99852 -388.460881) (xy 56.049849 -388.482693) (xy 56.097455 -388.511747)
			(xy 56.140323 -388.547422) (xy 56.17754 -388.588959) (xy 56.208313 -388.635472) (xy 56.231985 -388.685969)
			(xy 56.248053 -388.739376) (xy 56.255716 -388.79145) (xy 57.41619 -388.79145) (xy 57.420261 -388.735828)
			(xy 57.432387 -388.681391) (xy 57.45231 -388.6293) (xy 57.479606 -388.580665) (xy 57.513692 -388.536522)
			(xy 57.553841 -388.497813) (xy 57.599199 -388.465362) (xy 57.648799 -388.439861) (xy 57.701583 -388.421854)
			(xy 57.756426 -388.411724) (xy 57.81216 -388.409687) (xy 57.867597 -388.415787) (xy 57.921554 -388.429893)
			(xy 57.972883 -388.451705) (xy 58.020489 -388.480759) (xy 58.063357 -388.516434) (xy 58.100574 -388.557971)
			(xy 58.131347 -388.604484) (xy 58.155019 -388.654981) (xy 58.171087 -388.708388) (xy 58.179207 -388.763564)
			(xy 58.179716 -388.79145) (xy 58.179207 -388.819336) (xy 58.171087 -388.874512) (xy 58.163294 -388.900416)
			(xy 58.70397 -388.900416) (xy 58.708041 -388.844794) (xy 58.720167 -388.790357) (xy 58.74009 -388.738266)
			(xy 58.767386 -388.689631) (xy 58.801472 -388.645488) (xy 58.841621 -388.606779) (xy 58.886979 -388.574328)
			(xy 58.936579 -388.548827) (xy 58.989363 -388.53082) (xy 59.044206 -388.52069) (xy 59.09994 -388.518653)
			(xy 59.155377 -388.524753) (xy 59.209334 -388.538859) (xy 59.260663 -388.560671) (xy 59.308269 -388.589725)
			(xy 59.351137 -388.6254) (xy 59.388354 -388.666937) (xy 59.419127 -388.71345) (xy 59.442799 -388.763947)
			(xy 59.458867 -388.817354) (xy 59.466987 -388.87253) (xy 59.467496 -388.900416) (xy 59.466987 -388.928302)
			(xy 59.458867 -388.983478) (xy 59.442799 -389.036885) (xy 59.435807 -389.0518) (xy 61.746382 -389.0518)
			(xy 61.750453 -388.996178) (xy 61.762579 -388.941741) (xy 61.782502 -388.88965) (xy 61.809798 -388.841015)
			(xy 61.843884 -388.796872) (xy 61.884033 -388.758163) (xy 61.929391 -388.725712) (xy 61.978991 -388.700211)
			(xy 62.031775 -388.682204) (xy 62.086618 -388.672074) (xy 62.142352 -388.670037) (xy 62.197789 -388.676137)
			(xy 62.251746 -388.690243) (xy 62.303075 -388.712055) (xy 62.350681 -388.741109) (xy 62.393549 -388.776784)
			(xy 62.430766 -388.818321) (xy 62.461539 -388.864834) (xy 62.485211 -388.915331) (xy 62.501279 -388.968738)
			(xy 62.509399 -389.023914) (xy 62.509908 -389.0518) (xy 62.509399 -389.079686) (xy 62.501279 -389.134862)
			(xy 62.485211 -389.188269) (xy 62.461539 -389.238766) (xy 62.430766 -389.285279) (xy 62.393549 -389.326816)
			(xy 62.350681 -389.362491) (xy 62.303075 -389.391545) (xy 62.251746 -389.413357) (xy 62.197789 -389.427463)
			(xy 62.142352 -389.433563) (xy 62.086618 -389.431526) (xy 62.031775 -389.421396) (xy 61.978991 -389.403389)
			(xy 61.929391 -389.377888) (xy 61.884033 -389.345437) (xy 61.843884 -389.306728) (xy 61.809798 -389.262585)
			(xy 61.782502 -389.21395) (xy 61.762579 -389.161859) (xy 61.750453 -389.107422) (xy 61.746382 -389.0518)
			(xy 59.435807 -389.0518) (xy 59.419127 -389.087382) (xy 59.388354 -389.133895) (xy 59.351137 -389.175432)
			(xy 59.308269 -389.211107) (xy 59.260663 -389.240161) (xy 59.209334 -389.261973) (xy 59.155377 -389.276079)
			(xy 59.09994 -389.282179) (xy 59.044206 -389.280142) (xy 58.989363 -389.270012) (xy 58.936579 -389.252005)
			(xy 58.886979 -389.226504) (xy 58.841621 -389.194053) (xy 58.801472 -389.155344) (xy 58.767386 -389.111201)
			(xy 58.74009 -389.062566) (xy 58.720167 -389.010475) (xy 58.708041 -388.956038) (xy 58.70397 -388.900416)
			(xy 58.163294 -388.900416) (xy 58.155019 -388.927919) (xy 58.131347 -388.978416) (xy 58.100574 -389.024929)
			(xy 58.063357 -389.066466) (xy 58.020489 -389.102141) (xy 57.972883 -389.131195) (xy 57.921554 -389.153007)
			(xy 57.867597 -389.167113) (xy 57.81216 -389.173213) (xy 57.756426 -389.171176) (xy 57.701583 -389.161046)
			(xy 57.648799 -389.143039) (xy 57.599199 -389.117538) (xy 57.553841 -389.085087) (xy 57.513692 -389.046378)
			(xy 57.479606 -389.002235) (xy 57.45231 -388.9536) (xy 57.432387 -388.901509) (xy 57.420261 -388.847072)
			(xy 57.41619 -388.79145) (xy 56.255716 -388.79145) (xy 56.256173 -388.794552) (xy 56.256682 -388.822438)
			(xy 56.256173 -388.850324) (xy 56.248053 -388.9055) (xy 56.231985 -388.958907) (xy 56.208313 -389.009404)
			(xy 56.17754 -389.055917) (xy 56.140323 -389.097454) (xy 56.097455 -389.133129) (xy 56.049849 -389.162183)
			(xy 55.99852 -389.183995) (xy 55.944563 -389.198101) (xy 55.889126 -389.204201) (xy 55.833392 -389.202164)
			(xy 55.778549 -389.192034) (xy 55.725765 -389.174027) (xy 55.676165 -389.148526) (xy 55.630807 -389.116075)
			(xy 55.590658 -389.077366) (xy 55.556572 -389.033223) (xy 55.529276 -388.984588) (xy 55.509353 -388.932497)
			(xy 55.497227 -388.87806) (xy 55.493156 -388.822438) (xy 38.570805 -388.822438) (xy 41.118028 -389.877808)
			(xy 41.163005 -389.89711) (xy 41.24931 -389.943282) (xy 41.330681 -389.997681) (xy 41.406335 -390.059785)
			(xy 41.44137 -390.093962) (xy 42.492422 -391.145014) (xy 56.036208 -391.145014) (xy 56.040279 -391.089392)
			(xy 56.052405 -391.034955) (xy 56.072328 -390.982864) (xy 56.099624 -390.934229) (xy 56.13371 -390.890086)
			(xy 56.173859 -390.851377) (xy 56.219217 -390.818926) (xy 56.268817 -390.793425) (xy 56.321601 -390.775418)
			(xy 56.376444 -390.765288) (xy 56.432178 -390.763251) (xy 56.487615 -390.769351) (xy 56.541572 -390.783457)
			(xy 56.592901 -390.805269) (xy 56.640507 -390.834323) (xy 56.683375 -390.869998) (xy 56.720592 -390.911535)
			(xy 56.751365 -390.958048) (xy 56.775037 -391.008545) (xy 56.791105 -391.061952) (xy 56.799225 -391.117128)
			(xy 56.799734 -391.145014) (xy 56.799225 -391.1729) (xy 56.791105 -391.228076) (xy 56.775037 -391.281483)
			(xy 56.751365 -391.33198) (xy 56.728021 -391.367264) (xy 57.50001 -391.367264) (xy 57.504081 -391.311642)
			(xy 57.516207 -391.257205) (xy 57.53613 -391.205114) (xy 57.563426 -391.156479) (xy 57.597512 -391.112336)
			(xy 57.637661 -391.073627) (xy 57.683019 -391.041176) (xy 57.732619 -391.015675) (xy 57.785403 -390.997668)
			(xy 57.840246 -390.987538) (xy 57.89598 -390.985501) (xy 57.951417 -390.991601) (xy 58.005374 -391.005707)
			(xy 58.056703 -391.027519) (xy 58.104309 -391.056573) (xy 58.147177 -391.092248) (xy 58.151442 -391.097008)
			(xy 58.991244 -391.097008) (xy 58.995315 -391.041386) (xy 59.007441 -390.986949) (xy 59.027364 -390.934858)
			(xy 59.05466 -390.886223) (xy 59.088746 -390.84208) (xy 59.128895 -390.803371) (xy 59.174253 -390.77092)
			(xy 59.223853 -390.745419) (xy 59.276637 -390.727412) (xy 59.33148 -390.717282) (xy 59.387214 -390.715245)
			(xy 59.442651 -390.721345) (xy 59.496608 -390.735451) (xy 59.547937 -390.757263) (xy 59.595543 -390.786317)
			(xy 59.638411 -390.821992) (xy 59.675628 -390.863529) (xy 59.706401 -390.910042) (xy 59.730073 -390.960539)
			(xy 59.743391 -391.004806) (xy 61.82563 -391.004806) (xy 61.829701 -390.949184) (xy 61.841827 -390.894747)
			(xy 61.86175 -390.842656) (xy 61.889046 -390.794021) (xy 61.923132 -390.749878) (xy 61.963281 -390.711169)
			(xy 62.008639 -390.678718) (xy 62.058239 -390.653217) (xy 62.111023 -390.63521) (xy 62.165866 -390.62508)
			(xy 62.2216 -390.623043) (xy 62.277037 -390.629143) (xy 62.330994 -390.643249) (xy 62.382323 -390.665061)
			(xy 62.429929 -390.694115) (xy 62.472797 -390.72979) (xy 62.510014 -390.771327) (xy 62.540787 -390.81784)
			(xy 62.564459 -390.868337) (xy 62.580527 -390.921744) (xy 62.588647 -390.97692) (xy 62.589156 -391.004806)
			(xy 62.588647 -391.032692) (xy 62.580527 -391.087868) (xy 62.577242 -391.098786) (xy 63.318642 -391.098786)
			(xy 63.322713 -391.043164) (xy 63.334839 -390.988727) (xy 63.354762 -390.936636) (xy 63.382058 -390.888001)
			(xy 63.416144 -390.843858) (xy 63.456293 -390.805149) (xy 63.501651 -390.772698) (xy 63.551251 -390.747197)
			(xy 63.604035 -390.72919) (xy 63.658878 -390.71906) (xy 63.714612 -390.717023) (xy 63.770049 -390.723123)
			(xy 63.824006 -390.737229) (xy 63.875335 -390.759041) (xy 63.922941 -390.788095) (xy 63.965809 -390.82377)
			(xy 64.003026 -390.865307) (xy 64.033799 -390.91182) (xy 64.057471 -390.962317) (xy 64.073539 -391.015724)
			(xy 64.081659 -391.0709) (xy 64.082168 -391.098786) (xy 64.081659 -391.126672) (xy 64.073539 -391.181848)
			(xy 64.057471 -391.235255) (xy 64.033799 -391.285752) (xy 64.003026 -391.332265) (xy 63.965809 -391.373802)
			(xy 63.922941 -391.409477) (xy 63.875335 -391.438531) (xy 63.824006 -391.460343) (xy 63.770049 -391.474449)
			(xy 63.714612 -391.480549) (xy 63.658878 -391.478512) (xy 63.604035 -391.468382) (xy 63.551251 -391.450375)
			(xy 63.501651 -391.424874) (xy 63.456293 -391.392423) (xy 63.416144 -391.353714) (xy 63.382058 -391.309571)
			(xy 63.354762 -391.260936) (xy 63.334839 -391.208845) (xy 63.322713 -391.154408) (xy 63.318642 -391.098786)
			(xy 62.577242 -391.098786) (xy 62.564459 -391.141275) (xy 62.540787 -391.191772) (xy 62.510014 -391.238285)
			(xy 62.472797 -391.279822) (xy 62.429929 -391.315497) (xy 62.382323 -391.344551) (xy 62.330994 -391.366363)
			(xy 62.277037 -391.380469) (xy 62.2216 -391.386569) (xy 62.165866 -391.384532) (xy 62.111023 -391.374402)
			(xy 62.058239 -391.356395) (xy 62.008639 -391.330894) (xy 61.963281 -391.298443) (xy 61.923132 -391.259734)
			(xy 61.889046 -391.215591) (xy 61.86175 -391.166956) (xy 61.841827 -391.114865) (xy 61.829701 -391.060428)
			(xy 61.82563 -391.004806) (xy 59.743391 -391.004806) (xy 59.746141 -391.013946) (xy 59.754261 -391.069122)
			(xy 59.75477 -391.097008) (xy 59.754261 -391.124894) (xy 59.746141 -391.18007) (xy 59.730073 -391.233477)
			(xy 59.706401 -391.283974) (xy 59.675628 -391.330487) (xy 59.638411 -391.372024) (xy 59.595543 -391.407699)
			(xy 59.547937 -391.436753) (xy 59.496608 -391.458565) (xy 59.442651 -391.472671) (xy 59.387214 -391.478771)
			(xy 59.33148 -391.476734) (xy 59.276637 -391.466604) (xy 59.223853 -391.448597) (xy 59.174253 -391.423096)
			(xy 59.128895 -391.390645) (xy 59.088746 -391.351936) (xy 59.05466 -391.307793) (xy 59.027364 -391.259158)
			(xy 59.007441 -391.207067) (xy 58.995315 -391.15263) (xy 58.991244 -391.097008) (xy 58.151442 -391.097008)
			(xy 58.184394 -391.133785) (xy 58.215167 -391.180298) (xy 58.238839 -391.230795) (xy 58.254907 -391.284202)
			(xy 58.263027 -391.339378) (xy 58.263536 -391.367264) (xy 58.263027 -391.39515) (xy 58.254907 -391.450326)
			(xy 58.240847 -391.497058) (xy 60.565028 -391.497058) (xy 60.569099 -391.441436) (xy 60.581225 -391.386999)
			(xy 60.601148 -391.334908) (xy 60.628444 -391.286273) (xy 60.66253 -391.24213) (xy 60.702679 -391.203421)
			(xy 60.748037 -391.17097) (xy 60.797637 -391.145469) (xy 60.850421 -391.127462) (xy 60.905264 -391.117332)
			(xy 60.960998 -391.115295) (xy 61.016435 -391.121395) (xy 61.070392 -391.135501) (xy 61.121721 -391.157313)
			(xy 61.169327 -391.186367) (xy 61.212195 -391.222042) (xy 61.249412 -391.263579) (xy 61.280185 -391.310092)
			(xy 61.303857 -391.360589) (xy 61.319925 -391.413996) (xy 61.328045 -391.469172) (xy 61.328554 -391.497058)
			(xy 61.328045 -391.524944) (xy 61.319925 -391.58012) (xy 61.303857 -391.633527) (xy 61.282577 -391.678922)
			(xy 64.618868 -391.678922) (xy 64.622939 -391.6233) (xy 64.635065 -391.568863) (xy 64.654988 -391.516772)
			(xy 64.682284 -391.468137) (xy 64.71637 -391.423994) (xy 64.756519 -391.385285) (xy 64.801877 -391.352834)
			(xy 64.851477 -391.327333) (xy 64.904261 -391.309326) (xy 64.959104 -391.299196) (xy 65.014838 -391.297159)
			(xy 65.070275 -391.303259) (xy 65.124232 -391.317365) (xy 65.175561 -391.339177) (xy 65.223167 -391.368231)
			(xy 65.266035 -391.403906) (xy 65.303252 -391.445443) (xy 65.334025 -391.491956) (xy 65.357697 -391.542453)
			(xy 65.373765 -391.59586) (xy 65.381885 -391.651036) (xy 65.382394 -391.678922) (xy 65.381885 -391.706808)
			(xy 65.373765 -391.761984) (xy 65.357697 -391.815391) (xy 65.334025 -391.865888) (xy 65.303252 -391.912401)
			(xy 65.266035 -391.953938) (xy 65.223167 -391.989613) (xy 65.175561 -392.018667) (xy 65.124232 -392.040479)
			(xy 65.070275 -392.054585) (xy 65.014838 -392.060685) (xy 64.959104 -392.058648) (xy 64.904261 -392.048518)
			(xy 64.851477 -392.030511) (xy 64.801877 -392.00501) (xy 64.756519 -391.972559) (xy 64.71637 -391.93385)
			(xy 64.682284 -391.889707) (xy 64.654988 -391.841072) (xy 64.635065 -391.788981) (xy 64.622939 -391.734544)
			(xy 64.618868 -391.678922) (xy 61.282577 -391.678922) (xy 61.280185 -391.684024) (xy 61.249412 -391.730537)
			(xy 61.212195 -391.772074) (xy 61.169327 -391.807749) (xy 61.121721 -391.836803) (xy 61.070392 -391.858615)
			(xy 61.016435 -391.872721) (xy 60.960998 -391.878821) (xy 60.905264 -391.876784) (xy 60.850421 -391.866654)
			(xy 60.797637 -391.848647) (xy 60.748037 -391.823146) (xy 60.702679 -391.790695) (xy 60.66253 -391.751986)
			(xy 60.628444 -391.707843) (xy 60.601148 -391.659208) (xy 60.581225 -391.607117) (xy 60.569099 -391.55268)
			(xy 60.565028 -391.497058) (xy 58.240847 -391.497058) (xy 58.238839 -391.503733) (xy 58.215167 -391.55423)
			(xy 58.184394 -391.600743) (xy 58.147177 -391.64228) (xy 58.104309 -391.677955) (xy 58.056703 -391.707009)
			(xy 58.005374 -391.728821) (xy 57.951417 -391.742927) (xy 57.89598 -391.749027) (xy 57.840246 -391.74699)
			(xy 57.785403 -391.73686) (xy 57.732619 -391.718853) (xy 57.683019 -391.693352) (xy 57.637661 -391.660901)
			(xy 57.597512 -391.622192) (xy 57.563426 -391.578049) (xy 57.53613 -391.529414) (xy 57.516207 -391.477323)
			(xy 57.504081 -391.422886) (xy 57.50001 -391.367264) (xy 56.728021 -391.367264) (xy 56.720592 -391.378493)
			(xy 56.683375 -391.42003) (xy 56.640507 -391.455705) (xy 56.592901 -391.484759) (xy 56.541572 -391.506571)
			(xy 56.487615 -391.520677) (xy 56.432178 -391.526777) (xy 56.376444 -391.52474) (xy 56.321601 -391.51461)
			(xy 56.268817 -391.496603) (xy 56.219217 -391.471102) (xy 56.173859 -391.438651) (xy 56.13371 -391.399942)
			(xy 56.099624 -391.355799) (xy 56.072328 -391.307164) (xy 56.052405 -391.255073) (xy 56.040279 -391.200636)
			(xy 56.036208 -391.145014) (xy 42.492422 -391.145014) (xy 45.189394 -393.841986) (xy 45.219843 -393.873088)
			(xy 45.275815 -393.939751) (xy 45.325765 -394.011038) (xy 45.369313 -394.086407) (xy 45.406128 -394.165284)
			(xy 45.435928 -394.247069) (xy 45.458489 -394.33114) (xy 45.473637 -394.416857) (xy 45.481258 -394.503568)
			(xy 45.481748 -394.54709) (xy 45.481748 -395.87043) (xy 45.487612 -395.873605) (xy 45.500483 -395.877078)
			(xy 45.507148 -395.877288) (xy 45.868082 -395.877288) (xy 45.878252 -395.877711) (xy 45.897045 -395.885495)
			(xy 45.911423 -395.899882) (xy 45.919195 -395.918679) (xy 45.919644 -395.92885) (xy 45.919644 -396.21968)
			(xy 45.922438 -396.227808) (xy 45.92701 -396.24127) (xy 45.92955 -396.245842) (xy 45.945239 -396.273763)
			(xy 45.969945 -396.332852) (xy 45.986659 -396.394678) (xy 45.99509 -396.458167) (xy 45.99559 -396.49019)
			(xy 45.99559 -396.49654) (xy 45.995314 -396.510871) (xy 45.993283 -396.539465) (xy 45.991526 -396.55369)
			(xy 45.986822 -396.585417) (xy 45.970149 -396.647352) (xy 45.945486 -396.70656) (xy 45.929804 -396.734538)
			(xy 45.927518 -396.738348) (xy 45.925486 -396.743682) (xy 45.922184 -396.753842) (xy 45.921056 -396.757554)
			(xy 45.91978 -396.765205) (xy 45.919644 -396.769082) (xy 45.919644 -397.519652) (xy 45.922438 -397.52778)
			(xy 45.92701 -397.541242) (xy 45.92955 -397.545814) (xy 45.935997 -397.55729) (xy 47.225044 -397.55729)
			(xy 47.233827 -397.492446) (xy 47.251235 -397.429368) (xy 47.276953 -397.369197) (xy 47.293276 -397.340836)
			(xy 47.296576 -397.334804) (xy 47.300191 -397.321546) (xy 47.300388 -397.314674) (xy 47.300388 -397.028924)
			(xy 47.300841 -397.018773) (xy 47.308626 -397.000023) (xy 47.323013 -396.985699) (xy 47.341797 -396.977997)
			(xy 47.35195 -396.977616) (xy 48.06823 -396.977616) (xy 48.078356 -396.978101) (xy 48.097073 -396.985834)
			(xy 48.111427 -397.000121) (xy 48.11925 -397.018801) (xy 48.119792 -397.028924) (xy 48.119792 -397.314674)
			(xy 48.119995 -397.321546) (xy 48.123596 -397.334809) (xy 48.126904 -397.340836) (xy 48.143233 -397.369193)
			(xy 48.168948 -397.429366) (xy 48.186354 -397.492445) (xy 48.195135 -397.55729) (xy 48.195134 -397.622727)
			(xy 48.18635 -397.687572) (xy 48.168942 -397.750651) (xy 48.143226 -397.810822) (xy 48.126904 -397.839184)
			(xy 48.123595 -397.845212) (xy 48.119986 -397.858473) (xy 48.119792 -397.865346) (xy 48.119792 -398.6149)
			(xy 48.119985 -398.621773) (xy 48.123592 -398.635036) (xy 48.126904 -398.641062) (xy 48.143255 -398.669407)
			(xy 48.168968 -398.729582) (xy 48.186371 -398.792664) (xy 48.19515 -398.857512) (xy 48.195146 -398.92295)
			(xy 48.186359 -398.987796) (xy 48.168947 -399.050876) (xy 48.143227 -399.111048) (xy 48.126904 -399.13941)
			(xy 48.123586 -399.145433) (xy 48.119982 -399.158698) (xy 48.119792 -399.165572) (xy 48.119792 -399.451576)
			(xy 48.119359 -399.46173) (xy 48.11157 -399.480483) (xy 48.097176 -399.494808) (xy 48.078386 -399.502507)
			(xy 48.06823 -399.502884) (xy 47.35195 -399.502884) (xy 47.341829 -399.502333) (xy 47.323114 -399.494626)
			(xy 47.308757 -399.48036) (xy 47.300932 -399.461693) (xy 47.300388 -399.451576) (xy 47.300388 -399.165572)
			(xy 47.300208 -399.158698) (xy 47.296592 -399.145435) (xy 47.293276 -399.13941) (xy 47.276983 -399.111032)
			(xy 47.251261 -399.050865) (xy 47.233848 -398.98779) (xy 47.22506 -398.922948) (xy 47.225056 -398.857514)
			(xy 47.233835 -398.792671) (xy 47.25124 -398.729593) (xy 47.276955 -398.669423) (xy 47.293276 -398.641062)
			(xy 47.296603 -398.635043) (xy 47.300201 -398.621775) (xy 47.300388 -398.6149) (xy 47.300388 -397.865346)
			(xy 47.30018 -397.858474) (xy 47.296583 -397.845211) (xy 47.293276 -397.839184) (xy 47.276961 -397.810818)
			(xy 47.251241 -397.750649) (xy 47.23383 -397.687571) (xy 47.225045 -397.622727) (xy 47.225044 -397.55729)
			(xy 45.935997 -397.55729) (xy 45.945235 -397.573736) (xy 45.969932 -397.632826) (xy 45.986637 -397.694653)
			(xy 45.995058 -397.75814) (xy 45.99559 -397.790162) (xy 45.99559 -397.796512) (xy 45.995312 -397.810843)
			(xy 45.993276 -397.839436) (xy 45.991526 -397.853662) (xy 45.986817 -397.885387) (xy 45.970137 -397.947318)
			(xy 45.945466 -398.006521) (xy 45.929804 -398.03451) (xy 45.927518 -398.03832) (xy 45.925486 -398.043654)
			(xy 45.922184 -398.053814) (xy 45.921054 -398.057525) (xy 45.919774 -398.065177) (xy 45.919644 -398.069054)
			(xy 45.919644 -398.351502) (xy 45.919218 -398.361672) (xy 45.911432 -398.380463) (xy 45.897046 -398.394843)
			(xy 45.878252 -398.402622) (xy 45.868082 -398.403064) (xy 45.507148 -398.403064) (xy 45.500481 -398.403263)
			(xy 45.487607 -398.406735) (xy 45.481748 -398.409922) (xy 45.481748 -399.770346) (xy 45.487613 -399.77352)
			(xy 45.500483 -399.776992) (xy 45.507148 -399.777204) (xy 45.868082 -399.777204) (xy 45.878245 -399.777696)
			(xy 45.897026 -399.785466) (xy 45.911405 -399.79983) (xy 45.919194 -399.818604) (xy 45.919644 -399.828766)
			(xy 45.919644 -400.119596) (xy 45.922438 -400.127724) (xy 45.92701 -400.141186) (xy 45.92955 -400.145758)
			(xy 45.945239 -400.173679) (xy 45.969942 -400.232768) (xy 45.986654 -400.294595) (xy 45.995083 -400.358083)
			(xy 45.99559 -400.390106) (xy 45.99559 -400.396456) (xy 45.995313 -400.410787) (xy 45.993281 -400.439381)
			(xy 45.991526 -400.453606) (xy 45.986821 -400.485333) (xy 45.970146 -400.547266) (xy 45.945482 -400.606473)
			(xy 45.929804 -400.634454) (xy 45.927518 -400.638264) (xy 45.925486 -400.643598) (xy 45.922184 -400.653758)
			(xy 45.921057 -400.65747) (xy 45.919783 -400.665121) (xy 45.919644 -400.668998) (xy 45.919644 -401.419568)
			(xy 45.922438 -401.427696) (xy 45.92701 -401.441158) (xy 45.92955 -401.44573) (xy 45.945241 -401.473651)
			(xy 45.952152 -401.49018) (xy 47.223942 -401.49018) (xy 47.227933 -401.428013) (xy 47.239842 -401.366866)
			(xy 47.259471 -401.307745) (xy 47.2865 -401.251619) (xy 47.320484 -401.19941) (xy 47.360866 -401.151975)
			(xy 47.406982 -401.110094) (xy 47.458074 -401.074454) (xy 47.513305 -401.04564) (xy 47.571767 -401.024126)
			(xy 47.632501 -401.010264) (xy 47.694508 -401.004282) (xy 47.756771 -401.006278) (xy 47.818268 -401.016221)
			(xy 47.877989 -401.033945) (xy 47.934952 -401.059162) (xy 47.988223 -401.091455) (xy 48.036928 -401.130295)
			(xy 48.080265 -401.175045) (xy 48.117525 -401.224969) (xy 48.148094 -401.279248) (xy 48.171472 -401.336991)
			(xy 48.187273 -401.397249) (xy 48.195239 -401.459032) (xy 48.195738 -401.49018) (xy 48.195239 -401.521328)
			(xy 48.187273 -401.583111) (xy 48.171472 -401.643369) (xy 48.148094 -401.701112) (xy 48.117525 -401.755391)
			(xy 48.080265 -401.805315) (xy 48.036928 -401.850065) (xy 47.988223 -401.888905) (xy 47.934952 -401.921198)
			(xy 47.877989 -401.946415) (xy 47.818268 -401.964139) (xy 47.756771 -401.974082) (xy 47.694508 -401.976078)
			(xy 47.632501 -401.970096) (xy 47.571767 -401.956234) (xy 47.513305 -401.93472) (xy 47.458074 -401.905906)
			(xy 47.406982 -401.870266) (xy 47.360866 -401.828385) (xy 47.320484 -401.78095) (xy 47.2865 -401.728741)
			(xy 47.259471 -401.672615) (xy 47.239842 -401.613494) (xy 47.227933 -401.552347) (xy 47.223942 -401.49018)
			(xy 45.952152 -401.49018) (xy 45.969948 -401.532739) (xy 45.986663 -401.594566) (xy 45.995096 -401.658055)
			(xy 45.99559 -401.690078) (xy 45.99559 -401.696428) (xy 45.995314 -401.710759) (xy 45.993284 -401.739353)
			(xy 45.991526 -401.753578) (xy 45.986823 -401.785305) (xy 45.970151 -401.84724) (xy 45.945489 -401.906449)
			(xy 45.929804 -401.934426) (xy 45.927518 -401.938236) (xy 45.925486 -401.94357) (xy 45.922184 -401.95373)
			(xy 45.921055 -401.957441) (xy 45.919777 -401.965093) (xy 45.919644 -401.96897) (xy 45.919644 -402.251418)
			(xy 45.919145 -402.261572) (xy 45.911367 -402.280332) (xy 45.897002 -402.294687) (xy 45.878236 -402.302452)
			(xy 45.868082 -402.30298) (xy 45.458126 -402.30298) (xy 45.44799 -402.303433) (xy 45.429298 -402.311288)
			(xy 45.415088 -402.325748) (xy 45.410882 -402.334984) (xy 45.395508 -402.372536) (xy 45.359491 -402.445255)
			(xy 45.317679 -402.514804) (xy 45.270348 -402.580722) (xy 45.217813 -402.642572) (xy 45.189394 -402.671534)
			(xy 45.070776 -402.790152) (xy 47.223942 -402.790152) (xy 47.227933 -402.727985) (xy 47.239842 -402.666838)
			(xy 47.259471 -402.607717) (xy 47.2865 -402.551591) (xy 47.320484 -402.499382) (xy 47.360866 -402.451947)
			(xy 47.406982 -402.410066) (xy 47.458074 -402.374426) (xy 47.513305 -402.345612) (xy 47.571767 -402.324098)
			(xy 47.632501 -402.310236) (xy 47.694508 -402.304254) (xy 47.756771 -402.30625) (xy 47.818268 -402.316193)
			(xy 47.877989 -402.333917) (xy 47.934952 -402.359134) (xy 47.988223 -402.391427) (xy 48.036928 -402.430267)
			(xy 48.080265 -402.475017) (xy 48.117525 -402.524941) (xy 48.148094 -402.57922) (xy 48.171472 -402.636963)
			(xy 48.187273 -402.697221) (xy 48.195239 -402.759004) (xy 48.195738 -402.790152) (xy 48.195239 -402.8213)
			(xy 48.187273 -402.883083) (xy 48.171472 -402.943341) (xy 48.148094 -403.001084) (xy 48.117525 -403.055363)
			(xy 48.080265 -403.105287) (xy 48.036928 -403.150037) (xy 47.988223 -403.188877) (xy 47.934952 -403.22117)
			(xy 47.877989 -403.246387) (xy 47.818268 -403.264111) (xy 47.756771 -403.274054) (xy 47.694508 -403.27605)
			(xy 47.632501 -403.270068) (xy 47.571767 -403.256206) (xy 47.513305 -403.234692) (xy 47.458074 -403.205878)
			(xy 47.406982 -403.170238) (xy 47.360866 -403.128357) (xy 47.320484 -403.080922) (xy 47.2865 -403.028713)
			(xy 47.259471 -402.972587) (xy 47.239842 -402.913466) (xy 47.227933 -402.852319) (xy 47.223942 -402.790152)
			(xy 45.070776 -402.790152) (xy 44.874688 -402.98624) (xy 44.841362 -403.018804) (xy 44.769614 -403.078262)
			(xy 44.692631 -403.130766) (xy 44.611086 -403.175859) (xy 44.525689 -403.213147) (xy 44.437185 -403.242305)
			(xy 44.346348 -403.263078) (xy 44.253968 -403.275286) (xy 44.20743 -403.277578) (xy 44.194779 -403.278783)
			(xy 44.172942 -403.29172) (xy 44.165774 -403.302216) (xy 44.143368 -403.338766) (xy 44.093189 -403.408287)
			(xy 44.037226 -403.473243) (xy 43.975893 -403.533153) (xy 43.909642 -403.587576) (xy 43.838963 -403.63611)
			(xy 43.764378 -403.678396) (xy 43.686438 -403.714121) (xy 43.605717 -403.743022) (xy 43.522814 -403.764886)
			(xy 43.438339 -403.779551) (xy 43.352917 -403.786908) (xy 43.310048 -403.787356) (xy 43.309286 -403.787356)
			(xy 43.266413 -403.786874) (xy 43.180986 -403.779468) (xy 43.09651 -403.764756) (xy 43.01361 -403.742844)
			(xy 42.932896 -403.713896) (xy 42.893742 -403.696424) (xy 42.883328 -403.698964) (xy 42.880026 -403.69998)
			(xy 42.878248 -403.700488) (xy 42.877994 -403.700488) (xy 42.860693 -403.706544) (xy 42.825199 -403.715706)
			(xy 42.807128 -403.718776) (xy 42.806874 -403.718776) (xy 42.803318 -403.719284) (xy 42.800778 -403.719792)
			(xy 42.796714 -403.7203) (xy 42.796206 -403.7203) (xy 42.794936 -403.720554) (xy 42.794682 -403.720554)
			(xy 42.79011 -403.721062) (xy 42.789602 -403.721062) (xy 42.763948 -403.723094) (xy 42.7609 -403.723094)
			(xy 42.757598 -403.723348) (xy 42.745914 -403.723348) (xy 42.718754 -403.722727) (xy 42.665019 -403.714742)
			(xy 42.61296 -403.699216) (xy 42.56363 -403.676463) (xy 42.518025 -403.646944) (xy 42.477068 -403.611254)
			(xy 42.441588 -403.570116) (xy 42.412301 -403.524361) (xy 42.3898 -403.474915) (xy 42.37454 -403.422777)
			(xy 42.366829 -403.369002) (xy 42.366438 -403.34184) (xy 42.366438 -403.340316) (xy 42.367165 -403.307445)
			(xy 42.378527 -403.24269) (xy 42.389044 -403.211538) (xy 42.39006 -403.208998) (xy 42.390568 -403.206966)
			(xy 42.392346 -403.201886) (xy 42.394886 -403.187408) (xy 42.394886 -403.1869) (xy 42.38879 -403.172422)
			(xy 42.370614 -403.127004) (xy 42.342189 -403.033391) (xy 42.323074 -402.937443) (xy 42.313452 -402.840084)
			(xy 42.312844 -402.791168) (xy 42.312844 -402.407374) (xy 42.313312 -402.364517) (xy 42.320687 -402.279121)
			(xy 42.335363 -402.194673) (xy 42.345864 -402.15312) (xy 42.347642 -402.140166) (xy 42.345864 -402.127212)
			(xy 42.34307 -402.116544) (xy 42.31386 -402.082254) (xy 42.229278 -402.045678) (xy 42.205656 -402.046694)
			(xy 42.195242 -402.052536) (xy 42.153707 -402.075015) (xy 42.067202 -402.112927) (xy 42.022522 -402.128228)
			(xy 42.013316 -402.131705) (xy 41.998284 -402.144375) (xy 41.993312 -402.152866) (xy 41.971881 -402.192704)
			(xy 41.922833 -402.268721) (xy 41.867101 -402.339984) (xy 41.805143 -402.405905) (xy 41.73747 -402.465944)
			(xy 41.664636 -402.519607) (xy 41.587242 -402.566452) (xy 41.505923 -402.606095) (xy 41.421347 -402.638209)
			(xy 41.33421 -402.662531) (xy 41.245229 -402.678861) (xy 41.155134 -402.687064) (xy 41.1099 -402.687536)
			(xy 41.067891 -402.687089) (xy 40.984172 -402.680001) (xy 40.901345 -402.665899) (xy 40.819998 -402.644883)
			(xy 40.780208 -402.631402) (xy 40.76319 -402.628608) (xy 40.753223 -402.629084) (xy 40.734785 -402.636658)
			(xy 40.727376 -402.64334) (xy 40.384222 -402.98624) (xy 40.35077 -403.018927) (xy 40.278738 -403.078596)
			(xy 40.201439 -403.131261) (xy 40.119549 -403.17646) (xy 40.033789 -403.213798) (xy 39.944911 -403.242945)
			(xy 39.853695 -403.263646) (xy 39.807388 -403.270212) (xy 39.77005 -403.29485) (xy 39.747774 -403.331894)
			(xy 39.69773 -403.402381) (xy 39.641771 -403.468272) (xy 39.580319 -403.529071) (xy 39.513834 -403.584323)
			(xy 39.442817 -403.633612) (xy 39.367799 -403.676568) (xy 39.289344 -403.71287) (xy 39.208041 -403.742244)
			(xy 39.124501 -403.764469) (xy 39.039351 -403.77938) (xy 38.953229 -403.786863) (xy 38.910006 -403.787356)
			(xy 38.909752 -403.787356) (xy 38.868637 -403.786936) (xy 38.786685 -403.780164) (xy 38.70557 -403.766663)
			(xy 38.625844 -403.746523) (xy 38.548048 -403.719883) (xy 38.51021 -403.70379) (xy 38.493446 -403.696424)
			(xy 38.485064 -403.698202) (xy 38.477952 -403.700742) (xy 38.471856 -403.702774) (xy 38.46322 -403.705822)
			(xy 38.462712 -403.705822) (xy 38.43473 -403.714085) (xy 38.377075 -403.723012) (xy 38.347904 -403.723602)
			(xy 38.319723 -403.723096) (xy 38.263974 -403.714805) (xy 38.210052 -403.698401) (xy 38.159131 -403.674242)
			(xy 38.112317 -403.642854) (xy 38.09111 -403.624288) (xy 38.090602 -403.623526) (xy 38.087808 -403.620986)
			(xy 38.086792 -403.61997) (xy 38.081966 -403.615398) (xy 38.07079 -403.609302) (xy 38.061646 -403.607016)
			(xy 38.031928 -403.598634) (xy 38.022276 -403.59965) (xy 38.011623 -403.600168) (xy 37.991387 -403.593515)
			(xy 37.975588 -403.579225) (xy 37.966945 -403.559755) (xy 37.966396 -403.549104) (xy 37.966396 -403.34057)
			(xy 37.966773 -403.316313) (xy 37.972929 -403.26819) (xy 37.985151 -403.22124) (xy 37.993828 -403.198584)
			(xy 37.995606 -403.188678) (xy 37.979608 -403.150949) (xy 37.953129 -403.073388) (xy 37.933112 -402.993914)
			(xy 37.919691 -402.913064) (xy 37.912958 -402.831384) (xy 37.912548 -402.790406) (xy 37.912548 -402.408136)
			(xy 37.913023 -402.365147) (xy 37.920467 -402.27949) (xy 37.935251 -402.194792) (xy 37.945822 -402.15312)
			(xy 37.9476 -402.140166) (xy 37.945822 -402.127212) (xy 37.943028 -402.116544) (xy 37.93998 -402.10486)
			(xy 37.924994 -402.087334) (xy 37.829236 -402.045932) (xy 37.805614 -402.046948) (xy 37.7952 -402.05279)
			(xy 37.753719 -402.075191) (xy 37.66734 -402.112972) (xy 37.622734 -402.128228) (xy 37.593524 -402.15312)
			(xy 37.572078 -402.19294) (xy 37.523005 -402.268921) (xy 37.467255 -402.340148) (xy 37.405286 -402.406034)
			(xy 37.337606 -402.46604) (xy 37.264771 -402.519672) (xy 37.18738 -402.56649) (xy 37.106069 -402.60611)
			(xy 37.021504 -402.638205) (xy 36.934381 -402.662513) (xy 36.845415 -402.678833) (xy 36.755337 -402.687032)
			(xy 36.710112 -402.687536) (xy 36.665457 -402.687027) (xy 36.576507 -402.679022) (xy 36.488628 -402.6631)
			(xy 36.445444 -402.651722) (xy 36.436687 -402.649685) (xy 36.418783 -402.651205) (xy 36.402505 -402.658813)
			(xy 36.395914 -402.66493) (xy 36.389564 -402.67128) (xy 36.074604 -402.98624) (xy 36.041278 -403.018805)
			(xy 35.96953 -403.078264) (xy 35.892548 -403.130769) (xy 35.811003 -403.175863) (xy 35.725606 -403.213153)
			(xy 35.637102 -403.242312) (xy 35.546264 -403.263087) (xy 35.453885 -403.275296) (xy 35.407346 -403.277578)
			(xy 35.394693 -403.27878) (xy 35.37285 -403.291713) (xy 35.36569 -403.302216) (xy 35.343284 -403.338767)
			(xy 35.293105 -403.408288) (xy 35.237143 -403.473245) (xy 35.17581 -403.533156) (xy 35.10956 -403.587581)
			(xy 35.038881 -403.636115) (xy 34.964295 -403.678402) (xy 34.886355 -403.714129) (xy 34.805635 -403.743031)
			(xy 34.722731 -403.764896) (xy 34.638256 -403.779562) (xy 34.552833 -403.786921) (xy 34.509964 -403.787356)
			(xy 34.509202 -403.787356) (xy 34.466328 -403.786875) (xy 34.380901 -403.77947) (xy 34.296425 -403.764759)
			(xy 34.213524 -403.742849) (xy 34.13281 -403.713902) (xy 34.093658 -403.696424) (xy 34.083244 -403.698964)
			(xy 34.079942 -403.69998) (xy 34.078164 -403.700488) (xy 34.07791 -403.700488) (xy 34.060608 -403.70654)
			(xy 34.025113 -403.715695) (xy 34.007044 -403.718776) (xy 34.00679 -403.718776) (xy 34.003234 -403.719284)
			(xy 34.000694 -403.719792) (xy 33.99663 -403.7203) (xy 33.996122 -403.7203) (xy 33.994852 -403.720554)
			(xy 33.994598 -403.720554) (xy 33.990026 -403.721062) (xy 33.989518 -403.721062) (xy 33.963864 -403.723094)
			(xy 33.960816 -403.723094) (xy 33.957514 -403.723348) (xy 33.94583 -403.723348) (xy 33.918674 -403.722722)
			(xy 33.864948 -403.714727) (xy 33.812899 -403.699194) (xy 33.763579 -403.676436) (xy 33.717985 -403.646914)
			(xy 33.677038 -403.611224) (xy 33.641567 -403.570088) (xy 33.612288 -403.524338) (xy 33.589793 -403.474897)
			(xy 33.574537 -403.422766) (xy 33.566828 -403.368999) (xy 33.566354 -403.34184) (xy 33.566354 -403.340316)
			(xy 33.567081 -403.307445) (xy 33.578443 -403.24269) (xy 33.58896 -403.211538) (xy 33.589976 -403.208998)
			(xy 33.590484 -403.206966) (xy 33.592262 -403.201886) (xy 33.594802 -403.187408) (xy 33.594802 -403.1869)
			(xy 33.588706 -403.172422) (xy 33.570529 -403.127004) (xy 33.542104 -403.033391) (xy 33.522989 -402.937443)
			(xy 33.513367 -402.840084) (xy 33.51276 -402.791168) (xy 33.51276 -402.407374) (xy 33.513228 -402.364517)
			(xy 33.520602 -402.279121) (xy 33.535277 -402.194672) (xy 33.54578 -402.15312) (xy 33.547558 -402.140166)
			(xy 33.54578 -402.127212) (xy 33.542986 -402.116544) (xy 33.539938 -402.10486) (xy 33.524952 -402.087334)
			(xy 33.429194 -402.045932) (xy 33.405572 -402.046948) (xy 33.395158 -402.05279) (xy 33.353678 -402.075193)
			(xy 33.267301 -402.112979) (xy 33.222692 -402.128228) (xy 33.193482 -402.15312) (xy 33.172037 -402.192942)
			(xy 33.122965 -402.268926) (xy 33.067216 -402.340156) (xy 33.005247 -402.406046) (xy 32.937568 -402.466056)
			(xy 32.864734 -402.519692) (xy 32.787343 -402.566515) (xy 32.706032 -402.606139) (xy 32.621467 -402.638239)
			(xy 32.534343 -402.662551) (xy 32.445376 -402.678876) (xy 32.355296 -402.68708) (xy 32.31007 -402.687536)
			(xy 32.265416 -402.687025) (xy 32.176466 -402.679016) (xy 32.088588 -402.663091) (xy 32.045402 -402.651722)
			(xy 32.036642 -402.649675) (xy 32.018726 -402.651177) (xy 32.002432 -402.658775) (xy 31.995872 -402.66493)
			(xy 31.989522 -402.67128) (xy 31.674562 -402.98624) (xy 31.641236 -403.018803) (xy 31.569487 -403.078259)
			(xy 31.492504 -403.130762) (xy 31.410958 -403.175852) (xy 31.325561 -403.213138) (xy 31.237058 -403.242294)
			(xy 31.14622 -403.263065) (xy 31.053841 -403.27527) (xy 31.007304 -403.277578) (xy 30.994643 -403.278767)
			(xy 30.972778 -403.291688) (xy 30.965648 -403.302216) (xy 30.943241 -403.338766) (xy 30.893062 -403.408285)
			(xy 30.837099 -403.473239) (xy 30.775766 -403.533148) (xy 30.709515 -403.587569) (xy 30.638835 -403.636101)
			(xy 30.56425 -403.678385) (xy 30.48631 -403.714108) (xy 30.405589 -403.743008) (xy 30.322686 -403.764869)
			(xy 30.238212 -403.779532) (xy 30.152791 -403.786887) (xy 30.109922 -403.787356) (xy 30.109668 -403.787356)
			(xy 30.068552 -403.786937) (xy 29.9866 -403.780166) (xy 29.905485 -403.766666) (xy 29.825758 -403.746528)
			(xy 29.747961 -403.719888) (xy 29.710126 -403.70379) (xy 29.693362 -403.696424) (xy 29.68498 -403.698202)
			(xy 29.677868 -403.700742) (xy 29.671772 -403.702774) (xy 29.663136 -403.705822) (xy 29.662628 -403.705822)
			(xy 29.634646 -403.714086) (xy 29.576991 -403.723015) (xy 29.54782 -403.723602) (xy 29.519639 -403.723098)
			(xy 29.463889 -403.714808) (xy 29.409965 -403.698406) (xy 29.359042 -403.674249) (xy 29.312227 -403.642862)
			(xy 29.291026 -403.624288) (xy 29.290518 -403.623526) (xy 29.287724 -403.620986) (xy 29.286708 -403.61997)
			(xy 29.281882 -403.615398) (xy 29.270706 -403.609302) (xy 29.261562 -403.607016) (xy 29.231844 -403.598634)
			(xy 29.222192 -403.59965) (xy 29.211537 -403.600171) (xy 29.191294 -403.593522) (xy 29.175491 -403.579231)
			(xy 29.166844 -403.559757) (xy 29.166312 -403.549104) (xy 29.166312 -403.34057) (xy 29.166689 -403.316313)
			(xy 29.172845 -403.26819) (xy 29.185067 -403.22124) (xy 29.193744 -403.198584) (xy 29.195522 -403.188678)
			(xy 29.179525 -403.150949) (xy 29.153049 -403.073388) (xy 29.133033 -402.993913) (xy 29.119614 -402.913063)
			(xy 29.112881 -402.831384) (xy 29.112464 -402.790406) (xy 29.112464 -402.408136) (xy 29.112939 -402.365147)
			(xy 29.120383 -402.279491) (xy 29.135167 -402.194792) (xy 29.145738 -402.15312) (xy 29.147516 -402.140166)
			(xy 29.145738 -402.127212) (xy 29.142944 -402.116544) (xy 29.139896 -402.10486) (xy 29.12491 -402.087334)
			(xy 29.029152 -402.045932) (xy 29.00553 -402.046948) (xy 28.995116 -402.05279) (xy 28.953635 -402.075192)
			(xy 28.867257 -402.112974) (xy 28.82265 -402.128228) (xy 28.79344 -402.15312) (xy 28.771994 -402.192941)
			(xy 28.722922 -402.268923) (xy 28.667172 -402.34015) (xy 28.605203 -402.406038) (xy 28.537523 -402.466045)
			(xy 28.464689 -402.519678) (xy 28.387298 -402.566497) (xy 28.305986 -402.606118) (xy 28.221421 -402.638214)
			(xy 28.134298 -402.662523) (xy 28.045332 -402.678845) (xy 27.955253 -402.687045) (xy 27.910028 -402.687536)
			(xy 27.867098 -402.687066) (xy 27.781559 -402.679638) (xy 27.696976 -402.66488) (xy 27.613977 -402.6429)
			(xy 27.533176 -402.61386) (xy 27.493976 -402.59635) (xy 27.484578 -402.598382) (xy 27.452909 -402.609666)
			(xy 27.386862 -402.622195) (xy 27.35326 -402.623274) (xy 27.348942 -402.623274) (xy 27.320659 -402.622832)
			(xy 27.264693 -402.614624) (xy 27.21055 -402.598248) (xy 27.159417 -402.574063) (xy 27.112412 -402.542597)
			(xy 27.091132 -402.52396) (xy 27.090624 -402.523452) (xy 27.086814 -402.519896) (xy 27.081988 -402.515324)
			(xy 27.070812 -402.509228) (xy 27.061668 -402.506942) (xy 27.03195 -402.49856) (xy 27.022298 -402.499576)
			(xy 27.01164 -402.500099) (xy 26.991391 -402.493451) (xy 26.975579 -402.479161) (xy 26.966923 -402.459686)
			(xy 26.966418 -402.44903) (xy 26.966418 -402.241004) (xy 26.966785 -402.217702) (xy 26.972494 -402.171447)
			(xy 26.983791 -402.126232) (xy 26.991818 -402.104352) (xy 26.993342 -402.100542) (xy 26.995628 -402.089874)
			(xy 26.995628 -402.087842) (xy 26.979676 -402.050155) (xy 26.953276 -401.972686) (xy 26.93332 -401.893312)
			(xy 26.919941 -401.812569) (xy 26.91323 -401.731) (xy 26.912824 -401.690078) (xy 26.912824 -401.308062)
			(xy 26.913017 -401.27629) (xy 26.916959 -401.212868) (xy 26.920698 -401.181316) (xy 26.921206 -401.178014)
			(xy 26.921206 -400.90217) (xy 26.920698 -400.898868) (xy 26.916965 -400.867315) (xy 26.913026 -400.803894)
			(xy 26.912824 -400.772122) (xy 26.912824 -400.390106) (xy 26.913016 -400.358334) (xy 26.916955 -400.294912)
			(xy 26.920698 -400.26336) (xy 26.921206 -400.260058) (xy 26.921206 -400.001486) (xy 26.921632 -399.991417)
			(xy 26.929351 -399.972817) (xy 26.936192 -399.965418) (xy 26.956766 -399.944844) (xy 26.963346 -399.937462)
			(xy 26.970794 -399.919163) (xy 26.971244 -399.909284) (xy 26.971244 -399.899124) (xy 26.970736 -399.895314)
			(xy 26.968809 -399.881869) (xy 26.966651 -399.854792) (xy 26.966418 -399.841212) (xy 26.966418 -399.838418)
			(xy 26.966899 -399.811224) (xy 26.974621 -399.757388) (xy 26.989911 -399.705194) (xy 27.012458 -399.6557)
			(xy 27.041807 -399.609911) (xy 27.077361 -399.568754) (xy 27.1184 -399.533064) (xy 27.164092 -399.503564)
			(xy 27.21351 -399.480853) (xy 27.265653 -399.465391) (xy 27.319464 -399.457491) (xy 27.346656 -399.45691)
			(xy 27.356054 -399.45691) (xy 27.35961 -399.457164) (xy 27.361388 -399.457164) (xy 27.370607 -399.456785)
			(xy 27.387859 -399.450281) (xy 27.401679 -399.438078) (xy 27.41027 -399.421764) (xy 27.412513 -399.403464)
			(xy 27.410664 -399.394426) (xy 27.407616 -399.381726) (xy 27.40406 -399.375376) (xy 27.386905 -399.343819)
			(xy 27.359642 -399.277365) (xy 27.340777 -399.208058) (xy 27.330596 -399.136954) (xy 27.329384 -399.101056)
			(xy 27.329384 -399.099024) (xy 27.32913 -399.090134) (xy 27.329612 -399.056133) (xy 27.337547 -398.988596)
			(xy 27.353312 -398.922447) (xy 27.376692 -398.858591) (xy 27.407367 -398.797901) (xy 27.444918 -398.741208)
			(xy 27.488831 -398.689286) (xy 27.538505 -398.642845) (xy 27.593261 -398.602521) (xy 27.65235 -398.568866)
			(xy 27.714964 -398.542339) (xy 27.747468 -398.53235) (xy 27.751278 -398.531334) (xy 27.757882 -398.528286)
			(xy 27.764994 -398.524222) (xy 27.76845 -398.522136) (xy 27.774699 -398.517026) (xy 27.77744 -398.514062)
			(xy 27.794966 -398.491456) (xy 27.799253 -398.485052) (xy 27.804156 -398.470448) (xy 27.804618 -398.462754)
			(xy 27.804618 -398.453864) (xy 27.804124 -398.44386) (xy 27.796459 -398.425377) (xy 27.782308 -398.411231)
			(xy 27.763822 -398.403572) (xy 27.753818 -398.403064) (xy 27.551888 -398.403064) (xy 27.542403 -398.402636)
			(xy 27.524696 -398.395829) (xy 27.510608 -398.383124) (xy 27.505914 -398.37487) (xy 27.505152 -398.373346)
			(xy 27.50439 -398.37106) (xy 27.502645 -398.366424) (xy 27.500735 -398.356707) (xy 27.50058 -398.351756)
			(xy 27.50058 -398.07007) (xy 27.499056 -398.058132) (xy 27.494992 -398.042892) (xy 27.491182 -398.036542)
			(xy 27.475259 -398.008424) (xy 27.45017 -397.948875) (xy 27.433195 -397.886526) (xy 27.424635 -397.822477)
			(xy 27.424639 -397.757858) (xy 27.433208 -397.69381) (xy 27.450191 -397.631463) (xy 27.475288 -397.571918)
			(xy 27.491182 -397.543782) (xy 27.494992 -397.537432) (xy 27.499056 -397.522192) (xy 27.50058 -397.510254)
			(xy 27.50058 -396.770098) (xy 27.498548 -396.756128) (xy 27.497024 -396.75054) (xy 27.495246 -396.743428)
			(xy 27.491436 -396.737078) (xy 27.475474 -396.708936) (xy 27.450313 -396.64933) (xy 27.433272 -396.586915)
			(xy 27.424653 -396.522793) (xy 27.424126 -396.490444) (xy 27.424126 -396.49019) (xy 27.424687 -396.457588)
			(xy 27.433481 -396.392979) (xy 27.441652 -396.361412) (xy 27.450965 -396.32981) (xy 27.476962 -396.269274)
			(xy 27.493468 -396.240762) (xy 27.498802 -396.228062) (xy 27.50058 -396.221966) (xy 27.50058 -396.072106)
			(xy 27.500326 -395.92885) (xy 27.500807 -395.918716) (xy 27.508524 -395.899977) (xy 27.522811 -395.885602)
			(xy 27.541503 -395.877769) (xy 27.551634 -395.877288) (xy 27.753818 -395.877288) (xy 27.763822 -395.876797)
			(xy 27.782306 -395.869134) (xy 27.79645 -395.854981) (xy 27.804103 -395.836493) (xy 27.804618 -395.826488)
			(xy 27.804618 -395.811756) (xy 27.799792 -395.799564) (xy 27.796998 -395.792198) (xy 27.776932 -395.76629)
			(xy 27.770074 -395.761718) (xy 27.752294 -395.749526) (xy 27.744674 -395.746986) (xy 27.712363 -395.736879)
			(xy 27.650155 -395.710162) (xy 27.591473 -395.676396) (xy 27.537115 -395.636036) (xy 27.487818 -395.589631)
			(xy 27.444249 -395.53781) (xy 27.406999 -395.481275) (xy 27.376574 -395.420794) (xy 27.353387 -395.357186)
			(xy 27.337751 -395.291313) (xy 27.329878 -395.224069) (xy 27.329384 -395.190218) (xy 27.329384 -395.186916)
			(xy 27.330012 -395.154034) (xy 27.337772 -395.088725) (xy 27.344878 -395.056614) (xy 27.344878 -395.05636)
			(xy 27.346402 -395.050772) (xy 27.348198 -395.040519) (xy 27.344393 -395.020073) (xy 27.339036 -395.011148)
			(xy 27.339036 -395.010894) (xy 27.17038 -394.758672) (xy 27.17038 -394.758164) (xy 27.152092 -394.730732)
			(xy 27.087322 -394.633958) (xy 27.082935 -394.62784) (xy 27.071311 -394.618286) (xy 27.064462 -394.615162)
			(xy 26.803858 -394.507212) (xy 26.80335 -394.507212) (xy 26.77287 -394.494258) (xy 26.772362 -394.494512)
			(xy 26.394664 -394.33754) (xy 26.016458 -394.181076) (xy 26.016204 -394.180568) (xy 25.75306 -394.071602)
			(xy 25.752552 -394.071602) (xy 25.722072 -394.058648) (xy 25.721564 -394.058902) (xy 25.343866 -393.90193)
			(xy 24.96566 -393.745466) (xy 24.963882 -393.74191) (xy 24.951944 -393.712954) (xy 24.951944 -393.712446)
			(xy 24.90343 -393.596368) (xy 24.899529 -393.588876) (xy 24.88772 -393.576811) (xy 24.880316 -393.572746)
			(xy 24.26208 -393.31646) (xy 24.257493 -393.314412) (xy 24.249176 -393.308781) (xy 24.24557 -393.305284)
			(xy 24.236426 -393.29614) (xy 24.234648 -393.294108) (xy 24.222937 -393.284782) (xy 24.195541 -393.27275)
			(xy 24.165834 -393.269171) (xy 24.136364 -393.274353) (xy 24.109659 -393.28785) (xy 24.08801 -393.308506)
			(xy 24.080216 -393.321286) (xy 24.065551 -393.346069) (xy 24.029936 -393.39132) (xy 23.987933 -393.430714)
			(xy 23.940495 -393.463359) (xy 23.888696 -393.488516) (xy 23.833708 -393.505615) (xy 23.776776 -393.514269)
			(xy 23.747984 -393.514834) (xy 23.720714 -393.514369) (xy 23.666731 -393.506605) (xy 23.614402 -393.491237)
			(xy 23.564792 -393.468578) (xy 23.518913 -393.43909) (xy 23.477697 -393.403372) (xy 23.441984 -393.362152)
			(xy 23.4125 -393.316269) (xy 23.389847 -393.266657) (xy 23.374485 -393.214326) (xy 23.366727 -393.160342)
			(xy 23.366222 -393.133072) (xy 23.366786 -393.102946) (xy 23.376248 -393.043442) (xy 23.394949 -392.986165)
			(xy 23.422424 -392.932542) (xy 23.457988 -392.883906) (xy 23.478998 -392.862308) (xy 23.488169 -392.852589)
			(xy 23.501538 -392.82946) (xy 23.508459 -392.803657) (xy 23.508459 -392.776942) (xy 23.501538 -392.751139)
			(xy 23.488168 -392.72801) (xy 23.478998 -392.71829) (xy 23.208234 -392.447526) (xy 23.200614 -392.439906)
			(xy 23.20036 -392.439398) (xy 22.129242 -391.368534) (xy 22.122401 -391.361134) (xy 22.114684 -391.342535)
			(xy 22.114256 -391.332466) (xy 22.114256 -391.217912) (xy 22.113834 -391.207842) (xy 22.106118 -391.189238)
			(xy 22.09927 -391.181844) (xy 20.80387 -389.88619) (xy 20.773049 -389.854704) (xy 20.716452 -389.787168)
			(xy 20.69084 -389.751316) (xy 20.6883 -389.74776) (xy 20.661884 -389.721344) (xy 20.624544 -389.682952)
			(xy 20.557466 -389.599458) (xy 20.528026 -389.55472) (xy 20.505018 -389.517779) (xy 20.464829 -389.440576)
			(xy 20.447762 -389.400542) (xy 20.353782 -389.173974) (xy 20.352512 -389.171942) (xy 19.673316 -387.532626)
			(xy 19.672808 -387.531102) (xy 18.877026 -385.762754) (xy 18.858962 -385.721306) (xy 18.829524 -385.635811)
			(xy 18.80794 -385.548003) (xy 18.794388 -385.458603) (xy 18.791174 -385.413504) (xy 18.777204 -385.185412)
			(xy 18.775172 -385.173474) (xy 15.499842 -374.701816) (xy 15.499334 -374.700038) (xy 15.497556 -374.69445)
			(xy 15.497556 -317.744094) (xy 15.501874 -317.73368) (xy 16.1671 -316.12713) (xy 16.183864 -316.086744)
			(xy 16.46301 -315.412628) (xy 17.050766 -313.992768) (xy 17.05229 -313.982354) (xy 17.05229 -308.150768)
			(xy 17.052036 -308.145942) (xy 17.049496 -308.130194) (xy 17.047972 -308.125622) (xy 17.041368 -308.106318)
			(xy 17.03578 -308.09946) (xy 17.018548 -308.077006) (xy 16.990206 -308.028013) (xy 16.969415 -307.975369)
			(xy 16.956632 -307.920232) (xy 16.952135 -307.863811) (xy 16.956025 -307.807345) (xy 16.968216 -307.752074)
			(xy 16.988441 -307.69921) (xy 17.016254 -307.649916) (xy 17.03324 -307.627274) (xy 17.036288 -307.623464)
			(xy 17.042638 -307.611526) (xy 17.04467 -307.607716) (xy 17.04975 -307.592222) (xy 17.050877 -307.58851)
			(xy 17.052149 -307.580859) (xy 17.05229 -307.576982) (xy 17.05229 -302.771302) (xy 17.051528 -302.766984)
			(xy 17.04975 -302.756316) (xy 17.04594 -302.74387) (xy 17.045178 -302.742346) (xy 17.012037 -302.663771)
			(xy 16.952768 -302.503847) (xy 16.901646 -302.341135) (xy 16.858799 -302.176051) (xy 16.824338 -302.009016)
			(xy 16.798351 -301.840454) (xy 16.780903 -301.670795) (xy 16.772039 -301.500472) (xy 16.771366 -301.415196)
			(xy 16.771366 -301.409862) (xy 16.771904 -301.324096) (xy 16.780608 -301.152785) (xy 16.797994 -300.982136)
			(xy 16.824017 -300.81259) (xy 16.85861 -300.644582) (xy 16.901683 -300.478546) (xy 16.953126 -300.314909)
			(xy 17.012806 -300.154094) (xy 17.046194 -300.075092) (xy 17.046956 -300.073568) (xy 17.052544 -300.060614)
			(xy 17.05229 -300.049946) (xy 17.05229 -257.09118) (xy 17.052196 -257.086302) (xy 17.050411 -257.076711)
			(xy 17.048734 -257.07213) (xy 17.044924 -257.062986) (xy 15.226792 -255.244854) (xy 15.223941 -255.242148)
			(xy 15.217563 -255.237554) (xy 15.214092 -255.23571) (xy 15.208666 -255.233123) (xy 15.196986 -255.23029)
			(xy 15.190978 -255.230122) (xy 12.725908 -255.230122) (xy 12.716277 -255.2306) (xy 12.698401 -255.237796)
			(xy 12.684404 -255.25104) (xy 12.679934 -255.259586) (xy 12.671044 -255.27889) (xy 12.671044 -255.279398)
			(xy 12.646406 -255.334516) (xy 12.644302 -255.339465) (xy 12.642007 -255.349969) (xy 12.641834 -255.355344)
			(xy 12.641834 -255.370838) (xy 12.641955 -255.375386) (xy 12.643611 -255.384332) (xy 12.645136 -255.388618)
			(xy 12.648184 -255.397) (xy 12.65428 -255.404112) (xy 12.671681 -255.425013) (xy 12.701005 -255.470814)
			(xy 12.723529 -255.520315) (xy 12.738797 -255.572512) (xy 12.746499 -255.626348) (xy 12.74699 -255.65354)
			(xy 12.746501 -255.680789) (xy 12.73874 -255.734731) (xy 12.723381 -255.78702) (xy 12.700737 -255.836591)
			(xy 12.67127 -255.882435) (xy 12.635578 -255.923619) (xy 12.594389 -255.959305) (xy 12.54854 -255.988765)
			(xy 12.498966 -256.011401) (xy 12.446675 -256.026752) (xy 12.392731 -256.034505) (xy 12.365482 -256.035048)
			(xy 12.337743 -256.034549) (xy 12.28285 -256.026514) (xy 12.2297 -256.010616) (xy 12.17941 -255.98719)
			(xy 12.133043 -255.95673) (xy 12.091574 -255.919877) (xy 12.055879 -255.877408) (xy 12.026708 -255.830219)
			(xy 12.004677 -255.779303) (xy 11.99025 -255.725734) (xy 11.986514 -255.698244) (xy 11.98499 -255.684528)
			(xy 11.983317 -255.658794) (xy 11.986084 -255.6073) (xy 11.995762 -255.556648) (xy 12.012173 -255.50776)
			(xy 12.035019 -255.461528) (xy 12.063883 -255.418794) (xy 12.080748 -255.399286) (xy 12.081002 -255.399032)
			(xy 12.085652 -255.393436) (xy 12.091839 -255.380273) (xy 12.093194 -255.373124) (xy 12.09421 -255.366266)
			(xy 12.092432 -255.351788) (xy 12.070588 -255.302512) (xy 12.051792 -255.260348) (xy 12.051792 -255.260094)
			(xy 12.047788 -255.252059) (xy 12.035236 -255.239238) (xy 12.019039 -255.23152) (xy 12.010136 -255.230376)
			(xy 12.005564 -255.230122) (xy 11.086084 -255.230122) (xy 11.075938 -255.230564) (xy 11.057222 -255.238401)
			(xy 11.04298 -255.252855) (xy 11.03884 -255.262126) (xy 11.027664 -255.29413) (xy 11.027664 -255.294638)
			(xy 11.006836 -255.354582) (xy 11.006328 -255.356868) (xy 11.004296 -255.362964) (xy 11.004042 -255.378458)
			(xy 11.006328 -255.385824) (xy 11.008783 -255.393159) (xy 11.017453 -255.405959) (xy 11.023346 -255.41097)
			(xy 11.0236 -255.411224) (xy 11.04584 -255.429431) (xy 11.085118 -255.471392) (xy 11.117661 -255.518767)
			(xy 11.142733 -255.570486) (xy 11.159767 -255.625379) (xy 11.168377 -255.682206) (xy 11.168888 -255.710944)
			(xy 11.168888 -255.719072) (xy 11.168634 -255.726692) (xy 11.167019 -255.754477) (xy 11.15674 -255.809174)
			(xy 11.138625 -255.861797) (xy 11.113057 -255.911231) (xy 11.080578 -255.956425) (xy 11.041878 -255.996421)
			(xy 10.997778 -256.030371) (xy 10.949213 -256.057554) (xy 10.897215 -256.077393) (xy 10.842886 -256.089468)
			(xy 10.78738 -256.093521) (xy 10.731874 -256.089468) (xy 10.677545 -256.077393) (xy 10.625547 -256.057554)
			(xy 10.576982 -256.030371) (xy 10.532882 -255.996421) (xy 10.494182 -255.956425) (xy 10.461703 -255.911231)
			(xy 10.436135 -255.861797) (xy 10.41802 -255.809174) (xy 10.407741 -255.754477) (xy 10.406126 -255.726692)
			(xy 10.405872 -255.719072) (xy 10.405872 -255.709928) (xy 10.406522 -255.681385) (xy 10.41526 -255.624965)
			(xy 10.432305 -255.570478) (xy 10.457277 -255.519137) (xy 10.489618 -255.472089) (xy 10.528608 -255.430385)
			(xy 10.550652 -255.41224) (xy 10.55878 -255.40589) (xy 10.564622 -255.395222) (xy 10.564876 -255.39446)
			(xy 10.567119 -255.390041) (xy 10.570052 -255.380575) (xy 10.570718 -255.375664) (xy 10.570718 -255.374648)
			(xy 10.573258 -255.340866) (xy 10.570464 -255.331976) (xy 10.569448 -255.328166) (xy 10.567929 -255.323)
			(xy 10.563064 -255.313396) (xy 10.559796 -255.309116) (xy 10.551922 -255.299464) (xy 10.548683 -255.295306)
			(xy 10.543813 -255.285961) (xy 10.54227 -255.280922) (xy 10.54227 -255.280668) (xy 10.541508 -255.278128)
			(xy 10.536174 -255.263396) (xy 10.533814 -255.257623) (xy 10.526747 -255.247349) (xy 10.522204 -255.243076)
			(xy 10.515122 -255.237271) (xy 10.498073 -255.230624) (xy 10.48893 -255.230122) (xy 9.67613 -255.230122)
			(xy 9.669245 -255.230393) (xy 9.65599 -255.234138) (xy 9.649968 -255.237488) (xy 9.643364 -255.241552)
			(xy 9.634728 -255.251204) (xy 9.631426 -255.2573) (xy 9.626346 -255.266952) (xy 9.589516 -255.33731)
			(xy 9.586566 -255.34349) (xy 9.583725 -255.356881) (xy 9.583928 -255.363726) (xy 9.58469 -255.377442)
			(xy 9.592818 -255.38938) (xy 9.608659 -255.413327) (xy 9.63373 -255.464978) (xy 9.650762 -255.519807)
			(xy 9.65937 -255.576573) (xy 9.659874 -255.60528) (xy 9.659874 -255.611376) (xy 9.658996 -255.638355)
			(xy 9.650574 -255.691671) (xy 9.634721 -255.743269) (xy 9.611754 -255.792116) (xy 9.582129 -255.837238)
			(xy 9.546441 -255.877734) (xy 9.5054 -255.912794) (xy 9.459826 -255.941719) (xy 9.410631 -255.963932)
			(xy 9.358795 -255.978987) (xy 9.305355 -255.986586) (xy 9.278366 -255.987042) (xy 9.274048 -255.987042)
			(xy 9.246013 -255.986254) (xy 9.190622 -255.977459) (xy 9.13712 -255.960639) (xy 9.08666 -255.93616)
			(xy 9.063228 -255.920748) (xy 9.046982 -255.909389) (xy 9.016695 -255.883809) (xy 9.002776 -255.869694)
			(xy 8.995918 -255.862582) (xy 8.960104 -255.846834) (xy 8.948674 -255.847088) (xy 8.938556 -255.846844)
			(xy 8.919754 -255.839397) (xy 8.905284 -255.825269) (xy 8.897389 -255.806651) (xy 8.896858 -255.796542)
			(xy 8.896858 -255.60528) (xy 8.897345 -255.577347) (xy 8.905487 -255.522076) (xy 8.921593 -255.468582)
			(xy 8.945319 -255.418004) (xy 8.960358 -255.39446) (xy 8.963914 -255.389126) (xy 8.97255 -255.364742)
			(xy 8.971534 -255.353312) (xy 8.970518 -255.342644) (xy 8.929116 -255.264158) (xy 8.928608 -255.263142)
			(xy 8.9281 -255.262634) (xy 8.926068 -255.258824) (xy 8.922755 -255.252462) (xy 8.913215 -255.241759)
			(xy 8.907272 -255.237742) (xy 8.90143 -255.233932) (xy 8.887714 -255.230122) (xy 8.102346 -255.230122)
			(xy 8.090408 -255.231646) (xy 8.079364 -255.23501) (xy 8.061559 -255.249657) (xy 8.056118 -255.25984)
			(xy 8.039862 -255.295654) (xy 8.039862 -255.296162) (xy 8.018018 -255.34493) (xy 8.015307 -255.351697)
			(xy 8.01336 -255.366138) (xy 8.014208 -255.373378) (xy 8.015478 -255.380744) (xy 8.02132 -255.393698)
			(xy 8.0264 -255.399286) (xy 8.04452 -255.420378) (xy 8.075097 -255.466819) (xy 8.098614 -255.517205)
			(xy 8.114575 -255.570469) (xy 8.122642 -255.625484) (xy 8.123174 -255.653286) (xy 8.122712 -255.680539)
			(xy 8.114956 -255.734489) (xy 8.099601 -255.786787) (xy 8.076959 -255.836367) (xy 8.047491 -255.882219)
			(xy 8.011796 -255.923411) (xy 7.970603 -255.959103) (xy 7.924749 -255.988568) (xy 7.875168 -256.011208)
			(xy 7.82287 -256.02656) (xy 7.768919 -256.034313) (xy 7.741666 -256.034794) (xy 7.713927 -256.034294)
			(xy 7.659034 -256.026258) (xy 7.605882 -256.010359) (xy 7.555592 -255.986933) (xy 7.509224 -255.956473)
			(xy 7.467753 -255.919621) (xy 7.432055 -255.877154) (xy 7.40288 -255.829966) (xy 7.380845 -255.779051)
			(xy 7.366412 -255.725483) (xy 7.362698 -255.69799) (xy 7.361174 -255.684274) (xy 7.359506 -255.65857)
			(xy 7.362267 -255.607136) (xy 7.371919 -255.55654) (xy 7.388286 -255.507702) (xy 7.411071 -255.461507)
			(xy 7.43986 -255.418795) (xy 7.456678 -255.399286) (xy 7.456932 -255.399032) (xy 7.461581 -255.393435)
			(xy 7.467764 -255.380272) (xy 7.469124 -255.373124) (xy 7.47014 -255.366012) (xy 7.468362 -255.351534)
			(xy 7.427214 -255.260094) (xy 7.422813 -255.251392) (xy 7.408776 -255.237881) (xy 7.390725 -255.230547)
			(xy 7.380986 -255.230122) (xy 6.591808 -255.230122) (xy 6.583096 -255.231048) (xy 6.567025 -255.237992)
			(xy 6.554226 -255.249937) (xy 6.549898 -255.257554) (xy 6.54685 -255.26365) (xy 6.509258 -255.340612)
			(xy 6.506409 -255.347012) (xy 6.503957 -255.360801) (xy 6.504432 -255.36779) (xy 6.50494 -255.374648)
			(xy 6.510274 -255.387856) (xy 6.514592 -255.393444) (xy 6.529447 -255.413483) (xy 6.554382 -255.456685)
			(xy 6.573471 -255.502771) (xy 6.586388 -255.550951) (xy 6.592912 -255.600405) (xy 6.593332 -255.625346)
			(xy 6.593332 -255.633982) (xy 6.592302 -255.660852) (xy 6.583623 -255.713919) (xy 6.567578 -255.76524)
			(xy 6.544483 -255.8138) (xy 6.514797 -255.858634) (xy 6.479108 -255.898855) (xy 6.438124 -255.933665)
			(xy 6.392657 -255.962373) (xy 6.343609 -255.984411) (xy 6.291952 -255.999342) (xy 6.23871 -256.006869)
			(xy 6.211824 -256.007362) (xy 6.18493 -256.006897) (xy 6.131675 -255.999334) (xy 6.080011 -255.984369)
			(xy 6.030959 -255.962298) (xy 5.985491 -255.933559) (xy 5.944509 -255.898721) (xy 5.908825 -255.858474)
			(xy 5.879145 -255.813615) (xy 5.856057 -255.765034) (xy 5.840019 -255.713692) (xy 5.831348 -255.660607)
			(xy 5.830316 -255.633728) (xy 5.830316 -255.625346) (xy 5.830738 -255.600405) (xy 5.837269 -255.550953)
			(xy 5.850187 -255.502773) (xy 5.86927 -255.456686) (xy 5.894195 -255.413478) (xy 5.909056 -255.393444)
			(xy 5.913374 -255.387856) (xy 5.918708 -255.374648) (xy 5.919216 -255.36779) (xy 5.919697 -255.3608)
			(xy 5.91725 -255.347008) (xy 5.91439 -255.340612) (xy 5.88264 -255.275334) (xy 5.882386 -255.27508)
			(xy 5.874004 -255.258316) (xy 5.870406 -255.251691) (xy 5.860084 -255.240711) (xy 5.853684 -255.236726)
			(xy 5.84792 -255.233667) (xy 5.835314 -255.230316) (xy 5.828792 -255.230122) (xy 1.00076 -255.230122)
			(xy 0.990693 -255.230553) (xy 0.972102 -255.23828) (xy 0.964692 -255.245108) (xy 0.649986 -255.559814)
			(xy 0.643132 -255.567209) (xy 0.63539 -255.585808) (xy 0.635 -255.595882) (xy 0.635 -255.732026)
			(xy 3.944364 -255.732026) (xy 3.948435 -255.676404) (xy 3.960561 -255.621967) (xy 3.980484 -255.569876)
			(xy 4.00778 -255.521241) (xy 4.041866 -255.477098) (xy 4.082015 -255.438389) (xy 4.127373 -255.405938)
			(xy 4.176973 -255.380437) (xy 4.229757 -255.36243) (xy 4.2846 -255.3523) (xy 4.340334 -255.350263)
			(xy 4.395771 -255.356363) (xy 4.449728 -255.370469) (xy 4.501057 -255.392281) (xy 4.548663 -255.421335)
			(xy 4.591531 -255.45701) (xy 4.628748 -255.498547) (xy 4.659521 -255.54506) (xy 4.683193 -255.595557)
			(xy 4.699261 -255.648964) (xy 4.707381 -255.70414) (xy 4.70789 -255.732026) (xy 4.707381 -255.759912)
			(xy 4.699261 -255.815088) (xy 4.683193 -255.868495) (xy 4.659521 -255.918992) (xy 4.628748 -255.965505)
			(xy 4.591531 -256.007042) (xy 4.548663 -256.042717) (xy 4.501057 -256.071771) (xy 4.449728 -256.093583)
			(xy 4.395771 -256.107689) (xy 4.340334 -256.113789) (xy 4.2846 -256.111752) (xy 4.229757 -256.101622)
			(xy 4.176973 -256.083615) (xy 4.127373 -256.058114) (xy 4.082015 -256.025663) (xy 4.041866 -255.986954)
			(xy 4.00778 -255.942811) (xy 3.980484 -255.894176) (xy 3.960561 -255.842085) (xy 3.948435 -255.787648)
			(xy 3.944364 -255.732026) (xy 0.635 -255.732026) (xy 0.635 -256.516124) (xy 3.26466 -256.516124)
			(xy 3.268731 -256.460502) (xy 3.280857 -256.406065) (xy 3.30078 -256.353974) (xy 3.328076 -256.305339)
			(xy 3.362162 -256.261196) (xy 3.402311 -256.222487) (xy 3.447669 -256.190036) (xy 3.497269 -256.164535)
			(xy 3.550053 -256.146528) (xy 3.604896 -256.136398) (xy 3.66063 -256.134361) (xy 3.716067 -256.140461)
			(xy 3.770024 -256.154567) (xy 3.821353 -256.176379) (xy 3.868959 -256.205433) (xy 3.911827 -256.241108)
			(xy 3.949044 -256.282645) (xy 3.979817 -256.329158) (xy 4.003489 -256.379655) (xy 4.019557 -256.433062)
			(xy 4.025875 -256.475992) (xy 4.752846 -256.475992) (xy 4.756917 -256.42037) (xy 4.769043 -256.365933)
			(xy 4.788966 -256.313842) (xy 4.816262 -256.265207) (xy 4.850348 -256.221064) (xy 4.890497 -256.182355)
			(xy 4.935855 -256.149904) (xy 4.985455 -256.124403) (xy 5.038239 -256.106396) (xy 5.093082 -256.096266)
			(xy 5.148816 -256.094229) (xy 5.204253 -256.100329) (xy 5.25821 -256.114435) (xy 5.309539 -256.136247)
			(xy 5.357145 -256.165301) (xy 5.400013 -256.200976) (xy 5.43723 -256.242513) (xy 5.468003 -256.289026)
			(xy 5.491675 -256.339523) (xy 5.507743 -256.39293) (xy 5.515863 -256.448106) (xy 5.516372 -256.475992)
			(xy 5.515863 -256.503878) (xy 5.511108 -256.53619) (xy 6.261352 -256.53619) (xy 6.265423 -256.480568)
			(xy 6.277549 -256.426131) (xy 6.297472 -256.37404) (xy 6.324768 -256.325405) (xy 6.358854 -256.281262)
			(xy 6.399003 -256.242553) (xy 6.444361 -256.210102) (xy 6.493961 -256.184601) (xy 6.546745 -256.166594)
			(xy 6.601588 -256.156464) (xy 6.657322 -256.154427) (xy 6.712759 -256.160527) (xy 6.766716 -256.174633)
			(xy 6.818045 -256.196445) (xy 6.865651 -256.225499) (xy 6.908519 -256.261174) (xy 6.945736 -256.302711)
			(xy 6.976509 -256.349224) (xy 7.000181 -256.399721) (xy 7.016249 -256.453128) (xy 7.019614 -256.475992)
			(xy 7.769604 -256.475992) (xy 7.773675 -256.42037) (xy 7.785801 -256.365933) (xy 7.805724 -256.313842)
			(xy 7.83302 -256.265207) (xy 7.867106 -256.221064) (xy 7.907255 -256.182355) (xy 7.952613 -256.149904)
			(xy 8.002213 -256.124403) (xy 8.054997 -256.106396) (xy 8.10984 -256.096266) (xy 8.165574 -256.094229)
			(xy 8.221011 -256.100329) (xy 8.274968 -256.114435) (xy 8.326297 -256.136247) (xy 8.373903 -256.165301)
			(xy 8.416771 -256.200976) (xy 8.453988 -256.242513) (xy 8.484761 -256.289026) (xy 8.508433 -256.339523)
			(xy 8.513192 -256.355342) (xy 9.479024 -256.355342) (xy 9.483095 -256.29972) (xy 9.495221 -256.245283)
			(xy 9.515144 -256.193192) (xy 9.54244 -256.144557) (xy 9.576526 -256.100414) (xy 9.616675 -256.061705)
			(xy 9.662033 -256.029254) (xy 9.711633 -256.003753) (xy 9.764417 -255.985746) (xy 9.81926 -255.975616)
			(xy 9.874994 -255.973579) (xy 9.930431 -255.979679) (xy 9.984388 -255.993785) (xy 10.035717 -256.015597)
			(xy 10.083323 -256.044651) (xy 10.126191 -256.080326) (xy 10.163408 -256.121863) (xy 10.194181 -256.168376)
			(xy 10.217853 -256.218873) (xy 10.233921 -256.27228) (xy 10.242041 -256.327456) (xy 10.24255 -256.355342)
			(xy 10.242041 -256.383228) (xy 10.237286 -256.41554) (xy 11.047728 -256.41554) (xy 11.051799 -256.359918)
			(xy 11.063925 -256.305481) (xy 11.083848 -256.25339) (xy 11.111144 -256.204755) (xy 11.14523 -256.160612)
			(xy 11.185379 -256.121903) (xy 11.230737 -256.089452) (xy 11.280337 -256.063951) (xy 11.333121 -256.045944)
			(xy 11.387964 -256.035814) (xy 11.443698 -256.033777) (xy 11.499135 -256.039877) (xy 11.553092 -256.053983)
			(xy 11.604421 -256.075795) (xy 11.652027 -256.104849) (xy 11.694895 -256.140524) (xy 11.732112 -256.182061)
			(xy 11.762885 -256.228574) (xy 11.786557 -256.279071) (xy 11.802625 -256.332478) (xy 11.810745 -256.387654)
			(xy 11.811254 -256.41554) (xy 11.810888 -256.435606) (xy 12.455396 -256.435606) (xy 12.459467 -256.379984)
			(xy 12.471593 -256.325547) (xy 12.491516 -256.273456) (xy 12.518812 -256.224821) (xy 12.552898 -256.180678)
			(xy 12.593047 -256.141969) (xy 12.638405 -256.109518) (xy 12.688005 -256.084017) (xy 12.740789 -256.06601)
			(xy 12.795632 -256.05588) (xy 12.851366 -256.053843) (xy 12.906803 -256.059943) (xy 12.96076 -256.074049)
			(xy 13.012089 -256.095861) (xy 13.059695 -256.124915) (xy 13.102563 -256.16059) (xy 13.13978 -256.202127)
			(xy 13.170553 -256.24864) (xy 13.194225 -256.299137) (xy 13.210293 -256.352544) (xy 13.218413 -256.40772)
			(xy 13.218922 -256.435606) (xy 13.218413 -256.463492) (xy 13.210293 -256.518668) (xy 13.194225 -256.572075)
			(xy 13.170553 -256.622572) (xy 13.13978 -256.669085) (xy 13.102563 -256.710622) (xy 13.059695 -256.746297)
			(xy 13.012089 -256.775351) (xy 12.96076 -256.797163) (xy 12.906803 -256.811269) (xy 12.851366 -256.817369)
			(xy 12.795632 -256.815332) (xy 12.740789 -256.805202) (xy 12.688005 -256.787195) (xy 12.638405 -256.761694)
			(xy 12.593047 -256.729243) (xy 12.552898 -256.690534) (xy 12.518812 -256.646391) (xy 12.491516 -256.597756)
			(xy 12.471593 -256.545665) (xy 12.459467 -256.491228) (xy 12.455396 -256.435606) (xy 11.810888 -256.435606)
			(xy 11.810745 -256.443426) (xy 11.802625 -256.498602) (xy 11.786557 -256.552009) (xy 11.762885 -256.602506)
			(xy 11.732112 -256.649019) (xy 11.694895 -256.690556) (xy 11.652027 -256.726231) (xy 11.604421 -256.755285)
			(xy 11.553092 -256.777097) (xy 11.499135 -256.791203) (xy 11.443698 -256.797303) (xy 11.387964 -256.795266)
			(xy 11.333121 -256.785136) (xy 11.280337 -256.767129) (xy 11.230737 -256.741628) (xy 11.185379 -256.709177)
			(xy 11.14523 -256.670468) (xy 11.111144 -256.626325) (xy 11.083848 -256.57769) (xy 11.063925 -256.525599)
			(xy 11.051799 -256.471162) (xy 11.047728 -256.41554) (xy 10.237286 -256.41554) (xy 10.233921 -256.438404)
			(xy 10.217853 -256.491811) (xy 10.194181 -256.542308) (xy 10.163408 -256.588821) (xy 10.126191 -256.630358)
			(xy 10.083323 -256.666033) (xy 10.035717 -256.695087) (xy 9.984388 -256.716899) (xy 9.930431 -256.731005)
			(xy 9.874994 -256.737105) (xy 9.81926 -256.735068) (xy 9.764417 -256.724938) (xy 9.711633 -256.706931)
			(xy 9.662033 -256.68143) (xy 9.616675 -256.648979) (xy 9.576526 -256.61027) (xy 9.54244 -256.566127)
			(xy 9.515144 -256.517492) (xy 9.495221 -256.465401) (xy 9.483095 -256.410964) (xy 9.479024 -256.355342)
			(xy 8.513192 -256.355342) (xy 8.524501 -256.39293) (xy 8.532621 -256.448106) (xy 8.53313 -256.475992)
			(xy 8.532621 -256.503878) (xy 8.524501 -256.559054) (xy 8.508433 -256.612461) (xy 8.484761 -256.662958)
			(xy 8.453988 -256.709471) (xy 8.416771 -256.751008) (xy 8.373903 -256.786683) (xy 8.326297 -256.815737)
			(xy 8.274968 -256.837549) (xy 8.221011 -256.851655) (xy 8.165574 -256.857755) (xy 8.10984 -256.855718)
			(xy 8.054997 -256.845588) (xy 8.002213 -256.827581) (xy 7.952613 -256.80208) (xy 7.907255 -256.769629)
			(xy 7.867106 -256.73092) (xy 7.83302 -256.686777) (xy 7.805724 -256.638142) (xy 7.785801 -256.586051)
			(xy 7.773675 -256.531614) (xy 7.769604 -256.475992) (xy 7.019614 -256.475992) (xy 7.024369 -256.508304)
			(xy 7.024878 -256.53619) (xy 7.024369 -256.564076) (xy 7.016249 -256.619252) (xy 7.000181 -256.672659)
			(xy 6.976509 -256.723156) (xy 6.945736 -256.769669) (xy 6.908519 -256.811206) (xy 6.865651 -256.846881)
			(xy 6.818045 -256.875935) (xy 6.766716 -256.897747) (xy 6.712759 -256.911853) (xy 6.657322 -256.917953)
			(xy 6.601588 -256.915916) (xy 6.546745 -256.905786) (xy 6.493961 -256.887779) (xy 6.444361 -256.862278)
			(xy 6.399003 -256.829827) (xy 6.358854 -256.791118) (xy 6.324768 -256.746975) (xy 6.297472 -256.69834)
			(xy 6.277549 -256.646249) (xy 6.265423 -256.591812) (xy 6.261352 -256.53619) (xy 5.511108 -256.53619)
			(xy 5.507743 -256.559054) (xy 5.491675 -256.612461) (xy 5.468003 -256.662958) (xy 5.43723 -256.709471)
			(xy 5.400013 -256.751008) (xy 5.357145 -256.786683) (xy 5.309539 -256.815737) (xy 5.25821 -256.837549)
			(xy 5.204253 -256.851655) (xy 5.148816 -256.857755) (xy 5.093082 -256.855718) (xy 5.038239 -256.845588)
			(xy 4.985455 -256.827581) (xy 4.935855 -256.80208) (xy 4.890497 -256.769629) (xy 4.850348 -256.73092)
			(xy 4.816262 -256.686777) (xy 4.788966 -256.638142) (xy 4.769043 -256.586051) (xy 4.756917 -256.531614)
			(xy 4.752846 -256.475992) (xy 4.025875 -256.475992) (xy 4.027677 -256.488238) (xy 4.028186 -256.516124)
			(xy 4.027677 -256.54401) (xy 4.019557 -256.599186) (xy 4.003489 -256.652593) (xy 3.979817 -256.70309)
			(xy 3.949044 -256.749603) (xy 3.911827 -256.79114) (xy 3.868959 -256.826815) (xy 3.821353 -256.855869)
			(xy 3.770024 -256.877681) (xy 3.716067 -256.891787) (xy 3.66063 -256.897887) (xy 3.604896 -256.89585)
			(xy 3.550053 -256.88572) (xy 3.497269 -256.867713) (xy 3.447669 -256.842212) (xy 3.402311 -256.809761)
			(xy 3.362162 -256.771052) (xy 3.328076 -256.726909) (xy 3.30078 -256.678274) (xy 3.280857 -256.626183)
			(xy 3.268731 -256.571746) (xy 3.26466 -256.516124) (xy 0.635 -256.516124) (xy 0.635 -257.60807) (xy 3.22402 -257.60807)
			(xy 3.228091 -257.552448) (xy 3.240217 -257.498011) (xy 3.26014 -257.44592) (xy 3.287436 -257.397285)
			(xy 3.321522 -257.353142) (xy 3.361671 -257.314433) (xy 3.407029 -257.281982) (xy 3.456629 -257.256481)
			(xy 3.509413 -257.238474) (xy 3.564256 -257.228344) (xy 3.61999 -257.226307) (xy 3.675427 -257.232407)
			(xy 3.729384 -257.246513) (xy 3.780713 -257.268325) (xy 3.828319 -257.297379) (xy 3.871187 -257.333054)
			(xy 3.908404 -257.374591) (xy 3.939177 -257.421104) (xy 3.962849 -257.471601) (xy 3.978917 -257.525008)
			(xy 3.987037 -257.580184) (xy 3.987546 -257.60807) (xy 4.74802 -257.60807) (xy 4.752091 -257.552448)
			(xy 4.764217 -257.498011) (xy 4.78414 -257.44592) (xy 4.811436 -257.397285) (xy 4.845522 -257.353142)
			(xy 4.885671 -257.314433) (xy 4.931029 -257.281982) (xy 4.980629 -257.256481) (xy 5.033413 -257.238474)
			(xy 5.088256 -257.228344) (xy 5.14399 -257.226307) (xy 5.199427 -257.232407) (xy 5.253384 -257.246513)
			(xy 5.304713 -257.268325) (xy 5.352319 -257.297379) (xy 5.395187 -257.333054) (xy 5.432404 -257.374591)
			(xy 5.463177 -257.421104) (xy 5.486849 -257.471601) (xy 5.502917 -257.525008) (xy 5.511037 -257.580184)
			(xy 5.511546 -257.60807) (xy 7.03402 -257.60807) (xy 7.038091 -257.552448) (xy 7.050217 -257.498011)
			(xy 7.07014 -257.44592) (xy 7.097436 -257.397285) (xy 7.131522 -257.353142) (xy 7.171671 -257.314433)
			(xy 7.217029 -257.281982) (xy 7.266629 -257.256481) (xy 7.319413 -257.238474) (xy 7.374256 -257.228344)
			(xy 7.42999 -257.226307) (xy 7.485427 -257.232407) (xy 7.539384 -257.246513) (xy 7.590713 -257.268325)
			(xy 7.638319 -257.297379) (xy 7.681187 -257.333054) (xy 7.718404 -257.374591) (xy 7.749177 -257.421104)
			(xy 7.772849 -257.471601) (xy 7.788917 -257.525008) (xy 7.797037 -257.580184) (xy 7.797546 -257.60807)
			(xy 8.55802 -257.60807) (xy 8.562091 -257.552448) (xy 8.574217 -257.498011) (xy 8.59414 -257.44592)
			(xy 8.621436 -257.397285) (xy 8.655522 -257.353142) (xy 8.695671 -257.314433) (xy 8.741029 -257.281982)
			(xy 8.790629 -257.256481) (xy 8.843413 -257.238474) (xy 8.898256 -257.228344) (xy 8.95399 -257.226307)
			(xy 9.009427 -257.232407) (xy 9.063384 -257.246513) (xy 9.114713 -257.268325) (xy 9.162319 -257.297379)
			(xy 9.205187 -257.333054) (xy 9.242404 -257.374591) (xy 9.273177 -257.421104) (xy 9.296849 -257.471601)
			(xy 9.312917 -257.525008) (xy 9.321037 -257.580184) (xy 9.321546 -257.60807) (xy 10.08202 -257.60807)
			(xy 10.086091 -257.552448) (xy 10.098217 -257.498011) (xy 10.11814 -257.44592) (xy 10.145436 -257.397285)
			(xy 10.179522 -257.353142) (xy 10.219671 -257.314433) (xy 10.265029 -257.281982) (xy 10.314629 -257.256481)
			(xy 10.367413 -257.238474) (xy 10.422256 -257.228344) (xy 10.47799 -257.226307) (xy 10.533427 -257.232407)
			(xy 10.587384 -257.246513) (xy 10.638713 -257.268325) (xy 10.686319 -257.297379) (xy 10.729187 -257.333054)
			(xy 10.766404 -257.374591) (xy 10.797177 -257.421104) (xy 10.820849 -257.471601) (xy 10.836917 -257.525008)
			(xy 10.845037 -257.580184) (xy 10.845546 -257.60807) (xy 11.60602 -257.60807) (xy 11.610091 -257.552448)
			(xy 11.622217 -257.498011) (xy 11.64214 -257.44592) (xy 11.669436 -257.397285) (xy 11.703522 -257.353142)
			(xy 11.743671 -257.314433) (xy 11.789029 -257.281982) (xy 11.838629 -257.256481) (xy 11.891413 -257.238474)
			(xy 11.946256 -257.228344) (xy 12.00199 -257.226307) (xy 12.057427 -257.232407) (xy 12.111384 -257.246513)
			(xy 12.162713 -257.268325) (xy 12.210319 -257.297379) (xy 12.253187 -257.333054) (xy 12.290404 -257.374591)
			(xy 12.321177 -257.421104) (xy 12.344849 -257.471601) (xy 12.360917 -257.525008) (xy 12.369037 -257.580184)
			(xy 12.369546 -257.60807) (xy 13.13002 -257.60807) (xy 13.134091 -257.552448) (xy 13.146217 -257.498011)
			(xy 13.16614 -257.44592) (xy 13.193436 -257.397285) (xy 13.227522 -257.353142) (xy 13.267671 -257.314433)
			(xy 13.313029 -257.281982) (xy 13.362629 -257.256481) (xy 13.415413 -257.238474) (xy 13.470256 -257.228344)
			(xy 13.52599 -257.226307) (xy 13.581427 -257.232407) (xy 13.635384 -257.246513) (xy 13.686713 -257.268325)
			(xy 13.734319 -257.297379) (xy 13.777187 -257.333054) (xy 13.814404 -257.374591) (xy 13.845177 -257.421104)
			(xy 13.868849 -257.471601) (xy 13.884917 -257.525008) (xy 13.893037 -257.580184) (xy 13.893546 -257.60807)
			(xy 13.893037 -257.635956) (xy 13.884917 -257.691132) (xy 13.868849 -257.744539) (xy 13.845177 -257.795036)
			(xy 13.814404 -257.841549) (xy 13.777187 -257.883086) (xy 13.734319 -257.918761) (xy 13.686713 -257.947815)
			(xy 13.635384 -257.969627) (xy 13.581427 -257.983733) (xy 13.52599 -257.989833) (xy 13.470256 -257.987796)
			(xy 13.415413 -257.977666) (xy 13.362629 -257.959659) (xy 13.313029 -257.934158) (xy 13.267671 -257.901707)
			(xy 13.227522 -257.862998) (xy 13.193436 -257.818855) (xy 13.16614 -257.77022) (xy 13.146217 -257.718129)
			(xy 13.134091 -257.663692) (xy 13.13002 -257.60807) (xy 12.369546 -257.60807) (xy 12.369037 -257.635956)
			(xy 12.360917 -257.691132) (xy 12.344849 -257.744539) (xy 12.321177 -257.795036) (xy 12.290404 -257.841549)
			(xy 12.253187 -257.883086) (xy 12.210319 -257.918761) (xy 12.162713 -257.947815) (xy 12.111384 -257.969627)
			(xy 12.057427 -257.983733) (xy 12.00199 -257.989833) (xy 11.946256 -257.987796) (xy 11.891413 -257.977666)
			(xy 11.838629 -257.959659) (xy 11.789029 -257.934158) (xy 11.743671 -257.901707) (xy 11.703522 -257.862998)
			(xy 11.669436 -257.818855) (xy 11.64214 -257.77022) (xy 11.622217 -257.718129) (xy 11.610091 -257.663692)
			(xy 11.60602 -257.60807) (xy 10.845546 -257.60807) (xy 10.845037 -257.635956) (xy 10.836917 -257.691132)
			(xy 10.820849 -257.744539) (xy 10.797177 -257.795036) (xy 10.766404 -257.841549) (xy 10.729187 -257.883086)
			(xy 10.686319 -257.918761) (xy 10.638713 -257.947815) (xy 10.587384 -257.969627) (xy 10.533427 -257.983733)
			(xy 10.47799 -257.989833) (xy 10.422256 -257.987796) (xy 10.367413 -257.977666) (xy 10.314629 -257.959659)
			(xy 10.265029 -257.934158) (xy 10.219671 -257.901707) (xy 10.179522 -257.862998) (xy 10.145436 -257.818855)
			(xy 10.11814 -257.77022) (xy 10.098217 -257.718129) (xy 10.086091 -257.663692) (xy 10.08202 -257.60807)
			(xy 9.321546 -257.60807) (xy 9.321037 -257.635956) (xy 9.312917 -257.691132) (xy 9.296849 -257.744539)
			(xy 9.273177 -257.795036) (xy 9.242404 -257.841549) (xy 9.205187 -257.883086) (xy 9.162319 -257.918761)
			(xy 9.114713 -257.947815) (xy 9.063384 -257.969627) (xy 9.009427 -257.983733) (xy 8.95399 -257.989833)
			(xy 8.898256 -257.987796) (xy 8.843413 -257.977666) (xy 8.790629 -257.959659) (xy 8.741029 -257.934158)
			(xy 8.695671 -257.901707) (xy 8.655522 -257.862998) (xy 8.621436 -257.818855) (xy 8.59414 -257.77022)
			(xy 8.574217 -257.718129) (xy 8.562091 -257.663692) (xy 8.55802 -257.60807) (xy 7.797546 -257.60807)
			(xy 7.797037 -257.635956) (xy 7.788917 -257.691132) (xy 7.772849 -257.744539) (xy 7.749177 -257.795036)
			(xy 7.718404 -257.841549) (xy 7.681187 -257.883086) (xy 7.638319 -257.918761) (xy 7.590713 -257.947815)
			(xy 7.539384 -257.969627) (xy 7.485427 -257.983733) (xy 7.42999 -257.989833) (xy 7.374256 -257.987796)
			(xy 7.319413 -257.977666) (xy 7.266629 -257.959659) (xy 7.217029 -257.934158) (xy 7.171671 -257.901707)
			(xy 7.131522 -257.862998) (xy 7.097436 -257.818855) (xy 7.07014 -257.77022) (xy 7.050217 -257.718129)
			(xy 7.038091 -257.663692) (xy 7.03402 -257.60807) (xy 5.511546 -257.60807) (xy 5.511037 -257.635956)
			(xy 5.502917 -257.691132) (xy 5.486849 -257.744539) (xy 5.463177 -257.795036) (xy 5.432404 -257.841549)
			(xy 5.395187 -257.883086) (xy 5.352319 -257.918761) (xy 5.304713 -257.947815) (xy 5.253384 -257.969627)
			(xy 5.199427 -257.983733) (xy 5.14399 -257.989833) (xy 5.088256 -257.987796) (xy 5.033413 -257.977666)
			(xy 4.980629 -257.959659) (xy 4.931029 -257.934158) (xy 4.885671 -257.901707) (xy 4.845522 -257.862998)
			(xy 4.811436 -257.818855) (xy 4.78414 -257.77022) (xy 4.764217 -257.718129) (xy 4.752091 -257.663692)
			(xy 4.74802 -257.60807) (xy 3.987546 -257.60807) (xy 3.987037 -257.635956) (xy 3.978917 -257.691132)
			(xy 3.962849 -257.744539) (xy 3.939177 -257.795036) (xy 3.908404 -257.841549) (xy 3.871187 -257.883086)
			(xy 3.828319 -257.918761) (xy 3.780713 -257.947815) (xy 3.729384 -257.969627) (xy 3.675427 -257.983733)
			(xy 3.61999 -257.989833) (xy 3.564256 -257.987796) (xy 3.509413 -257.977666) (xy 3.456629 -257.959659)
			(xy 3.407029 -257.934158) (xy 3.361671 -257.901707) (xy 3.321522 -257.862998) (xy 3.287436 -257.818855)
			(xy 3.26014 -257.77022) (xy 3.240217 -257.718129) (xy 3.228091 -257.663692) (xy 3.22402 -257.60807)
			(xy 0.635 -257.60807) (xy 0.635 -258.510786) (xy 3.22402 -258.510786) (xy 3.228091 -258.455164) (xy 3.240217 -258.400727)
			(xy 3.26014 -258.348636) (xy 3.287436 -258.300001) (xy 3.321522 -258.255858) (xy 3.361671 -258.217149)
			(xy 3.407029 -258.184698) (xy 3.456629 -258.159197) (xy 3.509413 -258.14119) (xy 3.564256 -258.13106)
			(xy 3.61999 -258.129023) (xy 3.675427 -258.135123) (xy 3.729384 -258.149229) (xy 3.780713 -258.171041)
			(xy 3.828319 -258.200095) (xy 3.871187 -258.23577) (xy 3.908404 -258.277307) (xy 3.939177 -258.32382)
			(xy 3.962849 -258.374317) (xy 3.978917 -258.427724) (xy 3.987037 -258.4829) (xy 3.987546 -258.510786)
			(xy 4.74802 -258.510786) (xy 4.752091 -258.455164) (xy 4.764217 -258.400727) (xy 4.78414 -258.348636)
			(xy 4.811436 -258.300001) (xy 4.845522 -258.255858) (xy 4.885671 -258.217149) (xy 4.931029 -258.184698)
			(xy 4.980629 -258.159197) (xy 5.033413 -258.14119) (xy 5.088256 -258.13106) (xy 5.14399 -258.129023)
			(xy 5.199427 -258.135123) (xy 5.253384 -258.149229) (xy 5.304713 -258.171041) (xy 5.352319 -258.200095)
			(xy 5.395187 -258.23577) (xy 5.432404 -258.277307) (xy 5.463177 -258.32382) (xy 5.486849 -258.374317)
			(xy 5.502917 -258.427724) (xy 5.511037 -258.4829) (xy 5.511546 -258.510786) (xy 6.27202 -258.510786)
			(xy 6.276091 -258.455164) (xy 6.288217 -258.400727) (xy 6.30814 -258.348636) (xy 6.335436 -258.300001)
			(xy 6.369522 -258.255858) (xy 6.409671 -258.217149) (xy 6.455029 -258.184698) (xy 6.504629 -258.159197)
			(xy 6.557413 -258.14119) (xy 6.612256 -258.13106) (xy 6.66799 -258.129023) (xy 6.723427 -258.135123)
			(xy 6.777384 -258.149229) (xy 6.828713 -258.171041) (xy 6.876319 -258.200095) (xy 6.919187 -258.23577)
			(xy 6.956404 -258.277307) (xy 6.987177 -258.32382) (xy 7.010849 -258.374317) (xy 7.026917 -258.427724)
			(xy 7.035037 -258.4829) (xy 7.035546 -258.510786) (xy 7.79602 -258.510786) (xy 7.800091 -258.455164)
			(xy 7.812217 -258.400727) (xy 7.83214 -258.348636) (xy 7.859436 -258.300001) (xy 7.893522 -258.255858)
			(xy 7.933671 -258.217149) (xy 7.979029 -258.184698) (xy 8.028629 -258.159197) (xy 8.081413 -258.14119)
			(xy 8.136256 -258.13106) (xy 8.19199 -258.129023) (xy 8.247427 -258.135123) (xy 8.301384 -258.149229)
			(xy 8.352713 -258.171041) (xy 8.400319 -258.200095) (xy 8.443187 -258.23577) (xy 8.480404 -258.277307)
			(xy 8.511177 -258.32382) (xy 8.534849 -258.374317) (xy 8.550917 -258.427724) (xy 8.559037 -258.4829)
			(xy 8.559546 -258.510786) (xy 9.32002 -258.510786) (xy 9.324091 -258.455164) (xy 9.336217 -258.400727)
			(xy 9.35614 -258.348636) (xy 9.383436 -258.300001) (xy 9.417522 -258.255858) (xy 9.457671 -258.217149)
			(xy 9.503029 -258.184698) (xy 9.552629 -258.159197) (xy 9.605413 -258.14119) (xy 9.660256 -258.13106)
			(xy 9.71599 -258.129023) (xy 9.771427 -258.135123) (xy 9.825384 -258.149229) (xy 9.876713 -258.171041)
			(xy 9.924319 -258.200095) (xy 9.967187 -258.23577) (xy 10.004404 -258.277307) (xy 10.035177 -258.32382)
			(xy 10.058849 -258.374317) (xy 10.074917 -258.427724) (xy 10.083037 -258.4829) (xy 10.083546 -258.510786)
			(xy 10.84402 -258.510786) (xy 10.848091 -258.455164) (xy 10.860217 -258.400727) (xy 10.88014 -258.348636)
			(xy 10.907436 -258.300001) (xy 10.941522 -258.255858) (xy 10.981671 -258.217149) (xy 11.027029 -258.184698)
			(xy 11.076629 -258.159197) (xy 11.129413 -258.14119) (xy 11.184256 -258.13106) (xy 11.23999 -258.129023)
			(xy 11.295427 -258.135123) (xy 11.349384 -258.149229) (xy 11.400713 -258.171041) (xy 11.448319 -258.200095)
			(xy 11.491187 -258.23577) (xy 11.528404 -258.277307) (xy 11.559177 -258.32382) (xy 11.582849 -258.374317)
			(xy 11.598917 -258.427724) (xy 11.607037 -258.4829) (xy 11.607546 -258.510786) (xy 11.607037 -258.538672)
			(xy 11.602805 -258.567428) (xy 11.988798 -258.567428) (xy 11.992869 -258.511806) (xy 12.004995 -258.457369)
			(xy 12.024918 -258.405278) (xy 12.052214 -258.356643) (xy 12.0863 -258.3125) (xy 12.126449 -258.273791)
			(xy 12.171807 -258.24134) (xy 12.221407 -258.215839) (xy 12.274191 -258.197832) (xy 12.329034 -258.187702)
			(xy 12.384768 -258.185665) (xy 12.440205 -258.191765) (xy 12.494162 -258.205871) (xy 12.545491 -258.227683)
			(xy 12.593097 -258.256737) (xy 12.635965 -258.292412) (xy 12.673182 -258.333949) (xy 12.703955 -258.380462)
			(xy 12.727627 -258.430959) (xy 12.743695 -258.484366) (xy 12.747583 -258.510786) (xy 13.13002 -258.510786)
			(xy 13.134091 -258.455164) (xy 13.146217 -258.400727) (xy 13.16614 -258.348636) (xy 13.193436 -258.300001)
			(xy 13.227522 -258.255858) (xy 13.267671 -258.217149) (xy 13.313029 -258.184698) (xy 13.362629 -258.159197)
			(xy 13.415413 -258.14119) (xy 13.470256 -258.13106) (xy 13.52599 -258.129023) (xy 13.581427 -258.135123)
			(xy 13.635384 -258.149229) (xy 13.686713 -258.171041) (xy 13.734319 -258.200095) (xy 13.777187 -258.23577)
			(xy 13.814404 -258.277307) (xy 13.845177 -258.32382) (xy 13.868849 -258.374317) (xy 13.884917 -258.427724)
			(xy 13.893037 -258.4829) (xy 13.893546 -258.510786) (xy 13.893037 -258.538672) (xy 13.884917 -258.593848)
			(xy 13.868849 -258.647255) (xy 13.845177 -258.697752) (xy 13.814404 -258.744265) (xy 13.777187 -258.785802)
			(xy 13.734319 -258.821477) (xy 13.686713 -258.850531) (xy 13.635384 -258.872343) (xy 13.581427 -258.886449)
			(xy 13.52599 -258.892549) (xy 13.470256 -258.890512) (xy 13.415413 -258.880382) (xy 13.362629 -258.862375)
			(xy 13.313029 -258.836874) (xy 13.267671 -258.804423) (xy 13.227522 -258.765714) (xy 13.193436 -258.721571)
			(xy 13.16614 -258.672936) (xy 13.146217 -258.620845) (xy 13.134091 -258.566408) (xy 13.13002 -258.510786)
			(xy 12.747583 -258.510786) (xy 12.751815 -258.539542) (xy 12.752324 -258.567428) (xy 12.751815 -258.595314)
			(xy 12.743695 -258.65049) (xy 12.727627 -258.703897) (xy 12.703955 -258.754394) (xy 12.673182 -258.800907)
			(xy 12.635965 -258.842444) (xy 12.593097 -258.878119) (xy 12.545491 -258.907173) (xy 12.494162 -258.928985)
			(xy 12.440205 -258.943091) (xy 12.384768 -258.949191) (xy 12.329034 -258.947154) (xy 12.274191 -258.937024)
			(xy 12.221407 -258.919017) (xy 12.171807 -258.893516) (xy 12.126449 -258.861065) (xy 12.0863 -258.822356)
			(xy 12.052214 -258.778213) (xy 12.024918 -258.729578) (xy 12.004995 -258.677487) (xy 11.992869 -258.62305)
			(xy 11.988798 -258.567428) (xy 11.602805 -258.567428) (xy 11.598917 -258.593848) (xy 11.582849 -258.647255)
			(xy 11.559177 -258.697752) (xy 11.528404 -258.744265) (xy 11.491187 -258.785802) (xy 11.448319 -258.821477)
			(xy 11.400713 -258.850531) (xy 11.349384 -258.872343) (xy 11.295427 -258.886449) (xy 11.23999 -258.892549)
			(xy 11.184256 -258.890512) (xy 11.129413 -258.880382) (xy 11.076629 -258.862375) (xy 11.027029 -258.836874)
			(xy 10.981671 -258.804423) (xy 10.941522 -258.765714) (xy 10.907436 -258.721571) (xy 10.88014 -258.672936)
			(xy 10.860217 -258.620845) (xy 10.848091 -258.566408) (xy 10.84402 -258.510786) (xy 10.083546 -258.510786)
			(xy 10.083037 -258.538672) (xy 10.074917 -258.593848) (xy 10.058849 -258.647255) (xy 10.035177 -258.697752)
			(xy 10.004404 -258.744265) (xy 9.967187 -258.785802) (xy 9.924319 -258.821477) (xy 9.876713 -258.850531)
			(xy 9.825384 -258.872343) (xy 9.771427 -258.886449) (xy 9.71599 -258.892549) (xy 9.660256 -258.890512)
			(xy 9.605413 -258.880382) (xy 9.552629 -258.862375) (xy 9.503029 -258.836874) (xy 9.457671 -258.804423)
			(xy 9.417522 -258.765714) (xy 9.383436 -258.721571) (xy 9.35614 -258.672936) (xy 9.336217 -258.620845)
			(xy 9.324091 -258.566408) (xy 9.32002 -258.510786) (xy 8.559546 -258.510786) (xy 8.559037 -258.538672)
			(xy 8.550917 -258.593848) (xy 8.534849 -258.647255) (xy 8.511177 -258.697752) (xy 8.480404 -258.744265)
			(xy 8.443187 -258.785802) (xy 8.400319 -258.821477) (xy 8.352713 -258.850531) (xy 8.301384 -258.872343)
			(xy 8.247427 -258.886449) (xy 8.19199 -258.892549) (xy 8.136256 -258.890512) (xy 8.081413 -258.880382)
			(xy 8.028629 -258.862375) (xy 7.979029 -258.836874) (xy 7.933671 -258.804423) (xy 7.893522 -258.765714)
			(xy 7.859436 -258.721571) (xy 7.83214 -258.672936) (xy 7.812217 -258.620845) (xy 7.800091 -258.566408)
			(xy 7.79602 -258.510786) (xy 7.035546 -258.510786) (xy 7.035037 -258.538672) (xy 7.026917 -258.593848)
			(xy 7.010849 -258.647255) (xy 6.987177 -258.697752) (xy 6.956404 -258.744265) (xy 6.919187 -258.785802)
			(xy 6.876319 -258.821477) (xy 6.828713 -258.850531) (xy 6.777384 -258.872343) (xy 6.723427 -258.886449)
			(xy 6.66799 -258.892549) (xy 6.612256 -258.890512) (xy 6.557413 -258.880382) (xy 6.504629 -258.862375)
			(xy 6.455029 -258.836874) (xy 6.409671 -258.804423) (xy 6.369522 -258.765714) (xy 6.335436 -258.721571)
			(xy 6.30814 -258.672936) (xy 6.288217 -258.620845) (xy 6.276091 -258.566408) (xy 6.27202 -258.510786)
			(xy 5.511546 -258.510786) (xy 5.511037 -258.538672) (xy 5.502917 -258.593848) (xy 5.486849 -258.647255)
			(xy 5.463177 -258.697752) (xy 5.432404 -258.744265) (xy 5.395187 -258.785802) (xy 5.352319 -258.821477)
			(xy 5.304713 -258.850531) (xy 5.253384 -258.872343) (xy 5.199427 -258.886449) (xy 5.14399 -258.892549)
			(xy 5.088256 -258.890512) (xy 5.033413 -258.880382) (xy 4.980629 -258.862375) (xy 4.931029 -258.836874)
			(xy 4.885671 -258.804423) (xy 4.845522 -258.765714) (xy 4.811436 -258.721571) (xy 4.78414 -258.672936)
			(xy 4.764217 -258.620845) (xy 4.752091 -258.566408) (xy 4.74802 -258.510786) (xy 3.987546 -258.510786)
			(xy 3.987037 -258.538672) (xy 3.978917 -258.593848) (xy 3.962849 -258.647255) (xy 3.939177 -258.697752)
			(xy 3.908404 -258.744265) (xy 3.871187 -258.785802) (xy 3.828319 -258.821477) (xy 3.780713 -258.850531)
			(xy 3.729384 -258.872343) (xy 3.675427 -258.886449) (xy 3.61999 -258.892549) (xy 3.564256 -258.890512)
			(xy 3.509413 -258.880382) (xy 3.456629 -258.862375) (xy 3.407029 -258.836874) (xy 3.361671 -258.804423)
			(xy 3.321522 -258.765714) (xy 3.287436 -258.721571) (xy 3.26014 -258.672936) (xy 3.240217 -258.620845)
			(xy 3.228091 -258.566408) (xy 3.22402 -258.510786) (xy 0.635 -258.510786) (xy 0.635 -270.644366)
			(xy 5.002276 -270.644366) (xy 5.002704 -270.616994) (xy 5.010528 -270.562813) (xy 5.026025 -270.510308)
			(xy 5.048876 -270.460562) (xy 5.07861 -270.414598) (xy 5.096256 -270.393668) (xy 5.09651 -270.393414)
			(xy 5.102098 -270.386328) (xy 5.108344 -270.369411) (xy 5.108702 -270.360394) (xy 5.108702 -270.293338)
			(xy 5.108327 -270.284323) (xy 5.102092 -270.267406) (xy 5.09651 -270.260318) (xy 5.096256 -270.260318)
			(xy 5.096256 -270.260064) (xy 5.078626 -270.239125) (xy 5.048914 -270.193153) (xy 5.026077 -270.143407)
			(xy 5.010584 -270.090909) (xy 5.002752 -270.036735) (xy 5.002276 -270.009366) (xy 5.002746 -269.982115)
			(xy 5.010507 -269.928167) (xy 5.025865 -269.875873) (xy 5.048509 -269.826297) (xy 5.077978 -269.780447)
			(xy 5.113671 -269.739258) (xy 5.154862 -269.703567) (xy 5.200713 -269.674101) (xy 5.25029 -269.651459)
			(xy 5.302585 -269.636103) (xy 5.356533 -269.628345) (xy 5.383784 -269.627858) (xy 5.412522 -269.628403)
			(xy 5.469348 -269.637022) (xy 5.524238 -269.654068) (xy 5.57595 -269.679154) (xy 5.623314 -269.711714)
			(xy 5.644642 -269.730982) (xy 5.6515 -269.737586) (xy 5.669534 -269.744698) (xy 5.758434 -269.744698)
			(xy 5.776468 -269.737586) (xy 5.783326 -269.730982) (xy 5.804653 -269.711712) (xy 5.852016 -269.679147)
			(xy 5.903727 -269.654056) (xy 5.958618 -269.637006) (xy 6.015445 -269.628384) (xy 6.072923 -269.628384)
			(xy 6.12975 -269.637006) (xy 6.184641 -269.654056) (xy 6.236352 -269.679147) (xy 6.283715 -269.711712)
			(xy 6.305042 -269.730982) (xy 6.3119 -269.737586) (xy 6.329934 -269.744698) (xy 6.418834 -269.744698)
			(xy 6.436868 -269.737586) (xy 6.443726 -269.730982) (xy 6.465053 -269.711712) (xy 6.512416 -269.679147)
			(xy 6.564127 -269.654056) (xy 6.619018 -269.637006) (xy 6.675845 -269.628384) (xy 6.733323 -269.628384)
			(xy 6.79015 -269.637006) (xy 6.845041 -269.654056) (xy 6.896752 -269.679147) (xy 6.944115 -269.711712)
			(xy 6.965442 -269.730982) (xy 6.9723 -269.737586) (xy 6.990334 -269.744698) (xy 7.079234 -269.744698)
			(xy 7.097268 -269.737586) (xy 7.104126 -269.730982) (xy 7.125466 -269.711726) (xy 7.172824 -269.679156)
			(xy 7.224532 -269.65406) (xy 7.27942 -269.637006) (xy 7.336246 -269.62838) (xy 7.364984 -269.627858)
			(xy 7.392235 -269.628344) (xy 7.446183 -269.636101) (xy 7.498477 -269.651456) (xy 7.548054 -269.674098)
			(xy 7.593904 -269.703564) (xy 7.635094 -269.739256) (xy 7.670786 -269.780446) (xy 7.700252 -269.826296)
			(xy 7.722894 -269.875873) (xy 7.738249 -269.928167) (xy 7.746006 -269.982115) (xy 7.746492 -270.009366)
			(xy 7.746008 -270.036736) (xy 7.738195 -270.090914) (xy 7.72271 -270.143417) (xy 7.699872 -270.193164)
			(xy 7.670151 -270.239132) (xy 7.652512 -270.260064) (xy 7.652258 -270.260318) (xy 7.646653 -270.267392)
			(xy 7.640418 -270.284318) (xy 7.640066 -270.293338) (xy 7.640066 -270.360394) (xy 7.640433 -270.36941)
			(xy 7.646675 -270.386326) (xy 7.652258 -270.393414) (xy 7.652512 -270.393414) (xy 7.652512 -270.393668)
			(xy 7.670151 -270.4146) (xy 7.699863 -270.460573) (xy 7.722698 -270.51032) (xy 7.730174 -270.535654)
			(xy 8.785098 -270.535654) (xy 8.785596 -270.508285) (xy 8.793406 -270.454107) (xy 8.808888 -270.401605)
			(xy 8.831723 -270.351857) (xy 8.86144 -270.305889) (xy 8.879078 -270.284956) (xy 8.879332 -270.284702)
			(xy 8.884927 -270.277622) (xy 8.891168 -270.2607) (xy 8.891524 -270.251682) (xy 8.891524 -270.184626)
			(xy 8.891149 -270.175611) (xy 8.884913 -270.158694) (xy 8.879332 -270.151606) (xy 8.879078 -270.151606)
			(xy 8.879078 -270.151352) (xy 8.861446 -270.130414) (xy 8.831734 -270.084442) (xy 8.808897 -270.034696)
			(xy 8.793404 -269.982197) (xy 8.785574 -269.928023) (xy 8.785098 -269.900654) (xy 8.785535 -269.873401)
			(xy 8.793298 -269.819452) (xy 8.808659 -269.767156) (xy 8.831306 -269.717578) (xy 8.860778 -269.671727)
			(xy 8.896474 -269.630537) (xy 8.937669 -269.594847) (xy 8.983523 -269.565381) (xy 9.033104 -269.542741)
			(xy 9.085402 -269.527387) (xy 9.139353 -269.519631) (xy 9.166606 -269.519146) (xy 9.195344 -269.519681)
			(xy 9.252171 -269.528303) (xy 9.307061 -269.545351) (xy 9.358772 -269.57044) (xy 9.406136 -269.603001)
			(xy 9.427464 -269.62227) (xy 9.434322 -269.628874) (xy 9.452356 -269.635986) (xy 9.541256 -269.635986)
			(xy 9.55929 -269.628874) (xy 9.566148 -269.62227) (xy 9.587475 -269.603) (xy 9.634838 -269.570435)
			(xy 9.686549 -269.545344) (xy 9.74144 -269.528294) (xy 9.798267 -269.519672) (xy 9.855745 -269.519672)
			(xy 9.912572 -269.528294) (xy 9.967463 -269.545344) (xy 10.019174 -269.570435) (xy 10.066537 -269.603)
			(xy 10.087864 -269.62227) (xy 10.094722 -269.628874) (xy 10.112756 -269.635986) (xy 10.201656 -269.635986)
			(xy 10.21969 -269.628874) (xy 10.226548 -269.62227) (xy 10.247875 -269.603) (xy 10.295238 -269.570435)
			(xy 10.346949 -269.545344) (xy 10.40184 -269.528294) (xy 10.458667 -269.519672) (xy 10.516145 -269.519672)
			(xy 10.572972 -269.528294) (xy 10.627863 -269.545344) (xy 10.679574 -269.570435) (xy 10.726937 -269.603)
			(xy 10.748264 -269.62227) (xy 10.755122 -269.628874) (xy 10.773156 -269.635986) (xy 10.862056 -269.635986)
			(xy 10.88009 -269.628874) (xy 10.886948 -269.62227) (xy 10.908277 -269.603002) (xy 10.955638 -269.570434)
			(xy 11.007349 -269.54534) (xy 11.06224 -269.528289) (xy 11.119067 -269.519667) (xy 11.147806 -269.519146)
			(xy 11.175059 -269.519609) (xy 11.22901 -269.527366) (xy 11.281308 -269.542721) (xy 11.330889 -269.565364)
			(xy 11.376742 -269.594832) (xy 11.417935 -269.630525) (xy 11.453628 -269.671718) (xy 11.483096 -269.717571)
			(xy 11.505739 -269.767152) (xy 11.521094 -269.81945) (xy 11.528851 -269.873401) (xy 11.529314 -269.900654)
			(xy 11.528818 -269.928023) (xy 11.521007 -269.982201) (xy 11.505524 -270.034703) (xy 11.48269 -270.084451)
			(xy 11.452972 -270.130419) (xy 11.435334 -270.151352) (xy 11.43508 -270.151606) (xy 11.429483 -270.158685)
			(xy 11.423243 -270.175608) (xy 11.422888 -270.184626) (xy 11.422888 -270.251682) (xy 11.423256 -270.260698)
			(xy 11.429496 -270.277615) (xy 11.43508 -270.284702) (xy 11.435334 -270.284702) (xy 11.435334 -270.284956)
			(xy 11.452971 -270.305889) (xy 11.482682 -270.351862) (xy 11.505518 -270.40161) (xy 11.52101 -270.45411)
			(xy 11.528839 -270.508285) (xy 11.529314 -270.535654) (xy 11.528802 -270.562905) (xy 11.521051 -270.616854)
			(xy 11.505701 -270.669151) (xy 11.483065 -270.71873) (xy 11.453602 -270.764584) (xy 11.417913 -270.805777)
			(xy 11.376725 -270.841471) (xy 11.330876 -270.87094) (xy 11.2813 -270.893583) (xy 11.229005 -270.90894)
			(xy 11.175057 -270.916698) (xy 11.147806 -270.917162) (xy 11.119068 -270.916618) (xy 11.062242 -270.907998)
			(xy 11.007352 -270.890952) (xy 10.95564 -270.865865) (xy 10.908276 -270.833306) (xy 10.886948 -270.814038)
			(xy 10.88009 -270.807434) (xy 10.862056 -270.800322) (xy 10.773156 -270.800322) (xy 10.755122 -270.807434)
			(xy 10.748264 -270.814038) (xy 10.726937 -270.833308) (xy 10.679574 -270.865873) (xy 10.627863 -270.890964)
			(xy 10.572972 -270.908014) (xy 10.516145 -270.916636) (xy 10.458667 -270.916636) (xy 10.40184 -270.908014)
			(xy 10.346949 -270.890964) (xy 10.295238 -270.865873) (xy 10.247875 -270.833308) (xy 10.226548 -270.814038)
			(xy 10.21969 -270.807434) (xy 10.201656 -270.800322) (xy 10.112756 -270.800322) (xy 10.094722 -270.807434)
			(xy 10.087864 -270.814038) (xy 10.066537 -270.833308) (xy 10.019174 -270.865873) (xy 9.967463 -270.890964)
			(xy 9.912572 -270.908014) (xy 9.855745 -270.916636) (xy 9.798267 -270.916636) (xy 9.74144 -270.908014)
			(xy 9.686549 -270.890964) (xy 9.634838 -270.865873) (xy 9.587475 -270.833308) (xy 9.566148 -270.814038)
			(xy 9.55929 -270.807434) (xy 9.541256 -270.800322) (xy 9.452356 -270.800322) (xy 9.434322 -270.807434)
			(xy 9.427464 -270.814038) (xy 9.406131 -270.833302) (xy 9.358771 -270.86587) (xy 9.307061 -270.890964)
			(xy 9.252171 -270.908016) (xy 9.195345 -270.916641) (xy 9.166606 -270.917162) (xy 9.139355 -270.916676)
			(xy 9.085407 -270.908919) (xy 9.033113 -270.893564) (xy 8.983536 -270.870922) (xy 8.937686 -270.841456)
			(xy 8.896496 -270.805764) (xy 8.860804 -270.764574) (xy 8.831338 -270.718724) (xy 8.808696 -270.669147)
			(xy 8.793341 -270.616853) (xy 8.785584 -270.562905) (xy 8.785098 -270.535654) (xy 7.730174 -270.535654)
			(xy 7.73819 -270.562821) (xy 7.746018 -270.616997) (xy 7.746492 -270.644366) (xy 7.746013 -270.671619)
			(xy 7.73826 -270.72557) (xy 7.722908 -270.777868) (xy 7.700268 -270.82745) (xy 7.670802 -270.873304)
			(xy 7.63511 -270.914497) (xy 7.593918 -270.950191) (xy 7.548065 -270.979659) (xy 7.498485 -271.002301)
			(xy 7.446188 -271.017656) (xy 7.392237 -271.025412) (xy 7.364984 -271.025874) (xy 7.336246 -271.02534)
			(xy 7.27942 -271.016717) (xy 7.22453 -270.999668) (xy 7.172818 -270.974579) (xy 7.125454 -270.942018)
			(xy 7.104126 -270.92275) (xy 7.097268 -270.916146) (xy 7.079234 -270.909034) (xy 6.990334 -270.909034)
			(xy 6.9723 -270.916146) (xy 6.965442 -270.92275) (xy 6.944115 -270.94202) (xy 6.896752 -270.974585)
			(xy 6.845041 -270.999676) (xy 6.79015 -271.016726) (xy 6.733323 -271.025348) (xy 6.675845 -271.025348)
			(xy 6.619018 -271.016726) (xy 6.564127 -270.999676) (xy 6.512416 -270.974585) (xy 6.465053 -270.94202)
			(xy 6.443726 -270.92275) (xy 6.436868 -270.916146) (xy 6.418834 -270.909034) (xy 6.329934 -270.909034)
			(xy 6.3119 -270.916146) (xy 6.305042 -270.92275) (xy 6.283715 -270.94202) (xy 6.236352 -270.974585)
			(xy 6.184641 -270.999676) (xy 6.12975 -271.016726) (xy 6.072923 -271.025348) (xy 6.015445 -271.025348)
			(xy 5.958618 -271.016726) (xy 5.903727 -270.999676) (xy 5.852016 -270.974585) (xy 5.804653 -270.94202)
			(xy 5.783326 -270.92275) (xy 5.776468 -270.916146) (xy 5.758434 -270.909034) (xy 5.669534 -270.909034)
			(xy 5.6515 -270.916146) (xy 5.644642 -270.92275) (xy 5.62332 -270.942026) (xy 5.575957 -270.974592)
			(xy 5.524244 -270.999684) (xy 5.469352 -271.016733) (xy 5.412523 -271.025354) (xy 5.383784 -271.025874)
			(xy 5.356531 -271.025411) (xy 5.30258 -271.017654) (xy 5.250282 -271.002299) (xy 5.200701 -270.979656)
			(xy 5.154848 -270.950188) (xy 5.113655 -270.914495) (xy 5.077962 -270.873302) (xy 5.048494 -270.827449)
			(xy 5.025851 -270.777868) (xy 5.010496 -270.72557) (xy 5.002739 -270.671619) (xy 5.002276 -270.644366)
			(xy 0.635 -270.644366) (xy 0.635 -272.345912) (xy 11.635738 -272.345912) (xy 11.639809 -272.29029)
			(xy 11.651935 -272.235853) (xy 11.671858 -272.183762) (xy 11.699154 -272.135127) (xy 11.73324 -272.090984)
			(xy 11.773389 -272.052275) (xy 11.818747 -272.019824) (xy 11.868347 -271.994323) (xy 11.921131 -271.976316)
			(xy 11.975974 -271.966186) (xy 12.031708 -271.964149) (xy 12.087145 -271.970249) (xy 12.141102 -271.984355)
			(xy 12.192431 -272.006167) (xy 12.240037 -272.035221) (xy 12.282905 -272.070896) (xy 12.320122 -272.112433)
			(xy 12.350895 -272.158946) (xy 12.374567 -272.209443) (xy 12.390635 -272.26285) (xy 12.398755 -272.318026)
			(xy 12.399264 -272.345912) (xy 12.398755 -272.373798) (xy 12.390635 -272.428974) (xy 12.374894 -272.481294)
			(xy 13.765528 -272.481294) (xy 13.769599 -272.425672) (xy 13.781725 -272.371235) (xy 13.801648 -272.319144)
			(xy 13.828944 -272.270509) (xy 13.86303 -272.226366) (xy 13.903179 -272.187657) (xy 13.948537 -272.155206)
			(xy 13.998137 -272.129705) (xy 14.050921 -272.111698) (xy 14.105764 -272.101568) (xy 14.161498 -272.099531)
			(xy 14.216935 -272.105631) (xy 14.270892 -272.119737) (xy 14.322221 -272.141549) (xy 14.369827 -272.170603)
			(xy 14.412695 -272.206278) (xy 14.449912 -272.247815) (xy 14.480685 -272.294328) (xy 14.504357 -272.344825)
			(xy 14.520425 -272.398232) (xy 14.528545 -272.453408) (xy 14.529054 -272.481294) (xy 14.528545 -272.50918)
			(xy 14.520425 -272.564356) (xy 14.504357 -272.617763) (xy 14.480685 -272.66826) (xy 14.449912 -272.714773)
			(xy 14.412695 -272.75631) (xy 14.369827 -272.791985) (xy 14.322221 -272.821039) (xy 14.270892 -272.842851)
			(xy 14.216935 -272.856957) (xy 14.161498 -272.863057) (xy 14.105764 -272.86102) (xy 14.050921 -272.85089)
			(xy 13.998137 -272.832883) (xy 13.948537 -272.807382) (xy 13.903179 -272.774931) (xy 13.86303 -272.736222)
			(xy 13.828944 -272.692079) (xy 13.801648 -272.643444) (xy 13.781725 -272.591353) (xy 13.769599 -272.536916)
			(xy 13.765528 -272.481294) (xy 12.374894 -272.481294) (xy 12.374567 -272.482381) (xy 12.350895 -272.532878)
			(xy 12.320122 -272.579391) (xy 12.282905 -272.620928) (xy 12.240037 -272.656603) (xy 12.192431 -272.685657)
			(xy 12.141102 -272.707469) (xy 12.087145 -272.721575) (xy 12.031708 -272.727675) (xy 11.975974 -272.725638)
			(xy 11.921131 -272.715508) (xy 11.868347 -272.697501) (xy 11.818747 -272.672) (xy 11.773389 -272.639549)
			(xy 11.73324 -272.60084) (xy 11.699154 -272.556697) (xy 11.671858 -272.508062) (xy 11.651935 -272.455971)
			(xy 11.639809 -272.401534) (xy 11.635738 -272.345912) (xy 0.635 -272.345912) (xy 0.635 -273.245651)
			(xy 8.10893 -273.245651) (xy 8.10893 -273.191149) (xy 8.116686 -273.137201) (xy 8.132041 -273.084907)
			(xy 8.154682 -273.03533) (xy 8.184148 -272.98948) (xy 8.21984 -272.94829) (xy 8.26103 -272.912598)
			(xy 8.30688 -272.883132) (xy 8.356457 -272.860491) (xy 8.408751 -272.845136) (xy 8.462699 -272.83738)
			(xy 8.48995 -272.836894) (xy 8.517319 -272.837391) (xy 8.571497 -272.845201) (xy 8.624 -272.860683)
			(xy 8.673747 -272.883518) (xy 8.719715 -272.913236) (xy 8.740648 -272.930874) (xy 8.740902 -272.931128)
			(xy 8.747982 -272.936725) (xy 8.764904 -272.942964) (xy 8.773922 -272.94332) (xy 8.840978 -272.94332)
			(xy 8.849993 -272.942948) (xy 8.86691 -272.93671) (xy 8.873998 -272.931128) (xy 8.873998 -272.930874)
			(xy 8.874252 -272.930874) (xy 8.895188 -272.91324) (xy 8.94116 -272.883528) (xy 8.990907 -272.860692)
			(xy 9.043406 -272.845199) (xy 9.097581 -272.837369) (xy 9.12495 -272.836894) (xy 9.152201 -272.837376)
			(xy 9.206149 -272.845132) (xy 9.258444 -272.860488) (xy 9.308022 -272.883129) (xy 9.353873 -272.912595)
			(xy 9.360311 -272.918174) (xy 15.261334 -272.918174) (xy 15.265405 -272.862552) (xy 15.277531 -272.808115)
			(xy 15.297454 -272.756024) (xy 15.32475 -272.707389) (xy 15.358836 -272.663246) (xy 15.398985 -272.624537)
			(xy 15.444343 -272.592086) (xy 15.493943 -272.566585) (xy 15.546727 -272.548578) (xy 15.60157 -272.538448)
			(xy 15.657304 -272.536411) (xy 15.712741 -272.542511) (xy 15.766698 -272.556617) (xy 15.818027 -272.578429)
			(xy 15.865633 -272.607483) (xy 15.908501 -272.643158) (xy 15.945718 -272.684695) (xy 15.976491 -272.731208)
			(xy 16.000163 -272.781705) (xy 16.016231 -272.835112) (xy 16.024351 -272.890288) (xy 16.02486 -272.918174)
			(xy 16.024351 -272.94606) (xy 16.016231 -273.001236) (xy 16.000163 -273.054643) (xy 15.976491 -273.10514)
			(xy 15.945718 -273.151653) (xy 15.908501 -273.19319) (xy 15.865633 -273.228865) (xy 15.818027 -273.257919)
			(xy 15.766698 -273.279731) (xy 15.712741 -273.293837) (xy 15.657304 -273.299937) (xy 15.60157 -273.2979)
			(xy 15.546727 -273.28777) (xy 15.493943 -273.269763) (xy 15.444343 -273.244262) (xy 15.398985 -273.211811)
			(xy 15.358836 -273.173102) (xy 15.32475 -273.128959) (xy 15.297454 -273.080324) (xy 15.277531 -273.028233)
			(xy 15.265405 -272.973796) (xy 15.261334 -272.918174) (xy 9.360311 -272.918174) (xy 9.395063 -272.948287)
			(xy 9.430755 -272.989477) (xy 9.460221 -273.035328) (xy 9.482862 -273.084906) (xy 9.498218 -273.137201)
			(xy 9.505974 -273.191149) (xy 9.505974 -273.245651) (xy 9.498218 -273.299599) (xy 9.482862 -273.351894)
			(xy 9.460221 -273.401472) (xy 9.430755 -273.447323) (xy 9.395063 -273.488513) (xy 9.353873 -273.524205)
			(xy 9.308022 -273.553671) (xy 9.258444 -273.576312) (xy 9.206149 -273.591668) (xy 9.152201 -273.599424)
			(xy 9.12495 -273.59991) (xy 9.097581 -273.599412) (xy 9.043403 -273.591602) (xy 8.990901 -273.57612)
			(xy 8.941153 -273.553285) (xy 8.895185 -273.523568) (xy 8.874252 -273.50593) (xy 8.873998 -273.505676)
			(xy 8.866918 -273.50008) (xy 8.849996 -273.49384) (xy 8.840978 -273.493484) (xy 8.773922 -273.493484)
			(xy 8.764907 -273.493855) (xy 8.74799 -273.500093) (xy 8.740902 -273.505676) (xy 8.740902 -273.50593)
			(xy 8.740648 -273.50593) (xy 8.719713 -273.523565) (xy 8.67374 -273.553276) (xy 8.623993 -273.576112)
			(xy 8.571494 -273.591605) (xy 8.517319 -273.599435) (xy 8.48995 -273.59991) (xy 8.462699 -273.59942)
			(xy 8.408751 -273.591664) (xy 8.356457 -273.576309) (xy 8.30688 -273.553668) (xy 8.26103 -273.524202)
			(xy 8.21984 -273.48851) (xy 8.184148 -273.44732) (xy 8.154682 -273.40147) (xy 8.132041 -273.351893)
			(xy 8.116686 -273.299599) (xy 8.10893 -273.245651) (xy 0.635 -273.245651) (xy 0.635 -275.000212)
			(xy 4.903216 -275.000212) (xy 4.903685 -274.972842) (xy 4.911502 -274.918663) (xy 4.92699 -274.866159)
			(xy 4.949831 -274.816413) (xy 4.979555 -274.770446) (xy 4.997196 -274.749514) (xy 4.99745 -274.74926)
			(xy 5.003024 -274.742165) (xy 5.009277 -274.725254) (xy 5.009642 -274.71624) (xy 5.009642 -274.649184)
			(xy 5.009305 -274.640165) (xy 5.003045 -274.623247) (xy 4.99745 -274.616164) (xy 4.997196 -274.616164)
			(xy 4.997196 -274.61591) (xy 4.979548 -274.594986) (xy 4.949837 -274.549011) (xy 4.927003 -274.499261)
			(xy 4.911514 -274.446759) (xy 4.903689 -274.392582) (xy 4.903216 -274.365212) (xy 4.903667 -274.337958)
			(xy 4.911423 -274.284006) (xy 4.926778 -274.231706) (xy 4.949421 -274.182124) (xy 4.97889 -274.13627)
			(xy 5.014585 -274.095077) (xy 5.05578 -274.059383) (xy 5.101635 -274.029915) (xy 5.151217 -274.007274)
			(xy 5.203517 -273.99192) (xy 5.25747 -273.984166) (xy 5.284724 -273.983704) (xy 5.313464 -273.984212)
			(xy 5.370292 -273.992838) (xy 5.425183 -274.009892) (xy 5.476894 -274.034987) (xy 5.524256 -274.067556)
			(xy 5.545582 -274.086828) (xy 5.55244 -274.093432) (xy 5.570474 -274.100544) (xy 5.659374 -274.100544)
			(xy 5.677408 -274.093432) (xy 5.684266 -274.086828) (xy 5.705593 -274.067558) (xy 5.752956 -274.034993)
			(xy 5.804667 -274.009902) (xy 5.859558 -273.992852) (xy 5.916385 -273.98423) (xy 5.973863 -273.98423)
			(xy 6.03069 -273.992852) (xy 6.085581 -274.009902) (xy 6.137292 -274.034993) (xy 6.184655 -274.067558)
			(xy 6.205982 -274.086828) (xy 6.21284 -274.093432) (xy 6.230874 -274.100544) (xy 6.319774 -274.100544)
			(xy 6.337808 -274.093432) (xy 6.344666 -274.086828) (xy 6.365993 -274.067558) (xy 6.413356 -274.034993)
			(xy 6.465067 -274.009902) (xy 6.519958 -273.992852) (xy 6.576785 -273.98423) (xy 6.634263 -273.98423)
			(xy 6.69109 -273.992852) (xy 6.745981 -274.009902) (xy 6.797692 -274.034993) (xy 6.845055 -274.067558)
			(xy 6.866382 -274.086828) (xy 6.87324 -274.093432) (xy 6.891274 -274.100544) (xy 6.980174 -274.100544)
			(xy 6.998208 -274.093432) (xy 7.005066 -274.086828) (xy 7.026382 -274.067544) (xy 7.073747 -274.03498)
			(xy 7.125462 -274.00989) (xy 7.180355 -273.992843) (xy 7.237184 -273.984223) (xy 7.265924 -273.983704)
			(xy 7.293176 -273.984156) (xy 7.347126 -273.991916) (xy 7.399422 -274.007274) (xy 7.449 -274.029919)
			(xy 7.494851 -274.059389) (xy 7.521238 -274.082256) (xy 10.07567 -274.082256) (xy 10.079741 -274.026634)
			(xy 10.091867 -273.972197) (xy 10.11179 -273.920106) (xy 10.139086 -273.871471) (xy 10.173172 -273.827328)
			(xy 10.213321 -273.788619) (xy 10.258679 -273.756168) (xy 10.308279 -273.730667) (xy 10.361063 -273.71266)
			(xy 10.415906 -273.70253) (xy 10.47164 -273.700493) (xy 10.527077 -273.706593) (xy 10.581034 -273.720699)
			(xy 10.632363 -273.742511) (xy 10.679969 -273.771565) (xy 10.722837 -273.80724) (xy 10.760054 -273.848777)
			(xy 10.790827 -273.89529) (xy 10.814499 -273.945787) (xy 10.830567 -273.999194) (xy 10.838687 -274.05437)
			(xy 10.839196 -274.082256) (xy 10.838687 -274.110142) (xy 10.830567 -274.165318) (xy 10.814499 -274.218725)
			(xy 10.807983 -274.232624) (xy 15.393668 -274.232624) (xy 15.397739 -274.177002) (xy 15.409865 -274.122565)
			(xy 15.429788 -274.070474) (xy 15.457084 -274.021839) (xy 15.49117 -273.977696) (xy 15.531319 -273.938987)
			(xy 15.576677 -273.906536) (xy 15.626277 -273.881035) (xy 15.679061 -273.863028) (xy 15.733904 -273.852898)
			(xy 15.789638 -273.850861) (xy 15.845075 -273.856961) (xy 15.899032 -273.871067) (xy 15.950361 -273.892879)
			(xy 15.997967 -273.921933) (xy 16.040835 -273.957608) (xy 16.078052 -273.999145) (xy 16.108825 -274.045658)
			(xy 16.132497 -274.096155) (xy 16.148565 -274.149562) (xy 16.156685 -274.204738) (xy 16.157194 -274.232624)
			(xy 16.156685 -274.26051) (xy 16.148565 -274.315686) (xy 16.132497 -274.369093) (xy 16.108825 -274.41959)
			(xy 16.078052 -274.466103) (xy 16.040835 -274.50764) (xy 15.997967 -274.543315) (xy 15.950361 -274.572369)
			(xy 15.899032 -274.594181) (xy 15.845075 -274.608287) (xy 15.789638 -274.614387) (xy 15.733904 -274.61235)
			(xy 15.679061 -274.60222) (xy 15.626277 -274.584213) (xy 15.576677 -274.558712) (xy 15.531319 -274.526261)
			(xy 15.49117 -274.487552) (xy 15.457084 -274.443409) (xy 15.429788 -274.394774) (xy 15.409865 -274.342683)
			(xy 15.397739 -274.288246) (xy 15.393668 -274.232624) (xy 10.807983 -274.232624) (xy 10.790827 -274.269222)
			(xy 10.760054 -274.315735) (xy 10.722837 -274.357272) (xy 10.679969 -274.392947) (xy 10.632363 -274.422001)
			(xy 10.581034 -274.443813) (xy 10.527077 -274.457919) (xy 10.47164 -274.464019) (xy 10.415906 -274.461982)
			(xy 10.361063 -274.451852) (xy 10.308279 -274.433845) (xy 10.258679 -274.408344) (xy 10.213321 -274.375893)
			(xy 10.173172 -274.337184) (xy 10.139086 -274.293041) (xy 10.11179 -274.244406) (xy 10.091867 -274.192315)
			(xy 10.079741 -274.137878) (xy 10.07567 -274.082256) (xy 7.521238 -274.082256) (xy 7.536041 -274.095084)
			(xy 7.571733 -274.136278) (xy 7.601198 -274.182131) (xy 7.623838 -274.231712) (xy 7.639192 -274.284009)
			(xy 7.646947 -274.33796) (xy 7.647432 -274.365212) (xy 7.64699 -274.392583) (xy 7.639169 -274.446764)
			(xy 7.623675 -274.499268) (xy 7.600827 -274.549015) (xy 7.571097 -274.59498) (xy 7.553452 -274.61591)
			(xy 7.553198 -274.616164) (xy 7.54762 -274.623257) (xy 7.541368 -274.640169) (xy 7.541006 -274.649184)
			(xy 7.541006 -274.71624) (xy 7.541343 -274.725259) (xy 7.547604 -274.742176) (xy 7.553198 -274.74926)
			(xy 7.553452 -274.74926) (xy 7.553452 -274.749514) (xy 7.571057 -274.770474) (xy 7.600775 -274.816438)
			(xy 7.623619 -274.866179) (xy 7.639118 -274.918673) (xy 7.646954 -274.972845) (xy 7.647432 -275.000212)
			(xy 7.646933 -275.027462) (xy 7.639176 -275.081408) (xy 7.62382 -275.133702) (xy 7.60118 -275.183277)
			(xy 7.571714 -275.229126) (xy 7.536024 -275.270316) (xy 7.494836 -275.306007) (xy 7.448988 -275.335474)
			(xy 7.399413 -275.358116) (xy 7.34712 -275.373473) (xy 7.293174 -275.381233) (xy 7.265924 -275.38172)
			(xy 7.237186 -275.381176) (xy 7.18036 -275.372558) (xy 7.125469 -275.355512) (xy 7.073757 -275.330425)
			(xy 7.026394 -275.297865) (xy 7.005066 -275.278596) (xy 6.998208 -275.271992) (xy 6.980174 -275.26488)
			(xy 6.891274 -275.26488) (xy 6.87324 -275.271992) (xy 6.866382 -275.278596) (xy 6.845055 -275.297866)
			(xy 6.797692 -275.330431) (xy 6.745981 -275.355522) (xy 6.69109 -275.372572) (xy 6.634263 -275.381194)
			(xy 6.576785 -275.381194) (xy 6.519958 -275.372572) (xy 6.465067 -275.355522) (xy 6.413356 -275.330431)
			(xy 6.365993 -275.297866) (xy 6.344666 -275.278596) (xy 6.337808 -275.271992) (xy 6.319774 -275.26488)
			(xy 6.230874 -275.26488) (xy 6.21284 -275.271992) (xy 6.205982 -275.278596) (xy 6.184655 -275.297866)
			(xy 6.137292 -275.330431) (xy 6.085581 -275.355522) (xy 6.03069 -275.372572) (xy 5.973863 -275.381194)
			(xy 5.916385 -275.381194) (xy 5.859558 -275.372572) (xy 5.804667 -275.355522) (xy 5.752956 -275.330431)
			(xy 5.705593 -275.297866) (xy 5.684266 -275.278596) (xy 5.677408 -275.271992) (xy 5.659374 -275.26488)
			(xy 5.570474 -275.26488) (xy 5.55244 -275.271992) (xy 5.545582 -275.278596) (xy 5.524235 -275.297844)
			(xy 5.47688 -275.330416) (xy 5.425173 -275.355514) (xy 5.370286 -275.372569) (xy 5.313462 -275.381197)
			(xy 5.284724 -275.38172) (xy 5.257472 -275.381222) (xy 5.203523 -275.373469) (xy 5.151227 -275.358117)
			(xy 5.101647 -275.335478) (xy 5.055795 -275.306013) (xy 5.014602 -275.270323) (xy 4.978908 -275.229134)
			(xy 4.949439 -275.183284) (xy 4.926796 -275.133707) (xy 4.911439 -275.081412) (xy 4.90368 -275.027464)
			(xy 4.903216 -275.000212) (xy 0.635 -275.000212) (xy 0.635 -276.264624) (xy 15.394178 -276.264624)
			(xy 15.394684 -276.235706) (xy 15.403411 -276.178533) (xy 15.42067 -276.123333) (xy 15.446064 -276.07137)
			(xy 15.479011 -276.023837) (xy 15.518756 -275.981822) (xy 15.541244 -275.963634) (xy 15.550033 -275.95601)
			(xy 15.560225 -275.935122) (xy 15.560802 -275.923502) (xy 15.560802 -275.843746) (xy 15.560279 -275.832112)
			(xy 15.550079 -275.811203) (xy 15.541244 -275.803614) (xy 15.518776 -275.785404) (xy 15.479038 -275.743389)
			(xy 15.446096 -275.695859) (xy 15.420705 -275.643901) (xy 15.403445 -275.588706) (xy 15.394714 -275.531539)
			(xy 15.394178 -275.502624) (xy 15.394664 -275.475373) (xy 15.40242 -275.421425) (xy 15.417775 -275.36913)
			(xy 15.440417 -275.319553) (xy 15.469883 -275.273703) (xy 15.505574 -275.232512) (xy 15.546765 -275.196821)
			(xy 15.592615 -275.167355) (xy 15.642192 -275.144713) (xy 15.694487 -275.129358) (xy 15.748435 -275.121602)
			(xy 15.802937 -275.121602) (xy 15.856885 -275.129358) (xy 15.90918 -275.144713) (xy 15.958757 -275.167355)
			(xy 16.004607 -275.196821) (xy 16.045798 -275.232512) (xy 16.081489 -275.273703) (xy 16.110955 -275.319553)
			(xy 16.133597 -275.36913) (xy 16.148952 -275.421425) (xy 16.156708 -275.475373) (xy 16.157194 -275.502624)
			(xy 16.156624 -275.531539) (xy 16.147906 -275.588708) (xy 16.130658 -275.643906) (xy 16.105276 -275.695868)
			(xy 16.072342 -275.743403) (xy 16.03261 -275.785422) (xy 16.010128 -275.803614) (xy 16.001312 -275.811213)
			(xy 15.991136 -275.83212) (xy 15.99057 -275.843746) (xy 15.99057 -275.923502) (xy 15.991098 -275.935136)
			(xy 16.001292 -275.956047) (xy 16.010128 -275.963634) (xy 16.032634 -275.981799) (xy 16.072366 -276.023825)
			(xy 16.105302 -276.071365) (xy 16.130686 -276.123332) (xy 16.147938 -276.178534) (xy 16.156662 -276.235707)
			(xy 16.157194 -276.264624) (xy 16.156708 -276.291875) (xy 16.148952 -276.345823) (xy 16.133597 -276.398118)
			(xy 16.110955 -276.447695) (xy 16.081489 -276.493545) (xy 16.045798 -276.534736) (xy 16.004607 -276.570427)
			(xy 15.958757 -276.599893) (xy 15.90918 -276.622535) (xy 15.856885 -276.63789) (xy 15.802937 -276.645646)
			(xy 15.748435 -276.645646) (xy 15.694487 -276.63789) (xy 15.642192 -276.622535) (xy 15.592615 -276.599893)
			(xy 15.546765 -276.570427) (xy 15.505574 -276.534736) (xy 15.469883 -276.493545) (xy 15.440417 -276.447695)
			(xy 15.417775 -276.398118) (xy 15.40242 -276.345823) (xy 15.394664 -276.291875) (xy 15.394178 -276.264624)
			(xy 0.635 -276.264624) (xy 0.635 -277.280624) (xy 15.393668 -277.280624) (xy 15.397739 -277.225002)
			(xy 15.409865 -277.170565) (xy 15.429788 -277.118474) (xy 15.457084 -277.069839) (xy 15.49117 -277.025696)
			(xy 15.531319 -276.986987) (xy 15.576677 -276.954536) (xy 15.626277 -276.929035) (xy 15.679061 -276.911028)
			(xy 15.733904 -276.900898) (xy 15.789638 -276.898861) (xy 15.845075 -276.904961) (xy 15.899032 -276.919067)
			(xy 15.950361 -276.940879) (xy 15.997967 -276.969933) (xy 16.040835 -277.005608) (xy 16.078052 -277.047145)
			(xy 16.108825 -277.093658) (xy 16.132497 -277.144155) (xy 16.148565 -277.197562) (xy 16.156685 -277.252738)
			(xy 16.157194 -277.280624) (xy 16.156685 -277.30851) (xy 16.148565 -277.363686) (xy 16.132497 -277.417093)
			(xy 16.108825 -277.46759) (xy 16.078052 -277.514103) (xy 16.040835 -277.55564) (xy 15.997967 -277.591315)
			(xy 15.950361 -277.620369) (xy 15.899032 -277.642181) (xy 15.845075 -277.656287) (xy 15.789638 -277.662387)
			(xy 15.733904 -277.66035) (xy 15.679061 -277.65022) (xy 15.626277 -277.632213) (xy 15.576677 -277.606712)
			(xy 15.531319 -277.574261) (xy 15.49117 -277.535552) (xy 15.457084 -277.491409) (xy 15.429788 -277.442774)
			(xy 15.409865 -277.390683) (xy 15.397739 -277.336246) (xy 15.393668 -277.280624) (xy 0.635 -277.280624)
			(xy 0.635 -277.814278) (xy 11.344146 -277.814278) (xy 11.348217 -277.758656) (xy 11.360343 -277.704219)
			(xy 11.380266 -277.652128) (xy 11.407562 -277.603493) (xy 11.441648 -277.55935) (xy 11.481797 -277.520641)
			(xy 11.527155 -277.48819) (xy 11.576755 -277.462689) (xy 11.629539 -277.444682) (xy 11.684382 -277.434552)
			(xy 11.740116 -277.432515) (xy 11.795553 -277.438615) (xy 11.84951 -277.452721) (xy 11.900839 -277.474533)
			(xy 11.948445 -277.503587) (xy 11.991313 -277.539262) (xy 12.02853 -277.580799) (xy 12.059303 -277.627312)
			(xy 12.082975 -277.677809) (xy 12.099043 -277.731216) (xy 12.107163 -277.786392) (xy 12.107672 -277.814278)
			(xy 12.107163 -277.842164) (xy 12.099043 -277.89734) (xy 12.082975 -277.950747) (xy 12.059303 -278.001244)
			(xy 12.02853 -278.047757) (xy 11.991313 -278.089294) (xy 11.948445 -278.124969) (xy 11.900839 -278.154023)
			(xy 11.84951 -278.175835) (xy 11.795553 -278.189941) (xy 11.740116 -278.196041) (xy 11.684382 -278.194004)
			(xy 11.629539 -278.183874) (xy 11.576755 -278.165867) (xy 11.527155 -278.140366) (xy 11.481797 -278.107915)
			(xy 11.441648 -278.069206) (xy 11.407562 -278.025063) (xy 11.380266 -277.976428) (xy 11.360343 -277.924337)
			(xy 11.348217 -277.8699) (xy 11.344146 -277.814278) (xy 0.635 -277.814278) (xy 0.635 -279.73909)
			(xy 5.034026 -279.73909) (xy 5.034518 -279.710836) (xy 5.042855 -279.654948) (xy 5.059345 -279.6009)
			(xy 5.083626 -279.549876) (xy 5.115169 -279.502992) (xy 5.133848 -279.481788) (xy 5.140452 -279.474676)
			(xy 5.14731 -279.45715) (xy 5.14731 -279.369266) (xy 5.140452 -279.35174) (xy 5.133848 -279.344628)
			(xy 5.115176 -279.32342) (xy 5.083639 -279.276534) (xy 5.059362 -279.22551) (xy 5.042875 -279.171465)
			(xy 5.034539 -279.115578) (xy 5.034026 -279.087326) (xy 5.03448 -279.060072) (xy 5.042234 -279.006119)
			(xy 5.057588 -278.953819) (xy 5.08023 -278.904237) (xy 5.109699 -278.858382) (xy 5.145394 -278.817188)
			(xy 5.186588 -278.781494) (xy 5.232444 -278.752026) (xy 5.282027 -278.729386) (xy 5.334327 -278.714032)
			(xy 5.38828 -278.706279) (xy 5.415534 -278.705818) (xy 5.444273 -278.706343) (xy 5.501099 -278.714969)
			(xy 5.555989 -278.73202) (xy 5.6077 -278.75711) (xy 5.655064 -278.789673) (xy 5.676392 -278.808942)
			(xy 5.68325 -278.815546) (xy 5.701284 -278.822658) (xy 5.790184 -278.822658) (xy 5.808218 -278.815546)
			(xy 5.815076 -278.808942) (xy 5.836403 -278.789672) (xy 5.883766 -278.757107) (xy 5.935477 -278.732016)
			(xy 5.990368 -278.714966) (xy 6.047195 -278.706344) (xy 6.104673 -278.706344) (xy 6.1615 -278.714966)
			(xy 6.216391 -278.732016) (xy 6.268102 -278.757107) (xy 6.315465 -278.789672) (xy 6.336792 -278.808942)
			(xy 6.34365 -278.815546) (xy 6.361684 -278.822658) (xy 6.450584 -278.822658) (xy 6.468618 -278.815546)
			(xy 6.475476 -278.808942) (xy 6.496803 -278.789672) (xy 6.544166 -278.757107) (xy 6.595877 -278.732016)
			(xy 6.650768 -278.714966) (xy 6.707595 -278.706344) (xy 6.765073 -278.706344) (xy 6.8219 -278.714966)
			(xy 6.876791 -278.732016) (xy 6.928502 -278.757107) (xy 6.975865 -278.789672) (xy 6.997192 -278.808942)
			(xy 7.00405 -278.815546) (xy 7.022084 -278.822658) (xy 7.110984 -278.822658) (xy 7.129018 -278.815546)
			(xy 7.135876 -278.808942) (xy 7.15719 -278.789656) (xy 7.204555 -278.757092) (xy 7.25627 -278.732002)
			(xy 7.311164 -278.714955) (xy 7.367994 -278.706336) (xy 7.396734 -278.705818) (xy 7.423987 -278.706246)
			(xy 7.477938 -278.714008) (xy 7.530236 -278.729369) (xy 7.579815 -278.752016) (xy 7.625666 -278.781488)
			(xy 7.666857 -278.817186) (xy 7.702548 -278.858382) (xy 7.732013 -278.904238) (xy 7.754652 -278.95382)
			(xy 7.770005 -279.00612) (xy 7.777758 -279.060073) (xy 7.778242 -279.087326) (xy 7.777767 -279.11558)
			(xy 7.769428 -279.17147) (xy 7.752934 -279.225518) (xy 7.728649 -279.276542) (xy 7.697102 -279.323425)
			(xy 7.67842 -279.344628) (xy 7.671816 -279.35174) (xy 7.664958 -279.369266) (xy 7.664958 -279.45715)
			(xy 7.671816 -279.474676) (xy 7.67842 -279.481788) (xy 7.697095 -279.502995) (xy 7.728632 -279.54988)
			(xy 7.752909 -279.600904) (xy 7.769395 -279.654951) (xy 7.77773 -279.710837) (xy 7.778242 -279.73909)
			(xy 7.777713 -279.766339) (xy 7.769958 -279.820284) (xy 7.754606 -279.872576) (xy 7.731969 -279.92215)
			(xy 7.702507 -279.967999) (xy 7.66682 -280.009189) (xy 7.625634 -280.04488) (xy 7.579789 -280.074348)
			(xy 7.530217 -280.096991) (xy 7.477927 -280.112349) (xy 7.423983 -280.120109) (xy 7.396734 -280.120598)
			(xy 7.367994 -280.120115) (xy 7.311164 -280.111483) (xy 7.256273 -280.094423) (xy 7.204562 -280.069322)
			(xy 7.157201 -280.036749) (xy 7.135876 -280.017474) (xy 7.129018 -280.01087) (xy 7.110984 -280.003758)
			(xy 7.022084 -280.003758) (xy 7.00405 -280.01087) (xy 6.997192 -280.017474) (xy 6.975865 -280.036744)
			(xy 6.928502 -280.069309) (xy 6.876791 -280.0944) (xy 6.8219 -280.11145) (xy 6.765073 -280.120072)
			(xy 6.707595 -280.120072) (xy 6.650768 -280.11145) (xy 6.595877 -280.0944) (xy 6.544166 -280.069309)
			(xy 6.496803 -280.036744) (xy 6.475476 -280.017474) (xy 6.468618 -280.01087) (xy 6.450584 -280.003758)
			(xy 6.361684 -280.003758) (xy 6.34365 -280.01087) (xy 6.336792 -280.017474) (xy 6.315465 -280.036744)
			(xy 6.268102 -280.069309) (xy 6.216391 -280.0944) (xy 6.1615 -280.11145) (xy 6.104673 -280.120072)
			(xy 6.047195 -280.120072) (xy 5.990368 -280.11145) (xy 5.935477 -280.0944) (xy 5.883766 -280.069309)
			(xy 5.836403 -280.036744) (xy 5.815076 -280.017474) (xy 5.808218 -280.01087) (xy 5.790184 -280.003758)
			(xy 5.701284 -280.003758) (xy 5.68325 -280.01087) (xy 5.676392 -280.017474) (xy 5.655053 -280.036731)
			(xy 5.607694 -280.069298) (xy 5.555985 -280.094393) (xy 5.501097 -280.111447) (xy 5.444272 -280.120075)
			(xy 5.415534 -280.120598) (xy 5.388282 -280.120113) (xy 5.334331 -280.11236) (xy 5.282033 -280.097008)
			(xy 5.232452 -280.074369) (xy 5.186598 -280.044904) (xy 5.145405 -280.009212) (xy 5.109711 -279.968021)
			(xy 5.080243 -279.922169) (xy 5.0576 -279.87259) (xy 5.042245 -279.820293) (xy 5.034489 -279.766342)
			(xy 5.034026 -279.73909) (xy 0.635 -279.73909) (xy 0.635 -280.722651) (xy 9.692378 -280.722651) (xy 9.692378 -280.668149)
			(xy 9.700134 -280.614203) (xy 9.715488 -280.561909) (xy 9.738128 -280.512333) (xy 9.767593 -280.466483)
			(xy 9.803283 -280.425293) (xy 9.844472 -280.389602) (xy 9.890321 -280.360135) (xy 9.939896 -280.337493)
			(xy 9.992189 -280.322137) (xy 10.046135 -280.314379) (xy 10.073386 -280.313892) (xy 10.102124 -280.314426)
			(xy 10.158951 -280.323047) (xy 10.213842 -280.340094) (xy 10.265554 -280.365184) (xy 10.312917 -280.397746)
			(xy 10.334244 -280.417016) (xy 10.341102 -280.42362) (xy 10.359136 -280.430732) (xy 10.448036 -280.430732)
			(xy 10.46607 -280.42362) (xy 10.472928 -280.417016) (xy 10.494255 -280.397746) (xy 10.541618 -280.365181)
			(xy 10.593329 -280.34009) (xy 10.64822 -280.32304) (xy 10.705047 -280.314418) (xy 10.762525 -280.314418)
			(xy 10.819352 -280.32304) (xy 10.874243 -280.34009) (xy 10.925954 -280.365181) (xy 10.973317 -280.397746)
			(xy 10.994644 -280.417016) (xy 11.001502 -280.42362) (xy 11.019536 -280.430732) (xy 11.108436 -280.430732)
			(xy 11.12647 -280.42362) (xy 11.133328 -280.417016) (xy 11.154658 -280.397748) (xy 11.202019 -280.365182)
			(xy 11.25373 -280.34009) (xy 11.30862 -280.323038) (xy 11.365447 -280.314414) (xy 11.394186 -280.313892)
			(xy 11.42431 -280.31446) (xy 11.483807 -280.32394) (xy 11.541075 -280.342651) (xy 11.594692 -280.370128)
			(xy 11.643326 -280.405688) (xy 11.66495 -280.426668) (xy 11.672377 -280.433474) (xy 11.690955 -280.441215)
			(xy 11.701018 -280.441654) (xy 11.773154 -280.441654) (xy 11.783222 -280.441217) (xy 11.801821 -280.433506)
			(xy 11.809222 -280.426668) (xy 11.83087 -280.405712) (xy 11.879491 -280.370138) (xy 11.933102 -280.342652)
			(xy 11.990367 -280.323939) (xy 12.049863 -280.314463) (xy 12.079986 -280.313892) (xy 12.10724 -280.314354)
			(xy 12.161192 -280.32211) (xy 12.213491 -280.337465) (xy 12.263073 -280.360106) (xy 12.308928 -280.389574)
			(xy 12.350123 -280.425268) (xy 12.385818 -280.466461) (xy 12.415287 -280.512314) (xy 12.437931 -280.561895)
			(xy 12.453287 -280.614194) (xy 12.461045 -280.668147) (xy 12.461045 -280.722653) (xy 12.453287 -280.776606)
			(xy 12.437931 -280.828905) (xy 12.415287 -280.878486) (xy 12.385818 -280.924339) (xy 12.350123 -280.965532)
			(xy 12.308928 -281.001226) (xy 12.263073 -281.030694) (xy 12.213491 -281.053335) (xy 12.161192 -281.06869)
			(xy 12.10724 -281.076446) (xy 12.079986 -281.076908) (xy 12.049862 -281.076358) (xy 11.990364 -281.066874)
			(xy 11.933095 -281.048159) (xy 11.879478 -281.020678) (xy 11.830845 -280.985114) (xy 11.809222 -280.964132)
			(xy 11.801805 -280.957314) (xy 11.783219 -280.94958) (xy 11.773154 -280.949146) (xy 11.701018 -280.949146)
			(xy 11.690948 -280.949569) (xy 11.67235 -280.95729) (xy 11.66495 -280.964132) (xy 11.643315 -280.985101)
			(xy 11.59469 -281.020673) (xy 11.541076 -281.048157) (xy 11.483808 -281.066867) (xy 11.42431 -281.076339)
			(xy 11.394186 -281.076908) (xy 11.365447 -281.076391) (xy 11.308619 -281.067766) (xy 11.253729 -281.050715)
			(xy 11.202017 -281.025622) (xy 11.154655 -280.993055) (xy 11.133328 -280.973784) (xy 11.12647 -280.96718)
			(xy 11.108436 -280.960068) (xy 11.019536 -280.960068) (xy 11.001502 -280.96718) (xy 10.994644 -280.973784)
			(xy 10.973317 -280.993054) (xy 10.925954 -281.025619) (xy 10.874243 -281.05071) (xy 10.819352 -281.06776)
			(xy 10.762525 -281.076382) (xy 10.705047 -281.076382) (xy 10.64822 -281.06776) (xy 10.593329 -281.05071)
			(xy 10.541618 -281.025619) (xy 10.494255 -280.993054) (xy 10.472928 -280.973784) (xy 10.46607 -280.96718)
			(xy 10.448036 -280.960068) (xy 10.359136 -280.960068) (xy 10.341102 -280.96718) (xy 10.334244 -280.973784)
			(xy 10.312926 -280.993065) (xy 10.265561 -281.025629) (xy 10.213847 -281.050719) (xy 10.158955 -281.067767)
			(xy 10.102126 -281.076388) (xy 10.073386 -281.076908) (xy 10.046135 -281.076421) (xy 9.992189 -281.068663)
			(xy 9.939896 -281.053307) (xy 9.890321 -281.030665) (xy 9.844472 -281.001198) (xy 9.803283 -280.965507)
			(xy 9.767593 -280.924317) (xy 9.738128 -280.878467) (xy 9.715488 -280.828891) (xy 9.700134 -280.776597)
			(xy 9.692378 -280.722651) (xy 0.635 -280.722651) (xy 0.635 -282.382031) (xy 5.88618 -282.382031)
			(xy 5.88618 -282.327529) (xy 5.893936 -282.273582) (xy 5.909291 -282.221288) (xy 5.931932 -282.171711)
			(xy 5.961397 -282.125861) (xy 5.997088 -282.084671) (xy 6.038278 -282.04898) (xy 6.084128 -282.019514)
			(xy 6.133704 -281.996872) (xy 6.185998 -281.981517) (xy 6.239945 -281.97376) (xy 6.267196 -281.973274)
			(xy 6.295934 -281.973807) (xy 6.352761 -281.982428) (xy 6.407651 -281.999477) (xy 6.459363 -282.024566)
			(xy 6.506727 -282.057129) (xy 6.528054 -282.076398) (xy 6.534912 -282.083002) (xy 6.552946 -282.090114)
			(xy 6.641846 -282.090114) (xy 6.65988 -282.083002) (xy 6.666738 -282.076398) (xy 6.688065 -282.057128)
			(xy 6.735428 -282.024563) (xy 6.787139 -281.999472) (xy 6.84203 -281.982422) (xy 6.898857 -281.9738)
			(xy 6.956335 -281.9738) (xy 7.013162 -281.982422) (xy 7.068053 -281.999472) (xy 7.119764 -282.024563)
			(xy 7.167127 -282.057128) (xy 7.188454 -282.076398) (xy 7.195312 -282.083002) (xy 7.213346 -282.090114)
			(xy 7.302246 -282.090114) (xy 7.32028 -282.083002) (xy 7.327138 -282.076398) (xy 7.348476 -282.05714)
			(xy 7.395834 -282.024569) (xy 7.447543 -281.999474) (xy 7.502431 -281.98242) (xy 7.559258 -281.973796)
			(xy 7.587996 -281.973274) (xy 7.61812 -281.97384) (xy 7.677617 -281.983321) (xy 7.734885 -282.002033)
			(xy 7.788502 -282.02951) (xy 7.837136 -282.06507) (xy 7.85876 -282.08605) (xy 7.866186 -282.092858)
			(xy 7.884765 -282.100598) (xy 7.894828 -282.101036) (xy 7.966964 -282.101036) (xy 7.977033 -282.100609)
			(xy 7.995632 -282.092891) (xy 8.003032 -282.08605) (xy 8.024672 -282.065086) (xy 8.073296 -282.029514)
			(xy 8.126908 -282.00203) (xy 8.184175 -281.983318) (xy 8.243673 -281.973844) (xy 8.273796 -281.973274)
			(xy 8.301049 -281.973733) (xy 8.355001 -281.98149) (xy 8.407299 -281.996845) (xy 8.45688 -282.019488)
			(xy 8.502734 -282.048956) (xy 8.543928 -282.08465) (xy 8.579622 -282.125843) (xy 8.60909 -282.171696)
			(xy 8.631733 -282.221277) (xy 8.64709 -282.273575) (xy 8.654847 -282.327527) (xy 8.654847 -282.382033)
			(xy 8.64709 -282.435985) (xy 8.631733 -282.488283) (xy 8.60909 -282.537864) (xy 8.579622 -282.583717)
			(xy 8.543928 -282.62491) (xy 8.502734 -282.660604) (xy 8.45688 -282.690072) (xy 8.407299 -282.712715)
			(xy 8.355001 -282.72807) (xy 8.301049 -282.735827) (xy 8.273796 -282.73629) (xy 8.243672 -282.735739)
			(xy 8.184174 -282.726256) (xy 8.126905 -282.707541) (xy 8.073288 -282.68006) (xy 8.024656 -282.644496)
			(xy 8.003032 -282.623514) (xy 7.995613 -282.616697) (xy 7.977028 -282.608963) (xy 7.966964 -282.608528)
			(xy 7.894828 -282.608528) (xy 7.884759 -282.608961) (xy 7.866161 -282.616676) (xy 7.85876 -282.623514)
			(xy 7.837134 -282.644493) (xy 7.788505 -282.680061) (xy 7.734889 -282.707541) (xy 7.677619 -282.726249)
			(xy 7.61812 -282.735721) (xy 7.587996 -282.73629) (xy 7.559257 -282.735771) (xy 7.502429 -282.727148)
			(xy 7.447538 -282.710097) (xy 7.395827 -282.685004) (xy 7.348464 -282.652437) (xy 7.327138 -282.633166)
			(xy 7.32028 -282.626562) (xy 7.302246 -282.61945) (xy 7.213346 -282.61945) (xy 7.195312 -282.626562)
			(xy 7.188454 -282.633166) (xy 7.167127 -282.652436) (xy 7.119764 -282.685001) (xy 7.068053 -282.710092)
			(xy 7.013162 -282.727142) (xy 6.956335 -282.735764) (xy 6.898857 -282.735764) (xy 6.84203 -282.727142)
			(xy 6.787139 -282.710092) (xy 6.735428 -282.685001) (xy 6.688065 -282.652436) (xy 6.666738 -282.633166)
			(xy 6.65988 -282.626562) (xy 6.641846 -282.61945) (xy 6.552946 -282.61945) (xy 6.534912 -282.626562)
			(xy 6.528054 -282.633166) (xy 6.506729 -282.652439) (xy 6.459366 -282.685005) (xy 6.407654 -282.710097)
			(xy 6.352763 -282.727147) (xy 6.295935 -282.735769) (xy 6.267196 -282.73629) (xy 6.239945 -282.7358)
			(xy 6.185998 -282.728043) (xy 6.133704 -282.712688) (xy 6.084128 -282.690046) (xy 6.038278 -282.66058)
			(xy 5.997088 -282.624889) (xy 5.961397 -282.583699) (xy 5.931932 -282.537849) (xy 5.909291 -282.488272)
			(xy 5.893936 -282.435978) (xy 5.88618 -282.382031) (xy 0.635 -282.382031) (xy 0.635 -283.186451)
			(xy 9.692378 -283.186451) (xy 9.692378 -283.131949) (xy 9.700134 -283.078003) (xy 9.715488 -283.025709)
			(xy 9.738128 -282.976133) (xy 9.767593 -282.930283) (xy 9.803283 -282.889093) (xy 9.844472 -282.853402)
			(xy 9.890321 -282.823935) (xy 9.939896 -282.801293) (xy 9.992189 -282.785937) (xy 10.046135 -282.778179)
			(xy 10.073386 -282.777692) (xy 10.102124 -282.778226) (xy 10.158951 -282.786847) (xy 10.213842 -282.803894)
			(xy 10.265554 -282.828984) (xy 10.312917 -282.861546) (xy 10.334244 -282.880816) (xy 10.341102 -282.88742)
			(xy 10.359136 -282.894532) (xy 10.448036 -282.894532) (xy 10.46607 -282.88742) (xy 10.472928 -282.880816)
			(xy 10.494255 -282.861546) (xy 10.541618 -282.828981) (xy 10.593329 -282.80389) (xy 10.64822 -282.78684)
			(xy 10.705047 -282.778218) (xy 10.762525 -282.778218) (xy 10.819352 -282.78684) (xy 10.874243 -282.80389)
			(xy 10.925954 -282.828981) (xy 10.973317 -282.861546) (xy 10.994644 -282.880816) (xy 11.001502 -282.88742)
			(xy 11.019536 -282.894532) (xy 11.108436 -282.894532) (xy 11.12647 -282.88742) (xy 11.133328 -282.880816)
			(xy 11.154658 -282.861548) (xy 11.202019 -282.828982) (xy 11.25373 -282.80389) (xy 11.30862 -282.786838)
			(xy 11.365447 -282.778214) (xy 11.394186 -282.777692) (xy 11.42431 -282.77826) (xy 11.483807 -282.78774)
			(xy 11.541075 -282.806451) (xy 11.594692 -282.833928) (xy 11.643326 -282.869488) (xy 11.66495 -282.890468)
			(xy 11.672377 -282.897274) (xy 11.690955 -282.905015) (xy 11.701018 -282.905454) (xy 11.773154 -282.905454)
			(xy 11.783222 -282.905017) (xy 11.801821 -282.897306) (xy 11.809222 -282.890468) (xy 11.83087 -282.869512)
			(xy 11.879491 -282.833938) (xy 11.933102 -282.806452) (xy 11.990367 -282.787739) (xy 12.049863 -282.778263)
			(xy 12.079986 -282.777692) (xy 12.10724 -282.778154) (xy 12.161192 -282.78591) (xy 12.213491 -282.801265)
			(xy 12.263073 -282.823906) (xy 12.308928 -282.853374) (xy 12.350123 -282.889068) (xy 12.385818 -282.930261)
			(xy 12.415287 -282.976114) (xy 12.437931 -283.025695) (xy 12.453287 -283.077994) (xy 12.461045 -283.131947)
			(xy 12.461045 -283.186453) (xy 12.453287 -283.240406) (xy 12.437931 -283.292705) (xy 12.415287 -283.342286)
			(xy 12.385818 -283.388139) (xy 12.350123 -283.429332) (xy 12.308928 -283.465026) (xy 12.263073 -283.494494)
			(xy 12.213491 -283.517135) (xy 12.161192 -283.53249) (xy 12.10724 -283.540246) (xy 12.079986 -283.540708)
			(xy 12.049862 -283.540158) (xy 11.990364 -283.530674) (xy 11.933095 -283.511959) (xy 11.879478 -283.484478)
			(xy 11.830845 -283.448914) (xy 11.809222 -283.427932) (xy 11.801805 -283.421114) (xy 11.783219 -283.41338)
			(xy 11.773154 -283.412946) (xy 11.701018 -283.412946) (xy 11.690948 -283.413369) (xy 11.67235 -283.42109)
			(xy 11.66495 -283.427932) (xy 11.643315 -283.448901) (xy 11.59469 -283.484473) (xy 11.541076 -283.511957)
			(xy 11.483808 -283.530667) (xy 11.42431 -283.540139) (xy 11.394186 -283.540708) (xy 11.365447 -283.540191)
			(xy 11.308619 -283.531566) (xy 11.253729 -283.514515) (xy 11.202017 -283.489422) (xy 11.154655 -283.456855)
			(xy 11.133328 -283.437584) (xy 11.12647 -283.43098) (xy 11.108436 -283.423868) (xy 11.019536 -283.423868)
			(xy 11.001502 -283.43098) (xy 10.994644 -283.437584) (xy 10.973317 -283.456854) (xy 10.925954 -283.489419)
			(xy 10.874243 -283.51451) (xy 10.819352 -283.53156) (xy 10.762525 -283.540182) (xy 10.705047 -283.540182)
			(xy 10.64822 -283.53156) (xy 10.593329 -283.51451) (xy 10.541618 -283.489419) (xy 10.494255 -283.456854)
			(xy 10.472928 -283.437584) (xy 10.46607 -283.43098) (xy 10.448036 -283.423868) (xy 10.359136 -283.423868)
			(xy 10.341102 -283.43098) (xy 10.334244 -283.437584) (xy 10.312926 -283.456865) (xy 10.265561 -283.489429)
			(xy 10.213847 -283.514519) (xy 10.158955 -283.531567) (xy 10.102126 -283.540188) (xy 10.073386 -283.540708)
			(xy 10.046135 -283.540221) (xy 9.992189 -283.532463) (xy 9.939896 -283.517107) (xy 9.890321 -283.494465)
			(xy 9.844472 -283.464998) (xy 9.803283 -283.429307) (xy 9.767593 -283.388117) (xy 9.738128 -283.342267)
			(xy 9.715488 -283.292691) (xy 9.700134 -283.240397) (xy 9.692378 -283.186451) (xy 0.635 -283.186451)
			(xy 0.635 -284.845831) (xy 5.88618 -284.845831) (xy 5.88618 -284.791329) (xy 5.893936 -284.737382)
			(xy 5.909291 -284.685088) (xy 5.931932 -284.635511) (xy 5.961397 -284.589661) (xy 5.997088 -284.548471)
			(xy 6.038278 -284.51278) (xy 6.084128 -284.483314) (xy 6.133704 -284.460672) (xy 6.185998 -284.445317)
			(xy 6.239945 -284.43756) (xy 6.267196 -284.437074) (xy 6.295934 -284.437607) (xy 6.352761 -284.446228)
			(xy 6.407651 -284.463277) (xy 6.459363 -284.488366) (xy 6.506727 -284.520929) (xy 6.528054 -284.540198)
			(xy 6.534912 -284.546802) (xy 6.552946 -284.553914) (xy 6.641846 -284.553914) (xy 6.65988 -284.546802)
			(xy 6.666738 -284.540198) (xy 6.688065 -284.520928) (xy 6.735428 -284.488363) (xy 6.787139 -284.463272)
			(xy 6.84203 -284.446222) (xy 6.898857 -284.4376) (xy 6.956335 -284.4376) (xy 7.013162 -284.446222)
			(xy 7.068053 -284.463272) (xy 7.119764 -284.488363) (xy 7.167127 -284.520928) (xy 7.188454 -284.540198)
			(xy 7.195312 -284.546802) (xy 7.213346 -284.553914) (xy 7.302246 -284.553914) (xy 7.32028 -284.546802)
			(xy 7.327138 -284.540198) (xy 7.348476 -284.52094) (xy 7.395834 -284.488369) (xy 7.447543 -284.463274)
			(xy 7.502431 -284.44622) (xy 7.559258 -284.437596) (xy 7.587996 -284.437074) (xy 7.61812 -284.43764)
			(xy 7.677617 -284.447121) (xy 7.734885 -284.465833) (xy 7.788502 -284.49331) (xy 7.837136 -284.52887)
			(xy 7.85876 -284.54985) (xy 7.866186 -284.556658) (xy 7.884765 -284.564398) (xy 7.894828 -284.564836)
			(xy 7.966964 -284.564836) (xy 7.977033 -284.564409) (xy 7.995632 -284.556691) (xy 8.003032 -284.54985)
			(xy 8.024672 -284.528886) (xy 8.073296 -284.493314) (xy 8.126908 -284.46583) (xy 8.184175 -284.447118)
			(xy 8.243673 -284.437644) (xy 8.273796 -284.437074) (xy 8.301049 -284.437533) (xy 8.355001 -284.44529)
			(xy 8.407299 -284.460645) (xy 8.45688 -284.483288) (xy 8.502734 -284.512756) (xy 8.543928 -284.54845)
			(xy 8.579622 -284.589643) (xy 8.60909 -284.635496) (xy 8.631733 -284.685077) (xy 8.64709 -284.737375)
			(xy 8.654847 -284.791327) (xy 8.654847 -284.845833) (xy 8.64709 -284.899785) (xy 8.631733 -284.952083)
			(xy 8.60909 -285.001664) (xy 8.579622 -285.047517) (xy 8.543928 -285.08871) (xy 8.502734 -285.124404)
			(xy 8.45688 -285.153872) (xy 8.407299 -285.176515) (xy 8.355001 -285.19187) (xy 8.301049 -285.199627)
			(xy 8.273796 -285.20009) (xy 8.243672 -285.199539) (xy 8.184174 -285.190056) (xy 8.126905 -285.171341)
			(xy 8.073288 -285.14386) (xy 8.024656 -285.108296) (xy 8.003032 -285.087314) (xy 7.995613 -285.080497)
			(xy 7.977028 -285.072763) (xy 7.966964 -285.072328) (xy 7.894828 -285.072328) (xy 7.884759 -285.072761)
			(xy 7.866161 -285.080476) (xy 7.85876 -285.087314) (xy 7.837134 -285.108293) (xy 7.788505 -285.143861)
			(xy 7.734889 -285.171341) (xy 7.677619 -285.190049) (xy 7.61812 -285.199521) (xy 7.587996 -285.20009)
			(xy 7.559257 -285.199571) (xy 7.502429 -285.190948) (xy 7.447538 -285.173897) (xy 7.395827 -285.148804)
			(xy 7.348464 -285.116237) (xy 7.327138 -285.096966) (xy 7.32028 -285.090362) (xy 7.302246 -285.08325)
			(xy 7.213346 -285.08325) (xy 7.195312 -285.090362) (xy 7.188454 -285.096966) (xy 7.167127 -285.116236)
			(xy 7.119764 -285.148801) (xy 7.068053 -285.173892) (xy 7.013162 -285.190942) (xy 6.956335 -285.199564)
			(xy 6.898857 -285.199564) (xy 6.84203 -285.190942) (xy 6.787139 -285.173892) (xy 6.735428 -285.148801)
			(xy 6.688065 -285.116236) (xy 6.666738 -285.096966) (xy 6.65988 -285.090362) (xy 6.641846 -285.08325)
			(xy 6.552946 -285.08325) (xy 6.534912 -285.090362) (xy 6.528054 -285.096966) (xy 6.506729 -285.116239)
			(xy 6.459366 -285.148805) (xy 6.407654 -285.173897) (xy 6.352763 -285.190947) (xy 6.295935 -285.199569)
			(xy 6.267196 -285.20009) (xy 6.239945 -285.1996) (xy 6.185998 -285.191843) (xy 6.133704 -285.176488)
			(xy 6.084128 -285.153846) (xy 6.038278 -285.12438) (xy 5.997088 -285.088689) (xy 5.961397 -285.047499)
			(xy 5.931932 -285.001649) (xy 5.909291 -284.952072) (xy 5.893936 -284.899778) (xy 5.88618 -284.845831)
			(xy 0.635 -284.845831) (xy 0.635 -285.462218) (xy 11.958572 -285.462218) (xy 11.962643 -285.406596)
			(xy 11.974769 -285.352159) (xy 11.994692 -285.300068) (xy 12.021988 -285.251433) (xy 12.056074 -285.20729)
			(xy 12.096223 -285.168581) (xy 12.141581 -285.13613) (xy 12.191181 -285.110629) (xy 12.243965 -285.092622)
			(xy 12.298808 -285.082492) (xy 12.354542 -285.080455) (xy 12.409979 -285.086555) (xy 12.463936 -285.100661)
			(xy 12.515265 -285.122473) (xy 12.562871 -285.151527) (xy 12.605739 -285.187202) (xy 12.642956 -285.228739)
			(xy 12.673729 -285.275252) (xy 12.697401 -285.325749) (xy 12.713469 -285.379156) (xy 12.721589 -285.434332)
			(xy 12.722098 -285.462218) (xy 12.721589 -285.490104) (xy 12.713469 -285.54528) (xy 12.697401 -285.598687)
			(xy 12.673729 -285.649184) (xy 12.642956 -285.695697) (xy 12.605739 -285.737234) (xy 12.562871 -285.772909)
			(xy 12.515265 -285.801963) (xy 12.463936 -285.823775) (xy 12.409979 -285.837881) (xy 12.354542 -285.843981)
			(xy 12.298808 -285.841944) (xy 12.243965 -285.831814) (xy 12.191181 -285.813807) (xy 12.141581 -285.788306)
			(xy 12.096223 -285.755855) (xy 12.056074 -285.717146) (xy 12.021988 -285.673003) (xy 11.994692 -285.624368)
			(xy 11.974769 -285.572277) (xy 11.962643 -285.51784) (xy 11.958572 -285.462218) (xy 0.635 -285.462218)
			(xy 0.635 -287.131831) (xy 5.20038 -287.131831) (xy 5.20038 -287.077329) (xy 5.208136 -287.023382)
			(xy 5.223491 -286.971088) (xy 5.246132 -286.921511) (xy 5.275597 -286.875661) (xy 5.311288 -286.834471)
			(xy 5.352478 -286.79878) (xy 5.398328 -286.769314) (xy 5.447904 -286.746672) (xy 5.500198 -286.731317)
			(xy 5.554145 -286.72356) (xy 5.581396 -286.723074) (xy 5.61152 -286.72364) (xy 5.671017 -286.733121)
			(xy 5.728285 -286.751833) (xy 5.781902 -286.77931) (xy 5.830536 -286.81487) (xy 5.85216 -286.83585)
			(xy 5.859586 -286.842658) (xy 5.878165 -286.850398) (xy 5.888228 -286.850836) (xy 5.960364 -286.850836)
			(xy 5.970433 -286.850409) (xy 5.989032 -286.842691) (xy 5.996432 -286.83585) (xy 6.018072 -286.814886)
			(xy 6.066696 -286.779314) (xy 6.120308 -286.75183) (xy 6.177575 -286.733118) (xy 6.237073 -286.723644)
			(xy 6.267196 -286.723074) (xy 6.294449 -286.723533) (xy 6.348401 -286.73129) (xy 6.400699 -286.746645)
			(xy 6.45028 -286.769288) (xy 6.496134 -286.798756) (xy 6.537328 -286.83445) (xy 6.573022 -286.875643)
			(xy 6.60249 -286.921496) (xy 6.625133 -286.971077) (xy 6.64049 -287.023375) (xy 6.648247 -287.077327)
			(xy 6.648247 -287.131833) (xy 6.64049 -287.185785) (xy 6.625133 -287.238083) (xy 6.60249 -287.287664)
			(xy 6.573022 -287.333517) (xy 6.537328 -287.37471) (xy 6.496134 -287.410404) (xy 6.45028 -287.439872)
			(xy 6.400699 -287.462515) (xy 6.348401 -287.47787) (xy 6.294449 -287.485627) (xy 6.267196 -287.48609)
			(xy 6.237072 -287.485539) (xy 6.177574 -287.476056) (xy 6.120305 -287.457341) (xy 6.066688 -287.42986)
			(xy 6.018056 -287.394296) (xy 5.996432 -287.373314) (xy 5.989013 -287.366497) (xy 5.970428 -287.358763)
			(xy 5.960364 -287.358328) (xy 5.888228 -287.358328) (xy 5.878159 -287.358761) (xy 5.859561 -287.366476)
			(xy 5.85216 -287.373314) (xy 5.830534 -287.394293) (xy 5.781905 -287.429861) (xy 5.728289 -287.457341)
			(xy 5.671019 -287.476049) (xy 5.61152 -287.485521) (xy 5.581396 -287.48609) (xy 5.554145 -287.4856)
			(xy 5.500198 -287.477843) (xy 5.447904 -287.462488) (xy 5.398328 -287.439846) (xy 5.352478 -287.41038)
			(xy 5.311288 -287.374689) (xy 5.275597 -287.333499) (xy 5.246132 -287.287649) (xy 5.223491 -287.238072)
			(xy 5.208136 -287.185778) (xy 5.20038 -287.131831) (xy 0.635 -287.131831) (xy 0.635 -287.984001)
			(xy 11.94992 -287.984001) (xy 11.94992 -287.929499) (xy 11.957676 -287.875552) (xy 11.973031 -287.823257)
			(xy 11.995672 -287.773681) (xy 12.025138 -287.72783) (xy 12.060829 -287.686641) (xy 12.102019 -287.650949)
			(xy 12.147869 -287.621483) (xy 12.197446 -287.598842) (xy 12.24974 -287.583487) (xy 12.303687 -287.57573)
			(xy 12.330938 -287.575244) (xy 12.358307 -287.575736) (xy 12.412486 -287.583546) (xy 12.464989 -287.599028)
			(xy 12.514736 -287.621865) (xy 12.560704 -287.651585) (xy 12.581636 -287.669224) (xy 12.58189 -287.669478)
			(xy 12.588969 -287.675076) (xy 12.605892 -287.681314) (xy 12.61491 -287.68167) (xy 12.681966 -287.68167)
			(xy 12.690982 -287.681303) (xy 12.707899 -287.675063) (xy 12.714986 -287.669478) (xy 12.714986 -287.669224)
			(xy 12.71524 -287.669224) (xy 12.736187 -287.651603) (xy 12.782155 -287.621888) (xy 12.831899 -287.599048)
			(xy 12.884396 -287.583553) (xy 12.93857 -287.57572) (xy 12.965938 -287.575244) (xy 12.993191 -287.575703)
			(xy 13.047143 -287.58346) (xy 13.099441 -287.598816) (xy 13.149021 -287.621458) (xy 13.194875 -287.650927)
			(xy 13.236068 -287.68662) (xy 13.271762 -287.727813) (xy 13.301231 -287.773667) (xy 13.323873 -287.823247)
			(xy 13.33923 -287.875546) (xy 13.346987 -287.929497) (xy 13.346987 -287.984003) (xy 13.33923 -288.037954)
			(xy 13.323873 -288.090253) (xy 13.301231 -288.139833) (xy 13.271762 -288.185687) (xy 13.236068 -288.22688)
			(xy 13.194875 -288.262573) (xy 13.149021 -288.292042) (xy 13.099441 -288.314684) (xy 13.047143 -288.33004)
			(xy 12.993191 -288.337797) (xy 12.965938 -288.33826) (xy 12.938568 -288.337781) (xy 12.884389 -288.329968)
			(xy 12.831886 -288.314482) (xy 12.782139 -288.291643) (xy 12.736172 -288.261921) (xy 12.71524 -288.24428)
			(xy 12.714986 -288.244026) (xy 12.707914 -288.238419) (xy 12.690986 -288.232186) (xy 12.681966 -288.231834)
			(xy 12.61491 -288.231834) (xy 12.605893 -288.232189) (xy 12.588976 -288.238437) (xy 12.58189 -288.244026)
			(xy 12.58189 -288.24428) (xy 12.581636 -288.24428) (xy 12.560699 -288.261913) (xy 12.514728 -288.291626)
			(xy 12.464981 -288.314464) (xy 12.412482 -288.329956) (xy 12.358307 -288.337785) (xy 12.330938 -288.33826)
			(xy 12.303687 -288.33777) (xy 12.24974 -288.330013) (xy 12.197446 -288.314658) (xy 12.147869 -288.292017)
			(xy 12.102019 -288.262551) (xy 12.060829 -288.226859) (xy 12.025138 -288.18567) (xy 11.995672 -288.139819)
			(xy 11.973031 -288.090243) (xy 11.957676 -288.037948) (xy 11.94992 -287.984001) (xy 0.635 -287.984001)
			(xy 0.635 -289.258321) (xy 5.006068 -289.258321) (xy 5.006068 -289.203819) (xy 5.013824 -289.149872)
			(xy 5.029179 -289.097577) (xy 5.05182 -289.048) (xy 5.081286 -289.00215) (xy 5.116977 -288.96096)
			(xy 5.158167 -288.925268) (xy 5.204017 -288.895802) (xy 5.253593 -288.873161) (xy 5.305888 -288.857805)
			(xy 5.359835 -288.850048) (xy 5.387086 -288.849562) (xy 5.414457 -288.850021) (xy 5.468637 -288.857838)
			(xy 5.52114 -288.873328) (xy 5.570887 -288.896172) (xy 5.616853 -288.925899) (xy 5.637784 -288.943542)
			(xy 5.638038 -288.943796) (xy 5.645139 -288.949362) (xy 5.662045 -288.955621) (xy 5.671058 -288.955988)
			(xy 5.738114 -288.955988) (xy 5.747132 -288.95564) (xy 5.764049 -288.949387) (xy 5.771134 -288.943796)
			(xy 5.771134 -288.943542) (xy 5.771388 -288.943542) (xy 5.792319 -288.925902) (xy 5.838292 -288.896189)
			(xy 5.888039 -288.873352) (xy 5.94054 -288.857862) (xy 5.994717 -288.850035) (xy 6.022086 -288.849562)
			(xy 6.049339 -288.850025) (xy 6.10329 -288.857782) (xy 6.155589 -288.873137) (xy 6.205169 -288.89578)
			(xy 6.251023 -288.925247) (xy 6.292216 -288.960941) (xy 6.32791 -289.002134) (xy 6.357379 -289.047987)
			(xy 6.380021 -289.097568) (xy 6.395378 -289.149866) (xy 6.403135 -289.203817) (xy 6.403135 -289.258323)
			(xy 6.395378 -289.312274) (xy 6.380021 -289.364572) (xy 6.357379 -289.414153) (xy 6.32791 -289.460006)
			(xy 6.292216 -289.501199) (xy 6.251023 -289.536893) (xy 6.205169 -289.56636) (xy 6.155589 -289.589003)
			(xy 6.10329 -289.604358) (xy 6.049339 -289.612115) (xy 6.022086 -289.612578) (xy 5.994715 -289.612125)
			(xy 5.940535 -289.604305) (xy 5.888032 -289.588813) (xy 5.838285 -289.565968) (xy 5.792319 -289.536241)
			(xy 5.771388 -289.518598) (xy 5.771134 -289.518344) (xy 5.764047 -289.512759) (xy 5.74713 -289.506513)
			(xy 5.738114 -289.506152) (xy 5.671058 -289.506152) (xy 5.662043 -289.506525) (xy 5.645125 -289.51276)
			(xy 5.638038 -289.518344) (xy 5.638038 -289.518598) (xy 5.637784 -289.518598) (xy 5.616831 -289.536211)
			(xy 5.570864 -289.565927) (xy 5.521122 -289.588768) (xy 5.468626 -289.604265) (xy 5.414454 -289.6121)
			(xy 5.387086 -289.612578) (xy 5.359835 -289.612092) (xy 5.305888 -289.604335) (xy 5.253593 -289.588979)
			(xy 5.204017 -289.566338) (xy 5.158167 -289.536872) (xy 5.116977 -289.50118) (xy 5.081286 -289.45999)
			(xy 5.05182 -289.41414) (xy 5.029179 -289.364563) (xy 5.013824 -289.312268) (xy 5.006068 -289.258321)
			(xy 0.635 -289.258321) (xy 0.635 -304.457354) (xy 7.652256 -304.457354) (xy 7.656327 -304.401732)
			(xy 7.668453 -304.347295) (xy 7.688376 -304.295204) (xy 7.715672 -304.246569) (xy 7.749758 -304.202426)
			(xy 7.789907 -304.163717) (xy 7.835265 -304.131266) (xy 7.884865 -304.105765) (xy 7.937649 -304.087758)
			(xy 7.992492 -304.077628) (xy 8.048226 -304.075591) (xy 8.103663 -304.081691) (xy 8.15762 -304.095797)
			(xy 8.208949 -304.117609) (xy 8.256555 -304.146663) (xy 8.299423 -304.182338) (xy 8.33664 -304.223875)
			(xy 8.367413 -304.270388) (xy 8.391085 -304.320885) (xy 8.407153 -304.374292) (xy 8.415273 -304.429468)
			(xy 8.415782 -304.457354) (xy 8.415273 -304.48524) (xy 8.41306 -304.50028) (xy 14.926308 -304.50028)
			(xy 14.930379 -304.444658) (xy 14.942505 -304.390221) (xy 14.962428 -304.33813) (xy 14.989724 -304.289495)
			(xy 15.02381 -304.245352) (xy 15.063959 -304.206643) (xy 15.109317 -304.174192) (xy 15.158917 -304.148691)
			(xy 15.211701 -304.130684) (xy 15.266544 -304.120554) (xy 15.322278 -304.118517) (xy 15.377715 -304.124617)
			(xy 15.431672 -304.138723) (xy 15.483001 -304.160535) (xy 15.530607 -304.189589) (xy 15.573475 -304.225264)
			(xy 15.610692 -304.266801) (xy 15.641465 -304.313314) (xy 15.665137 -304.363811) (xy 15.681205 -304.417218)
			(xy 15.689325 -304.472394) (xy 15.689834 -304.50028) (xy 15.689325 -304.528166) (xy 15.681205 -304.583342)
			(xy 15.665137 -304.636749) (xy 15.641465 -304.687246) (xy 15.610692 -304.733759) (xy 15.573475 -304.775296)
			(xy 15.530607 -304.810971) (xy 15.483001 -304.840025) (xy 15.431672 -304.861837) (xy 15.377715 -304.875943)
			(xy 15.322278 -304.882043) (xy 15.266544 -304.880006) (xy 15.211701 -304.869876) (xy 15.158917 -304.851869)
			(xy 15.109317 -304.826368) (xy 15.063959 -304.793917) (xy 15.02381 -304.755208) (xy 14.989724 -304.711065)
			(xy 14.962428 -304.66243) (xy 14.942505 -304.610339) (xy 14.930379 -304.555902) (xy 14.926308 -304.50028)
			(xy 8.41306 -304.50028) (xy 8.407153 -304.540416) (xy 8.391085 -304.593823) (xy 8.367413 -304.64432)
			(xy 8.33664 -304.690833) (xy 8.299423 -304.73237) (xy 8.256555 -304.768045) (xy 8.208949 -304.797099)
			(xy 8.15762 -304.818911) (xy 8.103663 -304.833017) (xy 8.048226 -304.839117) (xy 7.992492 -304.83708)
			(xy 7.937649 -304.82695) (xy 7.884865 -304.808943) (xy 7.835265 -304.783442) (xy 7.789907 -304.750991)
			(xy 7.749758 -304.712282) (xy 7.715672 -304.668139) (xy 7.688376 -304.619504) (xy 7.668453 -304.567413)
			(xy 7.656327 -304.512976) (xy 7.652256 -304.457354) (xy 0.635 -304.457354) (xy 0.635 -305.159664)
			(xy 12.577824 -305.159664) (xy 12.581895 -305.104042) (xy 12.594021 -305.049605) (xy 12.613944 -304.997514)
			(xy 12.64124 -304.948879) (xy 12.675326 -304.904736) (xy 12.715475 -304.866027) (xy 12.760833 -304.833576)
			(xy 12.810433 -304.808075) (xy 12.863217 -304.790068) (xy 12.91806 -304.779938) (xy 12.973794 -304.777901)
			(xy 13.029231 -304.784001) (xy 13.083188 -304.798107) (xy 13.134517 -304.819919) (xy 13.182123 -304.848973)
			(xy 13.224991 -304.884648) (xy 13.262208 -304.926185) (xy 13.292981 -304.972698) (xy 13.316653 -305.023195)
			(xy 13.332721 -305.076602) (xy 13.340841 -305.131778) (xy 13.34135 -305.159664) (xy 13.340841 -305.18755)
			(xy 13.332721 -305.242726) (xy 13.316653 -305.296133) (xy 13.292981 -305.34663) (xy 13.262208 -305.393143)
			(xy 13.224991 -305.43468) (xy 13.182123 -305.470355) (xy 13.134517 -305.499409) (xy 13.083188 -305.521221)
			(xy 13.029231 -305.535327) (xy 12.973794 -305.541427) (xy 12.91806 -305.53939) (xy 12.863217 -305.52926)
			(xy 12.810433 -305.511253) (xy 12.760833 -305.485752) (xy 12.715475 -305.453301) (xy 12.675326 -305.414592)
			(xy 12.64124 -305.370449) (xy 12.613944 -305.321814) (xy 12.594021 -305.269723) (xy 12.581895 -305.215286)
			(xy 12.577824 -305.159664) (xy 0.635 -305.159664) (xy 0.635 -306.115466) (xy 13.635734 -306.115466)
			(xy 13.639805 -306.059844) (xy 13.651931 -306.005407) (xy 13.671854 -305.953316) (xy 13.69915 -305.904681)
			(xy 13.733236 -305.860538) (xy 13.773385 -305.821829) (xy 13.818743 -305.789378) (xy 13.868343 -305.763877)
			(xy 13.921127 -305.74587) (xy 13.97597 -305.73574) (xy 14.031704 -305.733703) (xy 14.087141 -305.739803)
			(xy 14.141098 -305.753909) (xy 14.192427 -305.775721) (xy 14.240033 -305.804775) (xy 14.282901 -305.84045)
			(xy 14.320118 -305.881987) (xy 14.350891 -305.9285) (xy 14.374563 -305.978997) (xy 14.390631 -306.032404)
			(xy 14.398751 -306.08758) (xy 14.39926 -306.115466) (xy 14.398751 -306.143352) (xy 14.390631 -306.198528)
			(xy 14.374563 -306.251935) (xy 14.350891 -306.302432) (xy 14.320118 -306.348945) (xy 14.282901 -306.390482)
			(xy 14.240033 -306.426157) (xy 14.192427 -306.455211) (xy 14.141098 -306.477023) (xy 14.087141 -306.491129)
			(xy 14.031704 -306.497229) (xy 13.97597 -306.495192) (xy 13.921127 -306.485062) (xy 13.868343 -306.467055)
			(xy 13.818743 -306.441554) (xy 13.773385 -306.409103) (xy 13.733236 -306.370394) (xy 13.69915 -306.326251)
			(xy 13.671854 -306.277616) (xy 13.651931 -306.225525) (xy 13.639805 -306.171088) (xy 13.635734 -306.115466)
			(xy 0.635 -306.115466) (xy 0.635 -306.731416) (xy 15.643858 -306.731416) (xy 15.647929 -306.675794)
			(xy 15.660055 -306.621357) (xy 15.679978 -306.569266) (xy 15.707274 -306.520631) (xy 15.74136 -306.476488)
			(xy 15.781509 -306.437779) (xy 15.826867 -306.405328) (xy 15.876467 -306.379827) (xy 15.929251 -306.36182)
			(xy 15.984094 -306.35169) (xy 16.039828 -306.349653) (xy 16.095265 -306.355753) (xy 16.149222 -306.369859)
			(xy 16.200551 -306.391671) (xy 16.248157 -306.420725) (xy 16.291025 -306.4564) (xy 16.328242 -306.497937)
			(xy 16.359015 -306.54445) (xy 16.382687 -306.594947) (xy 16.398755 -306.648354) (xy 16.406875 -306.70353)
			(xy 16.407384 -306.731416) (xy 16.406875 -306.759302) (xy 16.398755 -306.814478) (xy 16.382687 -306.867885)
			(xy 16.359015 -306.918382) (xy 16.328242 -306.964895) (xy 16.291025 -307.006432) (xy 16.248157 -307.042107)
			(xy 16.200551 -307.071161) (xy 16.149222 -307.092973) (xy 16.095265 -307.107079) (xy 16.039828 -307.113179)
			(xy 15.984094 -307.111142) (xy 15.929251 -307.101012) (xy 15.876467 -307.083005) (xy 15.826867 -307.057504)
			(xy 15.781509 -307.025053) (xy 15.74136 -306.986344) (xy 15.707274 -306.942201) (xy 15.679978 -306.893566)
			(xy 15.660055 -306.841475) (xy 15.647929 -306.787038) (xy 15.643858 -306.731416) (xy 0.635 -306.731416)
			(xy 0.635 -307.621686) (xy 12.02385 -307.621686) (xy 12.027921 -307.566064) (xy 12.040047 -307.511627)
			(xy 12.05997 -307.459536) (xy 12.087266 -307.410901) (xy 12.121352 -307.366758) (xy 12.161501 -307.328049)
			(xy 12.206859 -307.295598) (xy 12.256459 -307.270097) (xy 12.309243 -307.25209) (xy 12.364086 -307.24196)
			(xy 12.41982 -307.239923) (xy 12.475257 -307.246023) (xy 12.529214 -307.260129) (xy 12.580543 -307.281941)
			(xy 12.628149 -307.310995) (xy 12.671017 -307.34667) (xy 12.708234 -307.388207) (xy 12.739007 -307.43472)
			(xy 12.750091 -307.458364) (xy 13.739366 -307.458364) (xy 13.743437 -307.402742) (xy 13.755563 -307.348305)
			(xy 13.775486 -307.296214) (xy 13.802782 -307.247579) (xy 13.836868 -307.203436) (xy 13.877017 -307.164727)
			(xy 13.922375 -307.132276) (xy 13.971975 -307.106775) (xy 14.024759 -307.088768) (xy 14.079602 -307.078638)
			(xy 14.135336 -307.076601) (xy 14.190773 -307.082701) (xy 14.24473 -307.096807) (xy 14.296059 -307.118619)
			(xy 14.343665 -307.147673) (xy 14.386533 -307.183348) (xy 14.42375 -307.224885) (xy 14.454523 -307.271398)
			(xy 14.478195 -307.321895) (xy 14.494263 -307.375302) (xy 14.502383 -307.430478) (xy 14.502892 -307.458364)
			(xy 14.502383 -307.48625) (xy 14.494263 -307.541426) (xy 14.478195 -307.594833) (xy 14.454523 -307.64533)
			(xy 14.42375 -307.691843) (xy 14.386533 -307.73338) (xy 14.343665 -307.769055) (xy 14.296059 -307.798109)
			(xy 14.24473 -307.819921) (xy 14.190773 -307.834027) (xy 14.135336 -307.840127) (xy 14.079602 -307.83809)
			(xy 14.024759 -307.82796) (xy 13.971975 -307.809953) (xy 13.922375 -307.784452) (xy 13.877017 -307.752001)
			(xy 13.836868 -307.713292) (xy 13.802782 -307.669149) (xy 13.775486 -307.620514) (xy 13.755563 -307.568423)
			(xy 13.743437 -307.513986) (xy 13.739366 -307.458364) (xy 12.750091 -307.458364) (xy 12.762679 -307.485217)
			(xy 12.778747 -307.538624) (xy 12.786867 -307.5938) (xy 12.787376 -307.621686) (xy 12.786867 -307.649572)
			(xy 12.778747 -307.704748) (xy 12.762679 -307.758155) (xy 12.739007 -307.808652) (xy 12.708234 -307.855165)
			(xy 12.671017 -307.896702) (xy 12.628149 -307.932377) (xy 12.580543 -307.961431) (xy 12.529214 -307.983243)
			(xy 12.475257 -307.997349) (xy 12.41982 -308.003449) (xy 12.364086 -308.001412) (xy 12.309243 -307.991282)
			(xy 12.256459 -307.973275) (xy 12.206859 -307.947774) (xy 12.161501 -307.915323) (xy 12.121352 -307.876614)
			(xy 12.087266 -307.832471) (xy 12.05997 -307.783836) (xy 12.040047 -307.731745) (xy 12.027921 -307.677308)
			(xy 12.02385 -307.621686) (xy 0.635 -307.621686) (xy 0.635 -308.929024) (xy 13.201648 -308.929024)
			(xy 13.205719 -308.873402) (xy 13.217845 -308.818965) (xy 13.237768 -308.766874) (xy 13.265064 -308.718239)
			(xy 13.29915 -308.674096) (xy 13.339299 -308.635387) (xy 13.384657 -308.602936) (xy 13.434257 -308.577435)
			(xy 13.487041 -308.559428) (xy 13.541884 -308.549298) (xy 13.597618 -308.547261) (xy 13.653055 -308.553361)
			(xy 13.707012 -308.567467) (xy 13.758341 -308.589279) (xy 13.805947 -308.618333) (xy 13.848815 -308.654008)
			(xy 13.886032 -308.695545) (xy 13.916805 -308.742058) (xy 13.940477 -308.792555) (xy 13.956545 -308.845962)
			(xy 13.964665 -308.901138) (xy 13.965174 -308.929024) (xy 13.964665 -308.95691) (xy 13.956545 -309.012086)
			(xy 13.940477 -309.065493) (xy 13.916805 -309.11599) (xy 13.886032 -309.162503) (xy 13.848815 -309.20404)
			(xy 13.805947 -309.239715) (xy 13.758341 -309.268769) (xy 13.707012 -309.290581) (xy 13.653055 -309.304687)
			(xy 13.597618 -309.310787) (xy 13.541884 -309.30875) (xy 13.487041 -309.29862) (xy 13.434257 -309.280613)
			(xy 13.384657 -309.255112) (xy 13.339299 -309.222661) (xy 13.29915 -309.183952) (xy 13.265064 -309.139809)
			(xy 13.237768 -309.091174) (xy 13.217845 -309.039083) (xy 13.205719 -308.984646) (xy 13.201648 -308.929024)
			(xy 0.635 -308.929024) (xy 0.635 -318.52997) (xy 10.590784 -318.52997) (xy 10.591212 -318.502598)
			(xy 10.599036 -318.448417) (xy 10.614533 -318.395912) (xy 10.637383 -318.346166) (xy 10.667118 -318.300202)
			(xy 10.684764 -318.279272) (xy 10.685018 -318.279018) (xy 10.690605 -318.271932) (xy 10.696851 -318.255015)
			(xy 10.69721 -318.245998) (xy 10.69721 -318.178942) (xy 10.696831 -318.169927) (xy 10.690598 -318.15301)
			(xy 10.685018 -318.145922) (xy 10.684764 -318.145922) (xy 10.684764 -318.145668) (xy 10.667138 -318.124726)
			(xy 10.637425 -318.078755) (xy 10.614587 -318.02901) (xy 10.599093 -317.976512) (xy 10.591261 -317.922338)
			(xy 10.590784 -317.89497) (xy 10.59125 -317.867718) (xy 10.59901 -317.81377) (xy 10.614369 -317.761476)
			(xy 10.637013 -317.711899) (xy 10.666482 -317.666049) (xy 10.702175 -317.624859) (xy 10.743367 -317.589168)
			(xy 10.789218 -317.559702) (xy 10.838796 -317.537061) (xy 10.891092 -317.521706) (xy 10.94504 -317.513948)
			(xy 10.972292 -317.513462) (xy 10.999663 -317.513918) (xy 11.053843 -317.521736) (xy 11.106347 -317.537226)
			(xy 11.156093 -317.560071) (xy 11.202059 -317.589799) (xy 11.22299 -317.607442) (xy 11.223244 -317.607696)
			(xy 11.230343 -317.613265) (xy 11.24725 -317.619522) (xy 11.256264 -317.619888) (xy 11.32332 -317.619888)
			(xy 11.332338 -317.619543) (xy 11.349255 -317.613287) (xy 11.35634 -317.607696) (xy 11.35634 -317.607442)
			(xy 11.356594 -317.607442) (xy 11.377527 -317.589801) (xy 11.423495 -317.560077) (xy 11.473241 -317.537231)
			(xy 11.525743 -317.521735) (xy 11.579921 -317.513906) (xy 11.634663 -317.513906) (xy 11.688841 -317.521735)
			(xy 11.741343 -317.537231) (xy 11.791089 -317.560077) (xy 11.837057 -317.589801) (xy 11.85799 -317.607442)
			(xy 11.858244 -317.607696) (xy 11.865343 -317.613265) (xy 11.88225 -317.619522) (xy 11.891264 -317.619888)
			(xy 11.95832 -317.619888) (xy 11.967338 -317.619543) (xy 11.984255 -317.613287) (xy 11.99134 -317.607696)
			(xy 11.99134 -317.607442) (xy 11.991594 -317.607442) (xy 12.012523 -317.589799) (xy 12.058496 -317.560086)
			(xy 12.108244 -317.53725) (xy 12.160746 -317.52176) (xy 12.214922 -317.513934) (xy 12.242292 -317.513462)
			(xy 12.269542 -317.513985) (xy 12.323487 -317.52174) (xy 12.375779 -317.537092) (xy 12.425354 -317.55973)
			(xy 12.471203 -317.589193) (xy 12.512393 -317.624881) (xy 12.548084 -317.666067) (xy 12.577551 -317.711913)
			(xy 12.600194 -317.761486) (xy 12.615552 -317.813776) (xy 12.623312 -317.86772) (xy 12.6238 -317.89497)
			(xy 12.623316 -317.92234) (xy 12.615503 -317.976518) (xy 12.600018 -318.029021) (xy 12.57718 -318.078768)
			(xy 12.547459 -318.124736) (xy 12.52982 -318.145668) (xy 12.529566 -318.145922) (xy 12.52396 -318.152995)
			(xy 12.517726 -318.169922) (xy 12.517374 -318.178942) (xy 12.517374 -318.245998) (xy 12.517738 -318.255014)
			(xy 12.523981 -318.271931) (xy 12.529566 -318.279018) (xy 12.52982 -318.279018) (xy 12.52982 -318.279272)
			(xy 12.547463 -318.300201) (xy 12.577173 -318.346175) (xy 12.600008 -318.395923) (xy 12.615498 -318.448425)
			(xy 12.623326 -318.502601) (xy 12.6238 -318.52997) (xy 12.623317 -318.557222) (xy 12.615564 -318.611173)
			(xy 12.600211 -318.663471) (xy 12.577571 -318.713052) (xy 12.548106 -318.758905) (xy 12.512414 -318.800099)
			(xy 12.471223 -318.835793) (xy 12.425371 -318.865261) (xy 12.375792 -318.887903) (xy 12.323495 -318.903259)
			(xy 12.269544 -318.911015) (xy 12.242292 -318.911478) (xy 12.214921 -318.911022) (xy 12.160742 -318.903203)
			(xy 12.108238 -318.887711) (xy 12.058491 -318.864867) (xy 12.012525 -318.83514) (xy 11.991594 -318.817498)
			(xy 11.99134 -318.817244) (xy 11.984251 -318.811661) (xy 11.967336 -318.805414) (xy 11.95832 -318.805052)
			(xy 11.891264 -318.805052) (xy 11.882244 -318.80538) (xy 11.865327 -318.811646) (xy 11.858244 -318.817244)
			(xy 11.85799 -318.817498) (xy 11.837057 -318.835139) (xy 11.791089 -318.864863) (xy 11.741343 -318.887709)
			(xy 11.688841 -318.903205) (xy 11.634663 -318.911034) (xy 11.579921 -318.911034) (xy 11.525743 -318.903205)
			(xy 11.473241 -318.887709) (xy 11.423495 -318.864863) (xy 11.377527 -318.835139) (xy 11.356594 -318.817498)
			(xy 11.35634 -318.817244) (xy 11.349251 -318.811661) (xy 11.332336 -318.805414) (xy 11.32332 -318.805052)
			(xy 11.256264 -318.805052) (xy 11.247244 -318.80538) (xy 11.230327 -318.811646) (xy 11.223244 -318.817244)
			(xy 11.223244 -318.817498) (xy 11.22299 -318.817498) (xy 11.202072 -318.835155) (xy 11.156096 -318.864864)
			(xy 11.106344 -318.887697) (xy 11.053841 -318.903184) (xy 10.999662 -318.911007) (xy 10.972292 -318.911478)
			(xy 10.945038 -318.911052) (xy 10.891084 -318.903293) (xy 10.838783 -318.887935) (xy 10.789201 -318.865289)
			(xy 10.743347 -318.835817) (xy 10.702153 -318.80012) (xy 10.66646 -318.758923) (xy 10.636993 -318.713065)
			(xy 10.614352 -318.663481) (xy 10.598999 -318.611179) (xy 10.591245 -318.557224) (xy 10.590784 -318.52997)
			(xy 0.635 -318.52997) (xy 0.635 -323.153278) (xy 14.462504 -323.153278) (xy 14.466575 -323.097656)
			(xy 14.478701 -323.043219) (xy 14.498624 -322.991128) (xy 14.52592 -322.942493) (xy 14.560006 -322.89835)
			(xy 14.600155 -322.859641) (xy 14.645513 -322.82719) (xy 14.695113 -322.801689) (xy 14.747897 -322.783682)
			(xy 14.80274 -322.773552) (xy 14.858474 -322.771515) (xy 14.913911 -322.777615) (xy 14.967868 -322.791721)
			(xy 15.019197 -322.813533) (xy 15.066803 -322.842587) (xy 15.109671 -322.878262) (xy 15.146888 -322.919799)
			(xy 15.177661 -322.966312) (xy 15.201333 -323.016809) (xy 15.217401 -323.070216) (xy 15.225521 -323.125392)
			(xy 15.22603 -323.153278) (xy 15.225521 -323.181164) (xy 15.217401 -323.23634) (xy 15.201333 -323.289747)
			(xy 15.177661 -323.340244) (xy 15.146888 -323.386757) (xy 15.109671 -323.428294) (xy 15.066803 -323.463969)
			(xy 15.019197 -323.493023) (xy 14.967868 -323.514835) (xy 14.913911 -323.528941) (xy 14.858474 -323.535041)
			(xy 14.80274 -323.533004) (xy 14.747897 -323.522874) (xy 14.695113 -323.504867) (xy 14.645513 -323.479366)
			(xy 14.600155 -323.446915) (xy 14.560006 -323.408206) (xy 14.52592 -323.364063) (xy 14.498624 -323.315428)
			(xy 14.478701 -323.263337) (xy 14.466575 -323.2089) (xy 14.462504 -323.153278) (xy 0.635 -323.153278)
			(xy 0.635 -341.292688) (xy 11.713716 -341.292688) (xy 11.717787 -341.237066) (xy 11.729913 -341.182629)
			(xy 11.749836 -341.130538) (xy 11.777132 -341.081903) (xy 11.811218 -341.03776) (xy 11.851367 -340.999051)
			(xy 11.896725 -340.9666) (xy 11.946325 -340.941099) (xy 11.999109 -340.923092) (xy 12.053952 -340.912962)
			(xy 12.109686 -340.910925) (xy 12.165123 -340.917025) (xy 12.21908 -340.931131) (xy 12.270409 -340.952943)
			(xy 12.318015 -340.981997) (xy 12.360883 -341.017672) (xy 12.3981 -341.059209) (xy 12.428873 -341.105722)
			(xy 12.452545 -341.156219) (xy 12.468613 -341.209626) (xy 12.476733 -341.264802) (xy 12.477242 -341.292688)
			(xy 12.476733 -341.320574) (xy 12.468613 -341.37575) (xy 12.452545 -341.429157) (xy 12.428873 -341.479654)
			(xy 12.3981 -341.526167) (xy 12.360883 -341.567704) (xy 12.318015 -341.603379) (xy 12.270409 -341.632433)
			(xy 12.21908 -341.654245) (xy 12.165123 -341.668351) (xy 12.109686 -341.674451) (xy 12.053952 -341.672414)
			(xy 11.999109 -341.662284) (xy 11.946325 -341.644277) (xy 11.896725 -341.618776) (xy 11.851367 -341.586325)
			(xy 11.811218 -341.547616) (xy 11.777132 -341.503473) (xy 11.749836 -341.454838) (xy 11.729913 -341.402747)
			(xy 11.717787 -341.34831) (xy 11.713716 -341.292688) (xy 0.635 -341.292688) (xy 0.635 -348.976496)
			(xy 4.708641 -348.976496) (xy 4.708641 -348.847356) (xy 4.716591 -348.718461) (xy 4.732461 -348.590301)
			(xy 4.75619 -348.46336) (xy 4.787689 -348.338121) (xy 4.826838 -348.215058) (xy 4.873489 -348.094639)
			(xy 4.927464 -347.97732) (xy 4.988559 -347.863546) (xy 5.056542 -347.753749) (xy 5.131156 -347.648346)
			(xy 5.212117 -347.547736) (xy 5.299117 -347.452301) (xy 5.391828 -347.362402) (xy 5.489898 -347.278381)
			(xy 5.592953 -347.200557) (xy 5.700604 -347.129225) (xy 5.812443 -347.064655) (xy 5.928044 -347.007093)
			(xy 6.046969 -346.956756) (xy 6.168768 -346.913836) (xy 6.292978 -346.878495) (xy 6.419127 -346.850868)
			(xy 6.546739 -346.831059) (xy 6.675328 -346.819143) (xy 6.804406 -346.815167) (xy 6.933484 -346.819143)
			(xy 7.062073 -346.831059) (xy 7.189685 -346.850868) (xy 7.315834 -346.878495) (xy 7.440044 -346.913836)
			(xy 7.561843 -346.956756) (xy 7.680768 -347.007093) (xy 7.796369 -347.064655) (xy 7.908208 -347.129225)
			(xy 8.015859 -347.200557) (xy 8.118914 -347.278381) (xy 8.216984 -347.362402) (xy 8.309695 -347.452301)
			(xy 8.396695 -347.547736) (xy 8.477656 -347.648346) (xy 8.55227 -347.753749) (xy 8.620253 -347.863546)
			(xy 8.681348 -347.97732) (xy 8.735323 -348.094639) (xy 8.781974 -348.215058) (xy 8.821123 -348.338121)
			(xy 8.852622 -348.46336) (xy 8.876351 -348.590301) (xy 8.892221 -348.718461) (xy 8.900171 -348.847356)
			(xy 8.900668 -348.911926) (xy 8.900171 -348.976496) (xy 8.892221 -349.105391) (xy 8.876351 -349.233551)
			(xy 8.852622 -349.360492) (xy 8.821123 -349.485731) (xy 8.781974 -349.608794) (xy 8.735323 -349.729213)
			(xy 8.681348 -349.846532) (xy 8.620253 -349.960306) (xy 8.55227 -350.070103) (xy 8.477656 -350.175506)
			(xy 8.396695 -350.276116) (xy 8.309695 -350.371551) (xy 8.216984 -350.46145) (xy 8.118914 -350.545471)
			(xy 8.015859 -350.623295) (xy 7.908208 -350.694627) (xy 7.796369 -350.759197) (xy 7.680768 -350.816759)
			(xy 7.561843 -350.867096) (xy 7.440044 -350.910016) (xy 7.315834 -350.945357) (xy 7.189685 -350.972984)
			(xy 7.062073 -350.992793) (xy 6.933484 -351.004709) (xy 6.804406 -351.008686) (xy 6.675328 -351.004709)
			(xy 6.546739 -350.992793) (xy 6.419127 -350.972984) (xy 6.292978 -350.945357) (xy 6.168768 -350.910016)
			(xy 6.046969 -350.867096) (xy 5.928044 -350.816759) (xy 5.812443 -350.759197) (xy 5.700604 -350.694627)
			(xy 5.592953 -350.623295) (xy 5.489898 -350.545471) (xy 5.391828 -350.46145) (xy 5.299117 -350.371551)
			(xy 5.212117 -350.276116) (xy 5.131156 -350.175506) (xy 5.056542 -350.070103) (xy 4.988559 -349.960306)
			(xy 4.927464 -349.846532) (xy 4.873489 -349.729213) (xy 4.826838 -349.608794) (xy 4.787689 -349.485731)
			(xy 4.75619 -349.360492) (xy 4.732461 -349.233551) (xy 4.716591 -349.105391) (xy 4.708641 -348.976496)
			(xy 0.635 -348.976496) (xy 0.635 -365.288322) (xy 2.818128 -365.288322) (xy 2.822199 -365.2327) (xy 2.834325 -365.178263)
			(xy 2.854248 -365.126172) (xy 2.881544 -365.077537) (xy 2.91563 -365.033394) (xy 2.955779 -364.994685)
			(xy 3.001137 -364.962234) (xy 3.050737 -364.936733) (xy 3.103521 -364.918726) (xy 3.158364 -364.908596)
			(xy 3.214098 -364.906559) (xy 3.269535 -364.912659) (xy 3.323492 -364.926765) (xy 3.374821 -364.948577)
			(xy 3.422427 -364.977631) (xy 3.465295 -365.013306) (xy 3.502512 -365.054843) (xy 3.533285 -365.101356)
			(xy 3.556957 -365.151853) (xy 3.573025 -365.20526) (xy 3.581145 -365.260436) (xy 3.581654 -365.288322)
			(xy 3.581145 -365.316208) (xy 3.573025 -365.371384) (xy 3.56676 -365.392208) (xy 7.202932 -365.392208)
			(xy 7.203418 -365.364957) (xy 7.211174 -365.311009) (xy 7.226529 -365.258714) (xy 7.249171 -365.209137)
			(xy 7.278637 -365.163287) (xy 7.314328 -365.122096) (xy 7.355519 -365.086405) (xy 7.401369 -365.056939)
			(xy 7.450946 -365.034297) (xy 7.503241 -365.018942) (xy 7.557189 -365.011186) (xy 7.611691 -365.011186)
			(xy 7.665639 -365.018942) (xy 7.717934 -365.034297) (xy 7.767511 -365.056939) (xy 7.813361 -365.086405)
			(xy 7.854552 -365.122096) (xy 7.890243 -365.163287) (xy 7.919709 -365.209137) (xy 7.942351 -365.258714)
			(xy 7.957706 -365.311009) (xy 7.965462 -365.364957) (xy 7.965948 -365.392208) (xy 7.965512 -365.418628)
			(xy 7.958226 -365.470963) (xy 7.94378 -365.521791) (xy 7.922453 -365.570135) (xy 7.894652 -365.61507)
			(xy 7.86091 -365.655735) (xy 7.821875 -365.691348) (xy 7.80034 -365.70666) (xy 7.788863 -365.715046)
			(xy 7.770739 -365.736932) (xy 7.759346 -365.762963) (xy 7.755566 -365.791126) (xy 7.759691 -365.819241)
			(xy 7.771402 -365.845131) (xy 7.789793 -365.866792) (xy 7.801356 -365.875062) (xy 7.823355 -365.890327)
			(xy 7.863301 -365.925982) (xy 7.897866 -365.966875) (xy 7.926371 -366.012201) (xy 7.948254 -366.061069)
			(xy 7.963087 -366.112518) (xy 7.970576 -366.165536) (xy 7.971028 -366.192308) (xy 7.970542 -366.219559)
			(xy 7.962786 -366.273507) (xy 7.947431 -366.325802) (xy 7.924789 -366.375379) (xy 7.895323 -366.421229)
			(xy 7.859632 -366.46242) (xy 7.818441 -366.498111) (xy 7.772591 -366.527577) (xy 7.723014 -366.550219)
			(xy 7.670719 -366.565574) (xy 7.616771 -366.57333) (xy 7.562269 -366.57333) (xy 7.508321 -366.565574)
			(xy 7.456026 -366.550219) (xy 7.406449 -366.527577) (xy 7.360599 -366.498111) (xy 7.319408 -366.46242)
			(xy 7.283717 -366.421229) (xy 7.254251 -366.375379) (xy 7.231609 -366.325802) (xy 7.216254 -366.273507)
			(xy 7.208498 -366.219559) (xy 7.208012 -366.192308) (xy 7.208434 -366.165887) (xy 7.215719 -366.11355)
			(xy 7.230165 -366.062722) (xy 7.251495 -366.014376) (xy 7.279298 -365.969441) (xy 7.313043 -365.928777)
			(xy 7.352082 -365.893166) (xy 7.37362 -365.877856) (xy 7.385086 -365.869453) (xy 7.403216 -365.847574)
			(xy 7.414615 -365.821545) (xy 7.418399 -365.793383) (xy 7.414275 -365.765268) (xy 7.402562 -365.739379)
			(xy 7.384168 -365.717721) (xy 7.372604 -365.709454) (xy 7.350584 -365.694217) (xy 7.31064 -365.658556)
			(xy 7.276077 -365.617658) (xy 7.247575 -365.572327) (xy 7.225695 -365.523455) (xy 7.210867 -365.472002)
			(xy 7.203382 -365.418981) (xy 7.202932 -365.392208) (xy 3.56676 -365.392208) (xy 3.556957 -365.424791)
			(xy 3.533285 -365.475288) (xy 3.502512 -365.521801) (xy 3.465295 -365.563338) (xy 3.422427 -365.599013)
			(xy 3.374821 -365.628067) (xy 3.323492 -365.649879) (xy 3.269535 -365.663985) (xy 3.214098 -365.670085)
			(xy 3.158364 -365.668048) (xy 3.103521 -365.657918) (xy 3.050737 -365.639911) (xy 3.001137 -365.61441)
			(xy 2.955779 -365.581959) (xy 2.91563 -365.54325) (xy 2.881544 -365.499107) (xy 2.854248 -365.450472)
			(xy 2.834325 -365.398381) (xy 2.822199 -365.343944) (xy 2.818128 -365.288322) (xy 0.635 -365.288322)
			(xy 0.635 -368.23269) (xy 5.613144 -368.23269) (xy 5.617215 -368.177068) (xy 5.629341 -368.122631)
			(xy 5.649264 -368.07054) (xy 5.67656 -368.021905) (xy 5.710646 -367.977762) (xy 5.750795 -367.939053)
			(xy 5.796153 -367.906602) (xy 5.845753 -367.881101) (xy 5.898537 -367.863094) (xy 5.95338 -367.852964)
			(xy 6.009114 -367.850927) (xy 6.064551 -367.857027) (xy 6.118508 -367.871133) (xy 6.169837 -367.892945)
			(xy 6.217443 -367.921999) (xy 6.260311 -367.957674) (xy 6.297528 -367.999211) (xy 6.328301 -368.045724)
			(xy 6.351973 -368.096221) (xy 6.368041 -368.149628) (xy 6.376161 -368.204804) (xy 6.37667 -368.23269)
			(xy 6.376161 -368.260576) (xy 6.368041 -368.315752) (xy 6.351973 -368.369159) (xy 6.328301 -368.419656)
			(xy 6.297528 -368.466169) (xy 6.260311 -368.507706) (xy 6.217443 -368.543381) (xy 6.169837 -368.572435)
			(xy 6.118508 -368.594247) (xy 6.064551 -368.608353) (xy 6.009114 -368.614453) (xy 5.95338 -368.612416)
			(xy 5.898537 -368.602286) (xy 5.845753 -368.584279) (xy 5.796153 -368.558778) (xy 5.750795 -368.526327)
			(xy 5.710646 -368.487618) (xy 5.67656 -368.443475) (xy 5.649264 -368.39484) (xy 5.629341 -368.342749)
			(xy 5.617215 -368.288312) (xy 5.613144 -368.23269) (xy 0.635 -368.23269) (xy 0.635 -372.100847) (xy 8.642336 -372.100847)
			(xy 8.642336 -372.040913) (xy 8.650159 -371.981491) (xy 8.665671 -371.923598) (xy 8.688607 -371.868226)
			(xy 8.718575 -371.81632) (xy 8.755061 -371.768771) (xy 8.797441 -371.726391) (xy 8.84499 -371.689905)
			(xy 8.896896 -371.659937) (xy 8.952268 -371.637001) (xy 9.010161 -371.621489) (xy 9.069583 -371.613666)
			(xy 9.09955 -371.613176) (xy 9.96315 -371.613176) (xy 9.993118 -371.613658) (xy 10.052541 -371.621481)
			(xy 10.110435 -371.636994) (xy 10.165808 -371.65993) (xy 10.217714 -371.689898) (xy 10.265264 -371.726385)
			(xy 10.307645 -371.768766) (xy 10.344132 -371.816316) (xy 10.3741 -371.868222) (xy 10.397036 -371.923595)
			(xy 10.412549 -371.981489) (xy 10.420372 -372.040912) (xy 10.420372 -372.100848) (xy 10.412549 -372.160271)
			(xy 10.397036 -372.218165) (xy 10.3741 -372.273538) (xy 10.344132 -372.325444) (xy 10.307645 -372.372994)
			(xy 10.265264 -372.415375) (xy 10.217714 -372.451862) (xy 10.165808 -372.48183) (xy 10.110435 -372.504766)
			(xy 10.052541 -372.520279) (xy 9.993118 -372.528102) (xy 9.96315 -372.528592) (xy 9.09955 -372.528592)
			(xy 9.069583 -372.528094) (xy 9.010161 -372.520271) (xy 8.952268 -372.504759) (xy 8.896896 -372.481823)
			(xy 8.84499 -372.451855) (xy 8.797441 -372.415369) (xy 8.755061 -372.372989) (xy 8.718575 -372.32544)
			(xy 8.688607 -372.273534) (xy 8.665671 -372.218162) (xy 8.650159 -372.160269) (xy 8.642336 -372.100847)
			(xy 0.635 -372.100847) (xy 0.635 -372.921784) (xy 3.759198 -372.921784) (xy 3.763269 -372.866162)
			(xy 3.775395 -372.811725) (xy 3.795318 -372.759634) (xy 3.822614 -372.710999) (xy 3.8567 -372.666856)
			(xy 3.896849 -372.628147) (xy 3.942207 -372.595696) (xy 3.991807 -372.570195) (xy 4.044591 -372.552188)
			(xy 4.099434 -372.542058) (xy 4.155168 -372.540021) (xy 4.210605 -372.546121) (xy 4.264562 -372.560227)
			(xy 4.315891 -372.582039) (xy 4.363497 -372.611093) (xy 4.406365 -372.646768) (xy 4.443582 -372.688305)
			(xy 4.474355 -372.734818) (xy 4.498027 -372.785315) (xy 4.514095 -372.838722) (xy 4.522215 -372.893898)
			(xy 4.522724 -372.921784) (xy 4.522215 -372.94967) (xy 4.514095 -373.004846) (xy 4.498027 -373.058253)
			(xy 4.474355 -373.10875) (xy 4.443582 -373.155263) (xy 4.406365 -373.1968) (xy 4.363497 -373.232475)
			(xy 4.315891 -373.261529) (xy 4.264562 -373.283341) (xy 4.210605 -373.297447) (xy 4.155168 -373.303547)
			(xy 4.099434 -373.30151) (xy 4.044591 -373.29138) (xy 3.991807 -373.273373) (xy 3.942207 -373.247872)
			(xy 3.896849 -373.215421) (xy 3.8567 -373.176712) (xy 3.822614 -373.132569) (xy 3.795318 -373.083934)
			(xy 3.775395 -373.031843) (xy 3.763269 -372.977406) (xy 3.759198 -372.921784) (xy 0.635 -372.921784)
			(xy 0.635 -379.540516) (xy 2.180588 -379.540516) (xy 2.184659 -379.484894) (xy 2.196785 -379.430457)
			(xy 2.216708 -379.378366) (xy 2.244004 -379.329731) (xy 2.27809 -379.285588) (xy 2.318239 -379.246879)
			(xy 2.363597 -379.214428) (xy 2.413197 -379.188927) (xy 2.465981 -379.17092) (xy 2.520824 -379.16079)
			(xy 2.576558 -379.158753) (xy 2.631995 -379.164853) (xy 2.685952 -379.178959) (xy 2.737281 -379.200771)
			(xy 2.784887 -379.229825) (xy 2.827755 -379.2655) (xy 2.864972 -379.307037) (xy 2.895745 -379.35355)
			(xy 2.919417 -379.404047) (xy 2.935485 -379.457454) (xy 2.943605 -379.51263) (xy 2.944114 -379.540516)
			(xy 3.653788 -379.540516) (xy 3.657859 -379.484894) (xy 3.669985 -379.430457) (xy 3.689908 -379.378366)
			(xy 3.717204 -379.329731) (xy 3.75129 -379.285588) (xy 3.791439 -379.246879) (xy 3.836797 -379.214428)
			(xy 3.886397 -379.188927) (xy 3.939181 -379.17092) (xy 3.994024 -379.16079) (xy 4.049758 -379.158753)
			(xy 4.105195 -379.164853) (xy 4.159152 -379.178959) (xy 4.210481 -379.200771) (xy 4.258087 -379.229825)
			(xy 4.300955 -379.2655) (xy 4.338172 -379.307037) (xy 4.368945 -379.35355) (xy 4.392617 -379.404047)
			(xy 4.408685 -379.457454) (xy 4.416805 -379.51263) (xy 4.417314 -379.540516) (xy 4.416805 -379.568402)
			(xy 4.408685 -379.623578) (xy 4.392617 -379.676985) (xy 4.368945 -379.727482) (xy 4.338172 -379.773995)
			(xy 4.300955 -379.815532) (xy 4.258087 -379.851207) (xy 4.210481 -379.880261) (xy 4.159152 -379.902073)
			(xy 4.105195 -379.916179) (xy 4.049758 -379.922279) (xy 3.994024 -379.920242) (xy 3.939181 -379.910112)
			(xy 3.886397 -379.892105) (xy 3.836797 -379.866604) (xy 3.791439 -379.834153) (xy 3.75129 -379.795444)
			(xy 3.717204 -379.751301) (xy 3.689908 -379.702666) (xy 3.669985 -379.650575) (xy 3.657859 -379.596138)
			(xy 3.653788 -379.540516) (xy 2.944114 -379.540516) (xy 2.943605 -379.568402) (xy 2.935485 -379.623578)
			(xy 2.919417 -379.676985) (xy 2.895745 -379.727482) (xy 2.864972 -379.773995) (xy 2.827755 -379.815532)
			(xy 2.784887 -379.851207) (xy 2.737281 -379.880261) (xy 2.685952 -379.902073) (xy 2.631995 -379.916179)
			(xy 2.576558 -379.922279) (xy 2.520824 -379.920242) (xy 2.465981 -379.910112) (xy 2.413197 -379.892105)
			(xy 2.363597 -379.866604) (xy 2.318239 -379.834153) (xy 2.27809 -379.795444) (xy 2.244004 -379.751301)
			(xy 2.216708 -379.702666) (xy 2.196785 -379.650575) (xy 2.184659 -379.596138) (xy 2.180588 -379.540516)
			(xy 0.635 -379.540516) (xy 0.635 -381.338836) (xy 1.266188 -381.338836) (xy 1.270259 -381.283214)
			(xy 1.282385 -381.228777) (xy 1.302308 -381.176686) (xy 1.329604 -381.128051) (xy 1.36369 -381.083908)
			(xy 1.403839 -381.045199) (xy 1.449197 -381.012748) (xy 1.498797 -380.987247) (xy 1.551581 -380.96924)
			(xy 1.606424 -380.95911) (xy 1.662158 -380.957073) (xy 1.717595 -380.963173) (xy 1.771552 -380.977279)
			(xy 1.822881 -380.999091) (xy 1.870487 -381.028145) (xy 1.913355 -381.06382) (xy 1.950572 -381.105357)
			(xy 1.981345 -381.15187) (xy 2.005017 -381.202367) (xy 2.021085 -381.255774) (xy 2.029205 -381.31095)
			(xy 2.029714 -381.338836) (xy 2.029533 -381.348742) (xy 8.047988 -381.348742) (xy 8.052059 -381.29312)
			(xy 8.064185 -381.238683) (xy 8.084108 -381.186592) (xy 8.111404 -381.137957) (xy 8.14549 -381.093814)
			(xy 8.185639 -381.055105) (xy 8.230997 -381.022654) (xy 8.280597 -380.997153) (xy 8.333381 -380.979146)
			(xy 8.388224 -380.969016) (xy 8.443958 -380.966979) (xy 8.499395 -380.973079) (xy 8.553352 -380.987185)
			(xy 8.604681 -381.008997) (xy 8.652287 -381.038051) (xy 8.695155 -381.073726) (xy 8.732372 -381.115263)
			(xy 8.763145 -381.161776) (xy 8.786817 -381.212273) (xy 8.802885 -381.26568) (xy 8.811005 -381.320856)
			(xy 8.811458 -381.345694) (xy 9.548112 -381.345694) (xy 9.552183 -381.290072) (xy 9.564309 -381.235635)
			(xy 9.584232 -381.183544) (xy 9.611528 -381.134909) (xy 9.645614 -381.090766) (xy 9.685763 -381.052057)
			(xy 9.731121 -381.019606) (xy 9.780721 -380.994105) (xy 9.833505 -380.976098) (xy 9.888348 -380.965968)
			(xy 9.944082 -380.963931) (xy 9.999519 -380.970031) (xy 10.053476 -380.984137) (xy 10.104805 -381.005949)
			(xy 10.152411 -381.035003) (xy 10.195279 -381.070678) (xy 10.232496 -381.112215) (xy 10.263269 -381.158728)
			(xy 10.286941 -381.209225) (xy 10.303009 -381.262632) (xy 10.311129 -381.317808) (xy 10.311638 -381.345694)
			(xy 10.311517 -381.352298) (xy 11.832588 -381.352298) (xy 11.836659 -381.296676) (xy 11.848785 -381.242239)
			(xy 11.868708 -381.190148) (xy 11.896004 -381.141513) (xy 11.93009 -381.09737) (xy 11.970239 -381.058661)
			(xy 12.015597 -381.02621) (xy 12.065197 -381.000709) (xy 12.117981 -380.982702) (xy 12.172824 -380.972572)
			(xy 12.228558 -380.970535) (xy 12.283995 -380.976635) (xy 12.337952 -380.990741) (xy 12.389281 -381.012553)
			(xy 12.436887 -381.041607) (xy 12.479755 -381.077282) (xy 12.516972 -381.118819) (xy 12.547745 -381.165332)
			(xy 12.571417 -381.215829) (xy 12.587485 -381.269236) (xy 12.595605 -381.324412) (xy 12.596114 -381.352298)
			(xy 12.595605 -381.380184) (xy 12.590812 -381.41275) (xy 13.548104 -381.41275) (xy 13.552175 -381.357128)
			(xy 13.564301 -381.302691) (xy 13.584224 -381.2506) (xy 13.61152 -381.201965) (xy 13.645606 -381.157822)
			(xy 13.685755 -381.119113) (xy 13.731113 -381.086662) (xy 13.780713 -381.061161) (xy 13.833497 -381.043154)
			(xy 13.88834 -381.033024) (xy 13.944074 -381.030987) (xy 13.999511 -381.037087) (xy 14.053468 -381.051193)
			(xy 14.104797 -381.073005) (xy 14.152403 -381.102059) (xy 14.195271 -381.137734) (xy 14.232488 -381.179271)
			(xy 14.263261 -381.225784) (xy 14.286933 -381.276281) (xy 14.303001 -381.329688) (xy 14.311121 -381.384864)
			(xy 14.31163 -381.41275) (xy 14.311121 -381.440636) (xy 14.303001 -381.495812) (xy 14.286933 -381.549219)
			(xy 14.263261 -381.599716) (xy 14.232488 -381.646229) (xy 14.195271 -381.687766) (xy 14.152403 -381.723441)
			(xy 14.104797 -381.752495) (xy 14.053468 -381.774307) (xy 13.999511 -381.788413) (xy 13.944074 -381.794513)
			(xy 13.88834 -381.792476) (xy 13.833497 -381.782346) (xy 13.780713 -381.764339) (xy 13.731113 -381.738838)
			(xy 13.685755 -381.706387) (xy 13.645606 -381.667678) (xy 13.61152 -381.623535) (xy 13.584224 -381.5749)
			(xy 13.564301 -381.522809) (xy 13.552175 -381.468372) (xy 13.548104 -381.41275) (xy 12.590812 -381.41275)
			(xy 12.587485 -381.43536) (xy 12.571417 -381.488767) (xy 12.547745 -381.539264) (xy 12.516972 -381.585777)
			(xy 12.479755 -381.627314) (xy 12.436887 -381.662989) (xy 12.389281 -381.692043) (xy 12.337952 -381.713855)
			(xy 12.283995 -381.727961) (xy 12.228558 -381.734061) (xy 12.172824 -381.732024) (xy 12.117981 -381.721894)
			(xy 12.065197 -381.703887) (xy 12.015597 -381.678386) (xy 11.970239 -381.645935) (xy 11.93009 -381.607226)
			(xy 11.896004 -381.563083) (xy 11.868708 -381.514448) (xy 11.848785 -381.462357) (xy 11.836659 -381.40792)
			(xy 11.832588 -381.352298) (xy 10.311517 -381.352298) (xy 10.311129 -381.37358) (xy 10.303009 -381.428756)
			(xy 10.286941 -381.482163) (xy 10.263269 -381.53266) (xy 10.232496 -381.579173) (xy 10.195279 -381.62071)
			(xy 10.152411 -381.656385) (xy 10.104805 -381.685439) (xy 10.053476 -381.707251) (xy 9.999519 -381.721357)
			(xy 9.944082 -381.727457) (xy 9.888348 -381.72542) (xy 9.833505 -381.71529) (xy 9.780721 -381.697283)
			(xy 9.731121 -381.671782) (xy 9.685763 -381.639331) (xy 9.645614 -381.600622) (xy 9.611528 -381.556479)
			(xy 9.584232 -381.507844) (xy 9.564309 -381.455753) (xy 9.552183 -381.401316) (xy 9.548112 -381.345694)
			(xy 8.811458 -381.345694) (xy 8.811514 -381.348742) (xy 8.811005 -381.376628) (xy 8.802885 -381.431804)
			(xy 8.786817 -381.485211) (xy 8.763145 -381.535708) (xy 8.732372 -381.582221) (xy 8.695155 -381.623758)
			(xy 8.652287 -381.659433) (xy 8.604681 -381.688487) (xy 8.553352 -381.710299) (xy 8.499395 -381.724405)
			(xy 8.443958 -381.730505) (xy 8.388224 -381.728468) (xy 8.333381 -381.718338) (xy 8.280597 -381.700331)
			(xy 8.230997 -381.67483) (xy 8.185639 -381.642379) (xy 8.14549 -381.60367) (xy 8.111404 -381.559527)
			(xy 8.084108 -381.510892) (xy 8.064185 -381.458801) (xy 8.052059 -381.404364) (xy 8.047988 -381.348742)
			(xy 2.029533 -381.348742) (xy 2.029205 -381.366722) (xy 2.021085 -381.421898) (xy 2.005017 -381.475305)
			(xy 1.981345 -381.525802) (xy 1.950572 -381.572315) (xy 1.913355 -381.613852) (xy 1.870487 -381.649527)
			(xy 1.822881 -381.678581) (xy 1.771552 -381.700393) (xy 1.717595 -381.714499) (xy 1.662158 -381.720599)
			(xy 1.606424 -381.718562) (xy 1.551581 -381.708432) (xy 1.498797 -381.690425) (xy 1.449197 -381.664924)
			(xy 1.403839 -381.632473) (xy 1.36369 -381.593764) (xy 1.329604 -381.549621) (xy 1.302308 -381.500986)
			(xy 1.282385 -381.448895) (xy 1.270259 -381.394458) (xy 1.266188 -381.338836) (xy 0.635 -381.338836)
			(xy 0.635 -383.246884) (xy 4.633212 -383.246884) (xy 4.637283 -383.191262) (xy 4.649409 -383.136825)
			(xy 4.669332 -383.084734) (xy 4.696628 -383.036099) (xy 4.730714 -382.991956) (xy 4.770863 -382.953247)
			(xy 4.816221 -382.920796) (xy 4.865821 -382.895295) (xy 4.918605 -382.877288) (xy 4.973448 -382.867158)
			(xy 5.029182 -382.865121) (xy 5.084619 -382.871221) (xy 5.138576 -382.885327) (xy 5.189905 -382.907139)
			(xy 5.237511 -382.936193) (xy 5.280379 -382.971868) (xy 5.317596 -383.013405) (xy 5.348369 -383.059918)
			(xy 5.372041 -383.110415) (xy 5.388109 -383.163822) (xy 5.396229 -383.218998) (xy 5.396738 -383.246884)
			(xy 5.396229 -383.27477) (xy 5.388109 -383.329946) (xy 5.372041 -383.383353) (xy 5.348369 -383.43385)
			(xy 5.317596 -383.480363) (xy 5.280379 -383.5219) (xy 5.237511 -383.557575) (xy 5.189905 -383.586629)
			(xy 5.138576 -383.608441) (xy 5.084619 -383.622547) (xy 5.029182 -383.628647) (xy 4.973448 -383.62661)
			(xy 4.918605 -383.61648) (xy 4.865821 -383.598473) (xy 4.816221 -383.572972) (xy 4.770863 -383.540521)
			(xy 4.730714 -383.501812) (xy 4.696628 -383.457669) (xy 4.669332 -383.409034) (xy 4.649409 -383.356943)
			(xy 4.637283 -383.302506) (xy 4.633212 -383.246884) (xy 0.635 -383.246884) (xy 0.635 -384.746754)
			(xy 14.91564 -384.746754) (xy 14.919711 -384.691132) (xy 14.931837 -384.636695) (xy 14.95176 -384.584604)
			(xy 14.979056 -384.535969) (xy 15.013142 -384.491826) (xy 15.053291 -384.453117) (xy 15.098649 -384.420666)
			(xy 15.148249 -384.395165) (xy 15.201033 -384.377158) (xy 15.255876 -384.367028) (xy 15.31161 -384.364991)
			(xy 15.367047 -384.371091) (xy 15.421004 -384.385197) (xy 15.472333 -384.407009) (xy 15.519939 -384.436063)
			(xy 15.562807 -384.471738) (xy 15.600024 -384.513275) (xy 15.630797 -384.559788) (xy 15.654469 -384.610285)
			(xy 15.670537 -384.663692) (xy 15.678657 -384.718868) (xy 15.679166 -384.746754) (xy 15.678657 -384.77464)
			(xy 15.670537 -384.829816) (xy 15.654469 -384.883223) (xy 15.630797 -384.93372) (xy 15.600024 -384.980233)
			(xy 15.562807 -385.02177) (xy 15.519939 -385.057445) (xy 15.472333 -385.086499) (xy 15.421004 -385.108311)
			(xy 15.367047 -385.122417) (xy 15.31161 -385.128517) (xy 15.255876 -385.12648) (xy 15.201033 -385.11635)
			(xy 15.148249 -385.098343) (xy 15.098649 -385.072842) (xy 15.053291 -385.040391) (xy 15.013142 -385.001682)
			(xy 14.979056 -384.957539) (xy 14.95176 -384.908904) (xy 14.931837 -384.856813) (xy 14.919711 -384.802376)
			(xy 14.91564 -384.746754) (xy 0.635 -384.746754) (xy 0.635 -386.246878) (xy 4.662168 -386.246878)
			(xy 4.666239 -386.191256) (xy 4.678365 -386.136819) (xy 4.698288 -386.084728) (xy 4.725584 -386.036093)
			(xy 4.75967 -385.99195) (xy 4.799819 -385.953241) (xy 4.845177 -385.92079) (xy 4.894777 -385.895289)
			(xy 4.947561 -385.877282) (xy 5.002404 -385.867152) (xy 5.058138 -385.865115) (xy 5.113575 -385.871215)
			(xy 5.167532 -385.885321) (xy 5.218861 -385.907133) (xy 5.266467 -385.936187) (xy 5.309335 -385.971862)
			(xy 5.346552 -386.013399) (xy 5.377325 -386.059912) (xy 5.400997 -386.110409) (xy 5.417065 -386.163816)
			(xy 5.425185 -386.218992) (xy 5.425694 -386.246878) (xy 5.425185 -386.274764) (xy 5.417065 -386.32994)
			(xy 5.400997 -386.383347) (xy 5.377325 -386.433844) (xy 5.346552 -386.480357) (xy 5.309335 -386.521894)
			(xy 5.266467 -386.557569) (xy 5.218861 -386.586623) (xy 5.167532 -386.608435) (xy 5.113575 -386.622541)
			(xy 5.058138 -386.628641) (xy 5.002404 -386.626604) (xy 4.947561 -386.616474) (xy 4.894777 -386.598467)
			(xy 4.845177 -386.572966) (xy 4.799819 -386.540515) (xy 4.75967 -386.501806) (xy 4.725584 -386.457663)
			(xy 4.698288 -386.409028) (xy 4.678365 -386.356937) (xy 4.666239 -386.3025) (xy 4.662168 -386.246878)
			(xy 0.635 -386.246878) (xy 0.635 -388.37489) (xy 1.56972 -388.37489) (xy 1.56972 -387.51129) (xy 1.57021 -387.481322)
			(xy 1.578033 -387.4219) (xy 1.593546 -387.364007) (xy 1.616482 -387.308634) (xy 1.646449 -387.256728)
			(xy 1.682936 -387.209178) (xy 1.725316 -387.166798) (xy 1.772866 -387.130311) (xy 1.824772 -387.100344)
			(xy 1.880145 -387.077408) (xy 1.938038 -387.061895) (xy 1.99746 -387.054072) (xy 2.057396 -387.054072)
			(xy 2.116818 -387.061895) (xy 2.174711 -387.077408) (xy 2.230084 -387.100344) (xy 2.28199 -387.130311)
			(xy 2.32954 -387.166798) (xy 2.37192 -387.209178) (xy 2.408407 -387.256728) (xy 2.438374 -387.308634)
			(xy 2.46131 -387.364007) (xy 2.476823 -387.4219) (xy 2.484646 -387.481322) (xy 2.485136 -387.51129)
			(xy 2.485136 -388.21233) (xy 14.92834 -388.21233) (xy 14.932411 -388.156708) (xy 14.944537 -388.102271)
			(xy 14.96446 -388.05018) (xy 14.991756 -388.001545) (xy 15.025842 -387.957402) (xy 15.065991 -387.918693)
			(xy 15.111349 -387.886242) (xy 15.160949 -387.860741) (xy 15.213733 -387.842734) (xy 15.268576 -387.832604)
			(xy 15.32431 -387.830567) (xy 15.379747 -387.836667) (xy 15.433704 -387.850773) (xy 15.485033 -387.872585)
			(xy 15.532639 -387.901639) (xy 15.575507 -387.937314) (xy 15.612724 -387.978851) (xy 15.643497 -388.025364)
			(xy 15.667169 -388.075861) (xy 15.683237 -388.129268) (xy 15.691357 -388.184444) (xy 15.691866 -388.21233)
			(xy 15.691357 -388.240216) (xy 15.683237 -388.295392) (xy 15.667169 -388.348799) (xy 15.643497 -388.399296)
			(xy 15.612724 -388.445809) (xy 15.575507 -388.487346) (xy 15.532639 -388.523021) (xy 15.485033 -388.552075)
			(xy 15.433704 -388.573887) (xy 15.379747 -388.587993) (xy 15.32431 -388.594093) (xy 15.268576 -388.592056)
			(xy 15.213733 -388.581926) (xy 15.160949 -388.563919) (xy 15.111349 -388.538418) (xy 15.065991 -388.505967)
			(xy 15.025842 -388.467258) (xy 14.991756 -388.423115) (xy 14.96446 -388.37448) (xy 14.944537 -388.322389)
			(xy 14.932411 -388.267952) (xy 14.92834 -388.21233) (xy 2.485136 -388.21233) (xy 2.485136 -388.37489)
			(xy 2.484646 -388.404858) (xy 2.476823 -388.46428) (xy 2.46131 -388.522173) (xy 2.438374 -388.577546)
			(xy 2.408407 -388.629452) (xy 2.37192 -388.677002) (xy 2.32954 -388.719382) (xy 2.293879 -388.746746)
			(xy 4.630672 -388.746746) (xy 4.634743 -388.691124) (xy 4.646869 -388.636687) (xy 4.666792 -388.584596)
			(xy 4.694088 -388.535961) (xy 4.728174 -388.491818) (xy 4.768323 -388.453109) (xy 4.813681 -388.420658)
			(xy 4.863281 -388.395157) (xy 4.916065 -388.37715) (xy 4.970908 -388.36702) (xy 5.026642 -388.364983)
			(xy 5.082079 -388.371083) (xy 5.136036 -388.385189) (xy 5.187365 -388.407001) (xy 5.234971 -388.436055)
			(xy 5.277839 -388.47173) (xy 5.315056 -388.513267) (xy 5.345829 -388.55978) (xy 5.369501 -388.610277)
			(xy 5.385569 -388.663684) (xy 5.393689 -388.71886) (xy 5.394198 -388.746746) (xy 5.393689 -388.774632)
			(xy 5.385569 -388.829808) (xy 5.369501 -388.883215) (xy 5.345829 -388.933712) (xy 5.315056 -388.980225)
			(xy 5.277839 -389.021762) (xy 5.234971 -389.057437) (xy 5.187365 -389.086491) (xy 5.136036 -389.108303)
			(xy 5.082079 -389.122409) (xy 5.026642 -389.128509) (xy 4.970908 -389.126472) (xy 4.916065 -389.116342)
			(xy 4.863281 -389.098335) (xy 4.813681 -389.072834) (xy 4.768323 -389.040383) (xy 4.728174 -389.001674)
			(xy 4.694088 -388.957531) (xy 4.666792 -388.908896) (xy 4.646869 -388.856805) (xy 4.634743 -388.802368)
			(xy 4.630672 -388.746746) (xy 2.293879 -388.746746) (xy 2.28199 -388.755869) (xy 2.230084 -388.785836)
			(xy 2.174711 -388.808772) (xy 2.116818 -388.824285) (xy 2.057396 -388.832108) (xy 1.99746 -388.832108)
			(xy 1.938038 -388.824285) (xy 1.880145 -388.808772) (xy 1.824772 -388.785836) (xy 1.772866 -388.755869)
			(xy 1.725316 -388.719382) (xy 1.682936 -388.677002) (xy 1.646449 -388.629452) (xy 1.616482 -388.577546)
			(xy 1.593546 -388.522173) (xy 1.578033 -388.46428) (xy 1.57021 -388.404858) (xy 1.56972 -388.37489)
			(xy 0.635 -388.37489) (xy 0.635 -389.720836) (xy 4.413248 -389.720836) (xy 4.417319 -389.665214)
			(xy 4.429445 -389.610777) (xy 4.449368 -389.558686) (xy 4.476664 -389.510051) (xy 4.51075 -389.465908)
			(xy 4.550899 -389.427199) (xy 4.596257 -389.394748) (xy 4.645857 -389.369247) (xy 4.698641 -389.35124)
			(xy 4.753484 -389.34111) (xy 4.809218 -389.339073) (xy 4.864655 -389.345173) (xy 4.918612 -389.359279)
			(xy 4.969941 -389.381091) (xy 5.017547 -389.410145) (xy 5.060415 -389.44582) (xy 5.097632 -389.487357)
			(xy 5.128405 -389.53387) (xy 5.152077 -389.584367) (xy 5.168145 -389.637774) (xy 5.176265 -389.69295)
			(xy 5.176774 -389.720836) (xy 5.176301 -389.746744) (xy 14.934944 -389.746744) (xy 14.939015 -389.691122)
			(xy 14.951141 -389.636685) (xy 14.971064 -389.584594) (xy 14.99836 -389.535959) (xy 15.032446 -389.491816)
			(xy 15.072595 -389.453107) (xy 15.117953 -389.420656) (xy 15.167553 -389.395155) (xy 15.220337 -389.377148)
			(xy 15.27518 -389.367018) (xy 15.330914 -389.364981) (xy 15.386351 -389.371081) (xy 15.440308 -389.385187)
			(xy 15.491637 -389.406999) (xy 15.539243 -389.436053) (xy 15.582111 -389.471728) (xy 15.619328 -389.513265)
			(xy 15.650101 -389.559778) (xy 15.673773 -389.610275) (xy 15.689841 -389.663682) (xy 15.697961 -389.718858)
			(xy 15.69847 -389.746744) (xy 15.697961 -389.77463) (xy 15.689841 -389.829806) (xy 15.673773 -389.883213)
			(xy 15.650101 -389.93371) (xy 15.619328 -389.980223) (xy 15.582111 -390.02176) (xy 15.539243 -390.057435)
			(xy 15.491637 -390.086489) (xy 15.440308 -390.108301) (xy 15.386351 -390.122407) (xy 15.330914 -390.128507)
			(xy 15.27518 -390.12647) (xy 15.220337 -390.11634) (xy 15.167553 -390.098333) (xy 15.117953 -390.072832)
			(xy 15.072595 -390.040381) (xy 15.032446 -390.001672) (xy 14.99836 -389.957529) (xy 14.971064 -389.908894)
			(xy 14.951141 -389.856803) (xy 14.939015 -389.802366) (xy 14.934944 -389.746744) (xy 5.176301 -389.746744)
			(xy 5.176265 -389.748722) (xy 5.168145 -389.803898) (xy 5.152077 -389.857305) (xy 5.128405 -389.907802)
			(xy 5.097632 -389.954315) (xy 5.060415 -389.995852) (xy 5.017547 -390.031527) (xy 4.969941 -390.060581)
			(xy 4.918612 -390.082393) (xy 4.864655 -390.096499) (xy 4.809218 -390.102599) (xy 4.753484 -390.100562)
			(xy 4.698641 -390.090432) (xy 4.645857 -390.072425) (xy 4.596257 -390.046924) (xy 4.550899 -390.014473)
			(xy 4.51075 -389.975764) (xy 4.476664 -389.931621) (xy 4.449368 -389.882986) (xy 4.429445 -389.830895)
			(xy 4.417319 -389.776458) (xy 4.413248 -389.720836) (xy 0.635 -389.720836) (xy 0.635 -390.790938)
			(xy 1.383536 -390.790938) (xy 1.387607 -390.735316) (xy 1.399733 -390.680879) (xy 1.419656 -390.628788)
			(xy 1.446952 -390.580153) (xy 1.481038 -390.53601) (xy 1.521187 -390.497301) (xy 1.566545 -390.46485)
			(xy 1.616145 -390.439349) (xy 1.668929 -390.421342) (xy 1.723772 -390.411212) (xy 1.779506 -390.409175)
			(xy 1.834943 -390.415275) (xy 1.8889 -390.429381) (xy 1.940229 -390.451193) (xy 1.987835 -390.480247)
			(xy 2.030703 -390.515922) (xy 2.06792 -390.557459) (xy 2.098693 -390.603972) (xy 2.122365 -390.654469)
			(xy 2.138433 -390.707876) (xy 2.146553 -390.763052) (xy 2.147062 -390.790938) (xy 2.146553 -390.818824)
			(xy 2.138433 -390.874) (xy 2.122365 -390.927407) (xy 2.098693 -390.977904) (xy 2.06792 -391.024417)
			(xy 2.030703 -391.065954) (xy 1.987835 -391.101629) (xy 1.940229 -391.130683) (xy 1.8889 -391.152495)
			(xy 1.834943 -391.166601) (xy 1.779506 -391.172701) (xy 1.723772 -391.170664) (xy 1.668929 -391.160534)
			(xy 1.616145 -391.142527) (xy 1.566545 -391.117026) (xy 1.521187 -391.084575) (xy 1.481038 -391.045866)
			(xy 1.446952 -391.001723) (xy 1.419656 -390.953088) (xy 1.399733 -390.900997) (xy 1.387607 -390.84656)
			(xy 1.383536 -390.790938) (xy 0.635 -390.790938) (xy 0.635 -391.614914) (xy 13.80693 -391.614914)
			(xy 13.811001 -391.559292) (xy 13.823127 -391.504855) (xy 13.84305 -391.452764) (xy 13.870346 -391.404129)
			(xy 13.904432 -391.359986) (xy 13.944581 -391.321277) (xy 13.989939 -391.288826) (xy 14.039539 -391.263325)
			(xy 14.092323 -391.245318) (xy 14.147166 -391.235188) (xy 14.2029 -391.233151) (xy 14.258337 -391.239251)
			(xy 14.312294 -391.253357) (xy 14.363623 -391.275169) (xy 14.411229 -391.304223) (xy 14.454097 -391.339898)
			(xy 14.491314 -391.381435) (xy 14.522087 -391.427948) (xy 14.545759 -391.478445) (xy 14.561827 -391.531852)
			(xy 14.569947 -391.587028) (xy 14.570456 -391.614914) (xy 14.569947 -391.6428) (xy 14.566986 -391.66292)
			(xy 16.249394 -391.66292) (xy 16.253465 -391.607298) (xy 16.265591 -391.552861) (xy 16.285514 -391.50077)
			(xy 16.31281 -391.452135) (xy 16.346896 -391.407992) (xy 16.387045 -391.369283) (xy 16.432403 -391.336832)
			(xy 16.482003 -391.311331) (xy 16.534787 -391.293324) (xy 16.58963 -391.283194) (xy 16.645364 -391.281157)
			(xy 16.700801 -391.287257) (xy 16.754758 -391.301363) (xy 16.806087 -391.323175) (xy 16.853693 -391.352229)
			(xy 16.896561 -391.387904) (xy 16.933778 -391.429441) (xy 16.964551 -391.475954) (xy 16.988223 -391.526451)
			(xy 17.004291 -391.579858) (xy 17.012411 -391.635034) (xy 17.01292 -391.66292) (xy 17.012411 -391.690806)
			(xy 17.004291 -391.745982) (xy 16.988223 -391.799389) (xy 16.964551 -391.849886) (xy 16.933778 -391.896399)
			(xy 16.896561 -391.937936) (xy 16.853693 -391.973611) (xy 16.806087 -392.002665) (xy 16.754758 -392.024477)
			(xy 16.700801 -392.038583) (xy 16.645364 -392.044683) (xy 16.58963 -392.042646) (xy 16.534787 -392.032516)
			(xy 16.482003 -392.014509) (xy 16.432403 -391.989008) (xy 16.387045 -391.956557) (xy 16.346896 -391.917848)
			(xy 16.31281 -391.873705) (xy 16.285514 -391.82507) (xy 16.265591 -391.772979) (xy 16.253465 -391.718542)
			(xy 16.249394 -391.66292) (xy 14.566986 -391.66292) (xy 14.561827 -391.697976) (xy 14.545759 -391.751383)
			(xy 14.522087 -391.80188) (xy 14.491314 -391.848393) (xy 14.454097 -391.88993) (xy 14.411229 -391.925605)
			(xy 14.363623 -391.954659) (xy 14.312294 -391.976471) (xy 14.258337 -391.990577) (xy 14.2029 -391.996677)
			(xy 14.147166 -391.99464) (xy 14.092323 -391.98451) (xy 14.039539 -391.966503) (xy 13.989939 -391.941002)
			(xy 13.944581 -391.908551) (xy 13.904432 -391.869842) (xy 13.870346 -391.825699) (xy 13.84305 -391.777064)
			(xy 13.823127 -391.724973) (xy 13.811001 -391.670536) (xy 13.80693 -391.614914) (xy 0.635 -391.614914)
			(xy 0.635 -394.48232) (xy 2.2512 -394.48232) (xy 2.255271 -394.426698) (xy 2.267397 -394.372261)
			(xy 2.28732 -394.32017) (xy 2.314616 -394.271535) (xy 2.348702 -394.227392) (xy 2.388851 -394.188683)
			(xy 2.434209 -394.156232) (xy 2.483809 -394.130731) (xy 2.536593 -394.112724) (xy 2.591436 -394.102594)
			(xy 2.64717 -394.100557) (xy 2.702607 -394.106657) (xy 2.756564 -394.120763) (xy 2.807893 -394.142575)
			(xy 2.855499 -394.171629) (xy 2.898367 -394.207304) (xy 2.935584 -394.248841) (xy 2.966357 -394.295354)
			(xy 2.990029 -394.345851) (xy 3.006097 -394.399258) (xy 3.014217 -394.454434) (xy 3.014726 -394.48232)
			(xy 3.014217 -394.510206) (xy 3.006097 -394.565382) (xy 2.990029 -394.618789) (xy 2.966357 -394.669286)
			(xy 2.935584 -394.715799) (xy 2.900811 -394.754608) (xy 5.302756 -394.754608) (xy 5.306827 -394.698986)
			(xy 5.318953 -394.644549) (xy 5.338876 -394.592458) (xy 5.366172 -394.543823) (xy 5.400258 -394.49968)
			(xy 5.440407 -394.460971) (xy 5.485765 -394.42852) (xy 5.535365 -394.403019) (xy 5.588149 -394.385012)
			(xy 5.642992 -394.374882) (xy 5.698726 -394.372845) (xy 5.754163 -394.378945) (xy 5.80812 -394.393051)
			(xy 5.859449 -394.414863) (xy 5.907055 -394.443917) (xy 5.949923 -394.479592) (xy 5.98714 -394.521129)
			(xy 6.017913 -394.567642) (xy 6.041585 -394.618139) (xy 6.057653 -394.671546) (xy 6.065773 -394.726722)
			(xy 6.066282 -394.754608) (xy 6.066212 -394.758418) (xy 6.280656 -394.758418) (xy 6.284727 -394.702796)
			(xy 6.296853 -394.648359) (xy 6.316776 -394.596268) (xy 6.344072 -394.547633) (xy 6.378158 -394.50349)
			(xy 6.418307 -394.464781) (xy 6.463665 -394.43233) (xy 6.513265 -394.406829) (xy 6.566049 -394.388822)
			(xy 6.620892 -394.378692) (xy 6.676626 -394.376655) (xy 6.732063 -394.382755) (xy 6.78602 -394.396861)
			(xy 6.837349 -394.418673) (xy 6.884955 -394.447727) (xy 6.927823 -394.483402) (xy 6.96504 -394.524939)
			(xy 6.995813 -394.571452) (xy 7.019485 -394.621949) (xy 7.035553 -394.675356) (xy 7.043673 -394.730532)
			(xy 7.044182 -394.758418) (xy 7.043673 -394.786304) (xy 7.035553 -394.84148) (xy 7.019485 -394.894887)
			(xy 6.995813 -394.945384) (xy 6.96504 -394.991897) (xy 6.927823 -395.033434) (xy 6.884955 -395.069109)
			(xy 6.837349 -395.098163) (xy 6.78602 -395.119975) (xy 6.732063 -395.134081) (xy 6.676626 -395.140181)
			(xy 6.620892 -395.138144) (xy 6.566049 -395.128014) (xy 6.513265 -395.110007) (xy 6.463665 -395.084506)
			(xy 6.418307 -395.052055) (xy 6.378158 -395.013346) (xy 6.344072 -394.969203) (xy 6.316776 -394.920568)
			(xy 6.296853 -394.868477) (xy 6.284727 -394.81404) (xy 6.280656 -394.758418) (xy 6.066212 -394.758418)
			(xy 6.065773 -394.782494) (xy 6.057653 -394.83767) (xy 6.041585 -394.891077) (xy 6.017913 -394.941574)
			(xy 5.98714 -394.988087) (xy 5.949923 -395.029624) (xy 5.907055 -395.065299) (xy 5.859449 -395.094353)
			(xy 5.80812 -395.116165) (xy 5.754163 -395.130271) (xy 5.698726 -395.136371) (xy 5.642992 -395.134334)
			(xy 5.588149 -395.124204) (xy 5.535365 -395.106197) (xy 5.485765 -395.080696) (xy 5.440407 -395.048245)
			(xy 5.400258 -395.009536) (xy 5.366172 -394.965393) (xy 5.338876 -394.916758) (xy 5.318953 -394.864667)
			(xy 5.306827 -394.81023) (xy 5.302756 -394.754608) (xy 2.900811 -394.754608) (xy 2.898367 -394.757336)
			(xy 2.855499 -394.793011) (xy 2.807893 -394.822065) (xy 2.756564 -394.843877) (xy 2.702607 -394.857983)
			(xy 2.64717 -394.864083) (xy 2.591436 -394.862046) (xy 2.536593 -394.851916) (xy 2.483809 -394.833909)
			(xy 2.434209 -394.808408) (xy 2.388851 -394.775957) (xy 2.348702 -394.737248) (xy 2.314616 -394.693105)
			(xy 2.28732 -394.64447) (xy 2.267397 -394.592379) (xy 2.255271 -394.537942) (xy 2.2512 -394.48232)
			(xy 0.635 -394.48232) (xy 0.635 -395.206728) (xy 10.019536 -395.206728) (xy 10.023607 -395.151106)
			(xy 10.035733 -395.096669) (xy 10.055656 -395.044578) (xy 10.082952 -394.995943) (xy 10.117038 -394.9518)
			(xy 10.157187 -394.913091) (xy 10.202545 -394.88064) (xy 10.252145 -394.855139) (xy 10.304929 -394.837132)
			(xy 10.359772 -394.827002) (xy 10.415506 -394.824965) (xy 10.470943 -394.831065) (xy 10.5249 -394.845171)
			(xy 10.576229 -394.866983) (xy 10.623835 -394.896037) (xy 10.666703 -394.931712) (xy 10.70392 -394.973249)
			(xy 10.734693 -395.019762) (xy 10.758365 -395.070259) (xy 10.774433 -395.123666) (xy 10.782553 -395.178842)
			(xy 10.78302 -395.204442) (xy 11.574778 -395.204442) (xy 11.578849 -395.14882) (xy 11.590975 -395.094383)
			(xy 11.610898 -395.042292) (xy 11.638194 -394.993657) (xy 11.67228 -394.949514) (xy 11.712429 -394.910805)
			(xy 11.757787 -394.878354) (xy 11.807387 -394.852853) (xy 11.860171 -394.834846) (xy 11.915014 -394.824716)
			(xy 11.970748 -394.822679) (xy 12.026185 -394.828779) (xy 12.080142 -394.842885) (xy 12.131471 -394.864697)
			(xy 12.179077 -394.893751) (xy 12.221945 -394.929426) (xy 12.259162 -394.970963) (xy 12.289935 -395.017476)
			(xy 12.313607 -395.067973) (xy 12.329675 -395.12138) (xy 12.337795 -395.176556) (xy 12.338151 -395.19606)
			(xy 15.04772 -395.19606) (xy 15.051791 -395.140438) (xy 15.063917 -395.086001) (xy 15.08384 -395.03391)
			(xy 15.111136 -394.985275) (xy 15.145222 -394.941132) (xy 15.185371 -394.902423) (xy 15.230729 -394.869972)
			(xy 15.280329 -394.844471) (xy 15.333113 -394.826464) (xy 15.387956 -394.816334) (xy 15.44369 -394.814297)
			(xy 15.499127 -394.820397) (xy 15.553084 -394.834503) (xy 15.604413 -394.856315) (xy 15.652019 -394.885369)
			(xy 15.694887 -394.921044) (xy 15.732104 -394.962581) (xy 15.762877 -395.009094) (xy 15.786549 -395.059591)
			(xy 15.802617 -395.112998) (xy 15.810737 -395.168174) (xy 15.811246 -395.19606) (xy 16.06372 -395.19606)
			(xy 16.067791 -395.140438) (xy 16.079917 -395.086001) (xy 16.09984 -395.03391) (xy 16.127136 -394.985275)
			(xy 16.161222 -394.941132) (xy 16.201371 -394.902423) (xy 16.246729 -394.869972) (xy 16.296329 -394.844471)
			(xy 16.349113 -394.826464) (xy 16.403956 -394.816334) (xy 16.45969 -394.814297) (xy 16.515127 -394.820397)
			(xy 16.569084 -394.834503) (xy 16.620413 -394.856315) (xy 16.668019 -394.885369) (xy 16.710887 -394.921044)
			(xy 16.748104 -394.962581) (xy 16.778877 -395.009094) (xy 16.802549 -395.059591) (xy 16.818617 -395.112998)
			(xy 16.826737 -395.168174) (xy 16.827246 -395.19606) (xy 16.826737 -395.223946) (xy 16.818617 -395.279122)
			(xy 16.802549 -395.332529) (xy 16.778877 -395.383026) (xy 16.748104 -395.429539) (xy 16.710887 -395.471076)
			(xy 16.668019 -395.506751) (xy 16.620413 -395.535805) (xy 16.569084 -395.557617) (xy 16.515127 -395.571723)
			(xy 16.45969 -395.577823) (xy 16.403956 -395.575786) (xy 16.349113 -395.565656) (xy 16.296329 -395.547649)
			(xy 16.246729 -395.522148) (xy 16.201371 -395.489697) (xy 16.161222 -395.450988) (xy 16.127136 -395.406845)
			(xy 16.09984 -395.35821) (xy 16.079917 -395.306119) (xy 16.067791 -395.251682) (xy 16.06372 -395.19606)
			(xy 15.811246 -395.19606) (xy 15.810737 -395.223946) (xy 15.802617 -395.279122) (xy 15.786549 -395.332529)
			(xy 15.762877 -395.383026) (xy 15.732104 -395.429539) (xy 15.694887 -395.471076) (xy 15.652019 -395.506751)
			(xy 15.604413 -395.535805) (xy 15.553084 -395.557617) (xy 15.499127 -395.571723) (xy 15.44369 -395.577823)
			(xy 15.387956 -395.575786) (xy 15.333113 -395.565656) (xy 15.280329 -395.547649) (xy 15.230729 -395.522148)
			(xy 15.185371 -395.489697) (xy 15.145222 -395.450988) (xy 15.111136 -395.406845) (xy 15.08384 -395.35821)
			(xy 15.063917 -395.306119) (xy 15.051791 -395.251682) (xy 15.04772 -395.19606) (xy 12.338151 -395.19606)
			(xy 12.338304 -395.204442) (xy 12.337795 -395.232328) (xy 12.329675 -395.287504) (xy 12.313607 -395.340911)
			(xy 12.289935 -395.391408) (xy 12.259162 -395.437921) (xy 12.221945 -395.479458) (xy 12.179077 -395.515133)
			(xy 12.131471 -395.544187) (xy 12.080142 -395.565999) (xy 12.026185 -395.580105) (xy 11.970748 -395.586205)
			(xy 11.915014 -395.584168) (xy 11.860171 -395.574038) (xy 11.807387 -395.556031) (xy 11.757787 -395.53053)
			(xy 11.712429 -395.498079) (xy 11.67228 -395.45937) (xy 11.638194 -395.415227) (xy 11.610898 -395.366592)
			(xy 11.590975 -395.314501) (xy 11.578849 -395.260064) (xy 11.574778 -395.204442) (xy 10.78302 -395.204442)
			(xy 10.783062 -395.206728) (xy 10.782553 -395.234614) (xy 10.774433 -395.28979) (xy 10.758365 -395.343197)
			(xy 10.734693 -395.393694) (xy 10.70392 -395.440207) (xy 10.666703 -395.481744) (xy 10.623835 -395.517419)
			(xy 10.576229 -395.546473) (xy 10.5249 -395.568285) (xy 10.470943 -395.582391) (xy 10.415506 -395.588491)
			(xy 10.359772 -395.586454) (xy 10.304929 -395.576324) (xy 10.252145 -395.558317) (xy 10.202545 -395.532816)
			(xy 10.157187 -395.500365) (xy 10.117038 -395.461656) (xy 10.082952 -395.417513) (xy 10.055656 -395.368878)
			(xy 10.035733 -395.316787) (xy 10.023607 -395.26235) (xy 10.019536 -395.206728) (xy 0.635 -395.206728)
			(xy 0.635 -398.164722) (xy 3.141726 -398.164722) (xy 3.141726 -398.035362) (xy 3.149849 -397.906256)
			(xy 3.166062 -397.777916) (xy 3.190302 -397.650846) (xy 3.222472 -397.52555) (xy 3.262447 -397.40252)
			(xy 3.310068 -397.282244) (xy 3.365147 -397.165195) (xy 3.427467 -397.051835) (xy 3.496782 -396.942612)
			(xy 3.572818 -396.837957) (xy 3.655276 -396.738283) (xy 3.743829 -396.643983) (xy 3.838129 -396.55543)
			(xy 3.937803 -396.472972) (xy 4.042458 -396.396936) (xy 4.151681 -396.327621) (xy 4.265041 -396.265301)
			(xy 4.38209 -396.210222) (xy 4.502366 -396.162601) (xy 4.625396 -396.122626) (xy 4.750692 -396.090456)
			(xy 4.877762 -396.066216) (xy 5.006102 -396.050003) (xy 5.135208 -396.04188) (xy 5.199888 -396.041372)
			(xy 6.800088 -396.041372) (xy 6.864769 -396.041866) (xy 6.993875 -396.049988) (xy 7.122217 -396.066201)
			(xy 7.249287 -396.090441) (xy 7.374584 -396.122612) (xy 7.497614 -396.162587) (xy 7.617892 -396.210208)
			(xy 7.734942 -396.265287) (xy 7.848302 -396.327608) (xy 7.957526 -396.396923) (xy 8.062181 -396.47296)
			(xy 8.161856 -396.555418) (xy 8.256157 -396.643972) (xy 8.344711 -396.738272) (xy 8.427169 -396.837947)
			(xy 8.503206 -396.942603) (xy 8.572521 -397.051826) (xy 8.634842 -397.165187) (xy 8.689921 -397.282236)
			(xy 8.737543 -397.402514) (xy 8.777518 -397.525544) (xy 8.809688 -397.650841) (xy 8.833928 -397.777911)
			(xy 8.850142 -397.906253) (xy 8.858264 -398.035359) (xy 8.858264 -398.164721) (xy 8.850142 -398.293827)
			(xy 8.833928 -398.422169) (xy 8.809688 -398.549239) (xy 8.777518 -398.674536) (xy 8.737543 -398.797566)
			(xy 8.689921 -398.917844) (xy 8.634842 -399.034893) (xy 8.572521 -399.148254) (xy 8.503206 -399.257477)
			(xy 8.427169 -399.362133) (xy 8.344711 -399.461808) (xy 8.256157 -399.556108) (xy 8.161856 -399.644662)
			(xy 8.062181 -399.72712) (xy 7.957526 -399.803157) (xy 7.848302 -399.872472) (xy 7.734942 -399.934793)
			(xy 7.617892 -399.989872) (xy 7.497614 -400.037493) (xy 7.374584 -400.077468) (xy 7.249287 -400.109639)
			(xy 7.122217 -400.133879) (xy 6.993875 -400.150092) (xy 6.864769 -400.158214) (xy 6.800088 -400.158712)
			(xy 5.199888 -400.158712) (xy 5.135208 -400.158204) (xy 5.006102 -400.150081) (xy 4.877762 -400.133868)
			(xy 4.750692 -400.109628) (xy 4.625396 -400.077458) (xy 4.502366 -400.037483) (xy 4.38209 -399.989862)
			(xy 4.265041 -399.934783) (xy 4.151681 -399.872463) (xy 4.042458 -399.803148) (xy 3.937803 -399.727112)
			(xy 3.838129 -399.644654) (xy 3.743829 -399.556101) (xy 3.655276 -399.461801) (xy 3.572818 -399.362127)
			(xy 3.496782 -399.257472) (xy 3.427467 -399.148249) (xy 3.365147 -399.034889) (xy 3.310068 -398.91784)
			(xy 3.262447 -398.797564) (xy 3.222472 -398.674534) (xy 3.190302 -398.549238) (xy 3.166062 -398.422168)
			(xy 3.149849 -398.293828) (xy 3.141726 -398.164722) (xy 0.635 -398.164722) (xy 0.635 -402.232191)
			(xy 13.656034 -402.232191) (xy 13.656034 -402.177689) (xy 13.66379 -402.123741) (xy 13.679145 -402.071446)
			(xy 13.701786 -402.021868) (xy 13.731253 -401.976018) (xy 13.766944 -401.934827) (xy 13.808134 -401.899135)
			(xy 13.853985 -401.869668) (xy 13.903562 -401.847027) (xy 13.955857 -401.831671) (xy 14.009805 -401.823914)
			(xy 14.037056 -401.823428) (xy 14.063372 -401.823849) (xy 14.115503 -401.831092) (xy 14.166146 -401.84542)
			(xy 14.214345 -401.866561) (xy 14.259188 -401.894115) (xy 14.299825 -401.927562) (xy 14.31798 -401.946618)
			(xy 14.325505 -401.954016) (xy 14.344782 -401.962542) (xy 14.355318 -401.963128) (xy 14.429994 -401.963128)
			(xy 14.440544 -401.962601) (xy 14.459839 -401.954063) (xy 14.467332 -401.946618) (xy 14.487152 -401.92583)
			(xy 14.531924 -401.889855) (xy 14.581582 -401.860995) (xy 14.635004 -401.839902) (xy 14.690983 -401.827053)
			(xy 14.748256 -401.822738) (xy 14.805529 -401.827053) (xy 14.861508 -401.839902) (xy 14.91493 -401.860995)
			(xy 14.964588 -401.889855) (xy 15.00936 -401.92583) (xy 15.02918 -401.946618) (xy 15.036705 -401.954016)
			(xy 15.055982 -401.962542) (xy 15.066518 -401.963128) (xy 15.141194 -401.963128) (xy 15.151744 -401.962601)
			(xy 15.171039 -401.954063) (xy 15.178532 -401.946618) (xy 15.196683 -401.927557) (xy 15.237313 -401.8941)
			(xy 15.282154 -401.866541) (xy 15.330356 -401.845403) (xy 15.381005 -401.831088) (xy 15.433139 -401.823865)
			(xy 15.459456 -401.823428) (xy 15.486709 -401.823899) (xy 15.54066 -401.831655) (xy 15.592957 -401.847011)
			(xy 15.642537 -401.869653) (xy 15.688391 -401.899121) (xy 15.729583 -401.934814) (xy 15.765277 -401.976006)
			(xy 15.794745 -402.021859) (xy 15.817388 -402.071439) (xy 15.832744 -402.123737) (xy 15.840501 -402.177687)
			(xy 15.840501 -402.232193) (xy 15.832744 -402.286143) (xy 15.817388 -402.338441) (xy 15.794745 -402.388021)
			(xy 15.765277 -402.433874) (xy 15.729583 -402.475066) (xy 15.688391 -402.510759) (xy 15.642537 -402.540227)
			(xy 15.592957 -402.562869) (xy 15.54066 -402.578225) (xy 15.486709 -402.585981) (xy 15.459456 -402.586444)
			(xy 15.43314 -402.586024) (xy 15.381009 -402.578782) (xy 15.330365 -402.564455) (xy 15.282165 -402.543313)
			(xy 15.237323 -402.515758) (xy 15.196686 -402.48231) (xy 15.178532 -402.463254) (xy 15.170993 -402.455873)
			(xy 15.151727 -402.447335) (xy 15.141194 -402.446744) (xy 15.066518 -402.446744) (xy 15.055966 -402.447256)
			(xy 15.03667 -402.455802) (xy 15.02918 -402.463254) (xy 15.00936 -402.484042) (xy 14.964588 -402.520017)
			(xy 14.91493 -402.548877) (xy 14.861508 -402.56997) (xy 14.805529 -402.582819) (xy 14.748256 -402.587134)
			(xy 14.690983 -402.582819) (xy 14.635004 -402.56997) (xy 14.581582 -402.548877) (xy 14.531924 -402.520017)
			(xy 14.487152 -402.484042) (xy 14.467332 -402.463254) (xy 14.459793 -402.455873) (xy 14.440527 -402.447335)
			(xy 14.429994 -402.446744) (xy 14.355318 -402.446744) (xy 14.344766 -402.447256) (xy 14.32547 -402.455802)
			(xy 14.31798 -402.463254) (xy 14.299838 -402.482323) (xy 14.259204 -402.515776) (xy 14.214361 -402.543332)
			(xy 14.166157 -402.564468) (xy 14.115508 -402.578783) (xy 14.063373 -402.586006) (xy 14.037056 -402.586444)
			(xy 14.009805 -402.585966) (xy 13.955857 -402.578209) (xy 13.903562 -402.562853) (xy 13.853985 -402.540212)
			(xy 13.808134 -402.510745) (xy 13.766944 -402.475053) (xy 13.731253 -402.433862) (xy 13.701786 -402.388012)
			(xy 13.679145 -402.338434) (xy 13.66379 -402.286139) (xy 13.656034 -402.232191) (xy 0.635 -402.232191)
			(xy 0.635 -404.501858) (xy 17.351246 -404.501858) (xy 17.355317 -404.446236) (xy 17.367443 -404.391799)
			(xy 17.387366 -404.339708) (xy 17.414662 -404.291073) (xy 17.448748 -404.24693) (xy 17.488897 -404.208221)
			(xy 17.534255 -404.17577) (xy 17.583855 -404.150269) (xy 17.636639 -404.132262) (xy 17.691482 -404.122132)
			(xy 17.747216 -404.120095) (xy 17.802653 -404.126195) (xy 17.85661 -404.140301) (xy 17.907939 -404.162113)
			(xy 17.955545 -404.191167) (xy 17.998413 -404.226842) (xy 18.03563 -404.268379) (xy 18.066403 -404.314892)
			(xy 18.090075 -404.365389) (xy 18.106143 -404.418796) (xy 18.114263 -404.473972) (xy 18.114772 -404.501858)
			(xy 18.114263 -404.529744) (xy 18.106143 -404.58492) (xy 18.094299 -404.624286) (xy 18.644868 -404.624286)
			(xy 18.648939 -404.568664) (xy 18.661065 -404.514227) (xy 18.680988 -404.462136) (xy 18.708284 -404.413501)
			(xy 18.74237 -404.369358) (xy 18.782519 -404.330649) (xy 18.827877 -404.298198) (xy 18.877477 -404.272697)
			(xy 18.930261 -404.25469) (xy 18.985104 -404.24456) (xy 19.040838 -404.242523) (xy 19.096275 -404.248623)
			(xy 19.150232 -404.262729) (xy 19.201561 -404.284541) (xy 19.249167 -404.313595) (xy 19.292035 -404.34927)
			(xy 19.329252 -404.390807) (xy 19.360025 -404.43732) (xy 19.383697 -404.487817) (xy 19.399765 -404.541224)
			(xy 19.407885 -404.5964) (xy 19.408394 -404.624286) (xy 19.407885 -404.652172) (xy 19.399765 -404.707348)
			(xy 19.383697 -404.760755) (xy 19.360025 -404.811252) (xy 19.329252 -404.857765) (xy 19.292035 -404.899302)
			(xy 19.249167 -404.934977) (xy 19.201561 -404.964031) (xy 19.150232 -404.985843) (xy 19.096275 -404.999949)
			(xy 19.040838 -405.006049) (xy 18.985104 -405.004012) (xy 18.930261 -404.993882) (xy 18.877477 -404.975875)
			(xy 18.827877 -404.950374) (xy 18.782519 -404.917923) (xy 18.74237 -404.879214) (xy 18.708284 -404.835071)
			(xy 18.680988 -404.786436) (xy 18.661065 -404.734345) (xy 18.648939 -404.679908) (xy 18.644868 -404.624286)
			(xy 18.094299 -404.624286) (xy 18.090075 -404.638327) (xy 18.066403 -404.688824) (xy 18.03563 -404.735337)
			(xy 17.998413 -404.776874) (xy 17.955545 -404.812549) (xy 17.907939 -404.841603) (xy 17.85661 -404.863415)
			(xy 17.802653 -404.877521) (xy 17.747216 -404.883621) (xy 17.691482 -404.881584) (xy 17.636639 -404.871454)
			(xy 17.583855 -404.853447) (xy 17.534255 -404.827946) (xy 17.488897 -404.795495) (xy 17.448748 -404.756786)
			(xy 17.414662 -404.712643) (xy 17.387366 -404.664008) (xy 17.367443 -404.611917) (xy 17.355317 -404.55748)
			(xy 17.351246 -404.501858) (xy 0.635 -404.501858) (xy 0.635 -405.589994) (xy 27.42438 -405.589994)
			(xy 27.424968 -405.557265) (xy 27.433818 -405.492408) (xy 27.451302 -405.429328) (xy 27.477103 -405.369169)
			(xy 27.493468 -405.34082) (xy 27.496773 -405.334791) (xy 27.500385 -405.321531) (xy 27.50058 -405.314658)
			(xy 27.50058 -404.565358) (xy 27.500368 -404.558486) (xy 27.496774 -404.545223) (xy 27.493468 -404.539196)
			(xy 27.477107 -404.510844) (xy 27.451303 -404.450686) (xy 27.433811 -404.387607) (xy 27.42495 -404.322751)
			(xy 27.42438 -404.290022) (xy 27.424936 -404.257292) (xy 27.433795 -404.192434) (xy 27.451288 -404.129353)
			(xy 27.477098 -404.069196) (xy 27.493468 -404.040848) (xy 27.496799 -404.034831) (xy 27.500394 -404.021561)
			(xy 27.50058 -404.014686) (xy 27.50058 -403.728682) (xy 27.501013 -403.718549) (xy 27.508754 -403.69982)
			(xy 27.523057 -403.685463) (xy 27.541757 -403.677651) (xy 27.551888 -403.67712) (xy 28.268168 -403.67712)
			(xy 28.278323 -403.677548) (xy 28.297078 -403.685337) (xy 28.311404 -403.699732) (xy 28.319101 -403.718525)
			(xy 28.319476 -403.728682) (xy 28.319476 -404.014686) (xy 28.319676 -404.021559) (xy 28.323279 -404.034821)
			(xy 28.326588 -404.040848) (xy 28.342972 -404.069187) (xy 28.368769 -404.12935) (xy 28.386254 -404.192433)
			(xy 28.395109 -404.257292) (xy 28.395676 -404.290022) (xy 28.395101 -404.322751) (xy 28.386248 -404.387609)
			(xy 28.368761 -404.45069) (xy 28.342956 -404.510848) (xy 28.326588 -404.539196) (xy 28.323274 -404.545221)
			(xy 28.319668 -404.558484) (xy 28.319476 -404.565358) (xy 28.319476 -405.314658) (xy 28.319687 -405.32153)
			(xy 28.323282 -405.334793) (xy 28.326588 -405.34082) (xy 28.34296 -405.369166) (xy 28.368761 -405.429326)
			(xy 28.386249 -405.492407) (xy 28.395107 -405.557265) (xy 28.395676 -405.589994) (xy 28.395133 -405.622724)
			(xy 28.386271 -405.687584) (xy 28.368774 -405.750664) (xy 28.34296 -405.810821) (xy 28.326588 -405.839168)
			(xy 28.323284 -405.845198) (xy 28.319672 -405.858458) (xy 28.319476 -405.86533) (xy 28.319476 -406.151334)
			(xy 28.319002 -406.161461) (xy 28.311266 -406.18018) (xy 28.296976 -406.194534) (xy 28.278293 -406.202355)
			(xy 28.268168 -406.202896) (xy 27.551888 -406.202896) (xy 27.541733 -406.202488) (xy 27.522979 -406.194688)
			(xy 27.508656 -406.180287) (xy 27.500957 -406.161492) (xy 27.50058 -406.151334) (xy 27.50058 -405.86533)
			(xy 27.500379 -405.858457) (xy 27.496777 -405.845195) (xy 27.493468 -405.839168) (xy 27.477096 -405.810822)
			(xy 27.451294 -405.750662) (xy 27.433806 -405.687581) (xy 27.424948 -405.622723) (xy 27.42438 -405.589994)
			(xy 0.635 -405.589994) (xy 0.635 -406.722792) (xy 29.624863 -406.722792) (xy 29.624866 -406.657353)
			(xy 29.633653 -406.592507) (xy 29.651064 -406.529428) (xy 29.676785 -406.469256) (xy 29.693108 -406.440894)
			(xy 29.696425 -406.434871) (xy 29.700029 -406.421606) (xy 29.70022 -406.414732) (xy 29.70022 -405.665432)
			(xy 29.700013 -405.65856) (xy 29.696415 -405.645297) (xy 29.693108 -405.63927) (xy 29.676783 -405.61091)
			(xy 29.651068 -405.550738) (xy 29.633661 -405.487659) (xy 29.624879 -405.422815) (xy 29.624879 -405.357378)
			(xy 29.633662 -405.292534) (xy 29.65107 -405.229455) (xy 29.676786 -405.169284) (xy 29.693108 -405.140922)
			(xy 29.696415 -405.134894) (xy 29.700026 -405.121633) (xy 29.70022 -405.11476) (xy 29.70022 -404.828756)
			(xy 29.700586 -404.818597) (xy 29.7084 -404.799839) (xy 29.722814 -404.785517) (xy 29.74162 -404.777822)
			(xy 29.751782 -404.777448) (xy 30.468062 -404.777448) (xy 30.478187 -404.777958) (xy 30.496909 -404.785675)
			(xy 30.511267 -404.799954) (xy 30.519086 -404.818634) (xy 30.519624 -404.828756) (xy 30.519624 -405.11476)
			(xy 30.519828 -405.121632) (xy 30.523428 -405.134895) (xy 30.526736 -405.140922) (xy 30.543056 -405.169285)
			(xy 30.568775 -405.229455) (xy 30.586184 -405.292534) (xy 30.594969 -405.357378) (xy 30.594969 -405.422815)
			(xy 30.586186 -405.48766) (xy 30.568777 -405.550738) (xy 30.543059 -405.610909) (xy 30.536265 -405.622714)
			(xy 31.825019 -405.622714) (xy 31.825019 -405.557276) (xy 31.833804 -405.492431) (xy 31.851214 -405.429352)
			(xy 31.876933 -405.369181) (xy 31.893256 -405.34082) (xy 31.89656 -405.33479) (xy 31.900173 -405.32153)
			(xy 31.900368 -405.314658) (xy 31.900368 -404.565358) (xy 31.900158 -404.558486) (xy 31.896562 -404.545223)
			(xy 31.893256 -404.539196) (xy 31.876952 -404.510825) (xy 31.851232 -404.450656) (xy 31.833821 -404.387579)
			(xy 31.825035 -404.322737) (xy 31.825032 -404.257301) (xy 31.833813 -404.192458) (xy 31.851219 -404.12938)
			(xy 31.876935 -404.069209) (xy 31.893256 -404.040848) (xy 31.896586 -404.034831) (xy 31.900182 -404.021561)
			(xy 31.900368 -404.014686) (xy 31.900368 -403.728682) (xy 31.90075 -403.718506) (xy 31.908547 -403.699705)
			(xy 31.922945 -403.68532) (xy 31.941753 -403.677541) (xy 31.95193 -403.67712) (xy 32.66821 -403.67712)
			(xy 32.678366 -403.677625) (xy 32.697132 -403.685399) (xy 32.711496 -403.699761) (xy 32.719273 -403.718526)
			(xy 32.719772 -403.728682) (xy 32.719772 -404.014686) (xy 32.719973 -404.021559) (xy 32.723575 -404.034821)
			(xy 32.726884 -404.040848) (xy 32.743224 -404.069199) (xy 32.768939 -404.129373) (xy 32.786344 -404.192454)
			(xy 32.795125 -404.2573) (xy 32.795122 -404.322738) (xy 32.786336 -404.387583) (xy 32.768926 -404.450663)
			(xy 32.743207 -404.510834) (xy 32.726884 -404.539196) (xy 32.72357 -404.545221) (xy 32.719964 -404.558484)
			(xy 32.719772 -404.565358) (xy 32.719772 -405.314658) (xy 32.719983 -405.32153) (xy 32.723579 -405.334792)
			(xy 32.726884 -405.34082) (xy 32.7432 -405.369184) (xy 32.768917 -405.429355) (xy 32.786325 -405.492433)
			(xy 32.795109 -405.557277) (xy 32.79511 -405.622713) (xy 32.786327 -405.687557) (xy 32.768921 -405.750635)
			(xy 32.743205 -405.810807) (xy 32.726884 -405.839168) (xy 32.72358 -405.845198) (xy 32.719968 -405.858458)
			(xy 32.719772 -405.86533) (xy 32.719772 -406.151334) (xy 32.719295 -406.161493) (xy 32.711511 -406.180261)
			(xy 32.697141 -406.194624) (xy 32.678369 -406.202399) (xy 32.66821 -406.202896) (xy 31.95193 -406.202896)
			(xy 31.941778 -406.202343) (xy 31.923016 -406.194585) (xy 31.908651 -406.180237) (xy 31.900869 -406.161485)
			(xy 31.900368 -406.151334) (xy 31.900368 -405.86533) (xy 31.900169 -405.858457) (xy 31.896566 -405.845194)
			(xy 31.893256 -405.839168) (xy 31.876928 -405.81081) (xy 31.85121 -405.750638) (xy 31.833802 -405.687559)
			(xy 31.825019 -405.622714) (xy 30.536265 -405.622714) (xy 30.526736 -405.63927) (xy 30.523435 -405.645301)
			(xy 30.51982 -405.65856) (xy 30.519624 -405.665432) (xy 30.519624 -406.414732) (xy 30.519801 -406.421606)
			(xy 30.523419 -406.434869) (xy 30.526736 -406.440894) (xy 30.543032 -406.46927) (xy 30.568753 -406.529437)
			(xy 30.586165 -406.592513) (xy 30.594953 -406.657355) (xy 30.594954 -406.690068) (xy 34.024316 -406.690068)
			(xy 34.024888 -406.657339) (xy 34.033741 -406.592481) (xy 34.05123 -406.5294) (xy 34.077036 -406.469242)
			(xy 34.093404 -406.440894) (xy 34.096721 -406.434871) (xy 34.100325 -406.421606) (xy 34.100516 -406.414732)
			(xy 34.100516 -405.665432) (xy 34.10031 -405.65856) (xy 34.096711 -405.645297) (xy 34.093404 -405.63927)
			(xy 34.077027 -405.610927) (xy 34.051228 -405.550765) (xy 34.033741 -405.487684) (xy 34.024884 -405.422826)
			(xy 34.024316 -405.390096) (xy 34.024856 -405.357366) (xy 34.033719 -405.292506) (xy 34.051217 -405.229426)
			(xy 34.077032 -405.169269) (xy 34.093404 -405.140922) (xy 34.096711 -405.134894) (xy 34.100322 -405.121633)
			(xy 34.100516 -405.11476) (xy 34.100516 -404.828756) (xy 34.10095 -404.818642) (xy 34.108705 -404.79996)
			(xy 34.123017 -404.785666) (xy 34.14171 -404.777936) (xy 34.151824 -404.777448) (xy 34.868104 -404.777448)
			(xy 34.878207 -404.777981) (xy 34.896875 -404.78571) (xy 34.911168 -404.799992) (xy 34.918911 -404.818654)
			(xy 34.919412 -404.828756) (xy 34.919412 -405.11476) (xy 34.919618 -405.121632) (xy 34.923217 -405.134895)
			(xy 34.926524 -405.140922) (xy 34.942901 -405.169265) (xy 34.968699 -405.229427) (xy 34.986186 -405.292508)
			(xy 34.995043 -405.357367) (xy 34.995612 -405.390096) (xy 34.995065 -405.422826) (xy 34.986204 -405.487685)
			(xy 34.968708 -405.550765) (xy 34.951875 -405.589994) (xy 36.224464 -405.589994) (xy 36.225055 -405.557265)
			(xy 36.233904 -405.492408) (xy 36.251387 -405.429328) (xy 36.277187 -405.369169) (xy 36.293552 -405.34082)
			(xy 36.296856 -405.33479) (xy 36.300469 -405.32153) (xy 36.300664 -405.314658) (xy 36.300664 -404.565358)
			(xy 36.300454 -404.558486) (xy 36.296859 -404.545223) (xy 36.293552 -404.539196) (xy 36.27719 -404.510845)
			(xy 36.251386 -404.450686) (xy 36.233895 -404.387607) (xy 36.225034 -404.322751) (xy 36.224464 -404.290022)
			(xy 36.225022 -404.257292) (xy 36.233881 -404.192434) (xy 36.251373 -404.129354) (xy 36.277183 -404.069196)
			(xy 36.293552 -404.040848) (xy 36.296881 -404.03483) (xy 36.300478 -404.021561) (xy 36.300664 -404.014686)
			(xy 36.300664 -403.728682) (xy 36.301112 -403.718551) (xy 36.30885 -403.699825) (xy 36.323149 -403.685468)
			(xy 36.341843 -403.677654) (xy 36.351972 -403.67712) (xy 37.068252 -403.67712) (xy 37.078405 -403.677561)
			(xy 37.097161 -403.685345) (xy 37.111486 -403.699736) (xy 37.119184 -403.718527) (xy 37.11956 -403.728682)
			(xy 37.11956 -404.014686) (xy 37.119762 -404.021558) (xy 37.123364 -404.034821) (xy 37.126672 -404.040848)
			(xy 37.143054 -404.069188) (xy 37.168853 -404.129351) (xy 37.186338 -404.192433) (xy 37.195193 -404.257292)
			(xy 37.19576 -404.290022) (xy 37.195174 -404.322751) (xy 37.186323 -404.387608) (xy 37.168838 -404.450688)
			(xy 37.143037 -404.510847) (xy 37.126672 -404.539196) (xy 37.123357 -404.54522) (xy 37.119752 -404.558484)
			(xy 37.11956 -404.565358) (xy 37.11956 -405.314658) (xy 37.119773 -405.32153) (xy 37.123367 -405.334792)
			(xy 37.126672 -405.34082) (xy 37.143043 -405.369166) (xy 37.168844 -405.429327) (xy 37.186332 -405.492407)
			(xy 37.195191 -405.557265) (xy 37.19576 -405.589994) (xy 37.195206 -405.622724) (xy 37.186345 -405.687582)
			(xy 37.168852 -405.750662) (xy 37.143042 -405.81082) (xy 37.126672 -405.839168) (xy 37.123367 -405.845197)
			(xy 37.119756 -405.858457) (xy 37.11956 -405.86533) (xy 37.11956 -406.151334) (xy 37.119101 -406.161463)
			(xy 37.111362 -406.180185) (xy 37.097068 -406.19454) (xy 37.078379 -406.202358) (xy 37.068252 -406.202896)
			(xy 36.351972 -406.202896) (xy 36.341816 -406.202501) (xy 36.323062 -406.194696) (xy 36.308739 -406.180291)
			(xy 36.301041 -406.161493) (xy 36.300664 -406.151334) (xy 36.300664 -405.86533) (xy 36.300465 -405.858457)
			(xy 36.296862 -405.845194) (xy 36.293552 -405.839168) (xy 36.277179 -405.810823) (xy 36.251378 -405.750662)
			(xy 36.23389 -405.687581) (xy 36.225032 -405.622723) (xy 36.224464 -405.589994) (xy 34.951875 -405.589994)
			(xy 34.942895 -405.610923) (xy 34.926524 -405.63927) (xy 34.923222 -405.645301) (xy 34.919608 -405.65856)
			(xy 34.919412 -405.665432) (xy 34.919412 -406.414732) (xy 34.91959 -406.421606) (xy 34.923208 -406.434869)
			(xy 34.926524 -406.440894) (xy 34.942889 -406.469243) (xy 34.968691 -406.529403) (xy 34.98618 -406.592482)
			(xy 34.995041 -406.657339) (xy 34.995612 -406.690068) (xy 34.995053 -406.722792) (xy 38.424949 -406.722792)
			(xy 38.424953 -406.657353) (xy 38.433739 -406.592508) (xy 38.45115 -406.529428) (xy 38.476869 -406.469256)
			(xy 38.493192 -406.440894) (xy 38.496508 -406.43487) (xy 38.500113 -406.421606) (xy 38.500304 -406.414732)
			(xy 38.500304 -405.665432) (xy 38.500099 -405.65856) (xy 38.496499 -405.645297) (xy 38.493192 -405.63927)
			(xy 38.476868 -405.61091) (xy 38.451153 -405.550738) (xy 38.433747 -405.487659) (xy 38.424965 -405.422815)
			(xy 38.424965 -405.357378) (xy 38.433748 -405.292534) (xy 38.451155 -405.229455) (xy 38.476871 -405.169284)
			(xy 38.493192 -405.140922) (xy 38.496498 -405.134893) (xy 38.500109 -405.121633) (xy 38.500304 -405.11476)
			(xy 38.500304 -404.828756) (xy 38.500686 -404.818599) (xy 38.508497 -404.799844) (xy 38.522905 -404.785523)
			(xy 38.541706 -404.777825) (xy 38.551866 -404.777448) (xy 39.268146 -404.777448) (xy 39.278277 -404.777889)
			(xy 39.297 -404.785634) (xy 39.311355 -404.799934) (xy 39.319171 -404.818627) (xy 39.319708 -404.828756)
			(xy 39.319708 -405.11476) (xy 39.319914 -405.121632) (xy 39.323513 -405.134895) (xy 39.32682 -405.140922)
			(xy 39.34314 -405.169285) (xy 39.36886 -405.229455) (xy 39.38627 -405.292533) (xy 39.395055 -405.357378)
			(xy 39.395055 -405.422815) (xy 39.386272 -405.48766) (xy 39.368862 -405.550738) (xy 39.352083 -405.589994)
			(xy 40.624252 -405.589994) (xy 40.624844 -405.557265) (xy 40.633693 -405.492408) (xy 40.651176 -405.429328)
			(xy 40.676975 -405.369169) (xy 40.69334 -405.34082) (xy 40.696643 -405.334789) (xy 40.700257 -405.32153)
			(xy 40.700452 -405.314658) (xy 40.700452 -404.565358) (xy 40.700244 -404.558486) (xy 40.696647 -404.545223)
			(xy 40.69334 -404.539196) (xy 40.676977 -404.510845) (xy 40.651173 -404.450687) (xy 40.633683 -404.387608)
			(xy 40.624822 -404.322751) (xy 40.624252 -404.290022) (xy 40.624812 -404.257292) (xy 40.63367 -404.192434)
			(xy 40.651162 -404.129354) (xy 40.676971 -404.069196) (xy 40.69334 -404.040848) (xy 40.696669 -404.03483)
			(xy 40.700266 -404.021561) (xy 40.700452 -404.014686) (xy 40.700452 -403.728682) (xy 40.700912 -403.718553)
			(xy 40.708648 -403.699829) (xy 40.722942 -403.685473) (xy 40.741633 -403.677656) (xy 40.75176 -403.67712)
			(xy 41.46804 -403.67712) (xy 41.478199 -403.677489) (xy 41.496956 -403.685302) (xy 41.511279 -403.699715)
			(xy 41.518974 -403.71852) (xy 41.519348 -403.728682) (xy 41.519348 -404.014686) (xy 41.519539 -404.021559)
			(xy 41.523147 -404.034822) (xy 41.52646 -404.040848) (xy 41.542841 -404.069189) (xy 41.56864 -404.129351)
			(xy 41.586125 -404.192433) (xy 41.594981 -404.257292) (xy 41.595548 -404.290022) (xy 45.023794 -404.290022)
			(xy 45.027785 -404.227855) (xy 45.039694 -404.166708) (xy 45.059323 -404.107587) (xy 45.086352 -404.051461)
			(xy 45.120336 -403.999252) (xy 45.160718 -403.951817) (xy 45.206834 -403.909936) (xy 45.257926 -403.874296)
			(xy 45.313157 -403.845482) (xy 45.371619 -403.823968) (xy 45.432353 -403.810106) (xy 45.49436 -403.804124)
			(xy 45.556623 -403.80612) (xy 45.61812 -403.816063) (xy 45.677841 -403.833787) (xy 45.734804 -403.859004)
			(xy 45.788075 -403.891297) (xy 45.83678 -403.930137) (xy 45.880117 -403.974887) (xy 45.917377 -404.024811)
			(xy 45.947946 -404.07909) (xy 45.971324 -404.136833) (xy 45.987125 -404.197091) (xy 45.995091 -404.258874)
			(xy 45.99559 -404.290022) (xy 45.995091 -404.32117) (xy 45.987125 -404.382953) (xy 45.971324 -404.443211)
			(xy 45.947946 -404.500954) (xy 45.917377 -404.555233) (xy 45.880117 -404.605157) (xy 45.83678 -404.649907)
			(xy 45.788075 -404.688747) (xy 45.734804 -404.72104) (xy 45.677841 -404.746257) (xy 45.61812 -404.763981)
			(xy 45.556623 -404.773924) (xy 45.49436 -404.77592) (xy 45.432353 -404.769938) (xy 45.371619 -404.756076)
			(xy 45.313157 -404.734562) (xy 45.257926 -404.705748) (xy 45.206834 -404.670108) (xy 45.160718 -404.628227)
			(xy 45.120336 -404.580792) (xy 45.086352 -404.528583) (xy 45.059323 -404.472457) (xy 45.039694 -404.413336)
			(xy 45.027785 -404.352189) (xy 45.023794 -404.290022) (xy 41.595548 -404.290022) (xy 41.594963 -404.322751)
			(xy 41.586112 -404.387608) (xy 41.568627 -404.450688) (xy 41.542826 -404.510847) (xy 41.52646 -404.539196)
			(xy 41.523151 -404.545224) (xy 41.519541 -404.558485) (xy 41.519348 -404.565358) (xy 41.519348 -405.314658)
			(xy 41.51955 -405.321531) (xy 41.523151 -405.334794) (xy 41.52646 -405.34082) (xy 41.54283 -405.369167)
			(xy 41.568631 -405.429327) (xy 41.58612 -405.492407) (xy 41.594979 -405.557265) (xy 41.595548 -405.589994)
			(xy 41.594996 -405.622724) (xy 41.586135 -405.687582) (xy 41.568641 -405.750662) (xy 41.54283 -405.81082)
			(xy 41.52646 -405.839168) (xy 41.523161 -405.845201) (xy 41.519545 -405.858458) (xy 41.519348 -405.86533)
			(xy 41.519348 -406.151334) (xy 41.518901 -406.161464) (xy 41.51116 -406.180189) (xy 41.496861 -406.194544)
			(xy 41.478168 -406.20236) (xy 41.46804 -406.202896) (xy 40.75176 -406.202896) (xy 40.741603 -406.202511)
			(xy 40.722849 -406.194701) (xy 40.708527 -406.180294) (xy 40.700829 -406.161494) (xy 40.700452 -406.151334)
			(xy 40.700452 -405.86533) (xy 40.700255 -405.858457) (xy 40.696651 -405.845194) (xy 40.69334 -405.839168)
			(xy 40.676966 -405.810824) (xy 40.651165 -405.750663) (xy 40.633678 -405.687582) (xy 40.62482 -405.622723)
			(xy 40.624252 -405.589994) (xy 39.352083 -405.589994) (xy 39.343143 -405.610909) (xy 39.32682 -405.63927)
			(xy 39.323517 -405.645301) (xy 39.319904 -405.65856) (xy 39.319708 -405.665432) (xy 39.319708 -406.414732)
			(xy 39.319887 -406.421606) (xy 39.323504 -406.434869) (xy 39.32682 -406.440894) (xy 39.343116 -406.46927)
			(xy 39.368839 -406.529437) (xy 39.386251 -406.592513) (xy 39.395039 -406.657355) (xy 39.395041 -406.690068)
			(xy 42.8244 -406.690068) (xy 42.824974 -406.657339) (xy 42.833827 -406.592481) (xy 42.851315 -406.529401)
			(xy 42.877121 -406.469242) (xy 42.893488 -406.440894) (xy 42.896804 -406.43487) (xy 42.900409 -406.421606)
			(xy 42.9006 -406.414732) (xy 42.9006 -405.665432) (xy 42.900396 -405.65856) (xy 42.896796 -405.645297)
			(xy 42.893488 -405.63927) (xy 42.877109 -405.610928) (xy 42.851311 -405.550766) (xy 42.833825 -405.487684)
			(xy 42.824968 -405.422826) (xy 42.8244 -405.390096) (xy 42.824941 -405.357366) (xy 42.833804 -405.292506)
			(xy 42.851302 -405.229426) (xy 42.877116 -405.169269) (xy 42.893488 -405.140922) (xy 42.896794 -405.134893)
			(xy 42.900405 -405.121633) (xy 42.9006 -405.11476) (xy 42.9006 -404.828756) (xy 42.901049 -404.818644)
			(xy 42.908801 -404.799965) (xy 42.923109 -404.785672) (xy 42.941796 -404.777939) (xy 42.951908 -404.777448)
			(xy 43.668188 -404.777448) (xy 43.67829 -404.777994) (xy 43.696958 -404.785718) (xy 43.711251 -404.799995)
			(xy 43.718995 -404.818655) (xy 43.719496 -404.828756) (xy 43.719496 -405.11476) (xy 43.719704 -405.121632)
			(xy 43.723301 -405.134895) (xy 43.726608 -405.140922) (xy 43.742983 -405.169266) (xy 43.768782 -405.229427)
			(xy 43.786269 -405.292509) (xy 43.795127 -405.357367) (xy 43.795696 -405.390096) (xy 43.795152 -405.422826)
			(xy 43.78629 -405.487685) (xy 43.768793 -405.550766) (xy 43.751961 -405.589994) (xy 45.023794 -405.589994)
			(xy 45.027785 -405.527827) (xy 45.039694 -405.46668) (xy 45.059323 -405.407559) (xy 45.086352 -405.351433)
			(xy 45.120336 -405.299224) (xy 45.160718 -405.251789) (xy 45.206834 -405.209908) (xy 45.257926 -405.174268)
			(xy 45.313157 -405.145454) (xy 45.371619 -405.12394) (xy 45.432353 -405.110078) (xy 45.49436 -405.104096)
			(xy 45.556623 -405.106092) (xy 45.61812 -405.116035) (xy 45.677841 -405.133759) (xy 45.734804 -405.158976)
			(xy 45.788075 -405.191269) (xy 45.83678 -405.230109) (xy 45.880117 -405.274859) (xy 45.917377 -405.324783)
			(xy 45.947946 -405.379062) (xy 45.971324 -405.436805) (xy 45.987125 -405.497063) (xy 45.995091 -405.558846)
			(xy 45.99559 -405.589994) (xy 45.995091 -405.621142) (xy 45.987125 -405.682925) (xy 45.971324 -405.743183)
			(xy 45.947946 -405.800926) (xy 45.917377 -405.855205) (xy 45.880117 -405.905129) (xy 45.83678 -405.949879)
			(xy 45.788075 -405.988719) (xy 45.734804 -406.021012) (xy 45.677841 -406.046229) (xy 45.61812 -406.063953)
			(xy 45.556623 -406.073896) (xy 45.49436 -406.075892) (xy 45.432353 -406.06991) (xy 45.371619 -406.056048)
			(xy 45.313157 -406.034534) (xy 45.257926 -406.00572) (xy 45.206834 -405.97008) (xy 45.160718 -405.928199)
			(xy 45.120336 -405.880764) (xy 45.086352 -405.828555) (xy 45.059323 -405.772429) (xy 45.039694 -405.713308)
			(xy 45.027785 -405.652161) (xy 45.023794 -405.589994) (xy 43.751961 -405.589994) (xy 43.74298 -405.610923)
			(xy 43.726608 -405.63927) (xy 43.723304 -405.6453) (xy 43.719692 -405.65856) (xy 43.719496 -405.665432)
			(xy 43.719496 -406.414732) (xy 43.719676 -406.421606) (xy 43.723292 -406.434869) (xy 43.726608 -406.440894)
			(xy 43.742972 -406.469244) (xy 43.768774 -406.529403) (xy 43.786264 -406.592483) (xy 43.795125 -406.657339)
			(xy 43.795696 -406.690068) (xy 43.795139 -406.722792) (xy 47.225021 -406.722792) (xy 47.225025 -406.657353)
			(xy 47.233813 -406.592506) (xy 47.251227 -406.529426) (xy 47.27695 -406.469255) (xy 47.293276 -406.440894)
			(xy 47.296591 -406.43487) (xy 47.300197 -406.421606) (xy 47.300388 -406.414732) (xy 47.300388 -405.665432)
			(xy 47.300185 -405.65856) (xy 47.296584 -405.645297) (xy 47.293276 -405.63927) (xy 47.276949 -405.610911)
			(xy 47.25123 -405.55074) (xy 47.233821 -405.487661) (xy 47.225037 -405.422815) (xy 47.225038 -405.357378)
			(xy 47.233822 -405.292533) (xy 47.251232 -405.229454) (xy 47.276952 -405.169283) (xy 47.293276 -405.140922)
			(xy 47.296581 -405.134893) (xy 47.300193 -405.121633) (xy 47.300388 -405.11476) (xy 47.300388 -404.828756)
			(xy 47.300785 -404.818601) (xy 47.308593 -404.79985) (xy 47.322997 -404.785528) (xy 47.341792 -404.777828)
			(xy 47.35195 -404.777448) (xy 48.06823 -404.777448) (xy 48.07836 -404.777902) (xy 48.097083 -404.785641)
			(xy 48.111439 -404.799937) (xy 48.119255 -404.818629) (xy 48.119792 -404.828756) (xy 48.119792 -405.11476)
			(xy 48.12 -405.121632) (xy 48.123598 -405.134895) (xy 48.126904 -405.140922) (xy 48.143222 -405.169286)
			(xy 48.168937 -405.229457) (xy 48.186344 -405.292535) (xy 48.195127 -405.357379) (xy 48.195128 -405.422815)
			(xy 48.186345 -405.487658) (xy 48.168939 -405.550737) (xy 48.143225 -405.610908) (xy 48.126904 -405.63927)
			(xy 48.1236 -405.6453) (xy 48.119988 -405.65856) (xy 48.119792 -405.665432) (xy 48.119792 -406.414732)
			(xy 48.119973 -406.421606) (xy 48.123589 -406.434869) (xy 48.126904 -406.440894) (xy 48.143198 -406.469271)
			(xy 48.168916 -406.529439) (xy 48.186325 -406.592514) (xy 48.195111 -406.657356) (xy 48.195115 -406.72279)
			(xy 48.186336 -406.787632) (xy 48.168934 -406.850709) (xy 48.143223 -406.91088) (xy 48.126904 -406.939242)
			(xy 48.123575 -406.945259) (xy 48.119978 -406.958529) (xy 48.119792 -406.965404) (xy 48.119792 -407.251408)
			(xy 48.119385 -407.261564) (xy 48.111585 -407.280318) (xy 48.097184 -407.294641) (xy 48.078388 -407.302339)
			(xy 48.06823 -407.302716) (xy 47.35195 -407.302716) (xy 47.341821 -407.302231) (xy 47.323093 -407.294512)
			(xy 47.308733 -407.280224) (xy 47.30092 -407.261534) (xy 47.300388 -407.251408) (xy 47.300388 -406.965404)
			(xy 47.300196 -406.958531) (xy 47.296588 -406.945268) (xy 47.293276 -406.939242) (xy 47.276926 -406.910896)
			(xy 47.251208 -406.850722) (xy 47.233802 -406.78764) (xy 47.225021 -406.722792) (xy 43.795139 -406.722792)
			(xy 43.795139 -406.722798) (xy 43.78628 -406.787656) (xy 43.768788 -406.850737) (xy 43.742978 -406.910894)
			(xy 43.726608 -406.939242) (xy 43.723279 -406.94526) (xy 43.719682 -406.958529) (xy 43.719496 -406.965404)
			(xy 43.719496 -407.251408) (xy 43.71909 -407.261531) (xy 43.711339 -407.280236) (xy 43.697019 -407.29455)
			(xy 43.678312 -407.302294) (xy 43.668188 -407.302716) (xy 42.951908 -407.302716) (xy 42.941802 -407.302209)
			(xy 42.923127 -407.294477) (xy 42.908832 -407.280187) (xy 42.901094 -407.261514) (xy 42.9006 -407.251408)
			(xy 42.9006 -406.965404) (xy 42.900407 -406.958531) (xy 42.8968 -406.945268) (xy 42.893488 -406.939242)
			(xy 42.877138 -406.910884) (xy 42.851333 -406.850728) (xy 42.833839 -406.787651) (xy 42.824973 -406.722796)
			(xy 42.8244 -406.690068) (xy 39.395041 -406.690068) (xy 39.395043 -406.72279) (xy 39.386262 -406.787633)
			(xy 39.368857 -406.850711) (xy 39.343141 -406.910881) (xy 39.32682 -406.939242) (xy 39.323492 -406.94526)
			(xy 39.319894 -406.958529) (xy 39.319708 -406.965404) (xy 39.319708 -407.251408) (xy 39.319285 -407.261562)
			(xy 39.311488 -407.280313) (xy 39.297092 -407.294635) (xy 39.278302 -407.302336) (xy 39.268146 -407.302716)
			(xy 38.551866 -407.302716) (xy 38.541732 -407.3023) (xy 38.523001 -407.294553) (xy 38.508645 -407.280245)
			(xy 38.500835 -407.261541) (xy 38.500304 -407.251408) (xy 38.500304 -406.965404) (xy 38.50011 -406.958531)
			(xy 38.496503 -406.945268) (xy 38.493192 -406.939242) (xy 38.476844 -406.910895) (xy 38.451132 -406.85072)
			(xy 38.433728 -406.787638) (xy 38.424949 -406.722792) (xy 34.995053 -406.722792) (xy 34.995053 -406.722798)
			(xy 34.986195 -406.787656) (xy 34.968703 -406.850736) (xy 34.942894 -406.910894) (xy 34.926524 -406.939242)
			(xy 34.923196 -406.94526) (xy 34.919598 -406.958529) (xy 34.919412 -406.965404) (xy 34.919412 -407.251408)
			(xy 34.918922 -407.261516) (xy 34.911184 -407.280192) (xy 34.896888 -407.294486) (xy 34.878212 -407.302222)
			(xy 34.868104 -407.302716) (xy 34.151824 -407.302716) (xy 34.141705 -407.302265) (xy 34.123005 -407.294528)
			(xy 34.10869 -407.280222) (xy 34.100941 -407.261527) (xy 34.100516 -407.251408) (xy 34.100516 -406.965404)
			(xy 34.100321 -406.958531) (xy 34.096715 -406.945268) (xy 34.093404 -406.939242) (xy 34.077056 -406.910883)
			(xy 34.051249 -406.850727) (xy 34.033755 -406.787651) (xy 34.024889 -406.722796) (xy 34.024316 -406.690068)
			(xy 30.594954 -406.690068) (xy 30.594956 -406.72279) (xy 30.586176 -406.787633) (xy 30.568772 -406.850711)
			(xy 30.543057 -406.910881) (xy 30.526736 -406.939242) (xy 30.523409 -406.945261) (xy 30.519811 -406.958529)
			(xy 30.519624 -406.965404) (xy 30.519624 -407.251408) (xy 30.519185 -407.26156) (xy 30.511392 -407.280307)
			(xy 30.497001 -407.29463) (xy 30.478216 -407.302333) (xy 30.468062 -407.302716) (xy 29.751782 -407.302716)
			(xy 29.741649 -407.302287) (xy 29.722919 -407.294545) (xy 29.708561 -407.280241) (xy 29.700751 -407.261539)
			(xy 29.70022 -407.251408) (xy 29.70022 -406.965404) (xy 29.700024 -406.958531) (xy 29.696418 -406.945268)
			(xy 29.693108 -406.939242) (xy 29.67676 -406.910895) (xy 29.651046 -406.85072) (xy 29.633642 -406.787639)
			(xy 29.624863 -406.722792) (xy 0.635 -406.722792) (xy 0.635 -409.490164) (xy 27.42438 -409.490164)
			(xy 27.424955 -409.457435) (xy 27.433808 -409.392577) (xy 27.451296 -409.329497) (xy 27.477101 -409.269339)
			(xy 27.493468 -409.24099) (xy 27.496784 -409.234966) (xy 27.500389 -409.221702) (xy 27.50058 -409.214828)
			(xy 27.50058 -408.465528) (xy 27.50038 -408.458655) (xy 27.496777 -408.445393) (xy 27.493468 -408.439366)
			(xy 27.477095 -408.411021) (xy 27.451294 -408.35086) (xy 27.433806 -408.287779) (xy 27.424948 -408.222921)
			(xy 27.42438 -408.190192) (xy 27.424967 -408.157463) (xy 27.433817 -408.092606) (xy 27.451301 -408.029526)
			(xy 27.477103 -407.969367) (xy 27.493468 -407.941018) (xy 27.496774 -407.934989) (xy 27.500385 -407.921729)
			(xy 27.50058 -407.914856) (xy 27.50058 -407.628852) (xy 27.501045 -407.618743) (xy 27.508795 -407.600067)
			(xy 27.523098 -407.585775) (xy 27.541778 -407.578038) (xy 27.551888 -407.577544) (xy 28.268168 -407.577544)
			(xy 28.278268 -407.57811) (xy 28.296935 -407.585826) (xy 28.311229 -407.600098) (xy 28.318975 -407.618753)
			(xy 28.319476 -407.628852) (xy 28.319476 -407.914856) (xy 28.319688 -407.921728) (xy 28.323283 -407.93499)
			(xy 28.326588 -407.941018) (xy 28.34296 -407.969364) (xy 28.36876 -408.029525) (xy 28.386248 -408.092605)
			(xy 28.395107 -408.157463) (xy 28.395676 -408.190192) (xy 28.395132 -408.222922) (xy 28.38627 -408.287781)
			(xy 28.368774 -408.350862) (xy 28.34296 -408.411019) (xy 28.326588 -408.439366) (xy 28.323285 -408.445396)
			(xy 28.319672 -408.458656) (xy 28.319476 -408.465528) (xy 28.319476 -409.214828) (xy 28.31966 -409.221702)
			(xy 28.323274 -409.234964) (xy 28.326588 -409.24099) (xy 28.342948 -409.269342) (xy 28.368752 -409.3295)
			(xy 28.386243 -409.392579) (xy 28.395105 -409.457435) (xy 28.395676 -409.490164) (xy 28.39512 -409.522894)
			(xy 28.386262 -409.587753) (xy 28.368769 -409.650833) (xy 28.342958 -409.71099) (xy 28.326588 -409.739338)
			(xy 28.323259 -409.745356) (xy 28.319663 -409.758625) (xy 28.319476 -409.7655) (xy 28.319476 -410.051504)
			(xy 28.319087 -410.06163) (xy 28.311333 -410.080338) (xy 28.297008 -410.094653) (xy 28.278294 -410.102394)
			(xy 28.268168 -410.102812) (xy 27.551888 -410.102812) (xy 27.54178 -410.102325) (xy 27.523104 -410.094585)
			(xy 27.50881 -410.080289) (xy 27.501074 -410.061612) (xy 27.50058 -410.051504) (xy 27.50058 -409.7655)
			(xy 27.50039 -409.758627) (xy 27.496781 -409.745364) (xy 27.493468 -409.739338) (xy 27.477124 -409.710977)
			(xy 27.451315 -409.650822) (xy 27.433819 -409.587746) (xy 27.424953 -409.522892) (xy 27.42438 -409.490164)
			(xy 0.635 -409.490164) (xy 0.635 -410.248608) (xy 14.998698 -410.248608) (xy 15.002769 -410.192986)
			(xy 15.014895 -410.138549) (xy 15.034818 -410.086458) (xy 15.062114 -410.037823) (xy 15.0962 -409.99368)
			(xy 15.136349 -409.954971) (xy 15.181707 -409.92252) (xy 15.231307 -409.897019) (xy 15.284091 -409.879012)
			(xy 15.338934 -409.868882) (xy 15.394668 -409.866845) (xy 15.450105 -409.872945) (xy 15.504062 -409.887051)
			(xy 15.555391 -409.908863) (xy 15.602997 -409.937917) (xy 15.645865 -409.973592) (xy 15.683082 -410.015129)
			(xy 15.713855 -410.061642) (xy 15.737527 -410.112139) (xy 15.753595 -410.165546) (xy 15.761715 -410.220722)
			(xy 15.762224 -410.248608) (xy 15.761715 -410.276494) (xy 15.753595 -410.33167) (xy 15.737527 -410.385077)
			(xy 15.713855 -410.435574) (xy 15.683082 -410.482087) (xy 15.645865 -410.523624) (xy 15.602997 -410.559299)
			(xy 15.555391 -410.588353) (xy 15.504062 -410.610165) (xy 15.456095 -410.622705) (xy 29.624872 -410.622705)
			(xy 29.624874 -410.557268) (xy 29.633659 -410.492423) (xy 29.651068 -410.429343) (xy 29.676786 -410.369172)
			(xy 29.693108 -410.34081) (xy 29.69642 -410.334784) (xy 29.700027 -410.321521) (xy 29.70022 -410.314648)
			(xy 29.70022 -409.565348) (xy 29.700007 -409.558476) (xy 29.696413 -409.545214) (xy 29.693108 -409.539186)
			(xy 29.676797 -409.510819) (xy 29.65108 -409.450649) (xy 29.633672 -409.387571) (xy 29.624888 -409.322728)
			(xy 29.624886 -409.257293) (xy 29.633668 -409.192449) (xy 29.651073 -409.129371) (xy 29.676788 -409.0692)
			(xy 29.693108 -409.040838) (xy 29.69641 -409.034807) (xy 29.700023 -409.021548) (xy 29.70022 -409.014676)
			(xy 29.70022 -408.728672) (xy 29.700599 -408.718514) (xy 29.708408 -408.699757) (xy 29.722817 -408.685434)
			(xy 29.741621 -408.677738) (xy 29.751782 -408.677364) (xy 30.468062 -408.677364) (xy 30.478189 -408.677859)
			(xy 30.496914 -408.685578) (xy 30.511272 -408.699863) (xy 30.519089 -408.718547) (xy 30.519624 -408.728672)
			(xy 30.519624 -409.014676) (xy 30.519822 -409.021549) (xy 30.523426 -409.034812) (xy 30.526736 -409.040838)
			(xy 30.543069 -409.069193) (xy 30.568787 -409.129366) (xy 30.586195 -409.192446) (xy 30.594978 -409.257291)
			(xy 30.594976 -409.322729) (xy 30.586191 -409.387575) (xy 30.56878 -409.450654) (xy 30.54306 -409.510825)
			(xy 30.536116 -409.522889) (xy 31.825002 -409.522889) (xy 31.825006 -409.457449) (xy 31.833794 -409.392603)
			(xy 31.851208 -409.329523) (xy 31.876931 -409.269351) (xy 31.893256 -409.24099) (xy 31.896571 -409.234965)
			(xy 31.900177 -409.221702) (xy 31.900368 -409.214828) (xy 31.900368 -408.465528) (xy 31.900169 -408.458655)
			(xy 31.896566 -408.445392) (xy 31.893256 -408.439366) (xy 31.876926 -408.411009) (xy 31.851209 -408.350837)
			(xy 31.833801 -408.287757) (xy 31.825018 -408.222912) (xy 31.825019 -408.157474) (xy 31.833803 -408.092629)
			(xy 31.851213 -408.02955) (xy 31.876933 -407.969379) (xy 31.893256 -407.941018) (xy 31.896561 -407.934988)
			(xy 31.900173 -407.921729) (xy 31.900368 -407.914856) (xy 31.900368 -407.628852) (xy 31.900782 -407.618699)
			(xy 31.908587 -407.599952) (xy 31.922985 -407.585631) (xy 31.941775 -407.577927) (xy 31.95193 -407.577544)
			(xy 32.66821 -407.577544) (xy 32.678338 -407.578019) (xy 32.69706 -407.58575) (xy 32.711416 -407.60004)
			(xy 32.719234 -407.618727) (xy 32.719772 -407.628852) (xy 32.719772 -407.914856) (xy 32.719984 -407.921728)
			(xy 32.723579 -407.93499) (xy 32.726884 -407.941018) (xy 32.743199 -407.969383) (xy 32.768916 -408.029554)
			(xy 32.786324 -408.092632) (xy 32.795108 -408.157475) (xy 32.795109 -408.222911) (xy 32.786327 -408.287755)
			(xy 32.76892 -408.350833) (xy 32.743205 -408.411005) (xy 32.726884 -408.439366) (xy 32.72358 -408.445396)
			(xy 32.719968 -408.458656) (xy 32.719772 -408.465528) (xy 32.719772 -409.214828) (xy 32.719957 -409.221702)
			(xy 32.72357 -409.234964) (xy 32.726884 -409.24099) (xy 32.743175 -409.269368) (xy 32.768894 -409.329536)
			(xy 32.786305 -409.392611) (xy 32.795092 -409.457452) (xy 32.795096 -409.522886) (xy 32.786317 -409.587728)
			(xy 32.768915 -409.650806) (xy 32.743203 -409.710977) (xy 32.726884 -409.739338) (xy 32.723555 -409.745355)
			(xy 32.719959 -409.758625) (xy 32.719772 -409.7655) (xy 32.719772 -410.051504) (xy 32.719381 -410.061662)
			(xy 32.711579 -410.08042) (xy 32.697172 -410.094744) (xy 32.67837 -410.102438) (xy 32.66821 -410.102812)
			(xy 31.95193 -410.102812) (xy 31.941812 -410.102251) (xy 31.923101 -410.094542) (xy 31.908745 -410.080279)
			(xy 31.900916 -410.061619) (xy 31.900368 -410.051504) (xy 31.900368 -409.7655) (xy 31.90018 -409.758626)
			(xy 31.896569 -409.745364) (xy 31.893256 -409.739338) (xy 31.876903 -409.710994) (xy 31.851187 -409.650819)
			(xy 31.833782 -409.587737) (xy 31.825002 -409.522889) (xy 30.536116 -409.522889) (xy 30.526736 -409.539186)
			(xy 30.523429 -409.545215) (xy 30.519818 -409.558475) (xy 30.519624 -409.565348) (xy 30.519624 -410.314648)
			(xy 30.519833 -410.32152) (xy 30.523429 -410.334783) (xy 30.526736 -410.34081) (xy 30.543045 -410.369178)
			(xy 30.568766 -410.429348) (xy 30.586176 -410.492425) (xy 30.594962 -410.557268) (xy 30.594963 -410.589984)
			(xy 34.024316 -410.589984) (xy 34.024895 -410.557255) (xy 34.033746 -410.492397) (xy 34.051233 -410.429317)
			(xy 34.077037 -410.369158) (xy 34.093404 -410.34081) (xy 34.096715 -410.334784) (xy 34.100323 -410.321521)
			(xy 34.100516 -410.314648) (xy 34.100516 -409.565348) (xy 34.100303 -409.558476) (xy 34.096709 -409.545214)
			(xy 34.093404 -409.539186) (xy 34.077033 -409.51084) (xy 34.051233 -409.450679) (xy 34.033744 -409.387599)
			(xy 34.024886 -409.322741) (xy 34.024316 -409.290012) (xy 34.024863 -409.257282) (xy 34.033724 -409.192423)
			(xy 34.05122 -409.129343) (xy 34.077033 -409.069185) (xy 34.093404 -409.040838) (xy 34.096706 -409.034807)
			(xy 34.100319 -409.021548) (xy 34.100516 -409.014676) (xy 34.100516 -408.728672) (xy 34.100962 -408.718559)
			(xy 34.108712 -408.699878) (xy 34.123021 -408.685583) (xy 34.141711 -408.677852) (xy 34.151824 -408.677364)
			(xy 34.868104 -408.677364) (xy 34.878209 -408.677881) (xy 34.89688 -408.685613) (xy 34.911173 -408.6999)
			(xy 34.918914 -408.718568) (xy 34.919412 -408.728672) (xy 34.919412 -409.014676) (xy 34.919612 -409.021549)
			(xy 34.923215 -409.034811) (xy 34.926524 -409.040838) (xy 34.942907 -409.069178) (xy 34.968704 -409.129341)
			(xy 34.986189 -409.192423) (xy 34.995044 -409.257282) (xy 34.995612 -409.290012) (xy 34.995027 -409.322741)
			(xy 34.986177 -409.387598) (xy 34.968692 -409.450678) (xy 34.951757 -409.490164) (xy 36.224464 -409.490164)
			(xy 36.225041 -409.457435) (xy 36.233894 -409.392577) (xy 36.251381 -409.329497) (xy 36.277185 -409.269338)
			(xy 36.293552 -409.24099) (xy 36.296866 -409.234965) (xy 36.300473 -409.221702) (xy 36.300664 -409.214828)
			(xy 36.300664 -408.465528) (xy 36.300466 -408.458655) (xy 36.296862 -408.445392) (xy 36.293552 -408.439366)
			(xy 36.277178 -408.411021) (xy 36.251377 -408.350861) (xy 36.233889 -408.28778) (xy 36.225032 -408.222921)
			(xy 36.224464 -408.190192) (xy 36.225054 -408.157463) (xy 36.233903 -408.092606) (xy 36.251387 -408.029526)
			(xy 36.277187 -407.969367) (xy 36.293552 -407.941018) (xy 36.296856 -407.934988) (xy 36.300469 -407.921729)
			(xy 36.300664 -407.914856) (xy 36.300664 -407.628852) (xy 36.301145 -407.618745) (xy 36.308892 -407.600072)
			(xy 36.323189 -407.585781) (xy 36.341864 -407.578041) (xy 36.351972 -407.577544) (xy 37.068252 -407.577544)
			(xy 37.078351 -407.578123) (xy 37.097017 -407.585835) (xy 37.111312 -407.600102) (xy 37.119058 -407.618754)
			(xy 37.11956 -407.628852) (xy 37.11956 -407.914856) (xy 37.119774 -407.921728) (xy 37.123368 -407.93499)
			(xy 37.126672 -407.941018) (xy 37.143042 -407.969365) (xy 37.168843 -408.029525) (xy 37.186332 -408.092605)
			(xy 37.195191 -408.157463) (xy 37.19576 -408.190192) (xy 37.195205 -408.222922) (xy 37.186345 -408.28778)
			(xy 37.168851 -408.35086) (xy 37.143042 -408.411018) (xy 37.126672 -408.439366) (xy 37.123367 -408.445396)
			(xy 37.119756 -408.458656) (xy 37.11956 -408.465528) (xy 37.11956 -409.214828) (xy 37.119746 -409.221702)
			(xy 37.123359 -409.234964) (xy 37.126672 -409.24099) (xy 37.143031 -409.269343) (xy 37.168835 -409.329501)
			(xy 37.186327 -409.392579) (xy 37.195189 -409.457435) (xy 37.19576 -409.490164) (xy 37.195192 -409.522893)
			(xy 37.186336 -409.587751) (xy 37.168846 -409.650831) (xy 37.14304 -409.71099) (xy 37.126672 -409.739338)
			(xy 37.123342 -409.745355) (xy 37.119746 -409.758625) (xy 37.11956 -409.7655) (xy 37.11956 -410.051504)
			(xy 37.119186 -410.061632) (xy 37.111429 -410.080343) (xy 37.097099 -410.094659) (xy 37.07838 -410.102396)
			(xy 37.068252 -410.102812) (xy 36.351972 -410.102812) (xy 36.341863 -410.102338) (xy 36.323186 -410.094594)
			(xy 36.308893 -410.080293) (xy 36.301157 -410.061613) (xy 36.300664 -410.051504) (xy 36.300664 -409.7655)
			(xy 36.300476 -409.758626) (xy 36.296866 -409.745363) (xy 36.293552 -409.739338) (xy 36.277207 -409.710978)
			(xy 36.251399 -409.650823) (xy 36.233903 -409.587746) (xy 36.225037 -409.522892) (xy 36.224464 -409.490164)
			(xy 34.951757 -409.490164) (xy 34.94289 -409.510837) (xy 34.926524 -409.539186) (xy 34.923216 -409.545214)
			(xy 34.919606 -409.558475) (xy 34.919412 -409.565348) (xy 34.919412 -410.314648) (xy 34.919622 -410.32152)
			(xy 34.923218 -410.334783) (xy 34.926524 -410.34081) (xy 34.942896 -410.369156) (xy 34.968696 -410.429317)
			(xy 34.986183 -410.492397) (xy 34.995042 -410.557255) (xy 34.995612 -410.589984) (xy 34.99506 -410.622705)
			(xy 38.424958 -410.622705) (xy 38.42496 -410.557268) (xy 38.433744 -410.492423) (xy 38.451153 -410.429344)
			(xy 38.47687 -410.369172) (xy 38.493192 -410.34081) (xy 38.496503 -410.334783) (xy 38.500111 -410.321521)
			(xy 38.500304 -410.314648) (xy 38.500304 -409.565348) (xy 38.500093 -409.558476) (xy 38.496498 -409.545213)
			(xy 38.493192 -409.539186) (xy 38.476881 -409.510819) (xy 38.451165 -409.450648) (xy 38.433758 -409.387571)
			(xy 38.424974 -409.322728) (xy 38.424972 -409.257293) (xy 38.433754 -409.192449) (xy 38.451159 -409.129371)
			(xy 38.476872 -409.0692) (xy 38.493192 -409.040838) (xy 38.496493 -409.034806) (xy 38.500107 -409.021548)
			(xy 38.500304 -409.014676) (xy 38.500304 -408.728672) (xy 38.500699 -408.718516) (xy 38.508504 -408.699762)
			(xy 38.522909 -408.685439) (xy 38.541707 -408.677741) (xy 38.551866 -408.677364) (xy 39.268146 -408.677364)
			(xy 39.278279 -408.67779) (xy 39.297005 -408.685537) (xy 39.311361 -408.699842) (xy 39.319174 -408.718541)
			(xy 39.319708 -408.728672) (xy 39.319708 -409.014676) (xy 39.319908 -409.021549) (xy 39.323511 -409.034811)
			(xy 39.32682 -409.040838) (xy 39.343154 -409.069193) (xy 39.368872 -409.129365) (xy 39.386281 -409.192445)
			(xy 39.395064 -409.257291) (xy 39.395063 -409.322729) (xy 39.386277 -409.387575) (xy 39.368866 -409.450654)
			(xy 39.351976 -409.490164) (xy 40.624252 -409.490164) (xy 40.62483 -409.457435) (xy 40.633683 -409.392577)
			(xy 40.65117 -409.329497) (xy 40.676973 -409.269339) (xy 40.69334 -409.24099) (xy 40.696654 -409.234965)
			(xy 40.700261 -409.221702) (xy 40.700452 -409.214828) (xy 40.700452 -408.465528) (xy 40.700255 -408.458655)
			(xy 40.696651 -408.445392) (xy 40.69334 -408.439366) (xy 40.676965 -408.411022) (xy 40.651164 -408.350861)
			(xy 40.633677 -408.28778) (xy 40.62482 -408.222922) (xy 40.624252 -408.190192) (xy 40.624843 -408.157463)
			(xy 40.633692 -408.092606) (xy 40.651175 -408.029526) (xy 40.676975 -407.969367) (xy 40.69334 -407.941018)
			(xy 40.696644 -407.934988) (xy 40.700257 -407.921728) (xy 40.700452 -407.914856) (xy 40.700452 -407.628852)
			(xy 40.700945 -407.618746) (xy 40.708689 -407.600076) (xy 40.722983 -407.585785) (xy 40.741654 -407.578043)
			(xy 40.75176 -407.577544) (xy 41.46804 -407.577544) (xy 41.478144 -407.578051) (xy 41.496813 -407.585791)
			(xy 41.511104 -407.600081) (xy 41.518847 -407.618748) (xy 41.519348 -407.628852) (xy 41.519348 -407.914856)
			(xy 41.519551 -407.921729) (xy 41.523151 -407.934992) (xy 41.52646 -407.941018) (xy 41.542829 -407.969365)
			(xy 41.568631 -408.029525) (xy 41.58612 -408.092605) (xy 41.594979 -408.157463) (xy 41.595548 -408.190192)
			(xy 45.023794 -408.190192) (xy 45.027785 -408.128025) (xy 45.039694 -408.066878) (xy 45.059323 -408.007757)
			(xy 45.086352 -407.951631) (xy 45.120336 -407.899422) (xy 45.160718 -407.851987) (xy 45.206834 -407.810106)
			(xy 45.257926 -407.774466) (xy 45.313157 -407.745652) (xy 45.371619 -407.724138) (xy 45.432353 -407.710276)
			(xy 45.49436 -407.704294) (xy 45.556623 -407.70629) (xy 45.61812 -407.716233) (xy 45.677841 -407.733957)
			(xy 45.734804 -407.759174) (xy 45.788075 -407.791467) (xy 45.83678 -407.830307) (xy 45.880117 -407.875057)
			(xy 45.917377 -407.924981) (xy 45.947946 -407.97926) (xy 45.971324 -408.037003) (xy 45.987125 -408.097261)
			(xy 45.995091 -408.159044) (xy 45.99559 -408.190192) (xy 45.995091 -408.22134) (xy 45.987125 -408.283123)
			(xy 45.971324 -408.343381) (xy 45.947946 -408.401124) (xy 45.917377 -408.455403) (xy 45.880117 -408.505327)
			(xy 45.83678 -408.550077) (xy 45.788075 -408.588917) (xy 45.734804 -408.62121) (xy 45.677841 -408.646427)
			(xy 45.61812 -408.664151) (xy 45.556623 -408.674094) (xy 45.49436 -408.67609) (xy 45.432353 -408.670108)
			(xy 45.371619 -408.656246) (xy 45.313157 -408.634732) (xy 45.257926 -408.605918) (xy 45.206834 -408.570278)
			(xy 45.160718 -408.528397) (xy 45.120336 -408.480962) (xy 45.086352 -408.428753) (xy 45.059323 -408.372627)
			(xy 45.039694 -408.313506) (xy 45.027785 -408.252359) (xy 45.023794 -408.190192) (xy 41.595548 -408.190192)
			(xy 41.594995 -408.222922) (xy 41.586134 -408.28778) (xy 41.56864 -408.35086) (xy 41.54283 -408.411018)
			(xy 41.52646 -408.439366) (xy 41.523162 -408.445399) (xy 41.519545 -408.458656) (xy 41.519348 -408.465528)
			(xy 41.519348 -409.214828) (xy 41.519523 -409.221703) (xy 41.523142 -409.234966) (xy 41.52646 -409.24099)
			(xy 41.542818 -409.269344) (xy 41.568622 -409.329501) (xy 41.586114 -409.392579) (xy 41.594977 -409.457435)
			(xy 41.595548 -409.490164) (xy 41.594982 -409.522893) (xy 41.586125 -409.587751) (xy 41.568635 -409.650832)
			(xy 41.542828 -409.71099) (xy 41.52646 -409.739338) (xy 41.523136 -409.745358) (xy 41.519536 -409.758625)
			(xy 41.519348 -409.7655) (xy 41.519348 -410.051504) (xy 41.518819 -410.061607) (xy 41.511089 -410.080276)
			(xy 41.496806 -410.094569) (xy 41.478143 -410.102312) (xy 41.46804 -410.102812) (xy 40.75176 -410.102812)
			(xy 40.74165 -410.102348) (xy 40.722973 -410.094599) (xy 40.70868 -410.080296) (xy 40.700945 -410.061614)
			(xy 40.700452 -410.051504) (xy 40.700452 -409.7655) (xy 40.700266 -409.758626) (xy 40.696654 -409.745363)
			(xy 40.69334 -409.739338) (xy 40.676993 -409.710978) (xy 40.651186 -409.650823) (xy 40.633691 -409.587747)
			(xy 40.624825 -409.522892) (xy 40.624252 -409.490164) (xy 39.351976 -409.490164) (xy 39.343144 -409.510825)
			(xy 39.32682 -409.539186) (xy 39.323512 -409.545214) (xy 39.319902 -409.558475) (xy 39.319708 -409.565348)
			(xy 39.319708 -410.314648) (xy 39.319919 -410.32152) (xy 39.323514 -410.334783) (xy 39.32682 -410.34081)
			(xy 39.34313 -410.369178) (xy 39.368851 -410.429347) (xy 39.386262 -410.492425) (xy 39.395048 -410.557268)
			(xy 39.395049 -410.589984) (xy 42.8244 -410.589984) (xy 42.824981 -410.557255) (xy 42.833832 -410.492397)
			(xy 42.851318 -410.429317) (xy 42.877122 -410.369159) (xy 42.893488 -410.34081) (xy 42.896798 -410.334783)
			(xy 42.900407 -410.321521) (xy 42.9006 -410.314648) (xy 42.9006 -409.565348) (xy 42.90039 -409.558476)
			(xy 42.896794 -409.545213) (xy 42.893488 -409.539186) (xy 42.877116 -409.51084) (xy 42.851316 -409.45068)
			(xy 42.833828 -409.387599) (xy 42.82497 -409.322741) (xy 42.8244 -409.290012) (xy 42.824948 -409.257282)
			(xy 42.833809 -409.192423) (xy 42.851305 -409.129343) (xy 42.877117 -409.069185) (xy 42.893488 -409.040838)
			(xy 42.896788 -409.034806) (xy 42.900403 -409.021548) (xy 42.9006 -409.014676) (xy 42.9006 -408.728672)
			(xy 42.901062 -408.718561) (xy 42.908809 -408.699883) (xy 42.923113 -408.685589) (xy 42.941797 -408.677855)
			(xy 42.951908 -408.677364) (xy 43.668188 -408.677364) (xy 43.678292 -408.677894) (xy 43.696963 -408.685621)
			(xy 43.711257 -408.699904) (xy 43.718998 -408.718569) (xy 43.719496 -408.728672) (xy 43.719496 -409.014676)
			(xy 43.719697 -409.021549) (xy 43.723299 -409.034811) (xy 43.726608 -409.040838) (xy 43.742989 -409.069178)
			(xy 43.768787 -409.129341) (xy 43.786272 -409.192423) (xy 43.795128 -409.257282) (xy 43.795696 -409.290012)
			(xy 43.795114 -409.322741) (xy 43.786263 -409.387599) (xy 43.768777 -409.450679) (xy 43.751841 -409.490164)
			(xy 45.023794 -409.490164) (xy 45.027785 -409.427997) (xy 45.039694 -409.36685) (xy 45.059323 -409.307729)
			(xy 45.086352 -409.251603) (xy 45.120336 -409.199394) (xy 45.160718 -409.151959) (xy 45.206834 -409.110078)
			(xy 45.257926 -409.074438) (xy 45.313157 -409.045624) (xy 45.371619 -409.02411) (xy 45.432353 -409.010248)
			(xy 45.49436 -409.004266) (xy 45.556623 -409.006262) (xy 45.61812 -409.016205) (xy 45.677841 -409.033929)
			(xy 45.734804 -409.059146) (xy 45.788075 -409.091439) (xy 45.83678 -409.130279) (xy 45.880117 -409.175029)
			(xy 45.917377 -409.224953) (xy 45.947946 -409.279232) (xy 45.971324 -409.336975) (xy 45.987125 -409.397233)
			(xy 45.995091 -409.459016) (xy 45.99559 -409.490164) (xy 45.995091 -409.521312) (xy 45.987125 -409.583095)
			(xy 45.971324 -409.643353) (xy 45.947946 -409.701096) (xy 45.917377 -409.755375) (xy 45.880117 -409.805299)
			(xy 45.83678 -409.850049) (xy 45.788075 -409.888889) (xy 45.734804 -409.921182) (xy 45.677841 -409.946399)
			(xy 45.61812 -409.964123) (xy 45.556623 -409.974066) (xy 45.49436 -409.976062) (xy 45.432353 -409.97008)
			(xy 45.371619 -409.956218) (xy 45.313157 -409.934704) (xy 45.257926 -409.90589) (xy 45.206834 -409.87025)
			(xy 45.160718 -409.828369) (xy 45.120336 -409.780934) (xy 45.086352 -409.728725) (xy 45.059323 -409.672599)
			(xy 45.039694 -409.613478) (xy 45.027785 -409.552331) (xy 45.023794 -409.490164) (xy 43.751841 -409.490164)
			(xy 43.742974 -409.510837) (xy 43.726608 -409.539186) (xy 43.723299 -409.545213) (xy 43.71969 -409.558475)
			(xy 43.719496 -409.565348) (xy 43.719496 -410.314648) (xy 43.719709 -410.32152) (xy 43.723303 -410.334782)
			(xy 43.726608 -410.34081) (xy 43.742978 -410.369157) (xy 43.768779 -410.429317) (xy 43.786267 -410.492397)
			(xy 43.795126 -410.557255) (xy 43.795696 -410.589984) (xy 43.795146 -410.622705) (xy 47.22503 -410.622705)
			(xy 47.225032 -410.557267) (xy 47.233818 -410.492421) (xy 47.25123 -410.429342) (xy 47.276952 -410.369171)
			(xy 47.293276 -410.34081) (xy 47.296585 -410.334783) (xy 47.300195 -410.321521) (xy 47.300388 -410.314648)
			(xy 47.300388 -409.565348) (xy 47.300179 -409.558476) (xy 47.296583 -409.545213) (xy 47.293276 -409.539186)
			(xy 47.276963 -409.51082) (xy 47.251242 -409.45065) (xy 47.233832 -409.387572) (xy 47.225046 -409.322728)
			(xy 47.225045 -409.257292) (xy 47.233828 -409.192448) (xy 47.251235 -409.129369) (xy 47.276953 -409.069199)
			(xy 47.293276 -409.040838) (xy 47.296576 -409.034806) (xy 47.300191 -409.021548) (xy 47.300388 -409.014676)
			(xy 47.300388 -408.728672) (xy 47.300798 -408.718518) (xy 47.308601 -408.699767) (xy 47.323001 -408.685445)
			(xy 47.341793 -408.677744) (xy 47.35195 -408.677364) (xy 48.06823 -408.677364) (xy 48.078362 -408.677803)
			(xy 48.097088 -408.685545) (xy 48.111444 -408.699846) (xy 48.119258 -408.718542) (xy 48.119792 -408.728672)
			(xy 48.119792 -409.014676) (xy 48.119994 -409.021548) (xy 48.123595 -409.034811) (xy 48.126904 -409.040838)
			(xy 48.143235 -409.069194) (xy 48.168949 -409.129367) (xy 48.186355 -409.192447) (xy 48.195136 -409.257292)
			(xy 48.195135 -409.322729) (xy 48.186351 -409.387574) (xy 48.168943 -409.450653) (xy 48.143226 -409.510824)
			(xy 48.126904 -409.539186) (xy 48.123595 -409.545213) (xy 48.119985 -409.558475) (xy 48.119792 -409.565348)
			(xy 48.119792 -410.314648) (xy 48.120005 -410.32152) (xy 48.123599 -410.334782) (xy 48.126904 -410.34081)
			(xy 48.143211 -410.369179) (xy 48.168928 -410.429349) (xy 48.186336 -410.492426) (xy 48.19512 -410.557269)
			(xy 48.195122 -410.622704) (xy 48.186341 -410.687547) (xy 48.168937 -410.750625) (xy 48.143224 -410.810796)
			(xy 48.126904 -410.839158) (xy 48.123604 -410.84519) (xy 48.119989 -410.858448) (xy 48.119792 -410.86532)
			(xy 48.119792 -411.151324) (xy 48.119398 -411.161481) (xy 48.111593 -411.180235) (xy 48.097188 -411.194558)
			(xy 48.078389 -411.202255) (xy 48.06823 -411.202632) (xy 47.35195 -411.202632) (xy 47.341823 -411.202132)
			(xy 47.323098 -411.194415) (xy 47.308739 -411.180132) (xy 47.300923 -411.161448) (xy 47.300388 -411.151324)
			(xy 47.300388 -410.86532) (xy 47.30019 -410.858447) (xy 47.296586 -410.845184) (xy 47.293276 -410.839158)
			(xy 47.276939 -410.810805) (xy 47.251221 -410.750632) (xy 47.233813 -410.687552) (xy 47.22503 -410.622705)
			(xy 43.795146 -410.622705) (xy 43.795146 -410.622714) (xy 43.786285 -410.687573) (xy 43.768791 -410.750653)
			(xy 43.742979 -410.81081) (xy 43.726608 -410.839158) (xy 43.723309 -410.84519) (xy 43.719693 -410.858448)
			(xy 43.719496 -410.86532) (xy 43.719496 -411.151324) (xy 43.719035 -411.161435) (xy 43.711288 -411.180114)
			(xy 43.696984 -411.194408) (xy 43.678299 -411.202142) (xy 43.668188 -411.202632) (xy 42.951908 -411.202632)
			(xy 42.941804 -411.202109) (xy 42.923132 -411.19438) (xy 42.908838 -411.180095) (xy 42.901097 -411.161428)
			(xy 42.9006 -411.151324) (xy 42.9006 -410.86532) (xy 42.9004 -410.858447) (xy 42.896797 -410.845185)
			(xy 42.893488 -410.839158) (xy 42.877105 -410.810819) (xy 42.851307 -410.750655) (xy 42.833823 -410.687573)
			(xy 42.824968 -410.622714) (xy 42.8244 -410.589984) (xy 39.395049 -410.589984) (xy 39.39505 -410.622704)
			(xy 39.386268 -410.687548) (xy 39.36886 -410.750627) (xy 39.343142 -410.810797) (xy 39.32682 -410.839158)
			(xy 39.323522 -410.845191) (xy 39.319905 -410.858448) (xy 39.319708 -410.86532) (xy 39.319708 -411.151324)
			(xy 39.319298 -411.161479) (xy 39.311496 -411.18023) (xy 39.297096 -411.194552) (xy 39.278303 -411.202253)
			(xy 39.268146 -411.202632) (xy 38.551866 -411.202632) (xy 38.541734 -411.202201) (xy 38.523006 -411.194456)
			(xy 38.50865 -411.180153) (xy 38.500837 -411.161454) (xy 38.500304 -411.151324) (xy 38.500304 -410.86532)
			(xy 38.500104 -410.858447) (xy 38.496501 -410.845185) (xy 38.493192 -410.839158) (xy 38.476858 -410.810804)
			(xy 38.451144 -410.75063) (xy 38.433739 -410.68755) (xy 38.424958 -410.622705) (xy 34.99506 -410.622705)
			(xy 34.99506 -410.622714) (xy 34.9862 -410.687573) (xy 34.968706 -410.750653) (xy 34.942895 -410.810811)
			(xy 34.926524 -410.839158) (xy 34.923226 -410.845191) (xy 34.919609 -410.858448) (xy 34.919412 -410.86532)
			(xy 34.919412 -411.151324) (xy 34.918935 -411.161433) (xy 34.911192 -411.180109) (xy 34.896893 -411.194403)
			(xy 34.878213 -411.202139) (xy 34.868104 -411.202632) (xy 34.151824 -411.202632) (xy 34.141721 -411.202096)
			(xy 34.123049 -411.194372) (xy 34.108755 -411.180091) (xy 34.101013 -411.161427) (xy 34.100516 -411.151324)
			(xy 34.100516 -410.86532) (xy 34.100315 -410.858447) (xy 34.096713 -410.845185) (xy 34.093404 -410.839158)
			(xy 34.077022 -410.810818) (xy 34.051224 -410.750655) (xy 34.033739 -410.687573) (xy 34.024884 -410.622714)
			(xy 34.024316 -410.589984) (xy 30.594963 -410.589984) (xy 30.594964 -410.622704) (xy 30.586182 -410.687548)
			(xy 30.568775 -410.750626) (xy 30.543058 -410.810797) (xy 30.526736 -410.839158) (xy 30.523439 -410.845191)
			(xy 30.519822 -410.858448) (xy 30.519624 -410.86532) (xy 30.519624 -411.151324) (xy 30.519199 -411.161477)
			(xy 30.5114 -411.180225) (xy 30.497005 -411.194547) (xy 30.478217 -411.20225) (xy 30.468062 -411.202632)
			(xy 29.751782 -411.202632) (xy 29.741651 -411.202188) (xy 29.722924 -411.194449) (xy 29.708567 -411.180149)
			(xy 29.700753 -411.161453) (xy 29.70022 -411.151324) (xy 29.70022 -410.86532) (xy 29.700018 -410.858448)
			(xy 29.696416 -410.845185) (xy 29.693108 -410.839158) (xy 29.676773 -410.810804) (xy 29.651058 -410.750631)
			(xy 29.633653 -410.687551) (xy 29.624872 -410.622705) (xy 15.456095 -410.622705) (xy 15.450105 -410.624271)
			(xy 15.394668 -410.630371) (xy 15.338934 -410.628334) (xy 15.284091 -410.618204) (xy 15.231307 -410.600197)
			(xy 15.181707 -410.574696) (xy 15.136349 -410.542245) (xy 15.0962 -410.503536) (xy 15.062114 -410.459393)
			(xy 15.034818 -410.410758) (xy 15.014895 -410.358667) (xy 15.002769 -410.30423) (xy 14.998698 -410.248608)
			(xy 0.635 -410.248608) (xy 0.635 -412.090108) (xy 27.42388 -412.090108) (xy 27.427871 -412.027941)
			(xy 27.43978 -411.966794) (xy 27.459409 -411.907673) (xy 27.486438 -411.851547) (xy 27.520422 -411.799338)
			(xy 27.560804 -411.751903) (xy 27.60692 -411.710022) (xy 27.658012 -411.674382) (xy 27.713243 -411.645568)
			(xy 27.771705 -411.624054) (xy 27.832439 -411.610192) (xy 27.894446 -411.60421) (xy 27.956709 -411.606206)
			(xy 28.018206 -411.616149) (xy 28.077927 -411.633873) (xy 28.13489 -411.65909) (xy 28.188161 -411.691383)
			(xy 28.236866 -411.730223) (xy 28.280203 -411.774973) (xy 28.317463 -411.824897) (xy 28.348032 -411.879176)
			(xy 28.37141 -411.936919) (xy 28.387211 -411.997177) (xy 28.395177 -412.05896) (xy 28.395676 -412.090108)
			(xy 31.823922 -412.090108) (xy 31.827913 -412.027941) (xy 31.839822 -411.966794) (xy 31.859451 -411.907673)
			(xy 31.88648 -411.851547) (xy 31.920464 -411.799338) (xy 31.960846 -411.751903) (xy 32.006962 -411.710022)
			(xy 32.058054 -411.674382) (xy 32.113285 -411.645568) (xy 32.171747 -411.624054) (xy 32.232481 -411.610192)
			(xy 32.294488 -411.60421) (xy 32.356751 -411.606206) (xy 32.418248 -411.616149) (xy 32.477969 -411.633873)
			(xy 32.534932 -411.65909) (xy 32.588203 -411.691383) (xy 32.636908 -411.730223) (xy 32.680245 -411.774973)
			(xy 32.717505 -411.824897) (xy 32.748074 -411.879176) (xy 32.771452 -411.936919) (xy 32.787253 -411.997177)
			(xy 32.795219 -412.05896) (xy 32.795718 -412.090108) (xy 36.223964 -412.090108) (xy 36.227955 -412.027941)
			(xy 36.239864 -411.966794) (xy 36.259493 -411.907673) (xy 36.286522 -411.851547) (xy 36.320506 -411.799338)
			(xy 36.360888 -411.751903) (xy 36.407004 -411.710022) (xy 36.458096 -411.674382) (xy 36.513327 -411.645568)
			(xy 36.571789 -411.624054) (xy 36.632523 -411.610192) (xy 36.69453 -411.60421) (xy 36.756793 -411.606206)
			(xy 36.81829 -411.616149) (xy 36.878011 -411.633873) (xy 36.934974 -411.65909) (xy 36.988245 -411.691383)
			(xy 37.03695 -411.730223) (xy 37.080287 -411.774973) (xy 37.117547 -411.824897) (xy 37.148116 -411.879176)
			(xy 37.171494 -411.936919) (xy 37.187295 -411.997177) (xy 37.195261 -412.05896) (xy 37.19576 -412.090108)
			(xy 40.623752 -412.090108) (xy 40.627743 -412.027941) (xy 40.639652 -411.966794) (xy 40.659281 -411.907673)
			(xy 40.68631 -411.851547) (xy 40.720294 -411.799338) (xy 40.760676 -411.751903) (xy 40.806792 -411.710022)
			(xy 40.857884 -411.674382) (xy 40.913115 -411.645568) (xy 40.971577 -411.624054) (xy 41.032311 -411.610192)
			(xy 41.094318 -411.60421) (xy 41.156581 -411.606206) (xy 41.218078 -411.616149) (xy 41.277799 -411.633873)
			(xy 41.334762 -411.65909) (xy 41.388033 -411.691383) (xy 41.436738 -411.730223) (xy 41.480075 -411.774973)
			(xy 41.517335 -411.824897) (xy 41.547904 -411.879176) (xy 41.571282 -411.936919) (xy 41.587083 -411.997177)
			(xy 41.595049 -412.05896) (xy 41.595548 -412.090108) (xy 45.023794 -412.090108) (xy 45.027785 -412.027941)
			(xy 45.039694 -411.966794) (xy 45.059323 -411.907673) (xy 45.086352 -411.851547) (xy 45.120336 -411.799338)
			(xy 45.160718 -411.751903) (xy 45.206834 -411.710022) (xy 45.257926 -411.674382) (xy 45.313157 -411.645568)
			(xy 45.371619 -411.624054) (xy 45.432353 -411.610192) (xy 45.49436 -411.60421) (xy 45.556623 -411.606206)
			(xy 45.61812 -411.616149) (xy 45.677841 -411.633873) (xy 45.734804 -411.65909) (xy 45.788075 -411.691383)
			(xy 45.83678 -411.730223) (xy 45.880117 -411.774973) (xy 45.917377 -411.824897) (xy 45.947946 -411.879176)
			(xy 45.971324 -411.936919) (xy 45.987125 -411.997177) (xy 45.995091 -412.05896) (xy 45.99559 -412.090108)
			(xy 45.995091 -412.121256) (xy 45.987125 -412.183039) (xy 45.971324 -412.243297) (xy 45.947946 -412.30104)
			(xy 45.917377 -412.355319) (xy 45.880117 -412.405243) (xy 45.83678 -412.449993) (xy 45.788075 -412.488833)
			(xy 45.734804 -412.521126) (xy 45.677841 -412.546343) (xy 45.61812 -412.564067) (xy 45.556623 -412.57401)
			(xy 45.49436 -412.576006) (xy 45.432353 -412.570024) (xy 45.371619 -412.556162) (xy 45.313157 -412.534648)
			(xy 45.257926 -412.505834) (xy 45.206834 -412.470194) (xy 45.160718 -412.428313) (xy 45.120336 -412.380878)
			(xy 45.086352 -412.328669) (xy 45.059323 -412.272543) (xy 45.039694 -412.213422) (xy 45.027785 -412.152275)
			(xy 45.023794 -412.090108) (xy 41.595548 -412.090108) (xy 41.595049 -412.121256) (xy 41.587083 -412.183039)
			(xy 41.571282 -412.243297) (xy 41.547904 -412.30104) (xy 41.517335 -412.355319) (xy 41.480075 -412.405243)
			(xy 41.436738 -412.449993) (xy 41.388033 -412.488833) (xy 41.334762 -412.521126) (xy 41.277799 -412.546343)
			(xy 41.218078 -412.564067) (xy 41.156581 -412.57401) (xy 41.094318 -412.576006) (xy 41.032311 -412.570024)
			(xy 40.971577 -412.556162) (xy 40.913115 -412.534648) (xy 40.857884 -412.505834) (xy 40.806792 -412.470194)
			(xy 40.760676 -412.428313) (xy 40.720294 -412.380878) (xy 40.68631 -412.328669) (xy 40.659281 -412.272543)
			(xy 40.639652 -412.213422) (xy 40.627743 -412.152275) (xy 40.623752 -412.090108) (xy 37.19576 -412.090108)
			(xy 37.195261 -412.121256) (xy 37.187295 -412.183039) (xy 37.171494 -412.243297) (xy 37.148116 -412.30104)
			(xy 37.117547 -412.355319) (xy 37.080287 -412.405243) (xy 37.03695 -412.449993) (xy 36.988245 -412.488833)
			(xy 36.934974 -412.521126) (xy 36.878011 -412.546343) (xy 36.81829 -412.564067) (xy 36.756793 -412.57401)
			(xy 36.69453 -412.576006) (xy 36.632523 -412.570024) (xy 36.571789 -412.556162) (xy 36.513327 -412.534648)
			(xy 36.458096 -412.505834) (xy 36.407004 -412.470194) (xy 36.360888 -412.428313) (xy 36.320506 -412.380878)
			(xy 36.286522 -412.328669) (xy 36.259493 -412.272543) (xy 36.239864 -412.213422) (xy 36.227955 -412.152275)
			(xy 36.223964 -412.090108) (xy 32.795718 -412.090108) (xy 32.795219 -412.121256) (xy 32.787253 -412.183039)
			(xy 32.771452 -412.243297) (xy 32.748074 -412.30104) (xy 32.717505 -412.355319) (xy 32.680245 -412.405243)
			(xy 32.636908 -412.449993) (xy 32.588203 -412.488833) (xy 32.534932 -412.521126) (xy 32.477969 -412.546343)
			(xy 32.418248 -412.564067) (xy 32.356751 -412.57401) (xy 32.294488 -412.576006) (xy 32.232481 -412.570024)
			(xy 32.171747 -412.556162) (xy 32.113285 -412.534648) (xy 32.058054 -412.505834) (xy 32.006962 -412.470194)
			(xy 31.960846 -412.428313) (xy 31.920464 -412.380878) (xy 31.88648 -412.328669) (xy 31.859451 -412.272543)
			(xy 31.839822 -412.213422) (xy 31.827913 -412.152275) (xy 31.823922 -412.090108) (xy 28.395676 -412.090108)
			(xy 28.395177 -412.121256) (xy 28.387211 -412.183039) (xy 28.37141 -412.243297) (xy 28.348032 -412.30104)
			(xy 28.317463 -412.355319) (xy 28.280203 -412.405243) (xy 28.236866 -412.449993) (xy 28.188161 -412.488833)
			(xy 28.13489 -412.521126) (xy 28.077927 -412.546343) (xy 28.018206 -412.564067) (xy 27.956709 -412.57401)
			(xy 27.894446 -412.576006) (xy 27.832439 -412.570024) (xy 27.771705 -412.556162) (xy 27.713243 -412.534648)
			(xy 27.658012 -412.505834) (xy 27.60692 -412.470194) (xy 27.560804 -412.428313) (xy 27.520422 -412.380878)
			(xy 27.486438 -412.328669) (xy 27.459409 -412.272543) (xy 27.43978 -412.213422) (xy 27.427871 -412.152275)
			(xy 27.42388 -412.090108) (xy 0.635 -412.090108) (xy 0.635 -412.752286) (xy 17.883122 -412.752286)
			(xy 17.887193 -412.696664) (xy 17.899319 -412.642227) (xy 17.919242 -412.590136) (xy 17.946538 -412.541501)
			(xy 17.980624 -412.497358) (xy 18.020773 -412.458649) (xy 18.066131 -412.426198) (xy 18.115731 -412.400697)
			(xy 18.168515 -412.38269) (xy 18.223358 -412.37256) (xy 18.279092 -412.370523) (xy 18.334529 -412.376623)
			(xy 18.388486 -412.390729) (xy 18.439815 -412.412541) (xy 18.487421 -412.441595) (xy 18.530289 -412.47727)
			(xy 18.567506 -412.518807) (xy 18.598279 -412.56532) (xy 18.621951 -412.615817) (xy 18.638019 -412.669224)
			(xy 18.646139 -412.7244) (xy 18.646648 -412.752286) (xy 18.646139 -412.780172) (xy 18.638019 -412.835348)
			(xy 18.621951 -412.888755) (xy 18.598527 -412.938722) (xy 19.503896 -412.938722) (xy 19.507967 -412.8831)
			(xy 19.520093 -412.828663) (xy 19.540016 -412.776572) (xy 19.567312 -412.727937) (xy 19.601398 -412.683794)
			(xy 19.641547 -412.645085) (xy 19.686905 -412.612634) (xy 19.736505 -412.587133) (xy 19.789289 -412.569126)
			(xy 19.844132 -412.558996) (xy 19.899866 -412.556959) (xy 19.955303 -412.563059) (xy 20.00926 -412.577165)
			(xy 20.060589 -412.598977) (xy 20.108195 -412.628031) (xy 20.151063 -412.663706) (xy 20.1683 -412.682944)
			(xy 20.874988 -412.682944) (xy 20.879059 -412.627322) (xy 20.891185 -412.572885) (xy 20.911108 -412.520794)
			(xy 20.938404 -412.472159) (xy 20.97249 -412.428016) (xy 21.012639 -412.389307) (xy 21.057997 -412.356856)
			(xy 21.107597 -412.331355) (xy 21.160381 -412.313348) (xy 21.215224 -412.303218) (xy 21.270958 -412.301181)
			(xy 21.326395 -412.307281) (xy 21.380352 -412.321387) (xy 21.431681 -412.343199) (xy 21.479287 -412.372253)
			(xy 21.522155 -412.407928) (xy 21.559372 -412.449465) (xy 21.590145 -412.495978) (xy 21.613817 -412.546475)
			(xy 21.629885 -412.599882) (xy 21.638005 -412.655058) (xy 21.638514 -412.682944) (xy 21.638005 -412.71083)
			(xy 21.629885 -412.766006) (xy 21.613817 -412.819413) (xy 21.590145 -412.86991) (xy 21.559372 -412.916423)
			(xy 21.522155 -412.95796) (xy 21.479287 -412.993635) (xy 21.431681 -413.022689) (xy 21.380352 -413.044501)
			(xy 21.326395 -413.058607) (xy 21.270958 -413.064707) (xy 21.215224 -413.06267) (xy 21.160381 -413.05254)
			(xy 21.107597 -413.034533) (xy 21.057997 -413.009032) (xy 21.012639 -412.976581) (xy 20.97249 -412.937872)
			(xy 20.938404 -412.893729) (xy 20.911108 -412.845094) (xy 20.891185 -412.793003) (xy 20.879059 -412.738566)
			(xy 20.874988 -412.682944) (xy 20.1683 -412.682944) (xy 20.18828 -412.705243) (xy 20.219053 -412.751756)
			(xy 20.242725 -412.802253) (xy 20.258793 -412.85566) (xy 20.266913 -412.910836) (xy 20.267422 -412.938722)
			(xy 20.266913 -412.966608) (xy 20.258793 -413.021784) (xy 20.242725 -413.075191) (xy 20.219053 -413.125688)
			(xy 20.18828 -413.172201) (xy 20.151063 -413.213738) (xy 20.108195 -413.249413) (xy 20.060589 -413.278467)
			(xy 20.00926 -413.300279) (xy 19.955303 -413.314385) (xy 19.899866 -413.320485) (xy 19.844132 -413.318448)
			(xy 19.789289 -413.308318) (xy 19.736505 -413.290311) (xy 19.686905 -413.26481) (xy 19.641547 -413.232359)
			(xy 19.601398 -413.19365) (xy 19.567312 -413.149507) (xy 19.540016 -413.100872) (xy 19.520093 -413.048781)
			(xy 19.507967 -412.994344) (xy 19.503896 -412.938722) (xy 18.598527 -412.938722) (xy 18.598279 -412.939252)
			(xy 18.567506 -412.985765) (xy 18.530289 -413.027302) (xy 18.487421 -413.062977) (xy 18.439815 -413.092031)
			(xy 18.388486 -413.113843) (xy 18.334529 -413.127949) (xy 18.279092 -413.134049) (xy 18.223358 -413.132012)
			(xy 18.168515 -413.121882) (xy 18.115731 -413.103875) (xy 18.066131 -413.078374) (xy 18.020773 -413.045923)
			(xy 17.980624 -413.007214) (xy 17.946538 -412.963071) (xy 17.919242 -412.914436) (xy 17.899319 -412.862345)
			(xy 17.887193 -412.807908) (xy 17.883122 -412.752286) (xy 0.635 -412.752286) (xy 0.635 -414.985454)
			(xy 17.471896 -414.985454) (xy 17.475967 -414.929832) (xy 17.488093 -414.875395) (xy 17.508016 -414.823304)
			(xy 17.535312 -414.774669) (xy 17.569398 -414.730526) (xy 17.609547 -414.691817) (xy 17.654905 -414.659366)
			(xy 17.704505 -414.633865) (xy 17.757289 -414.615858) (xy 17.812132 -414.605728) (xy 17.867866 -414.603691)
			(xy 17.923303 -414.609791) (xy 17.97726 -414.623897) (xy 18.028589 -414.645709) (xy 18.076195 -414.674763)
			(xy 18.119063 -414.710438) (xy 18.15628 -414.751975) (xy 18.187053 -414.798488) (xy 18.210725 -414.848985)
			(xy 18.226793 -414.902392) (xy 18.234913 -414.957568) (xy 18.235422 -414.985454) (xy 19.503896 -414.985454)
			(xy 19.507967 -414.929832) (xy 19.520093 -414.875395) (xy 19.540016 -414.823304) (xy 19.567312 -414.774669)
			(xy 19.601398 -414.730526) (xy 19.641547 -414.691817) (xy 19.686905 -414.659366) (xy 19.736505 -414.633865)
			(xy 19.789289 -414.615858) (xy 19.844132 -414.605728) (xy 19.899866 -414.603691) (xy 19.955303 -414.609791)
			(xy 20.00926 -414.623897) (xy 20.060589 -414.645709) (xy 20.108195 -414.674763) (xy 20.151063 -414.710438)
			(xy 20.18828 -414.751975) (xy 20.219053 -414.798488) (xy 20.242725 -414.848985) (xy 20.258793 -414.902392)
			(xy 20.266913 -414.957568) (xy 20.267422 -414.985454) (xy 20.519896 -414.985454) (xy 20.523967 -414.929832)
			(xy 20.536093 -414.875395) (xy 20.556016 -414.823304) (xy 20.583312 -414.774669) (xy 20.617398 -414.730526)
			(xy 20.657547 -414.691817) (xy 20.702905 -414.659366) (xy 20.752505 -414.633865) (xy 20.805289 -414.615858)
			(xy 20.860132 -414.605728) (xy 20.915866 -414.603691) (xy 20.971303 -414.609791) (xy 21.02526 -414.623897)
			(xy 21.076589 -414.645709) (xy 21.124195 -414.674763) (xy 21.167063 -414.710438) (xy 21.20428 -414.751975)
			(xy 21.235053 -414.798488) (xy 21.258725 -414.848985) (xy 21.274793 -414.902392) (xy 21.282913 -414.957568)
			(xy 21.283422 -414.985454) (xy 21.282913 -415.01334) (xy 21.274793 -415.068516) (xy 21.258725 -415.121923)
			(xy 21.235053 -415.17242) (xy 21.20428 -415.218933) (xy 21.167063 -415.26047) (xy 21.124195 -415.296145)
			(xy 21.076589 -415.325199) (xy 21.02526 -415.347011) (xy 20.971303 -415.361117) (xy 20.915866 -415.367217)
			(xy 20.860132 -415.36518) (xy 20.805289 -415.35505) (xy 20.752505 -415.337043) (xy 20.702905 -415.311542)
			(xy 20.657547 -415.279091) (xy 20.617398 -415.240382) (xy 20.583312 -415.196239) (xy 20.556016 -415.147604)
			(xy 20.536093 -415.095513) (xy 20.523967 -415.041076) (xy 20.519896 -414.985454) (xy 20.267422 -414.985454)
			(xy 20.266913 -415.01334) (xy 20.258793 -415.068516) (xy 20.242725 -415.121923) (xy 20.219053 -415.17242)
			(xy 20.18828 -415.218933) (xy 20.151063 -415.26047) (xy 20.108195 -415.296145) (xy 20.060589 -415.325199)
			(xy 20.00926 -415.347011) (xy 19.955303 -415.361117) (xy 19.899866 -415.367217) (xy 19.844132 -415.36518)
			(xy 19.789289 -415.35505) (xy 19.736505 -415.337043) (xy 19.686905 -415.311542) (xy 19.641547 -415.279091)
			(xy 19.601398 -415.240382) (xy 19.567312 -415.196239) (xy 19.540016 -415.147604) (xy 19.520093 -415.095513)
			(xy 19.507967 -415.041076) (xy 19.503896 -414.985454) (xy 18.235422 -414.985454) (xy 18.234913 -415.01334)
			(xy 18.226793 -415.068516) (xy 18.210725 -415.121923) (xy 18.187053 -415.17242) (xy 18.15628 -415.218933)
			(xy 18.119063 -415.26047) (xy 18.076195 -415.296145) (xy 18.028589 -415.325199) (xy 17.97726 -415.347011)
			(xy 17.923303 -415.361117) (xy 17.867866 -415.367217) (xy 17.812132 -415.36518) (xy 17.757289 -415.35505)
			(xy 17.704505 -415.337043) (xy 17.654905 -415.311542) (xy 17.609547 -415.279091) (xy 17.569398 -415.240382)
			(xy 17.535312 -415.196239) (xy 17.508016 -415.147604) (xy 17.488093 -415.095513) (xy 17.475967 -415.041076)
			(xy 17.471896 -414.985454) (xy 0.635 -414.985454) (xy 0.635 -415.999676) (xy 0.635532 -416.00965)
			(xy 0.643237 -416.028054) (xy 0.657381 -416.042127) (xy 0.675824 -416.049739) (xy 0.6858 -416.050222)
			(xy 0.695198 -416.04946) (xy 0.712626 -416.04639) (xy 0.747861 -416.043085) (xy 0.765556 -416.042856)
			(xy 0.766318 -416.042856) (xy 0.792098 -416.043282) (xy 0.843189 -416.050228) (xy 0.892879 -416.063992)
			(xy 0.940263 -416.084322) (xy 0.984477 -416.110847) (xy 1.024716 -416.143086) (xy 1.060247 -416.18045)
			(xy 1.07569 -416.201098) (xy 1.083301 -416.210483) (xy 1.104775 -416.221493) (xy 1.116838 -416.22218)
			(xy 52.460398 -416.22218)
		)
		(stroke
			(width 0)
			(type solid)
		)
		(fill yes)
		(layer "In7.Cu")
		(net "GND")
	)
	(gr_poly
		(pts
			(xy 175.33239 -310.268874) (xy 175.433228 -310.207152) (xy 175.446182 -310.182514) (xy 175.445166 -310.16829)
			(xy 175.444658 -310.149748) (xy 175.445101 -310.125751) (xy 175.452601 -310.078348) (xy 175.467425 -310.032702)
			(xy 175.489207 -309.989937) (xy 175.517411 -309.951106) (xy 175.551343 -309.917165) (xy 175.590167 -309.88895)
			(xy 175.632926 -309.867156) (xy 175.678568 -309.85232) (xy 175.72597 -309.844807) (xy 175.749966 -309.84444)
			(xy 175.76408 -309.844563) (xy 175.792193 -309.847108) (xy 175.8061 -309.84952) (xy 175.8188 -309.85206)
			(xy 175.842168 -309.844694) (xy 175.919638 -309.767224) (xy 175.927004 -309.743602) (xy 175.924718 -309.731156)
			(xy 175.922234 -309.717191) (xy 175.919562 -309.688951) (xy 175.919384 -309.674768) (xy 175.919833 -309.650758)
			(xy 175.92735 -309.603329) (xy 175.942194 -309.557661) (xy 175.964 -309.514877) (xy 175.992231 -309.476031)
			(xy 176.026191 -309.44208) (xy 176.065044 -309.41386) (xy 176.107833 -309.392065) (xy 176.153505 -309.377232)
			(xy 176.200936 -309.369727) (xy 176.224946 -309.369206) (xy 176.239129 -309.369391) (xy 176.267368 -309.372061)
			(xy 176.281334 -309.37454) (xy 176.29378 -309.376826) (xy 176.317402 -309.36946) (xy 176.394872 -309.29199)
			(xy 176.402238 -309.268622) (xy 176.399698 -309.255922) (xy 176.397302 -309.242013) (xy 176.394762 -309.213901)
			(xy 176.394618 -309.199788) (xy 176.394805 -309.185606) (xy 176.39748 -309.157367) (xy 176.399952 -309.1434)
			(xy 176.402238 -309.130954) (xy 176.394872 -309.107332) (xy 176.317402 -309.029862) (xy 176.29378 -309.022496)
			(xy 176.281334 -309.024782) (xy 176.267369 -309.027265) (xy 176.239129 -309.029932) (xy 176.224946 -309.030116)
			(xy 176.200123 -309.029634) (xy 176.151131 -309.021609) (xy 176.104083 -309.005764) (xy 176.060218 -308.982516)
			(xy 176.020693 -308.952477) (xy 175.986547 -308.916439) (xy 175.958683 -308.875352) (xy 175.937832 -308.830298)
			(xy 175.924546 -308.782464) (xy 175.919174 -308.73311) (xy 175.921857 -308.683538) (xy 175.932525 -308.635053)
			(xy 175.950897 -308.588933) (xy 175.976489 -308.546392) (xy 176.008626 -308.508553) (xy 176.046461 -308.476411)
			(xy 176.088998 -308.450814) (xy 176.135117 -308.432436) (xy 176.1836 -308.421762) (xy 176.233172 -308.419073)
			(xy 176.282526 -308.424439) (xy 176.330362 -308.437719) (xy 176.375419 -308.458564) (xy 176.416509 -308.486424)
			(xy 176.452552 -308.520564) (xy 176.482595 -308.560086) (xy 176.505849 -308.603948) (xy 176.5217 -308.650995)
			(xy 176.529731 -308.699986) (xy 176.530254 -308.724808) (xy 176.530067 -308.73899) (xy 176.527393 -308.76723)
			(xy 176.52492 -308.781196) (xy 176.522634 -308.793642) (xy 176.53 -308.817264) (xy 176.60747 -308.894734)
			(xy 176.631092 -308.9021) (xy 176.643538 -308.899814) (xy 176.657503 -308.89733) (xy 176.685743 -308.89466)
			(xy 176.699926 -308.89448) (xy 176.714108 -308.894668) (xy 176.742347 -308.897343) (xy 176.756314 -308.899814)
			(xy 176.76876 -308.9021) (xy 176.792382 -308.894734) (xy 176.869852 -308.817264) (xy 176.877218 -308.793642)
			(xy 176.874932 -308.781196) (xy 176.872446 -308.767231) (xy 176.869773 -308.738991) (xy 176.869598 -308.724808)
			(xy 176.87012 -308.699553) (xy 176.878433 -308.649731) (xy 176.894834 -308.601957) (xy 176.918875 -308.557534)
			(xy 176.949899 -308.517674) (xy 176.987061 -308.483464) (xy 177.029347 -308.455838) (xy 177.075603 -308.435548)
			(xy 177.124568 -308.423148) (xy 177.174906 -308.418977) (xy 177.225244 -308.423148) (xy 177.274209 -308.435548)
			(xy 177.320465 -308.455838) (xy 177.362751 -308.483464) (xy 177.399913 -308.517674) (xy 177.430937 -308.557534)
			(xy 177.454978 -308.601957) (xy 177.471379 -308.649731) (xy 177.479692 -308.699553) (xy 177.480214 -308.724808)
			(xy 177.480027 -308.73899) (xy 177.477353 -308.76723) (xy 177.47488 -308.781196) (xy 177.472594 -308.793642)
			(xy 177.47996 -308.817264) (xy 177.55743 -308.894734) (xy 177.581052 -308.9021) (xy 177.593498 -308.899814)
			(xy 177.607463 -308.897328) (xy 177.635703 -308.894655) (xy 177.649886 -308.89448) (xy 177.664069 -308.894666)
			(xy 177.692308 -308.897338) (xy 177.706274 -308.899814) (xy 177.71872 -308.9021) (xy 177.742342 -308.894734)
			(xy 177.819812 -308.817264) (xy 177.827178 -308.793642) (xy 177.824892 -308.781196) (xy 177.822407 -308.767231)
			(xy 177.819734 -308.738991) (xy 177.819558 -308.724808) (xy 177.820043 -308.699984) (xy 177.828075 -308.650989)
			(xy 177.843927 -308.603939) (xy 177.867182 -308.560073) (xy 177.897228 -308.520548) (xy 177.933272 -308.486405)
			(xy 177.974366 -308.458543) (xy 178.019426 -308.437696) (xy 178.067265 -308.424414) (xy 178.116623 -308.419047)
			(xy 178.166199 -308.421736) (xy 178.214687 -308.43241) (xy 178.260808 -308.450789) (xy 178.303349 -308.476387)
			(xy 178.341188 -308.50853) (xy 178.373329 -308.546372) (xy 178.398923 -308.588915) (xy 178.417297 -308.635038)
			(xy 178.427968 -308.683527) (xy 178.430189 -308.724554) (xy 178.769022 -308.724554) (xy 178.772982 -308.6755)
			(xy 178.784759 -308.627716) (xy 178.80405 -308.58244) (xy 178.830353 -308.540844) (xy 178.862988 -308.504007)
			(xy 178.901109 -308.472882) (xy 178.94373 -308.448275) (xy 178.989746 -308.430823) (xy 179.037965 -308.420979)
			(xy 179.08714 -308.418998) (xy 179.135995 -308.42493) (xy 179.183266 -308.438622) (xy 179.227728 -308.45972)
			(xy 179.268231 -308.487676) (xy 179.303724 -308.521768) (xy 179.333289 -308.561112) (xy 179.35616 -308.604689)
			(xy 179.371744 -308.65137) (xy 179.379639 -308.699947) (xy 179.380134 -308.724554) (xy 179.380129 -308.724808)
			(xy 179.719236 -308.724808) (xy 179.723196 -308.675754) (xy 179.734973 -308.62797) (xy 179.754264 -308.582694)
			(xy 179.780567 -308.541098) (xy 179.813202 -308.504261) (xy 179.851323 -308.473136) (xy 179.893944 -308.448529)
			(xy 179.93996 -308.431077) (xy 179.988179 -308.421233) (xy 180.037354 -308.419252) (xy 180.086209 -308.425184)
			(xy 180.13348 -308.438876) (xy 180.177942 -308.459974) (xy 180.218445 -308.48793) (xy 180.253938 -308.522022)
			(xy 180.283503 -308.561366) (xy 180.306374 -308.604943) (xy 180.321958 -308.651624) (xy 180.329853 -308.700201)
			(xy 180.330348 -308.724808) (xy 180.669196 -308.724808) (xy 180.673156 -308.675754) (xy 180.684933 -308.62797)
			(xy 180.704224 -308.582694) (xy 180.730527 -308.541098) (xy 180.763162 -308.504261) (xy 180.801283 -308.473136)
			(xy 180.843904 -308.448529) (xy 180.88992 -308.431077) (xy 180.938139 -308.421233) (xy 180.987314 -308.419252)
			(xy 181.036169 -308.425184) (xy 181.08344 -308.438876) (xy 181.127902 -308.459974) (xy 181.168405 -308.48793)
			(xy 181.203898 -308.522022) (xy 181.233463 -308.561366) (xy 181.256334 -308.604943) (xy 181.271918 -308.651624)
			(xy 181.279813 -308.700201) (xy 181.280308 -308.724808) (xy 181.619156 -308.724808) (xy 181.623116 -308.675754)
			(xy 181.634893 -308.62797) (xy 181.654184 -308.582694) (xy 181.680487 -308.541098) (xy 181.713122 -308.504261)
			(xy 181.751243 -308.473136) (xy 181.793864 -308.448529) (xy 181.83988 -308.431077) (xy 181.888099 -308.421233)
			(xy 181.937274 -308.419252) (xy 181.986129 -308.425184) (xy 182.0334 -308.438876) (xy 182.077862 -308.459974)
			(xy 182.118365 -308.48793) (xy 182.153858 -308.522022) (xy 182.183423 -308.561366) (xy 182.206294 -308.604943)
			(xy 182.221878 -308.651624) (xy 182.229773 -308.700201) (xy 182.230268 -308.724808) (xy 182.569116 -308.724808)
			(xy 182.573076 -308.675754) (xy 182.584853 -308.62797) (xy 182.604144 -308.582694) (xy 182.630447 -308.541098)
			(xy 182.663082 -308.504261) (xy 182.701203 -308.473136) (xy 182.743824 -308.448529) (xy 182.78984 -308.431077)
			(xy 182.838059 -308.421233) (xy 182.887234 -308.419252) (xy 182.936089 -308.425184) (xy 182.98336 -308.438876)
			(xy 183.027822 -308.459974) (xy 183.068325 -308.48793) (xy 183.103818 -308.522022) (xy 183.133383 -308.561366)
			(xy 183.156254 -308.604943) (xy 183.171838 -308.651624) (xy 183.179733 -308.700201) (xy 183.180228 -308.724808)
			(xy 183.519076 -308.724808) (xy 183.523036 -308.675754) (xy 183.534813 -308.62797) (xy 183.554104 -308.582694)
			(xy 183.580407 -308.541098) (xy 183.613042 -308.504261) (xy 183.651163 -308.473136) (xy 183.693784 -308.448529)
			(xy 183.7398 -308.431077) (xy 183.788019 -308.421233) (xy 183.837194 -308.419252) (xy 183.886049 -308.425184)
			(xy 183.93332 -308.438876) (xy 183.977782 -308.459974) (xy 184.018285 -308.48793) (xy 184.053778 -308.522022)
			(xy 184.083343 -308.561366) (xy 184.106214 -308.604943) (xy 184.121798 -308.651624) (xy 184.129693 -308.700201)
			(xy 184.130188 -308.724808) (xy 184.46929 -308.724808) (xy 184.47325 -308.675754) (xy 184.485027 -308.62797)
			(xy 184.504318 -308.582694) (xy 184.530621 -308.541098) (xy 184.563256 -308.504261) (xy 184.601377 -308.473136)
			(xy 184.643998 -308.448529) (xy 184.690014 -308.431077) (xy 184.738233 -308.421233) (xy 184.787408 -308.419252)
			(xy 184.836263 -308.425184) (xy 184.883534 -308.438876) (xy 184.927996 -308.459974) (xy 184.968499 -308.48793)
			(xy 185.003992 -308.522022) (xy 185.033557 -308.561366) (xy 185.056428 -308.604943) (xy 185.072012 -308.651624)
			(xy 185.079907 -308.700201) (xy 185.080402 -308.724808) (xy 185.41925 -308.724808) (xy 185.42321 -308.675754)
			(xy 185.434987 -308.62797) (xy 185.454278 -308.582694) (xy 185.480581 -308.541098) (xy 185.513216 -308.504261)
			(xy 185.551337 -308.473136) (xy 185.593958 -308.448529) (xy 185.639974 -308.431077) (xy 185.688193 -308.421233)
			(xy 185.737368 -308.419252) (xy 185.786223 -308.425184) (xy 185.833494 -308.438876) (xy 185.877956 -308.459974)
			(xy 185.918459 -308.48793) (xy 185.953952 -308.522022) (xy 185.983517 -308.561366) (xy 186.006388 -308.604943)
			(xy 186.021972 -308.651624) (xy 186.029867 -308.700201) (xy 186.030362 -308.724808) (xy 186.36921 -308.724808)
			(xy 186.37317 -308.675754) (xy 186.384947 -308.62797) (xy 186.404238 -308.582694) (xy 186.430541 -308.541098)
			(xy 186.463176 -308.504261) (xy 186.501297 -308.473136) (xy 186.543918 -308.448529) (xy 186.589934 -308.431077)
			(xy 186.638153 -308.421233) (xy 186.687328 -308.419252) (xy 186.736183 -308.425184) (xy 186.783454 -308.438876)
			(xy 186.827916 -308.459974) (xy 186.868419 -308.48793) (xy 186.903912 -308.522022) (xy 186.933477 -308.561366)
			(xy 186.956348 -308.604943) (xy 186.971932 -308.651624) (xy 186.979827 -308.700201) (xy 186.980322 -308.724808)
			(xy 187.31917 -308.724808) (xy 187.32313 -308.675754) (xy 187.334907 -308.62797) (xy 187.354198 -308.582694)
			(xy 187.380501 -308.541098) (xy 187.413136 -308.504261) (xy 187.451257 -308.473136) (xy 187.493878 -308.448529)
			(xy 187.539894 -308.431077) (xy 187.588113 -308.421233) (xy 187.637288 -308.419252) (xy 187.686143 -308.425184)
			(xy 187.733414 -308.438876) (xy 187.777876 -308.459974) (xy 187.818379 -308.48793) (xy 187.853872 -308.522022)
			(xy 187.883437 -308.561366) (xy 187.906308 -308.604943) (xy 187.921892 -308.651624) (xy 187.929787 -308.700201)
			(xy 187.930282 -308.724808) (xy 188.26913 -308.724808) (xy 188.27309 -308.675754) (xy 188.284867 -308.62797)
			(xy 188.304158 -308.582694) (xy 188.330461 -308.541098) (xy 188.363096 -308.504261) (xy 188.401217 -308.473136)
			(xy 188.443838 -308.448529) (xy 188.489854 -308.431077) (xy 188.538073 -308.421233) (xy 188.587248 -308.419252)
			(xy 188.636103 -308.425184) (xy 188.683374 -308.438876) (xy 188.727836 -308.459974) (xy 188.768339 -308.48793)
			(xy 188.803832 -308.522022) (xy 188.833397 -308.561366) (xy 188.856268 -308.604943) (xy 188.871852 -308.651624)
			(xy 188.879747 -308.700201) (xy 188.880242 -308.724808) (xy 188.879747 -308.749415) (xy 188.871852 -308.797992)
			(xy 188.856268 -308.844673) (xy 188.833397 -308.88825) (xy 188.803832 -308.927594) (xy 188.768339 -308.961686)
			(xy 188.727836 -308.989642) (xy 188.683374 -309.01074) (xy 188.636103 -309.024432) (xy 188.587248 -309.030364)
			(xy 188.538073 -309.028383) (xy 188.489854 -309.018539) (xy 188.443838 -309.001087) (xy 188.401217 -308.97648)
			(xy 188.363096 -308.945355) (xy 188.330461 -308.908518) (xy 188.304158 -308.866922) (xy 188.284867 -308.821646)
			(xy 188.27309 -308.773862) (xy 188.26913 -308.724808) (xy 187.930282 -308.724808) (xy 187.929787 -308.749415)
			(xy 187.921892 -308.797992) (xy 187.906308 -308.844673) (xy 187.883437 -308.88825) (xy 187.853872 -308.927594)
			(xy 187.818379 -308.961686) (xy 187.777876 -308.989642) (xy 187.733414 -309.01074) (xy 187.686143 -309.024432)
			(xy 187.637288 -309.030364) (xy 187.588113 -309.028383) (xy 187.539894 -309.018539) (xy 187.493878 -309.001087)
			(xy 187.451257 -308.97648) (xy 187.413136 -308.945355) (xy 187.380501 -308.908518) (xy 187.354198 -308.866922)
			(xy 187.334907 -308.821646) (xy 187.32313 -308.773862) (xy 187.31917 -308.724808) (xy 186.980322 -308.724808)
			(xy 186.979827 -308.749415) (xy 186.971932 -308.797992) (xy 186.956348 -308.844673) (xy 186.933477 -308.88825)
			(xy 186.903912 -308.927594) (xy 186.868419 -308.961686) (xy 186.827916 -308.989642) (xy 186.783454 -309.01074)
			(xy 186.736183 -309.024432) (xy 186.687328 -309.030364) (xy 186.638153 -309.028383) (xy 186.589934 -309.018539)
			(xy 186.543918 -309.001087) (xy 186.501297 -308.97648) (xy 186.463176 -308.945355) (xy 186.430541 -308.908518)
			(xy 186.404238 -308.866922) (xy 186.384947 -308.821646) (xy 186.37317 -308.773862) (xy 186.36921 -308.724808)
			(xy 186.030362 -308.724808) (xy 186.029867 -308.749415) (xy 186.021972 -308.797992) (xy 186.006388 -308.844673)
			(xy 185.983517 -308.88825) (xy 185.953952 -308.927594) (xy 185.918459 -308.961686) (xy 185.877956 -308.989642)
			(xy 185.833494 -309.01074) (xy 185.786223 -309.024432) (xy 185.737368 -309.030364) (xy 185.688193 -309.028383)
			(xy 185.639974 -309.018539) (xy 185.593958 -309.001087) (xy 185.551337 -308.97648) (xy 185.513216 -308.945355)
			(xy 185.480581 -308.908518) (xy 185.454278 -308.866922) (xy 185.434987 -308.821646) (xy 185.42321 -308.773862)
			(xy 185.41925 -308.724808) (xy 185.080402 -308.724808) (xy 185.079907 -308.749415) (xy 185.072012 -308.797992)
			(xy 185.056428 -308.844673) (xy 185.033557 -308.88825) (xy 185.003992 -308.927594) (xy 184.968499 -308.961686)
			(xy 184.927996 -308.989642) (xy 184.883534 -309.01074) (xy 184.836263 -309.024432) (xy 184.787408 -309.030364)
			(xy 184.738233 -309.028383) (xy 184.690014 -309.018539) (xy 184.643998 -309.001087) (xy 184.601377 -308.97648)
			(xy 184.563256 -308.945355) (xy 184.530621 -308.908518) (xy 184.504318 -308.866922) (xy 184.485027 -308.821646)
			(xy 184.47325 -308.773862) (xy 184.46929 -308.724808) (xy 184.130188 -308.724808) (xy 184.129693 -308.749415)
			(xy 184.121798 -308.797992) (xy 184.106214 -308.844673) (xy 184.083343 -308.88825) (xy 184.053778 -308.927594)
			(xy 184.018285 -308.961686) (xy 183.977782 -308.989642) (xy 183.93332 -309.01074) (xy 183.886049 -309.024432)
			(xy 183.837194 -309.030364) (xy 183.788019 -309.028383) (xy 183.7398 -309.018539) (xy 183.693784 -309.001087)
			(xy 183.651163 -308.97648) (xy 183.613042 -308.945355) (xy 183.580407 -308.908518) (xy 183.554104 -308.866922)
			(xy 183.534813 -308.821646) (xy 183.523036 -308.773862) (xy 183.519076 -308.724808) (xy 183.180228 -308.724808)
			(xy 183.179733 -308.749415) (xy 183.171838 -308.797992) (xy 183.156254 -308.844673) (xy 183.133383 -308.88825)
			(xy 183.103818 -308.927594) (xy 183.068325 -308.961686) (xy 183.027822 -308.989642) (xy 182.98336 -309.01074)
			(xy 182.936089 -309.024432) (xy 182.887234 -309.030364) (xy 182.838059 -309.028383) (xy 182.78984 -309.018539)
			(xy 182.743824 -309.001087) (xy 182.701203 -308.97648) (xy 182.663082 -308.945355) (xy 182.630447 -308.908518)
			(xy 182.604144 -308.866922) (xy 182.584853 -308.821646) (xy 182.573076 -308.773862) (xy 182.569116 -308.724808)
			(xy 182.230268 -308.724808) (xy 182.229773 -308.749415) (xy 182.221878 -308.797992) (xy 182.206294 -308.844673)
			(xy 182.183423 -308.88825) (xy 182.153858 -308.927594) (xy 182.118365 -308.961686) (xy 182.077862 -308.989642)
			(xy 182.0334 -309.01074) (xy 181.986129 -309.024432) (xy 181.937274 -309.030364) (xy 181.888099 -309.028383)
			(xy 181.83988 -309.018539) (xy 181.793864 -309.001087) (xy 181.751243 -308.97648) (xy 181.713122 -308.945355)
			(xy 181.680487 -308.908518) (xy 181.654184 -308.866922) (xy 181.634893 -308.821646) (xy 181.623116 -308.773862)
			(xy 181.619156 -308.724808) (xy 181.280308 -308.724808) (xy 181.279813 -308.749415) (xy 181.271918 -308.797992)
			(xy 181.256334 -308.844673) (xy 181.233463 -308.88825) (xy 181.203898 -308.927594) (xy 181.168405 -308.961686)
			(xy 181.127902 -308.989642) (xy 181.08344 -309.01074) (xy 181.036169 -309.024432) (xy 180.987314 -309.030364)
			(xy 180.938139 -309.028383) (xy 180.88992 -309.018539) (xy 180.843904 -309.001087) (xy 180.801283 -308.97648)
			(xy 180.763162 -308.945355) (xy 180.730527 -308.908518) (xy 180.704224 -308.866922) (xy 180.684933 -308.821646)
			(xy 180.673156 -308.773862) (xy 180.669196 -308.724808) (xy 180.330348 -308.724808) (xy 180.329853 -308.749415)
			(xy 180.321958 -308.797992) (xy 180.306374 -308.844673) (xy 180.283503 -308.88825) (xy 180.253938 -308.927594)
			(xy 180.218445 -308.961686) (xy 180.177942 -308.989642) (xy 180.13348 -309.01074) (xy 180.086209 -309.024432)
			(xy 180.037354 -309.030364) (xy 179.988179 -309.028383) (xy 179.93996 -309.018539) (xy 179.893944 -309.001087)
			(xy 179.851323 -308.97648) (xy 179.813202 -308.945355) (xy 179.780567 -308.908518) (xy 179.754264 -308.866922)
			(xy 179.734973 -308.821646) (xy 179.723196 -308.773862) (xy 179.719236 -308.724808) (xy 179.380129 -308.724808)
			(xy 179.379639 -308.749161) (xy 179.371744 -308.797738) (xy 179.35616 -308.844419) (xy 179.333289 -308.887996)
			(xy 179.303724 -308.92734) (xy 179.268231 -308.961432) (xy 179.227728 -308.989388) (xy 179.183266 -309.010486)
			(xy 179.135995 -309.024178) (xy 179.08714 -309.03011) (xy 179.037965 -309.028129) (xy 178.989746 -309.018285)
			(xy 178.94373 -309.000833) (xy 178.901109 -308.976226) (xy 178.862988 -308.945101) (xy 178.830353 -308.908264)
			(xy 178.80405 -308.866668) (xy 178.784759 -308.821392) (xy 178.772982 -308.773608) (xy 178.769022 -308.724554)
			(xy 178.430189 -308.724554) (xy 178.430652 -308.733103) (xy 178.425281 -308.78246) (xy 178.411995 -308.830298)
			(xy 178.391145 -308.875356) (xy 178.363279 -308.916448) (xy 178.329132 -308.95249) (xy 178.289605 -308.982532)
			(xy 178.245737 -309.005784) (xy 178.198686 -309.021632) (xy 178.14969 -309.029659) (xy 178.124866 -309.030116)
			(xy 178.110683 -309.029933) (xy 178.082443 -309.027265) (xy 178.068478 -309.024782) (xy 178.056032 -309.022496)
			(xy 178.03241 -309.029862) (xy 177.95494 -309.107332) (xy 177.947574 -309.130954) (xy 177.94986 -309.1434)
			(xy 177.952346 -309.157365) (xy 177.955019 -309.185605) (xy 177.955194 -309.199788) (xy 177.955008 -309.21397)
			(xy 177.952335 -309.24221) (xy 177.94986 -309.256176) (xy 177.947574 -309.268622) (xy 177.95494 -309.292244)
			(xy 178.03241 -309.369714) (xy 178.056032 -309.37708) (xy 178.068478 -309.374794) (xy 178.082443 -309.372307)
			(xy 178.110683 -309.369632) (xy 178.124866 -309.36946) (xy 178.148796 -309.369923) (xy 178.196072 -309.377385)
			(xy 178.241604 -309.392132) (xy 178.284278 -309.413803) (xy 178.323048 -309.441866) (xy 178.356965 -309.475634)
			(xy 178.385197 -309.514281) (xy 178.407054 -309.55686) (xy 178.422 -309.602327) (xy 178.429669 -309.64957)
			(xy 178.430174 -309.673498) (xy 178.430174 -309.675276) (xy 178.429412 -309.697628) (xy 178.429158 -309.699406)
			(xy 178.429158 -309.700168) (xy 178.428895 -309.706855) (xy 178.431476 -309.71998) (xy 178.434238 -309.726076)
			(xy 178.434238 -309.72633) (xy 178.437543 -309.732534) (xy 178.446952 -309.742972) (xy 178.45278 -309.746904)
			(xy 178.525424 -309.792624) (xy 178.525932 -309.792878) (xy 178.528218 -309.794148) (xy 178.534273 -309.797611)
			(xy 178.547665 -309.801488) (xy 178.554634 -309.801768) (xy 178.568604 -309.801768) (xy 178.575208 -309.797958)
			(xy 178.581558 -309.79618) (xy 178.587654 -309.792624) (xy 178.623489 -309.772204) (xy 178.698014 -309.736849)
			(xy 178.736498 -309.722012) (xy 178.751738 -309.71617) (xy 178.769518 -309.690516) (xy 178.769518 -309.674514)
			(xy 178.77001 -309.650538) (xy 178.777552 -309.603183) (xy 178.792405 -309.557588) (xy 178.814204 -309.514877)
			(xy 178.842413 -309.4761) (xy 178.876338 -309.44221) (xy 178.915144 -309.414041) (xy 178.957877 -309.392285)
			(xy 179.003486 -309.377479) (xy 179.05085 -309.369985) (xy 179.074826 -309.36946) (xy 179.098465 -309.369905)
			(xy 179.145176 -309.377193) (xy 179.190207 -309.391592) (xy 179.232482 -309.412758) (xy 179.270991 -309.440184)
			(xy 179.304813 -309.473217) (xy 179.333142 -309.511067) (xy 179.355301 -309.552829) (xy 179.37076 -309.597507)
			(xy 179.379151 -309.644034) (xy 179.380134 -309.667656) (xy 179.380388 -309.674768) (xy 179.38496 -309.690008)
			(xy 179.386855 -309.695499) (xy 179.392763 -309.705497) (xy 179.396644 -309.70982) (xy 179.405026 -309.71871)
			(xy 179.415948 -309.722774) (xy 179.454105 -309.737583) (xy 179.527993 -309.772811) (xy 179.563522 -309.793132)
			(xy 179.569872 -309.796942) (xy 179.582318 -309.800244) (xy 179.592251 -309.802304) (xy 179.612298 -309.799301)
			(xy 179.62118 -309.794402) (xy 179.621688 -309.794148) (xy 179.709064 -309.739538) (xy 179.721764 -309.714392)
			(xy 179.720494 -309.699914) (xy 179.719478 -309.675276) (xy 179.719478 -309.674768) (xy 179.72 -309.649492)
			(xy 179.728321 -309.599628) (xy 179.744735 -309.551815) (xy 179.768795 -309.507355) (xy 179.799846 -309.467462)
			(xy 179.837038 -309.433224) (xy 179.879359 -309.405574) (xy 179.925654 -309.385267) (xy 179.97466 -309.372857)
			(xy 180.02504 -309.368683) (xy 180.07542 -309.372857) (xy 180.124426 -309.385267) (xy 180.170721 -309.405574)
			(xy 180.213042 -309.433224) (xy 180.250234 -309.467462) (xy 180.281285 -309.507355) (xy 180.305345 -309.551815)
			(xy 180.321759 -309.599628) (xy 180.33008 -309.649492) (xy 180.330602 -309.674768) (xy 180.329586 -309.700168)
			(xy 180.328316 -309.714392) (xy 180.341016 -309.739538) (xy 180.37683 -309.762144) (xy 180.377084 -309.762144)
			(xy 180.442108 -309.80253) (xy 180.470302 -309.802784) (xy 180.482748 -309.795418) (xy 180.519746 -309.77405)
			(xy 180.596821 -309.737166) (xy 180.636672 -309.721758) (xy 180.646136 -309.717687) (xy 180.661013 -309.703463)
			(xy 180.669132 -309.68455) (xy 180.669692 -309.67426) (xy 180.670253 -309.649032) (xy 180.678632 -309.599275)
			(xy 180.695079 -309.551574) (xy 180.719144 -309.507225) (xy 180.750174 -309.467437) (xy 180.787324 -309.433292)
			(xy 180.829582 -309.405721) (xy 180.875798 -309.385473) (xy 180.924715 -309.373099) (xy 180.975 -309.368937)
			(xy 181.025285 -309.373099) (xy 181.074202 -309.385473) (xy 181.120418 -309.405721) (xy 181.162676 -309.433292)
			(xy 181.199826 -309.467437) (xy 181.230856 -309.507225) (xy 181.254921 -309.551574) (xy 181.271368 -309.599275)
			(xy 181.279747 -309.649032) (xy 181.280308 -309.67426) (xy 181.281324 -309.683912) (xy 181.283307 -309.692346)
			(xy 181.29208 -309.707274) (xy 181.305336 -309.718414) (xy 181.313328 -309.721758) (xy 181.343947 -309.733434)
			(xy 181.40369 -309.76038) (xy 181.432708 -309.775606) (xy 181.432962 -309.77586) (xy 181.438804 -309.778908)
			(xy 181.450742 -309.781956) (xy 181.478682 -309.781956) (xy 181.4849 -309.781814) (xy 181.496981 -309.778867)
			(xy 181.502558 -309.776114) (xy 181.506622 -309.773828) (xy 181.570376 -309.734458) (xy 181.577835 -309.729438)
			(xy 181.588944 -309.715314) (xy 181.594529 -309.698235) (xy 181.594506 -309.689246) (xy 181.594506 -309.684674)
			(xy 181.594252 -309.675022) (xy 181.594252 -309.674514) (xy 181.594783 -309.64854) (xy 181.602949 -309.597238)
			(xy 181.619034 -309.547843) (xy 181.642645 -309.501571) (xy 181.673199 -309.459558) (xy 181.709945 -309.422839)
			(xy 181.751981 -309.392316) (xy 181.798271 -309.36874) (xy 181.847678 -309.352691) (xy 181.898986 -309.344563)
			(xy 181.92496 -309.34406) (xy 181.950952 -309.34454) (xy 182.002298 -309.352666) (xy 182.051739 -309.368724)
			(xy 182.098061 -309.39232) (xy 182.14012 -309.422871) (xy 182.176883 -309.459625) (xy 182.207443 -309.501678)
			(xy 182.231048 -309.547994) (xy 182.247117 -309.597432) (xy 182.255254 -309.648776) (xy 182.255668 -309.674768)
			(xy 182.255414 -309.688738) (xy 182.255414 -309.688992) (xy 182.255499 -309.697903) (xy 182.26101 -309.714835)
			(xy 182.271966 -309.728872) (xy 182.27929 -309.73395) (xy 182.336948 -309.769764) (xy 182.337456 -309.769764)
			(xy 182.35422 -309.780432) (xy 182.360197 -309.78394) (xy 182.373462 -309.787931) (xy 182.380382 -309.788306)
			(xy 182.394352 -309.78856) (xy 182.405274 -309.782464) (xy 182.405782 -309.782464) (xy 182.417212 -309.776114)
			(xy 182.448454 -309.759858) (xy 182.462988 -309.752761) (xy 182.492458 -309.739423) (xy 182.507382 -309.733188)
			(xy 182.512462 -309.730902) (xy 182.536084 -309.714392) (xy 182.544688 -309.707802) (xy 182.555791 -309.689213)
			(xy 182.558234 -309.667699) (xy 182.555388 -309.657242) (xy 182.547006 -309.631588) (xy 182.550975 -309.605411)
			(xy 182.566155 -309.554691) (xy 182.589224 -309.507039) (xy 182.619593 -309.463672) (xy 182.656484 -309.425699)
			(xy 182.698955 -309.39409) (xy 182.74592 -309.369653) (xy 182.79618 -309.353013) (xy 182.848449 -309.344595)
			(xy 182.87492 -309.34406) (xy 182.900907 -309.344571) (xy 182.952241 -309.352704) (xy 183.001671 -309.368766)
			(xy 183.04798 -309.392363) (xy 183.090028 -309.422912) (xy 183.12678 -309.459663) (xy 183.157331 -309.50171)
			(xy 183.180929 -309.548018) (xy 183.196993 -309.597447) (xy 183.205128 -309.648781) (xy 183.205628 -309.674768)
			(xy 183.205628 -309.682388) (xy 183.206404 -309.694567) (xy 183.217684 -309.71617) (xy 183.227218 -309.72379)
			(xy 183.237378 -309.731156) (xy 183.242966 -309.733442) (xy 183.296814 -309.757572) (xy 183.343042 -309.781448)
			(xy 183.34355 -309.781956) (xy 183.349392 -309.785004) (xy 183.361838 -309.788052) (xy 183.36895 -309.787798)
			(xy 183.375642 -309.787444) (xy 183.38851 -309.783719) (xy 183.39435 -309.780432) (xy 183.438546 -309.753508)
			(xy 183.439054 -309.753508) (xy 183.470296 -309.734204) (xy 183.477746 -309.729179) (xy 183.488836 -309.715053)
			(xy 183.494401 -309.697978) (xy 183.494426 -309.688992) (xy 183.494426 -309.688738) (xy 183.494172 -309.675276)
			(xy 183.494172 -309.674514) (xy 183.494703 -309.648541) (xy 183.502869 -309.59724) (xy 183.518955 -309.547846)
			(xy 183.542565 -309.501575) (xy 183.57312 -309.459564) (xy 183.609867 -309.422847) (xy 183.651902 -309.392326)
			(xy 183.698192 -309.368753) (xy 183.747599 -309.352706) (xy 183.798907 -309.344582) (xy 183.82488 -309.34406)
			(xy 183.850869 -309.344568) (xy 183.902208 -309.352696) (xy 183.951643 -309.368755) (xy 183.997958 -309.392349)
			(xy 184.040011 -309.422898) (xy 184.076768 -309.459649) (xy 184.107324 -309.501698) (xy 184.130925 -309.548009)
			(xy 184.146992 -309.597441) (xy 184.155128 -309.648779) (xy 184.155588 -309.674768) (xy 184.155334 -309.688738)
			(xy 184.155334 -309.688992) (xy 184.155419 -309.697902) (xy 184.160931 -309.714833) (xy 184.17189 -309.728866)
			(xy 184.17921 -309.73395) (xy 184.236868 -309.769764) (xy 184.237376 -309.769764) (xy 184.2516 -309.779162)
			(xy 184.25668 -309.781956) (xy 184.258712 -309.782972) (xy 184.264037 -309.785437) (xy 184.275453 -309.788138)
			(xy 184.281318 -309.788306) (xy 184.295288 -309.788306) (xy 184.307988 -309.78475) (xy 184.314084 -309.781194)
			(xy 184.335099 -309.768941) (xy 184.378171 -309.746323) (xy 184.40019 -309.735982) (xy 184.40654 -309.732934)
			(xy 184.416954 -309.724044) (xy 184.42813 -309.707788) (xy 184.435496 -309.696866) (xy 184.437581 -309.693731)
			(xy 184.440898 -309.686972) (xy 184.4421 -309.683404) (xy 184.444132 -309.676546) (xy 184.444386 -309.668926)
			(xy 184.444386 -309.668672) (xy 184.445348 -309.642993) (xy 184.454234 -309.592382) (xy 184.470839 -309.543754)
			(xy 184.494764 -309.498279) (xy 184.525434 -309.457051) (xy 184.562111 -309.421061) (xy 184.603911 -309.391176)
			(xy 184.649831 -309.368115) (xy 184.698764 -309.352432) (xy 184.749534 -309.344506) (xy 184.800919 -309.344525)
			(xy 184.851683 -309.352491) (xy 184.900604 -309.368211) (xy 184.946506 -309.391308) (xy 184.988284 -309.421225)
			(xy 185.024933 -309.457242) (xy 185.055571 -309.498494) (xy 185.079462 -309.543987) (xy 185.096029 -309.592628)
			(xy 185.104876 -309.643246) (xy 185.105802 -309.668926) (xy 185.106056 -309.676292) (xy 185.110374 -309.690262)
			(xy 185.121296 -309.706518) (xy 185.12155 -309.707026) (xy 185.128916 -309.717948) (xy 185.129424 -309.718456)
			(xy 185.133234 -309.724298) (xy 185.14441 -309.733696) (xy 185.151522 -309.736744) (xy 185.198004 -309.75808)
			(xy 185.243724 -309.781702) (xy 185.255408 -309.788306) (xy 185.282078 -309.788052) (xy 185.30316 -309.77586)
			(xy 185.304684 -309.775098) (xy 185.37047 -309.734204) (xy 185.377859 -309.729174) (xy 185.388916 -309.715146)
			(xy 185.394509 -309.698183) (xy 185.3946 -309.689246) (xy 185.3946 -309.687976) (xy 185.394346 -309.674768)
			(xy 185.394856 -309.648781) (xy 185.402986 -309.597446) (xy 185.419047 -309.548016) (xy 185.442643 -309.501706)
			(xy 185.473193 -309.459658) (xy 185.509944 -309.422907) (xy 185.551992 -309.392357) (xy 185.598302 -309.368761)
			(xy 185.647732 -309.3527) (xy 185.699067 -309.34457) (xy 185.751041 -309.34457) (xy 185.802376 -309.3527)
			(xy 185.851806 -309.368761) (xy 185.898116 -309.392357) (xy 185.940164 -309.422907) (xy 185.976915 -309.459658)
			(xy 186.007465 -309.501706) (xy 186.031061 -309.548016) (xy 186.047122 -309.597446) (xy 186.055252 -309.648781)
			(xy 186.055762 -309.674768) (xy 186.055508 -309.688738) (xy 186.055508 -309.688992) (xy 186.055593 -309.697903)
			(xy 186.061103 -309.714836) (xy 186.072059 -309.728873) (xy 186.079384 -309.73395) (xy 186.137042 -309.769764)
			(xy 186.13755 -309.769764) (xy 186.154314 -309.780432) (xy 186.160291 -309.783941) (xy 186.173556 -309.787933)
			(xy 186.180476 -309.788306) (xy 186.194446 -309.78856) (xy 186.205368 -309.782464) (xy 186.205876 -309.782464)
			(xy 186.217306 -309.776114) (xy 186.248548 -309.759858) (xy 186.263082 -309.752761) (xy 186.292552 -309.739423)
			(xy 186.307476 -309.733188) (xy 186.312556 -309.730902) (xy 186.336178 -309.714392) (xy 186.344783 -309.707803)
			(xy 186.355888 -309.689214) (xy 186.358331 -309.667699) (xy 186.355482 -309.657242) (xy 186.3471 -309.631588)
			(xy 186.351069 -309.605411) (xy 186.366249 -309.554691) (xy 186.389318 -309.507038) (xy 186.419686 -309.463671)
			(xy 186.456577 -309.425697) (xy 186.499048 -309.394087) (xy 186.546013 -309.36965) (xy 186.596273 -309.353009)
			(xy 186.648542 -309.34459) (xy 186.675014 -309.34406) (xy 186.701001 -309.344571) (xy 186.752336 -309.352703)
			(xy 186.801767 -309.368764) (xy 186.848077 -309.392361) (xy 186.890126 -309.42291) (xy 186.926878 -309.459661)
			(xy 186.95743 -309.501708) (xy 186.981029 -309.548017) (xy 186.997093 -309.597446) (xy 187.005228 -309.648781)
			(xy 187.005722 -309.674768) (xy 187.005722 -309.682388) (xy 187.006498 -309.694568) (xy 187.017776 -309.716171)
			(xy 187.027312 -309.72379) (xy 187.037472 -309.731156) (xy 187.04306 -309.733442) (xy 187.096908 -309.757572)
			(xy 187.143136 -309.781448) (xy 187.143644 -309.781956) (xy 187.149486 -309.785004) (xy 187.161932 -309.788052)
			(xy 187.169044 -309.787798) (xy 187.175737 -309.787444) (xy 187.188606 -309.783721) (xy 187.194444 -309.780432)
			(xy 187.23864 -309.753508) (xy 187.239148 -309.753508) (xy 187.27039 -309.734204) (xy 187.277841 -309.72918)
			(xy 187.288932 -309.715054) (xy 187.294498 -309.697978) (xy 187.29452 -309.688992) (xy 187.29452 -309.688738)
			(xy 187.294266 -309.675276) (xy 187.294266 -309.674514) (xy 187.294797 -309.648541) (xy 187.302963 -309.597239)
			(xy 187.319049 -309.547845) (xy 187.342659 -309.501574) (xy 187.373214 -309.459562) (xy 187.40996 -309.422844)
			(xy 187.451996 -309.392323) (xy 187.498286 -309.368749) (xy 187.547693 -309.352702) (xy 187.599 -309.344576)
			(xy 187.624974 -309.34406) (xy 187.650963 -309.344568) (xy 187.702303 -309.352695) (xy 187.751739 -309.368753)
			(xy 187.798054 -309.392347) (xy 187.840109 -309.422896) (xy 187.876867 -309.459647) (xy 187.907423 -309.501696)
			(xy 187.931025 -309.548007) (xy 187.947092 -309.597441) (xy 187.955228 -309.648779) (xy 187.955682 -309.674768)
			(xy 187.955428 -309.688738) (xy 187.955428 -309.688992) (xy 187.955513 -309.697903) (xy 187.961025 -309.714834)
			(xy 187.971982 -309.728868) (xy 187.979304 -309.73395) (xy 188.036962 -309.769764) (xy 188.03747 -309.769764)
			(xy 188.054234 -309.780432) (xy 188.060211 -309.783938) (xy 188.073476 -309.787925) (xy 188.080396 -309.788306)
			(xy 188.094366 -309.78856) (xy 188.105288 -309.782464) (xy 188.105796 -309.782464) (xy 188.117226 -309.776114)
			(xy 188.148468 -309.759858) (xy 188.163002 -309.752761) (xy 188.192472 -309.739424) (xy 188.207396 -309.733188)
			(xy 188.212476 -309.730902) (xy 188.236098 -309.714392) (xy 188.2447 -309.707801) (xy 188.2558 -309.689213)
			(xy 188.258243 -309.6677) (xy 188.255402 -309.657242) (xy 188.24702 -309.631588) (xy 188.250988 -309.605408)
			(xy 188.266167 -309.554682) (xy 188.289235 -309.507024) (xy 188.319601 -309.463649) (xy 188.356491 -309.425667)
			(xy 188.398961 -309.394048) (xy 188.445927 -309.3696) (xy 188.496188 -309.352948) (xy 188.54846 -309.344517)
			(xy 188.574934 -309.34406) (xy 188.60092 -309.344572) (xy 188.652253 -309.352707) (xy 188.701681 -309.36877)
			(xy 188.747988 -309.392367) (xy 188.790034 -309.422917) (xy 188.826784 -309.459668) (xy 188.857334 -309.501714)
			(xy 188.880931 -309.548021) (xy 188.896994 -309.597449) (xy 188.905128 -309.648782) (xy 188.905642 -309.674768)
			(xy 188.905642 -309.683404) (xy 188.905972 -309.692048) (xy 188.91171 -309.708354) (xy 188.922561 -309.72181)
			(xy 188.929772 -309.726584) (xy 188.937392 -309.731156) (xy 188.941202 -309.73268) (xy 188.973747 -309.746445)
			(xy 189.03693 -309.7781) (xy 189.06744 -309.795926) (xy 189.075544 -309.800276) (xy 189.093641 -309.803478)
			(xy 189.111707 -309.800106) (xy 189.119764 -309.795672) (xy 189.120272 -309.795418) (xy 189.208918 -309.739792)
			(xy 189.221618 -309.714646) (xy 189.220348 -309.700168) (xy 189.219332 -309.674768) (xy 189.219805 -309.650758)
			(xy 189.227322 -309.603331) (xy 189.242164 -309.557663) (xy 189.263967 -309.514878) (xy 189.292195 -309.476031)
			(xy 189.326151 -309.442078) (xy 189.365001 -309.413854) (xy 189.407787 -309.392054) (xy 189.453456 -309.377215)
			(xy 189.500884 -309.369703) (xy 189.524894 -309.369206) (xy 189.550294 -309.370222) (xy 189.564518 -309.371492)
			(xy 189.589664 -309.358792) (xy 189.61227 -309.322978) (xy 189.61227 -309.322724) (xy 189.652656 -309.2577)
			(xy 189.65291 -309.229506) (xy 189.645798 -309.21706) (xy 189.62795 -309.186365) (xy 189.596297 -309.122799)
			(xy 189.582552 -309.09006) (xy 189.582298 -309.089298) (xy 189.580774 -309.085996) (xy 189.575983 -309.076432)
			(xy 189.560242 -309.061984) (xy 189.550294 -309.058056) (xy 189.54242 -309.055516) (xy 189.524894 -309.055516)
			(xy 189.498907 -309.055006) (xy 189.447573 -309.046875) (xy 189.398142 -309.030813) (xy 189.351833 -309.007217)
			(xy 189.309785 -308.976668) (xy 189.273034 -308.939916) (xy 189.242484 -308.897869) (xy 189.218887 -308.851559)
			(xy 189.202826 -308.802129) (xy 189.194694 -308.750795) (xy 189.194186 -308.724808) (xy 189.194648 -308.699837)
			(xy 189.202167 -308.650463) (xy 189.21702 -308.60278) (xy 189.23887 -308.55787) (xy 189.26722 -308.516754)
			(xy 189.301428 -308.480365) (xy 189.340715 -308.44953) (xy 189.38419 -308.424949) (xy 189.430865 -308.407179)
			(xy 189.47968 -308.396626) (xy 189.504574 -308.394608) (xy 189.517782 -308.393846) (xy 189.569598 -308.360826)
			(xy 189.570614 -308.360064) (xy 189.579758 -308.353968) (xy 189.58941 -308.342792) (xy 189.592204 -308.335934)
			(xy 189.601299 -308.315664) (xy 189.621119 -308.275897) (xy 189.631828 -308.256432) (xy 189.638432 -308.24424)
			(xy 189.637924 -308.217062) (xy 189.603634 -308.160928) (xy 189.58433 -308.129432) (xy 189.579309 -308.121975)
			(xy 189.565185 -308.110872) (xy 189.548106 -308.105295) (xy 189.539118 -308.105302) (xy 189.538864 -308.105302)
			(xy 189.525402 -308.105556) (xy 189.52464 -308.105556) (xy 189.498665 -308.105027) (xy 189.447359 -308.096865)
			(xy 189.39796 -308.080781) (xy 189.351683 -308.057172) (xy 189.309666 -308.026619) (xy 189.272943 -307.989872)
			(xy 189.242417 -307.947836) (xy 189.218838 -307.901544) (xy 189.202786 -307.852135) (xy 189.194656 -307.800824)
			(xy 189.194186 -307.774848) (xy 189.194666 -307.748856) (xy 189.202791 -307.697511) (xy 189.218849 -307.64807)
			(xy 189.242444 -307.60175) (xy 189.272995 -307.559691) (xy 189.30975 -307.52293) (xy 189.351804 -307.492372)
			(xy 189.39812 -307.468769) (xy 189.447559 -307.452703) (xy 189.498902 -307.44457) (xy 189.524894 -307.44414)
			(xy 189.538864 -307.444394) (xy 189.539118 -307.444394) (xy 189.548027 -307.444305) (xy 189.564953 -307.438789)
			(xy 189.578984 -307.427831) (xy 189.584076 -307.420518) (xy 189.61989 -307.36286) (xy 189.61989 -307.362352)
			(xy 189.630558 -307.345588) (xy 189.634065 -307.339611) (xy 189.638056 -307.326346) (xy 189.638432 -307.319426)
			(xy 189.638686 -307.305456) (xy 189.632082 -307.293264) (xy 189.631828 -307.29301) (xy 189.617731 -307.267288)
			(xy 189.592313 -307.21442) (xy 189.581028 -307.187346) (xy 189.576835 -307.178182) (xy 189.562671 -307.163867)
			(xy 189.544105 -307.156069) (xy 189.534038 -307.155596) (xy 189.524894 -307.155596) (xy 189.498905 -307.155112)
			(xy 189.447568 -307.14698) (xy 189.398135 -307.130917) (xy 189.351824 -307.107319) (xy 189.309774 -307.076767)
			(xy 189.273022 -307.040012) (xy 189.242471 -306.997961) (xy 189.218876 -306.951648) (xy 189.202815 -306.902214)
			(xy 189.194686 -306.850877) (xy 189.194186 -306.824888) (xy 189.19465 -306.799918) (xy 189.202171 -306.750546)
			(xy 189.217026 -306.702866) (xy 189.238877 -306.657959) (xy 189.267228 -306.616845) (xy 189.301435 -306.580459)
			(xy 189.340721 -306.549625) (xy 189.384195 -306.525046) (xy 189.430868 -306.507278) (xy 189.479682 -306.496726)
			(xy 189.504574 -306.494688) (xy 189.517782 -306.493926) (xy 189.569598 -306.460906) (xy 189.570614 -306.460144)
			(xy 189.579758 -306.454048) (xy 189.58941 -306.442872) (xy 189.592204 -306.436014) (xy 189.601299 -306.415744)
			(xy 189.62112 -306.375978) (xy 189.631828 -306.356512) (xy 189.638432 -306.34432) (xy 189.637924 -306.317142)
			(xy 189.603634 -306.261008) (xy 189.58433 -306.229512) (xy 189.579307 -306.222058) (xy 189.565182 -306.210959)
			(xy 189.548105 -306.205384) (xy 189.539118 -306.205382) (xy 189.538864 -306.205382) (xy 189.525402 -306.205636)
			(xy 189.52464 -306.205636) (xy 189.498664 -306.205107) (xy 189.447357 -306.196943) (xy 189.397957 -306.180858)
			(xy 189.351679 -306.157247) (xy 189.309663 -306.12669) (xy 189.272941 -306.089939) (xy 189.242417 -306.047899)
			(xy 189.218842 -306.001603) (xy 189.202796 -305.95219) (xy 189.194673 -305.900876) (xy 189.194673 -305.848924)
			(xy 189.202796 -305.79761) (xy 189.218842 -305.748197) (xy 189.242417 -305.701901) (xy 189.272941 -305.659861)
			(xy 189.309663 -305.62311) (xy 189.351679 -305.592553) (xy 189.397957 -305.568942) (xy 189.447357 -305.552857)
			(xy 189.498664 -305.544693) (xy 189.52464 -305.54422) (xy 189.525402 -305.54422) (xy 189.55639 -305.54549)
			(xy 189.565026 -305.538378) (xy 189.56528 -305.538378) (xy 189.582806 -305.529742) (xy 189.590802 -305.525296)
			(xy 189.603206 -305.511866) (xy 189.610083 -305.494927) (xy 189.610746 -305.4858) (xy 189.611 -305.477418)
			(xy 189.638178 -305.432714) (xy 189.638686 -305.405536) (xy 189.632082 -305.393598) (xy 189.618358 -305.368353)
			(xy 189.593576 -305.316502) (xy 189.582552 -305.289966) (xy 189.582298 -305.289204) (xy 189.580774 -305.285902)
			(xy 189.575984 -305.276337) (xy 189.560243 -305.261887) (xy 189.550294 -305.257962) (xy 189.54242 -305.255422)
			(xy 189.524894 -305.255422) (xy 189.498907 -305.254912) (xy 189.447572 -305.246781) (xy 189.398142 -305.230719)
			(xy 189.351832 -305.207124) (xy 189.309783 -305.176574) (xy 189.273031 -305.139823) (xy 189.242481 -305.097775)
			(xy 189.218884 -305.051466) (xy 189.202821 -305.002036) (xy 189.194689 -304.950701) (xy 189.194186 -304.924714)
			(xy 189.194648 -304.899742) (xy 189.202166 -304.850368) (xy 189.217018 -304.802684) (xy 189.238868 -304.757774)
			(xy 189.267218 -304.716657) (xy 189.301426 -304.680267) (xy 189.340713 -304.649431) (xy 189.384188 -304.624849)
			(xy 189.430863 -304.60708) (xy 189.479679 -304.596526) (xy 189.504574 -304.594514) (xy 189.517782 -304.593752)
			(xy 189.569598 -304.560732) (xy 189.570614 -304.55997) (xy 189.579758 -304.553874) (xy 189.58941 -304.542698)
			(xy 189.592204 -304.53584) (xy 189.601299 -304.51557) (xy 189.621118 -304.475803) (xy 189.631828 -304.456338)
			(xy 189.638432 -304.444146) (xy 189.637924 -304.416968) (xy 189.603634 -304.360834) (xy 189.58433 -304.329338)
			(xy 189.579302 -304.321893) (xy 189.565174 -304.31081) (xy 189.548103 -304.305244) (xy 189.539118 -304.305208)
			(xy 189.538864 -304.305208) (xy 189.525402 -304.305462) (xy 189.52464 -304.305462) (xy 189.498668 -304.304933)
			(xy 189.447367 -304.296769) (xy 189.397974 -304.280685) (xy 189.351704 -304.257075) (xy 189.309696 -304.226519)
			(xy 189.272981 -304.189771) (xy 189.242465 -304.147734) (xy 189.218898 -304.101442) (xy 189.202859 -304.052035)
			(xy 189.194743 -304.000727) (xy 189.194186 -303.974754) (xy 189.194699 -303.948769) (xy 189.202835 -303.89744)
			(xy 189.2189 -303.848015) (xy 189.242498 -303.801711) (xy 189.273049 -303.759669) (xy 189.309799 -303.722923)
			(xy 189.351846 -303.692377) (xy 189.398152 -303.668785) (xy 189.447579 -303.652726) (xy 189.498909 -303.644596)
			(xy 189.524894 -303.644046) (xy 189.538548 -303.644209) (xy 189.56576 -303.646501) (xy 189.57925 -303.648618)
			(xy 189.591188 -303.65065) (xy 189.613794 -303.643538) (xy 189.690248 -303.57064) (xy 189.698122 -303.548288)
			(xy 189.696852 -303.536096) (xy 189.695804 -303.527052) (xy 189.694662 -303.508878) (xy 189.694566 -303.499774)
			(xy 189.695088 -303.474519) (xy 189.703401 -303.424697) (xy 189.719802 -303.376923) (xy 189.743843 -303.3325)
			(xy 189.774867 -303.29264) (xy 189.812029 -303.25843) (xy 189.854315 -303.230804) (xy 189.900571 -303.210514)
			(xy 189.949536 -303.198114) (xy 189.999874 -303.193943) (xy 190.050212 -303.198114) (xy 190.099177 -303.210514)
			(xy 190.145433 -303.230804) (xy 190.187719 -303.25843) (xy 190.224881 -303.29264) (xy 190.255905 -303.3325)
			(xy 190.279946 -303.376923) (xy 190.296347 -303.424697) (xy 190.30466 -303.474519) (xy 190.305182 -303.499774)
			(xy 190.304662 -303.526021) (xy 190.295724 -303.577746) (xy 190.287402 -303.602644) (xy 190.284566 -303.61192)
			(xy 190.285338 -303.631286) (xy 190.293251 -303.648978) (xy 190.307171 -303.662463) (xy 190.325106 -303.669809)
			(xy 190.344487 -303.669964) (xy 190.353696 -303.666906) (xy 190.382906 -303.657) (xy 190.386816 -303.655821)
			(xy 190.39422 -303.652376) (xy 190.397638 -303.650142) (xy 190.431066 -303.627547) (xy 190.501029 -303.587343)
			(xy 190.574083 -303.553074) (xy 190.61176 -303.538636) (xy 190.621089 -303.534661) (xy 190.63584 -303.520772)
			(xy 190.644103 -303.502271) (xy 190.64478 -303.492154) (xy 190.645805 -303.468556) (xy 190.654233 -303.422081)
			(xy 190.66972 -303.377459) (xy 190.691896 -303.335756) (xy 190.720232 -303.297967) (xy 190.754051 -303.264994)
			(xy 190.792546 -303.237625) (xy 190.834798 -303.216513) (xy 190.879798 -303.202161) (xy 190.926471 -303.194914)
			(xy 190.950088 -303.194466) (xy 190.976342 -303.195011) (xy 191.028077 -303.203988) (xy 191.077514 -303.22168)
			(xy 191.123198 -303.247565) (xy 191.163782 -303.280882) (xy 191.198071 -303.320648) (xy 191.225055 -303.365692)
			(xy 191.243938 -303.414687) (xy 191.249554 -303.440338) (xy 191.252225 -303.451022) (xy 191.265153 -303.468822)
			(xy 191.284351 -303.479565) (xy 191.295274 -303.480978) (xy 191.325335 -303.483737) (xy 191.385068 -303.492508)
			(xy 191.414654 -303.498504) (xy 191.419819 -303.499451) (xy 191.430317 -303.499451) (xy 191.435482 -303.498504)
			(xy 191.465066 -303.492495) (xy 191.5248 -303.483727) (xy 191.554862 -303.480978) (xy 191.565772 -303.479548)
			(xy 191.584933 -303.468779) (xy 191.597859 -303.451001) (xy 191.600582 -303.440338) (xy 191.60623 -303.414697)
			(xy 191.625112 -303.365711) (xy 191.652094 -303.320675) (xy 191.68638 -303.280917) (xy 191.72696 -303.247609)
			(xy 191.772639 -303.221731) (xy 191.82207 -303.204046) (xy 191.873798 -303.195076) (xy 191.900048 -303.194466)
			(xy 191.92366 -303.19491) (xy 191.97032 -303.202186) (xy 192.015304 -303.216557) (xy 192.057541 -303.23768)
			(xy 192.096023 -303.265052) (xy 192.129833 -303.298021) (xy 192.158167 -303.335801) (xy 192.180347 -303.377492)
			(xy 192.195847 -303.422099) (xy 192.204297 -303.468561) (xy 192.205356 -303.492154) (xy 192.205998 -303.502283)
			(xy 192.214234 -303.520814) (xy 192.229027 -303.534684) (xy 192.238376 -303.538636) (xy 192.2761 -303.553058)
			(xy 192.349242 -303.587318) (xy 192.419287 -303.627533) (xy 192.452752 -303.650142) (xy 192.456162 -303.652438)
			(xy 192.463565 -303.656013) (xy 192.467484 -303.657254) (xy 192.493756 -303.665471) (xy 192.54333 -303.689392)
			(xy 192.588258 -303.721193) (xy 192.627299 -303.759996) (xy 192.659374 -303.804728) (xy 192.671954 -303.829212)
			(xy 192.678304 -303.842166) (xy 192.702942 -303.85766) (xy 192.997074 -303.85766) (xy 193.021712 -303.842166)
			(xy 193.028062 -303.829212) (xy 193.04012 -303.805775) (xy 193.07053 -303.762729) (xy 193.107383 -303.725051)
			(xy 193.149746 -303.693696) (xy 193.196546 -303.669457) (xy 193.246599 -303.652949) (xy 193.298636 -303.644589)
			(xy 193.35134 -303.644589) (xy 193.403377 -303.652949) (xy 193.45343 -303.669457) (xy 193.50023 -303.693696)
			(xy 193.542593 -303.725051) (xy 193.579446 -303.762729) (xy 193.609856 -303.805775) (xy 193.621914 -303.829212)
			(xy 193.628264 -303.842166) (xy 193.652902 -303.85766) (xy 193.947034 -303.85766) (xy 193.971672 -303.842166)
			(xy 193.978022 -303.829212) (xy 193.990081 -303.805775) (xy 194.020493 -303.762729) (xy 194.057346 -303.725051)
			(xy 194.099708 -303.693694) (xy 194.146507 -303.669452) (xy 194.196559 -303.652938) (xy 194.248596 -303.644572)
			(xy 194.274948 -303.644046) (xy 194.288602 -303.644207) (xy 194.315815 -303.646495) (xy 194.329304 -303.648618)
			(xy 194.341242 -303.65065) (xy 194.363848 -303.643538) (xy 194.440302 -303.57064) (xy 194.448176 -303.548288)
			(xy 194.446906 -303.536096) (xy 194.445858 -303.527052) (xy 194.444716 -303.508878) (xy 194.44462 -303.499774)
			(xy 194.445068 -303.475783) (xy 194.452578 -303.428392) (xy 194.46741 -303.38276) (xy 194.489197 -303.340009)
			(xy 194.517403 -303.301194) (xy 194.551335 -303.267268) (xy 194.590156 -303.239068) (xy 194.63291 -303.217289)
			(xy 194.678545 -303.202466) (xy 194.725937 -303.194964) (xy 194.749928 -303.194466) (xy 194.764111 -303.194649)
			(xy 194.792351 -303.197316) (xy 194.806316 -303.1998) (xy 194.818762 -303.202086) (xy 194.842384 -303.19472)
			(xy 194.919854 -303.11725) (xy 194.92722 -303.093628) (xy 194.924934 -303.081182) (xy 194.922449 -303.067217)
			(xy 194.919777 -303.038977) (xy 194.9196 -303.024794) (xy 194.920086 -302.999974) (xy 194.928118 -302.950988)
			(xy 194.943969 -302.903947) (xy 194.967221 -302.86009) (xy 194.997263 -302.820572) (xy 195.033301 -302.786435)
			(xy 195.074388 -302.758578) (xy 195.11944 -302.737736) (xy 195.167271 -302.724456) (xy 195.21662 -302.719089)
			(xy 195.266187 -302.721777) (xy 195.314666 -302.732448) (xy 195.360781 -302.750822) (xy 195.403315 -302.776414)
			(xy 195.441149 -302.80855) (xy 195.473285 -302.846383) (xy 195.498877 -302.888917) (xy 195.517251 -302.935032)
			(xy 195.527923 -302.983511) (xy 195.530162 -303.024794) (xy 195.869064 -303.024794) (xy 195.873024 -302.97574)
			(xy 195.884801 -302.927956) (xy 195.904092 -302.88268) (xy 195.930395 -302.841084) (xy 195.96303 -302.804247)
			(xy 196.001151 -302.773122) (xy 196.043772 -302.748515) (xy 196.089788 -302.731063) (xy 196.138007 -302.721219)
			(xy 196.187182 -302.719238) (xy 196.236037 -302.72517) (xy 196.283308 -302.738862) (xy 196.32777 -302.75996)
			(xy 196.368273 -302.787916) (xy 196.403766 -302.822008) (xy 196.433331 -302.861352) (xy 196.456202 -302.904929)
			(xy 196.471786 -302.95161) (xy 196.479681 -303.000187) (xy 196.480176 -303.024794) (xy 196.819278 -303.024794)
			(xy 196.823238 -302.97574) (xy 196.835015 -302.927956) (xy 196.854306 -302.88268) (xy 196.880609 -302.841084)
			(xy 196.913244 -302.804247) (xy 196.951365 -302.773122) (xy 196.993986 -302.748515) (xy 197.040002 -302.731063)
			(xy 197.088221 -302.721219) (xy 197.137396 -302.719238) (xy 197.186251 -302.72517) (xy 197.233522 -302.738862)
			(xy 197.277984 -302.75996) (xy 197.318487 -302.787916) (xy 197.35398 -302.822008) (xy 197.383545 -302.861352)
			(xy 197.406416 -302.904929) (xy 197.422 -302.95161) (xy 197.429895 -303.000187) (xy 197.43039 -303.024794)
			(xy 197.769238 -303.024794) (xy 197.773198 -302.97574) (xy 197.784975 -302.927956) (xy 197.804266 -302.88268)
			(xy 197.830569 -302.841084) (xy 197.863204 -302.804247) (xy 197.901325 -302.773122) (xy 197.943946 -302.748515)
			(xy 197.989962 -302.731063) (xy 198.038181 -302.721219) (xy 198.087356 -302.719238) (xy 198.136211 -302.72517)
			(xy 198.183482 -302.738862) (xy 198.227944 -302.75996) (xy 198.268447 -302.787916) (xy 198.30394 -302.822008)
			(xy 198.333505 -302.861352) (xy 198.356376 -302.904929) (xy 198.37196 -302.95161) (xy 198.379855 -303.000187)
			(xy 198.38035 -303.024794) (xy 198.703958 -303.024794) (xy 198.707918 -302.97574) (xy 198.719695 -302.927956)
			(xy 198.738986 -302.88268) (xy 198.765289 -302.841084) (xy 198.797924 -302.804247) (xy 198.836045 -302.773122)
			(xy 198.878666 -302.748515) (xy 198.924682 -302.731063) (xy 198.972901 -302.721219) (xy 199.022076 -302.719238)
			(xy 199.070931 -302.72517) (xy 199.118202 -302.738862) (xy 199.162664 -302.75996) (xy 199.203167 -302.787916)
			(xy 199.23866 -302.822008) (xy 199.268225 -302.861352) (xy 199.291096 -302.904929) (xy 199.30668 -302.95161)
			(xy 199.314575 -303.000187) (xy 199.31507 -303.024794) (xy 199.314575 -303.049401) (xy 199.309984 -303.077651)
			(xy 203.951303 -303.077651) (xy 203.951303 -303.023149) (xy 203.95906 -302.969202) (xy 203.974416 -302.916908)
			(xy 203.997058 -302.867332) (xy 204.026525 -302.821483) (xy 204.062218 -302.780295) (xy 204.103409 -302.744606)
			(xy 204.14926 -302.715142) (xy 204.198838 -302.692505) (xy 204.251133 -302.677153) (xy 204.305081 -302.669401)
			(xy 204.332332 -302.66894) (xy 204.360674 -302.669466) (xy 204.416737 -302.677839) (xy 204.470941 -302.694424)
			(xy 204.522089 -302.718857) (xy 204.569054 -302.750597) (xy 204.610798 -302.788944) (xy 204.629004 -302.810672)
			(xy 204.637791 -302.820791) (xy 204.659494 -302.836494) (xy 204.684534 -302.846013) (xy 204.711188 -302.848695)
			(xy 204.737622 -302.844356) (xy 204.762019 -302.833292) (xy 204.782701 -302.816266) (xy 204.790802 -302.805592)
			(xy 204.806246 -302.784717) (xy 204.841816 -302.746889) (xy 204.882188 -302.714234) (xy 204.926614 -302.687356)
			(xy 204.974275 -302.66675) (xy 205.02429 -302.652797) (xy 205.075736 -302.645755) (xy 205.101698 -302.645318)
			(xy 205.128953 -302.645729) (xy 205.182908 -302.653486) (xy 205.235209 -302.668843) (xy 205.284793 -302.691487)
			(xy 205.33065 -302.720957) (xy 205.371846 -302.756653) (xy 205.407542 -302.797849) (xy 205.437012 -302.843705)
			(xy 205.459656 -302.893289) (xy 205.475014 -302.94559) (xy 205.482771 -302.999545) (xy 205.482771 -303.026826)
			(xy 205.73568 -303.026826) (xy 205.739751 -302.971204) (xy 205.751877 -302.916767) (xy 205.7718 -302.864676)
			(xy 205.799096 -302.816041) (xy 205.833182 -302.771898) (xy 205.873331 -302.733189) (xy 205.918689 -302.700738)
			(xy 205.968289 -302.675237) (xy 206.021073 -302.65723) (xy 206.075916 -302.6471) (xy 206.13165 -302.645063)
			(xy 206.187087 -302.651163) (xy 206.241044 -302.665269) (xy 206.292373 -302.687081) (xy 206.339979 -302.716135)
			(xy 206.382847 -302.75181) (xy 206.420064 -302.793347) (xy 206.450837 -302.83986) (xy 206.474509 -302.890357)
			(xy 206.490577 -302.943764) (xy 206.498697 -302.99894) (xy 206.499206 -303.026826) (xy 206.75168 -303.026826)
			(xy 206.755751 -302.971204) (xy 206.767877 -302.916767) (xy 206.7878 -302.864676) (xy 206.815096 -302.816041)
			(xy 206.849182 -302.771898) (xy 206.889331 -302.733189) (xy 206.934689 -302.700738) (xy 206.984289 -302.675237)
			(xy 207.037073 -302.65723) (xy 207.091916 -302.6471) (xy 207.14765 -302.645063) (xy 207.203087 -302.651163)
			(xy 207.257044 -302.665269) (xy 207.308373 -302.687081) (xy 207.355979 -302.716135) (xy 207.398847 -302.75181)
			(xy 207.436064 -302.793347) (xy 207.466837 -302.83986) (xy 207.490509 -302.890357) (xy 207.506577 -302.943764)
			(xy 207.514697 -302.99894) (xy 207.515206 -303.026826) (xy 207.76768 -303.026826) (xy 207.771751 -302.971204)
			(xy 207.783877 -302.916767) (xy 207.8038 -302.864676) (xy 207.831096 -302.816041) (xy 207.865182 -302.771898)
			(xy 207.905331 -302.733189) (xy 207.950689 -302.700738) (xy 208.000289 -302.675237) (xy 208.053073 -302.65723)
			(xy 208.107916 -302.6471) (xy 208.16365 -302.645063) (xy 208.219087 -302.651163) (xy 208.273044 -302.665269)
			(xy 208.324373 -302.687081) (xy 208.371979 -302.716135) (xy 208.414847 -302.75181) (xy 208.452064 -302.793347)
			(xy 208.482837 -302.83986) (xy 208.506509 -302.890357) (xy 208.522577 -302.943764) (xy 208.530697 -302.99894)
			(xy 208.531206 -303.026826) (xy 208.78368 -303.026826) (xy 208.787751 -302.971204) (xy 208.799877 -302.916767)
			(xy 208.8198 -302.864676) (xy 208.847096 -302.816041) (xy 208.881182 -302.771898) (xy 208.921331 -302.733189)
			(xy 208.966689 -302.700738) (xy 209.016289 -302.675237) (xy 209.069073 -302.65723) (xy 209.123916 -302.6471)
			(xy 209.17965 -302.645063) (xy 209.235087 -302.651163) (xy 209.289044 -302.665269) (xy 209.340373 -302.687081)
			(xy 209.387979 -302.716135) (xy 209.430847 -302.75181) (xy 209.468064 -302.793347) (xy 209.498837 -302.83986)
			(xy 209.522509 -302.890357) (xy 209.538577 -302.943764) (xy 209.546697 -302.99894) (xy 209.547206 -303.026826)
			(xy 209.546697 -303.054712) (xy 209.538577 -303.109888) (xy 209.522509 -303.163295) (xy 209.498837 -303.213792)
			(xy 209.468064 -303.260305) (xy 209.430847 -303.301842) (xy 209.387979 -303.337517) (xy 209.340373 -303.366571)
			(xy 209.289044 -303.388383) (xy 209.235087 -303.402489) (xy 209.17965 -303.408589) (xy 209.123916 -303.406552)
			(xy 209.069073 -303.396422) (xy 209.016289 -303.378415) (xy 208.966689 -303.352914) (xy 208.921331 -303.320463)
			(xy 208.881182 -303.281754) (xy 208.847096 -303.237611) (xy 208.8198 -303.188976) (xy 208.799877 -303.136885)
			(xy 208.787751 -303.082448) (xy 208.78368 -303.026826) (xy 208.531206 -303.026826) (xy 208.530697 -303.054712)
			(xy 208.522577 -303.109888) (xy 208.506509 -303.163295) (xy 208.482837 -303.213792) (xy 208.452064 -303.260305)
			(xy 208.414847 -303.301842) (xy 208.371979 -303.337517) (xy 208.324373 -303.366571) (xy 208.273044 -303.388383)
			(xy 208.219087 -303.402489) (xy 208.16365 -303.408589) (xy 208.107916 -303.406552) (xy 208.053073 -303.396422)
			(xy 208.000289 -303.378415) (xy 207.950689 -303.352914) (xy 207.905331 -303.320463) (xy 207.865182 -303.281754)
			(xy 207.831096 -303.237611) (xy 207.8038 -303.188976) (xy 207.783877 -303.136885) (xy 207.771751 -303.082448)
			(xy 207.76768 -303.026826) (xy 207.515206 -303.026826) (xy 207.514697 -303.054712) (xy 207.506577 -303.109888)
			(xy 207.490509 -303.163295) (xy 207.466837 -303.213792) (xy 207.436064 -303.260305) (xy 207.398847 -303.301842)
			(xy 207.355979 -303.337517) (xy 207.308373 -303.366571) (xy 207.257044 -303.388383) (xy 207.203087 -303.402489)
			(xy 207.14765 -303.408589) (xy 207.091916 -303.406552) (xy 207.037073 -303.396422) (xy 206.984289 -303.378415)
			(xy 206.934689 -303.352914) (xy 206.889331 -303.320463) (xy 206.849182 -303.281754) (xy 206.815096 -303.237611)
			(xy 206.7878 -303.188976) (xy 206.767877 -303.136885) (xy 206.755751 -303.082448) (xy 206.75168 -303.026826)
			(xy 206.499206 -303.026826) (xy 206.498697 -303.054712) (xy 206.490577 -303.109888) (xy 206.474509 -303.163295)
			(xy 206.450837 -303.213792) (xy 206.420064 -303.260305) (xy 206.382847 -303.301842) (xy 206.339979 -303.337517)
			(xy 206.292373 -303.366571) (xy 206.241044 -303.388383) (xy 206.187087 -303.402489) (xy 206.13165 -303.408589)
			(xy 206.075916 -303.406552) (xy 206.021073 -303.396422) (xy 205.968289 -303.378415) (xy 205.918689 -303.352914)
			(xy 205.873331 -303.320463) (xy 205.833182 -303.281754) (xy 205.799096 -303.237611) (xy 205.7718 -303.188976)
			(xy 205.751877 -303.136885) (xy 205.739751 -303.082448) (xy 205.73568 -303.026826) (xy 205.482771 -303.026826)
			(xy 205.482771 -303.054055) (xy 205.475014 -303.10801) (xy 205.459656 -303.160311) (xy 205.437012 -303.209895)
			(xy 205.407542 -303.255751) (xy 205.371846 -303.296947) (xy 205.33065 -303.332643) (xy 205.284793 -303.362113)
			(xy 205.235209 -303.384757) (xy 205.182908 -303.400114) (xy 205.128953 -303.407871) (xy 205.101698 -303.408334)
			(xy 205.073355 -303.40783) (xy 205.017293 -303.399449) (xy 204.96309 -303.382857) (xy 204.911942 -303.358421)
			(xy 204.864978 -303.326678) (xy 204.823233 -303.28833) (xy 204.805026 -303.266602) (xy 204.796314 -303.256414)
			(xy 204.774592 -303.240716) (xy 204.749535 -303.231205) (xy 204.722868 -303.228533) (xy 204.696422 -303.232885)
			(xy 204.672017 -303.243962) (xy 204.65133 -303.261001) (xy 204.643228 -303.271682) (xy 204.627819 -303.292584)
			(xy 204.592244 -303.330412) (xy 204.551867 -303.363066) (xy 204.507434 -303.389942) (xy 204.459767 -303.410543)
			(xy 204.409746 -303.42449) (xy 204.358296 -303.431523) (xy 204.332332 -303.431956) (xy 204.305081 -303.431399)
			(xy 204.251133 -303.423647) (xy 204.198838 -303.408295) (xy 204.14926 -303.385658) (xy 204.103409 -303.356194)
			(xy 204.062218 -303.320505) (xy 204.026525 -303.279317) (xy 203.997058 -303.233468) (xy 203.974416 -303.183892)
			(xy 203.95906 -303.131598) (xy 203.951303 -303.077651) (xy 199.309984 -303.077651) (xy 199.30668 -303.097978)
			(xy 199.291096 -303.144659) (xy 199.268225 -303.188236) (xy 199.23866 -303.22758) (xy 199.203167 -303.261672)
			(xy 199.162664 -303.289628) (xy 199.118202 -303.310726) (xy 199.070931 -303.324418) (xy 199.022076 -303.33035)
			(xy 198.972901 -303.328369) (xy 198.924682 -303.318525) (xy 198.878666 -303.301073) (xy 198.836045 -303.276466)
			(xy 198.797924 -303.245341) (xy 198.765289 -303.208504) (xy 198.738986 -303.166908) (xy 198.719695 -303.121632)
			(xy 198.707918 -303.073848) (xy 198.703958 -303.024794) (xy 198.38035 -303.024794) (xy 198.379855 -303.049401)
			(xy 198.37196 -303.097978) (xy 198.356376 -303.144659) (xy 198.333505 -303.188236) (xy 198.30394 -303.22758)
			(xy 198.268447 -303.261672) (xy 198.227944 -303.289628) (xy 198.183482 -303.310726) (xy 198.136211 -303.324418)
			(xy 198.087356 -303.33035) (xy 198.038181 -303.328369) (xy 197.989962 -303.318525) (xy 197.943946 -303.301073)
			(xy 197.901325 -303.276466) (xy 197.863204 -303.245341) (xy 197.830569 -303.208504) (xy 197.804266 -303.166908)
			(xy 197.784975 -303.121632) (xy 197.773198 -303.073848) (xy 197.769238 -303.024794) (xy 197.43039 -303.024794)
			(xy 197.429895 -303.049401) (xy 197.422 -303.097978) (xy 197.406416 -303.144659) (xy 197.383545 -303.188236)
			(xy 197.35398 -303.22758) (xy 197.318487 -303.261672) (xy 197.277984 -303.289628) (xy 197.233522 -303.310726)
			(xy 197.186251 -303.324418) (xy 197.137396 -303.33035) (xy 197.088221 -303.328369) (xy 197.040002 -303.318525)
			(xy 196.993986 -303.301073) (xy 196.951365 -303.276466) (xy 196.913244 -303.245341) (xy 196.880609 -303.208504)
			(xy 196.854306 -303.166908) (xy 196.835015 -303.121632) (xy 196.823238 -303.073848) (xy 196.819278 -303.024794)
			(xy 196.480176 -303.024794) (xy 196.479681 -303.049401) (xy 196.471786 -303.097978) (xy 196.456202 -303.144659)
			(xy 196.433331 -303.188236) (xy 196.403766 -303.22758) (xy 196.368273 -303.261672) (xy 196.32777 -303.289628)
			(xy 196.283308 -303.310726) (xy 196.236037 -303.324418) (xy 196.187182 -303.33035) (xy 196.138007 -303.328369)
			(xy 196.089788 -303.318525) (xy 196.043772 -303.301073) (xy 196.001151 -303.276466) (xy 195.96303 -303.245341)
			(xy 195.930395 -303.208504) (xy 195.904092 -303.166908) (xy 195.884801 -303.121632) (xy 195.873024 -303.073848)
			(xy 195.869064 -303.024794) (xy 195.530162 -303.024794) (xy 195.530611 -303.033078) (xy 195.525245 -303.082427)
			(xy 195.511965 -303.130258) (xy 195.491122 -303.17531) (xy 195.463266 -303.216397) (xy 195.429129 -303.252436)
			(xy 195.389612 -303.282478) (xy 195.345755 -303.30573) (xy 195.298714 -303.321581) (xy 195.249728 -303.329614)
			(xy 195.224908 -303.330102) (xy 195.210726 -303.329916) (xy 195.182486 -303.327243) (xy 195.16852 -303.324768)
			(xy 195.156074 -303.322482) (xy 195.132452 -303.329848) (xy 195.054982 -303.407318) (xy 195.047616 -303.43094)
			(xy 195.049902 -303.443386) (xy 195.052388 -303.457351) (xy 195.055063 -303.485591) (xy 195.055236 -303.499774)
			(xy 195.055137 -303.508878) (xy 195.053992 -303.527051) (xy 195.05295 -303.536096) (xy 195.05168 -303.548288)
			(xy 195.059554 -303.57064) (xy 195.136008 -303.643538) (xy 195.158614 -303.65065) (xy 195.170552 -303.648618)
			(xy 195.18404 -303.646488) (xy 195.211253 -303.644201) (xy 195.224908 -303.644046) (xy 195.251261 -303.644559)
			(xy 195.303301 -303.652921) (xy 195.353355 -303.669434) (xy 195.400155 -303.693677) (xy 195.442517 -303.725038)
			(xy 195.479367 -303.762722) (xy 195.509773 -303.805775) (xy 195.521834 -303.829212) (xy 195.528184 -303.842166)
			(xy 195.552822 -303.85766) (xy 195.846954 -303.85766) (xy 195.871592 -303.842166) (xy 195.877942 -303.829212)
			(xy 195.89 -303.805775) (xy 195.92041 -303.762729) (xy 195.957263 -303.725051) (xy 195.999626 -303.693696)
			(xy 196.046426 -303.669457) (xy 196.096479 -303.652949) (xy 196.148516 -303.644589) (xy 196.20122 -303.644589)
			(xy 196.253257 -303.652949) (xy 196.30331 -303.669457) (xy 196.35011 -303.693696) (xy 196.392473 -303.725051)
			(xy 196.429326 -303.762729) (xy 196.459736 -303.805775) (xy 196.471794 -303.829212) (xy 196.478144 -303.842166)
			(xy 196.502782 -303.85766) (xy 196.797168 -303.85766) (xy 196.821806 -303.842166) (xy 196.828156 -303.829212)
			(xy 196.840214 -303.805775) (xy 196.870624 -303.762729) (xy 196.907477 -303.725051) (xy 196.94984 -303.693696)
			(xy 196.99664 -303.669457) (xy 197.046693 -303.652949) (xy 197.09873 -303.644589) (xy 197.151434 -303.644589)
			(xy 197.203471 -303.652949) (xy 197.253524 -303.669457) (xy 197.300324 -303.693696) (xy 197.342687 -303.725051)
			(xy 197.37954 -303.762729) (xy 197.40995 -303.805775) (xy 197.422008 -303.829212) (xy 197.428358 -303.842166)
			(xy 197.452996 -303.85766) (xy 197.746874 -303.85766) (xy 197.771512 -303.842166) (xy 197.777862 -303.828958)
			(xy 197.789932 -303.805506) (xy 197.820371 -303.762434) (xy 197.857258 -303.724737) (xy 197.899659 -303.69337)
			(xy 197.9465 -303.669129) (xy 197.996593 -303.652626) (xy 198.048671 -303.64428) (xy 198.075042 -303.643792)
			(xy 199.025002 -303.643792) (xy 199.051837 -303.644314) (xy 199.104804 -303.652978) (xy 199.155677 -303.670079)
			(xy 199.203122 -303.695168) (xy 199.245894 -303.727588) (xy 199.264778 -303.746662) (xy 199.270874 -303.753266)
			(xy 199.28713 -303.761394) (xy 199.292456 -303.763856) (xy 199.303872 -303.766552) (xy 199.309736 -303.766728)
			(xy 199.379586 -303.766728) (xy 199.390099 -303.766204) (xy 199.409381 -303.757813) (xy 199.416924 -303.750472)
			(xy 199.435862 -303.730771) (xy 199.479012 -303.697247) (xy 199.527087 -303.671275) (xy 199.578779 -303.653563)
			(xy 199.632681 -303.644593) (xy 199.660002 -303.644046) (xy 199.684625 -303.644501) (xy 199.733326 -303.651812)
			(xy 199.780402 -303.666271) (xy 199.82481 -303.687559) (xy 199.865565 -303.715204) (xy 199.901766 -303.748592)
			(xy 199.917558 -303.76749) (xy 199.92519 -303.776004) (xy 199.945766 -303.785905) (xy 199.957182 -303.78654)
			(xy 200.965816 -303.78654) (xy 201.019778 -303.787198) (xy 201.127079 -303.798778) (xy 201.179938 -303.809654)
			(xy 201.191876 -303.812194) (xy 201.215244 -303.806352) (xy 201.295254 -303.734978) (xy 201.30389 -303.712626)
			(xy 201.30262 -303.700434) (xy 201.300842 -303.662588) (xy 201.301306 -303.635337) (xy 201.309065 -303.58139)
			(xy 201.324422 -303.529097) (xy 201.347066 -303.479521) (xy 201.376535 -303.433673) (xy 201.41223 -303.392486)
			(xy 201.453423 -303.356798) (xy 201.499276 -303.327337) (xy 201.548855 -303.304701) (xy 201.601151 -303.289352)
			(xy 201.655099 -303.281602) (xy 201.68235 -303.28108) (xy 201.711675 -303.281616) (xy 201.769632 -303.290595)
			(xy 201.825529 -303.308349) (xy 201.878046 -303.33446) (xy 201.902314 -303.35093) (xy 201.905784 -303.35324)
			(xy 201.913316 -303.356814) (xy 201.9173 -303.358042) (xy 201.945787 -303.366876) (xy 201.999806 -303.392149)
			(xy 202.049236 -303.425516) (xy 202.092876 -303.466166) (xy 202.129661 -303.513108) (xy 202.158697 -303.565201)
			(xy 202.169522 -303.592992) (xy 202.173078 -303.601521) (xy 202.1852 -303.615446) (xy 202.193144 -303.62017)
			(xy 202.220322 -303.634902) (xy 202.228665 -303.638944) (xy 202.247023 -303.641427) (xy 202.256136 -303.639728)
			(xy 202.277543 -303.635005) (xy 202.321085 -303.629908) (xy 202.343004 -303.629568) (xy 202.347576 -303.629568)
			(xy 202.374626 -303.630344) (xy 202.428107 -303.638591) (xy 202.479886 -303.654314) (xy 202.528924 -303.677197)
			(xy 202.574235 -303.706781) (xy 202.614911 -303.742471) (xy 202.650134 -303.783551) (xy 202.679199 -303.829197)
			(xy 202.701521 -303.878492) (xy 202.716652 -303.930447) (xy 202.724289 -303.984019) (xy 202.724766 -304.011076)
			(xy 202.724241 -304.039434) (xy 202.715833 -304.095523) (xy 202.699212 -304.149748) (xy 202.674747 -304.200915)
			(xy 202.642975 -304.247896) (xy 202.624182 -304.26914) (xy 202.619356 -304.274474) (xy 202.612752 -304.287682)
			(xy 202.611482 -304.295556) (xy 202.610475 -304.302968) (xy 202.612283 -304.317811) (xy 202.615038 -304.324766)
			(xy 202.640946 -304.382932) (xy 202.645261 -304.391621) (xy 202.6591 -304.405197) (xy 202.66787 -304.409348)
			(xy 202.731624 -304.435764) (xy 202.736311 -304.437561) (xy 202.746163 -304.439476) (xy 202.751182 -304.439574)
			(xy 204.097636 -304.439574) (xy 204.124814 -304.431446) (xy 204.130656 -304.42789) (xy 204.153324 -304.414455)
			(xy 204.201569 -304.393264) (xy 204.252269 -304.378909) (xy 204.304461 -304.371663) (xy 204.357155 -304.371663)
			(xy 204.409347 -304.378909) (xy 204.460047 -304.393264) (xy 204.508292 -304.414455) (xy 204.53096 -304.42789)
			(xy 204.536802 -304.431446) (xy 204.56398 -304.439574) (xy 214.659718 -304.439574) (xy 214.666576 -304.432716)
			(xy 217.353642 -304.432716) (xy 217.362024 -304.431954) (xy 217.369628 -304.430438) (xy 217.383462 -304.423452)
			(xy 217.389202 -304.418238) (xy 217.842846 -303.964594) (xy 217.850247 -303.957755) (xy 217.868845 -303.950039)
			(xy 217.878914 -303.949608) (xy 231.981248 -303.949608) (xy 231.98963 -303.948846) (xy 231.997234 -303.947329)
			(xy 232.011066 -303.940341) (xy 232.016808 -303.93513) (xy 232.30332 -303.648618) (xy 232.310162 -303.641219)
			(xy 232.317879 -303.62262) (xy 232.318306 -303.61255) (xy 232.318306 -288.092896) (xy 232.29316 -288.064194)
			(xy 232.27411 -288.061654) (xy 232.246929 -288.057593) (xy 232.194036 -288.042677) (xy 232.14383 -288.020326)
			(xy 232.09735 -287.991003) (xy 232.055559 -287.955314) (xy 232.01932 -287.913999) (xy 231.989385 -287.867911)
			(xy 231.966372 -287.818005) (xy 231.950758 -287.765313) (xy 231.942866 -287.710926) (xy 231.942386 -287.683448)
			(xy 231.942838 -287.656715) (xy 231.950309 -287.603773) (xy 231.965096 -287.552392) (xy 231.98691 -287.503578)
			(xy 232.015325 -287.458286) (xy 232.049783 -287.417405) (xy 232.069386 -287.399222) (xy 232.069894 -287.398714)
			(xy 232.074212 -287.39465) (xy 232.08234 -287.38322) (xy 232.087354 -287.375336) (xy 232.091908 -287.357233)
			(xy 232.09123 -287.347914) (xy 232.081832 -287.267142) (xy 232.079795 -287.254837) (xy 232.065679 -287.234313)
			(xy 232.054908 -287.228026) (xy 232.033166 -287.216211) (xy 231.992655 -287.187796) (xy 231.974136 -287.171384)
			(xy 231.974136 -287.17113) (xy 231.971088 -287.168336) (xy 231.967538 -287.165146) (xy 231.959486 -287.160024)
			(xy 231.955086 -287.158176) (xy 231.945942 -287.15462) (xy 231.857296 -287.15462) (xy 231.839516 -287.161478)
			(xy 231.832404 -287.168336) (xy 231.811077 -287.187607) (xy 231.763714 -287.220173) (xy 231.712003 -287.245266)
			(xy 231.657112 -287.26232) (xy 231.600285 -287.270948) (xy 231.571546 -287.27146) (xy 231.544292 -287.271)
			(xy 231.490339 -287.263248) (xy 231.438038 -287.247895) (xy 231.388455 -287.225255) (xy 231.3426 -287.195787)
			(xy 231.301406 -287.160093) (xy 231.265712 -287.118898) (xy 231.236244 -287.073043) (xy 231.213604 -287.02346)
			(xy 231.198252 -286.971159) (xy 231.1905 -286.917206) (xy 231.190038 -286.889952) (xy 231.190598 -286.860295)
			(xy 231.199775 -286.801696) (xy 231.217917 -286.745225) (xy 231.244585 -286.692244) (xy 231.279136 -286.644033)
			(xy 231.320736 -286.601754) (xy 231.344216 -286.583628) (xy 231.349042 -286.580072) (xy 231.356408 -286.571436)
			(xy 231.369362 -286.546036) (xy 231.372049 -286.540375) (xy 231.374881 -286.528172) (xy 231.37495 -286.521906)
			(xy 231.37368 -286.450532) (xy 231.372903 -286.439511) (xy 231.363284 -286.419644) (xy 231.355138 -286.412178)
			(xy 231.350058 -286.40786) (xy 231.347772 -286.406336) (xy 231.334065 -286.397174) (xy 231.30812 -286.376825)
			(xy 231.295956 -286.365696) (xy 231.292403 -286.36251) (xy 231.284348 -286.357396) (xy 231.279954 -286.355536)
			(xy 231.27081 -286.35198) (xy 231.182164 -286.35198) (xy 231.164384 -286.358838) (xy 231.157272 -286.365696)
			(xy 231.135945 -286.384967) (xy 231.088582 -286.417532) (xy 231.036871 -286.442624) (xy 230.98198 -286.459675)
			(xy 230.925153 -286.468299) (xy 230.896414 -286.46882) (xy 230.86916 -286.468358) (xy 230.815207 -286.460603)
			(xy 230.762907 -286.445248) (xy 230.713324 -286.422607) (xy 230.667468 -286.393139) (xy 230.626273 -286.357446)
			(xy 230.590577 -286.316253) (xy 230.561106 -286.270399) (xy 230.538461 -286.220818) (xy 230.523103 -286.168518)
			(xy 230.515344 -286.114566) (xy 230.514906 -286.087312) (xy 230.515499 -286.057612) (xy 230.524744 -285.998934)
			(xy 230.542951 -285.942392) (xy 230.5558 -285.915608) (xy 230.557832 -285.91129) (xy 230.561134 -285.905194)
			(xy 230.563273 -285.900881) (xy 230.566091 -285.891678) (xy 230.566722 -285.886906) (xy 230.567738 -285.877)
			(xy 230.547672 -285.800546) (xy 230.54183 -285.792672) (xy 230.525574 -285.770574) (xy 230.5177 -285.765494)
			(xy 230.504061 -285.756391) (xy 230.478243 -285.736169) (xy 230.466138 -285.725108) (xy 230.45928 -285.71825)
			(xy 230.440738 -285.71063) (xy 230.351584 -285.71063) (xy 230.333804 -285.717488) (xy 230.326692 -285.724346)
			(xy 230.305365 -285.743616) (xy 230.258002 -285.776181) (xy 230.206291 -285.801272) (xy 230.1514 -285.818322)
			(xy 230.094573 -285.826944) (xy 230.037095 -285.826944) (xy 229.980268 -285.818322) (xy 229.925377 -285.801272)
			(xy 229.873666 -285.776181) (xy 229.826303 -285.743616) (xy 229.804976 -285.724346) (xy 229.797864 -285.717488)
			(xy 229.780084 -285.71063) (xy 229.691184 -285.71063) (xy 229.673404 -285.717488) (xy 229.666292 -285.724346)
			(xy 229.644964 -285.743616) (xy 229.597601 -285.776179) (xy 229.545889 -285.801271) (xy 229.490999 -285.818322)
			(xy 229.434173 -285.826948) (xy 229.405434 -285.82747) (xy 229.378182 -285.827009) (xy 229.324233 -285.819257)
			(xy 229.271936 -285.803905) (xy 229.222357 -285.781267) (xy 229.176504 -285.751803) (xy 229.135311 -285.716113)
			(xy 229.099618 -285.674923) (xy 229.070149 -285.629073) (xy 229.047507 -285.579496) (xy 229.03215 -285.5272)
			(xy 229.024393 -285.473252) (xy 229.024393 -285.418748) (xy 229.03215 -285.3648) (xy 229.047507 -285.312504)
			(xy 229.070149 -285.262927) (xy 229.099618 -285.217077) (xy 229.135311 -285.175887) (xy 229.176504 -285.140197)
			(xy 229.222357 -285.110733) (xy 229.271936 -285.088095) (xy 229.324233 -285.072743) (xy 229.378182 -285.064991)
			(xy 229.405434 -285.064454) (xy 229.434172 -285.064978) (xy 229.490996 -285.073606) (xy 229.545883 -285.090662)
			(xy 229.597589 -285.115759) (xy 229.644945 -285.14833) (xy 229.666292 -285.167578) (xy 229.673404 -285.174436)
			(xy 229.691184 -285.181294) (xy 229.780084 -285.181294) (xy 229.797864 -285.174436) (xy 229.804976 -285.167578)
			(xy 229.826303 -285.148308) (xy 229.873666 -285.115743) (xy 229.925377 -285.090652) (xy 229.980268 -285.073602)
			(xy 230.037095 -285.06498) (xy 230.094573 -285.06498) (xy 230.1514 -285.073602) (xy 230.206291 -285.090652)
			(xy 230.258002 -285.115743) (xy 230.305365 -285.148308) (xy 230.326692 -285.167578) (xy 230.333804 -285.174436)
			(xy 230.351584 -285.181294) (xy 230.440484 -285.181294) (xy 230.458264 -285.174436) (xy 230.465376 -285.167578)
			(xy 230.486703 -285.148305) (xy 230.534064 -285.115736) (xy 230.585776 -285.090638) (xy 230.640666 -285.073581)
			(xy 230.697494 -285.06495) (xy 230.726234 -285.064454) (xy 230.75636 -285.065018) (xy 230.815863 -285.074482)
			(xy 230.873138 -285.093185) (xy 230.926759 -285.120662) (xy 230.975392 -285.156229) (xy 230.996998 -285.17723)
			(xy 231.00411 -285.184342) (xy 231.022906 -285.192216) (xy 231.115362 -285.192216) (xy 231.134158 -285.184342)
			(xy 231.14127 -285.17723) (xy 231.162895 -285.156253) (xy 231.211531 -285.120698) (xy 231.265148 -285.093227)
			(xy 231.322416 -285.074521) (xy 231.381911 -285.065045) (xy 231.412034 -285.064454) (xy 231.439066 -285.064926)
			(xy 231.492587 -285.072563) (xy 231.544494 -285.087678) (xy 231.593748 -285.109968) (xy 231.639362 -285.138989)
			(xy 231.680423 -285.174157) (xy 231.716109 -285.21477) (xy 231.745704 -285.260013) (xy 231.768617 -285.308981)
			(xy 231.784387 -285.360693) (xy 231.7927 -285.414113) (xy 231.793542 -285.441136) (xy 231.793542 -285.446216)
			(xy 231.793152 -285.471235) (xy 231.786612 -285.520844) (xy 231.773633 -285.56917) (xy 231.754439 -285.61538)
			(xy 231.742234 -285.637224) (xy 231.74198 -285.637478) (xy 231.741726 -285.63824) (xy 231.737386 -285.646622)
			(xy 231.734647 -285.665285) (xy 231.736392 -285.674562) (xy 231.751378 -285.740602) (xy 231.75322 -285.747523)
			(xy 231.760177 -285.760034) (xy 231.765094 -285.76524) (xy 231.772206 -285.772352) (xy 231.775762 -285.774892)
			(xy 231.785849 -285.782081) (xy 231.805168 -285.797588) (xy 231.81437 -285.80588) (xy 231.817672 -285.808928)
			(xy 231.824784 -285.815786) (xy 231.842564 -285.822644) (xy 231.931464 -285.822644) (xy 231.949244 -285.815786)
			(xy 231.956356 -285.808928) (xy 231.977306 -285.789999) (xy 232.023746 -285.757889) (xy 232.074409 -285.732967)
			(xy 232.128188 -285.715777) (xy 232.183913 -285.706693) (xy 232.212134 -285.705804) (xy 232.21696 -285.705804)
			(xy 232.22839 -285.703518) (xy 232.235604 -285.701749) (xy 232.248642 -285.694647) (xy 232.254044 -285.689548)
			(xy 232.30332 -285.640272) (xy 232.310171 -285.632876) (xy 232.317908 -285.614277) (xy 232.318306 -285.604204)
			(xy 232.318306 -282.230068) (xy 232.310686 -282.211272) (xy 232.30332 -282.20416) (xy 231.503728 -281.404568)
			(xy 231.496883 -281.397169) (xy 231.489156 -281.378571) (xy 231.488742 -281.3685) (xy 231.488742 -258.208272)
			(xy 231.481122 -258.189476) (xy 231.473756 -258.182364) (xy 231.305862 -258.01447) (xy 231.298692 -258.007855)
			(xy 231.280797 -258.000131) (xy 231.271064 -257.999484) (xy 231.240838 -257.998976) (xy 231.231652 -257.99919)
			(xy 231.214344 -258.005317) (xy 231.207056 -258.010914) (xy 231.191487 -258.023604) (xy 231.158142 -258.046001)
			(xy 231.140508 -258.055618) (xy 231.129586 -258.061206) (xy 231.11587 -258.081018) (xy 231.100376 -258.186428)
			(xy 231.107996 -258.209288) (xy 231.116886 -258.217924) (xy 231.138087 -258.239585) (xy 231.174045 -258.288373)
			(xy 231.201839 -258.342233) (xy 231.220767 -258.399809) (xy 231.230356 -258.459654) (xy 231.230932 -258.489958)
			(xy 231.230444 -258.51743) (xy 231.222555 -258.571806) (xy 231.20696 -258.624492) (xy 231.183983 -258.674402)
			(xy 231.169464 -258.69773) (xy 231.16413 -258.705858) (xy 231.16032 -258.7244) (xy 231.175306 -258.811776)
			(xy 231.185212 -258.827778) (xy 231.192832 -258.833874) (xy 231.215706 -258.852037) (xy 231.256181 -258.894144)
			(xy 231.28976 -258.941932) (xy 231.315658 -258.994283) (xy 231.333267 -259.049971) (xy 231.342176 -259.107693)
			(xy 231.342692 -259.136896) (xy 231.342167 -259.165701) (xy 231.333507 -259.222656) (xy 231.316385 -259.277663)
			(xy 231.291188 -259.329471) (xy 231.258489 -259.376902) (xy 231.219033 -259.418879) (xy 231.173714 -259.454448)
			(xy 231.123564 -259.4828) (xy 231.09682 -259.493512) (xy 231.085644 -259.49783) (xy 231.069896 -259.514594)
			(xy 231.039416 -259.614416) (xy 231.043226 -259.63753) (xy 231.050338 -259.647182) (xy 231.066941 -259.671537)
			(xy 231.093243 -259.724284) (xy 231.111125 -259.780447) (xy 231.120161 -259.838691) (xy 231.120696 -259.868162)
			(xy 231.12021 -259.895413) (xy 231.112454 -259.949361) (xy 231.097099 -260.001656) (xy 231.074457 -260.051233)
			(xy 231.044991 -260.097083) (xy 231.0093 -260.138274) (xy 230.968109 -260.173965) (xy 230.922259 -260.203431)
			(xy 230.872682 -260.226073) (xy 230.820387 -260.241428) (xy 230.766439 -260.249184) (xy 230.711937 -260.249184)
			(xy 230.657989 -260.241428) (xy 230.605694 -260.226073) (xy 230.556117 -260.203431) (xy 230.510267 -260.173965)
			(xy 230.469076 -260.138274) (xy 230.433385 -260.097083) (xy 230.403919 -260.051233) (xy 230.381277 -260.001656)
			(xy 230.365922 -259.949361) (xy 230.358166 -259.895413) (xy 230.35768 -259.868162) (xy 230.358208 -259.839358)
			(xy 230.366873 -259.782406) (xy 230.383999 -259.727403) (xy 230.409198 -259.675599) (xy 230.441896 -259.628171)
			(xy 230.481353 -259.586197) (xy 230.526669 -259.55063) (xy 230.576817 -259.522278) (xy 230.603552 -259.511546)
			(xy 230.614728 -259.507228) (xy 230.630476 -259.490464) (xy 230.660956 -259.390642) (xy 230.657146 -259.367528)
			(xy 230.650034 -259.357876) (xy 230.633435 -259.33352) (xy 230.60714 -259.280772) (xy 230.589266 -259.224609)
			(xy 230.580237 -259.166366) (xy 230.579676 -259.136896) (xy 230.58016 -259.109423) (xy 230.588043 -259.055044)
			(xy 230.603631 -259.002354) (xy 230.626604 -258.95244) (xy 230.641144 -258.929124) (xy 230.646478 -258.920996)
			(xy 230.650288 -258.902454) (xy 230.635302 -258.815078) (xy 230.625396 -258.799076) (xy 230.617776 -258.79298)
			(xy 230.594904 -258.774816) (xy 230.554433 -258.732708) (xy 230.520859 -258.684919) (xy 230.494967 -258.632569)
			(xy 230.477364 -258.576881) (xy 230.468462 -258.51916) (xy 230.467916 -258.489958) (xy 230.468475 -258.460389)
			(xy 230.477605 -258.401959) (xy 230.495641 -258.345637) (xy 230.52215 -258.292773) (xy 230.556497 -258.244631)
			(xy 230.59786 -258.202364) (xy 230.645249 -258.166985) (xy 230.671116 -258.152646) (xy 230.682038 -258.147058)
			(xy 230.695754 -258.127246) (xy 230.711248 -258.021836) (xy 230.703628 -257.998976) (xy 230.694738 -257.99034)
			(xy 230.673543 -257.968677) (xy 230.637596 -257.919885) (xy 230.609814 -257.866024) (xy 230.590894 -257.808449)
			(xy 230.581314 -257.748608) (xy 230.580692 -257.718306) (xy 230.581152 -257.691712) (xy 230.58854 -257.63904)
			(xy 230.603172 -257.587904) (xy 230.624766 -257.539297) (xy 230.652902 -257.49416) (xy 230.669592 -257.47345)
			(xy 230.675213 -257.466178) (xy 230.681326 -257.448858) (xy 230.68153 -257.439668) (xy 230.681022 -257.409442)
			(xy 230.680349 -257.399712) (xy 230.672655 -257.381807) (xy 230.666036 -257.374644) (xy 230.27894 -256.987548)
			(xy 230.271541 -256.980706) (xy 230.252942 -256.972986) (xy 230.242872 -256.972562) (xy 229.782878 -256.972562)
			(xy 229.77281 -256.972134) (xy 229.754215 -256.96441) (xy 229.74681 -256.957576) (xy 229.234746 -256.445512)
			(xy 229.231312 -256.441895) (xy 229.225811 -256.433577) (xy 229.223824 -256.429002) (xy 229.216458 -256.41173)
			(xy 229.214449 -256.407167) (xy 229.208948 -256.398855) (xy 229.205536 -256.39522) (xy 227.017326 -254.20701)
			(xy 227.009924 -254.200174) (xy 226.991326 -254.192465) (xy 226.981258 -254.192024) (xy 200.319386 -254.192024)
			(xy 200.308718 -254.19431) (xy 200.303384 -254.197104) (xy 200.277626 -254.208793) (xy 200.223525 -254.225299)
			(xy 200.167581 -254.233651) (xy 200.1393 -254.234188) (xy 200.137776 -254.234188) (xy 200.109492 -254.233679)
			(xy 200.053543 -254.225335) (xy 199.999441 -254.208818) (xy 199.973692 -254.197104) (xy 199.968358 -254.19431)
			(xy 199.95769 -254.192024) (xy 180.253386 -254.192024) (xy 180.23459 -254.199644) (xy 180.227478 -254.20701)
			(xy 179.301648 -255.13284) (xy 188.35573 -255.13284) (xy 188.359801 -255.077218) (xy 188.371927 -255.022781)
			(xy 188.39185 -254.97069) (xy 188.419146 -254.922055) (xy 188.453232 -254.877912) (xy 188.493381 -254.839203)
			(xy 188.538739 -254.806752) (xy 188.588339 -254.781251) (xy 188.641123 -254.763244) (xy 188.695966 -254.753114)
			(xy 188.7517 -254.751077) (xy 188.807137 -254.757177) (xy 188.861094 -254.771283) (xy 188.912423 -254.793095)
			(xy 188.960029 -254.822149) (xy 189.002897 -254.857824) (xy 189.040114 -254.899361) (xy 189.070887 -254.945874)
			(xy 189.094559 -254.996371) (xy 189.110627 -255.049778) (xy 189.118747 -255.104954) (xy 189.119256 -255.13284)
			(xy 189.118747 -255.160726) (xy 189.110627 -255.215902) (xy 189.094559 -255.269309) (xy 189.070887 -255.319806)
			(xy 189.040114 -255.366319) (xy 189.002897 -255.407856) (xy 188.960029 -255.443531) (xy 188.912423 -255.472585)
			(xy 188.861094 -255.494397) (xy 188.807137 -255.508503) (xy 188.7517 -255.514603) (xy 188.695966 -255.512566)
			(xy 188.641123 -255.502436) (xy 188.588339 -255.484429) (xy 188.538739 -255.458928) (xy 188.493381 -255.426477)
			(xy 188.453232 -255.387768) (xy 188.419146 -255.343625) (xy 188.39185 -255.29499) (xy 188.371927 -255.242899)
			(xy 188.359801 -255.188462) (xy 188.35573 -255.13284) (xy 179.301648 -255.13284) (xy 178.660552 -255.773936)
			(xy 178.656102 -255.778658) (xy 178.655146 -255.780286) (xy 189.018924 -255.780286) (xy 189.022995 -255.724664)
			(xy 189.035121 -255.670227) (xy 189.055044 -255.618136) (xy 189.08234 -255.569501) (xy 189.116426 -255.525358)
			(xy 189.156575 -255.486649) (xy 189.201933 -255.454198) (xy 189.251533 -255.428697) (xy 189.304317 -255.41069)
			(xy 189.35916 -255.40056) (xy 189.414894 -255.398523) (xy 189.470331 -255.404623) (xy 189.524288 -255.418729)
			(xy 189.575617 -255.440541) (xy 189.623223 -255.469595) (xy 189.666091 -255.50527) (xy 189.703308 -255.546807)
			(xy 189.734081 -255.59332) (xy 189.757753 -255.643817) (xy 189.773821 -255.697224) (xy 189.781941 -255.7524)
			(xy 189.782051 -255.758442) (xy 199.922382 -255.758442) (xy 199.926453 -255.70282) (xy 199.938579 -255.648383)
			(xy 199.958502 -255.596292) (xy 199.985798 -255.547657) (xy 200.019884 -255.503514) (xy 200.060033 -255.464805)
			(xy 200.105391 -255.432354) (xy 200.154991 -255.406853) (xy 200.207775 -255.388846) (xy 200.262618 -255.378716)
			(xy 200.318352 -255.376679) (xy 200.373789 -255.382779) (xy 200.427746 -255.396885) (xy 200.479075 -255.418697)
			(xy 200.526681 -255.447751) (xy 200.569549 -255.483426) (xy 200.606766 -255.524963) (xy 200.637539 -255.571476)
			(xy 200.661211 -255.621973) (xy 200.677279 -255.67538) (xy 200.685399 -255.730556) (xy 200.685908 -255.758442)
			(xy 215.692736 -255.758442) (xy 215.693195 -255.731188) (xy 215.700947 -255.677235) (xy 215.7163 -255.624934)
			(xy 215.738941 -255.575351) (xy 215.768408 -255.529496) (xy 215.804103 -255.488301) (xy 215.845297 -255.452607)
			(xy 215.891153 -255.42314) (xy 215.940736 -255.400499) (xy 215.993037 -255.385146) (xy 216.04699 -255.377394)
			(xy 216.074244 -255.376934) (xy 216.101583 -255.377377) (xy 216.155701 -255.385171) (xy 216.208154 -255.400608)
			(xy 216.257867 -255.423372) (xy 216.303824 -255.452996) (xy 216.345083 -255.488875) (xy 216.363296 -255.509268)
			(xy 216.370154 -255.517396) (xy 216.388696 -255.52654) (xy 216.483946 -255.530604) (xy 216.502996 -255.523492)
			(xy 216.51087 -255.516126) (xy 216.532322 -255.496096) (xy 216.580241 -255.462211) (xy 216.632784 -255.436062)
			(xy 216.68871 -255.418266) (xy 216.746702 -255.409242) (xy 216.776046 -255.408684) (xy 216.803298 -255.409135)
			(xy 216.857247 -255.416898) (xy 216.909541 -255.432258) (xy 216.959118 -255.454904) (xy 217.004968 -255.484374)
			(xy 217.046158 -255.520069) (xy 217.081848 -255.561262) (xy 217.111314 -255.607115) (xy 217.133955 -255.656694)
			(xy 217.149311 -255.708991) (xy 217.157068 -255.76294) (xy 217.157554 -255.790192) (xy 217.157096 -255.816948)
			(xy 217.149632 -255.869936) (xy 217.134836 -255.92136) (xy 217.112997 -255.970212) (xy 217.084545 -256.015533)
			(xy 217.050038 -256.056432) (xy 217.010154 -256.092106) (xy 216.965675 -256.121856) (xy 216.917475 -256.145098)
			(xy 216.892124 -256.153666) (xy 216.881964 -256.156968) (xy 216.86647 -256.17043) (xy 216.825068 -256.255774)
			(xy 216.824052 -256.276094) (xy 216.827862 -256.286254) (xy 216.839252 -256.318605) (xy 216.851476 -256.385822)
			(xy 218.904818 -256.385822) (xy 218.908889 -256.3302) (xy 218.921015 -256.275763) (xy 218.940938 -256.223672)
			(xy 218.968234 -256.175037) (xy 219.00232 -256.130894) (xy 219.042469 -256.092185) (xy 219.087827 -256.059734)
			(xy 219.137427 -256.034233) (xy 219.190211 -256.016226) (xy 219.245054 -256.006096) (xy 219.300788 -256.004059)
			(xy 219.356225 -256.010159) (xy 219.410182 -256.024265) (xy 219.461511 -256.046077) (xy 219.509117 -256.075131)
			(xy 219.551985 -256.110806) (xy 219.589202 -256.152343) (xy 219.619975 -256.198856) (xy 219.643647 -256.249353)
			(xy 219.659715 -256.30276) (xy 219.667835 -256.357936) (xy 219.668344 -256.385822) (xy 219.667835 -256.413708)
			(xy 219.659715 -256.468884) (xy 219.643647 -256.522291) (xy 219.619975 -256.572788) (xy 219.589202 -256.619301)
			(xy 219.551985 -256.660838) (xy 219.509117 -256.696513) (xy 219.461511 -256.725567) (xy 219.410182 -256.747379)
			(xy 219.356225 -256.761485) (xy 219.300788 -256.767585) (xy 219.245054 -256.765548) (xy 219.190211 -256.755418)
			(xy 219.137427 -256.737411) (xy 219.087827 -256.71191) (xy 219.042469 -256.679459) (xy 219.00232 -256.64075)
			(xy 218.968234 -256.596607) (xy 218.940938 -256.547972) (xy 218.921015 -256.495881) (xy 218.908889 -256.441444)
			(xy 218.904818 -256.385822) (xy 216.851476 -256.385822) (xy 216.851522 -256.386077) (xy 216.852246 -256.420366)
			(xy 216.85176 -256.447617) (xy 216.844004 -256.501565) (xy 216.828649 -256.55386) (xy 216.806007 -256.603437)
			(xy 216.776541 -256.649287) (xy 216.74085 -256.690478) (xy 216.699659 -256.726169) (xy 216.653809 -256.755635)
			(xy 216.604232 -256.778277) (xy 216.551937 -256.793632) (xy 216.497989 -256.801388) (xy 216.443487 -256.801388)
			(xy 216.389539 -256.793632) (xy 216.337244 -256.778277) (xy 216.287667 -256.755635) (xy 216.241817 -256.726169)
			(xy 216.200626 -256.690478) (xy 216.164935 -256.649287) (xy 216.135469 -256.603437) (xy 216.112827 -256.55386)
			(xy 216.097472 -256.501565) (xy 216.089716 -256.447617) (xy 216.08923 -256.420366) (xy 216.089607 -256.39588)
			(xy 216.09588 -256.347311) (xy 216.108319 -256.299944) (xy 216.11717 -256.27711) (xy 216.121742 -256.26568)
			(xy 216.119964 -256.242312) (xy 216.065862 -256.151888) (xy 216.045796 -256.139188) (xy 216.033858 -256.137918)
			(xy 216.006102 -256.134531) (xy 215.951964 -256.120529) (xy 215.900448 -256.09878) (xy 215.852656 -256.069748)
			(xy 215.80961 -256.034056) (xy 215.772232 -255.992465) (xy 215.74132 -255.945867) (xy 215.717537 -255.895258)
			(xy 215.701391 -255.841721) (xy 215.693228 -255.786401) (xy 215.692736 -255.758442) (xy 200.685908 -255.758442)
			(xy 200.685399 -255.786328) (xy 200.677279 -255.841504) (xy 200.661211 -255.894911) (xy 200.637539 -255.945408)
			(xy 200.606766 -255.991921) (xy 200.569549 -256.033458) (xy 200.526681 -256.069133) (xy 200.479075 -256.098187)
			(xy 200.427746 -256.119999) (xy 200.373789 -256.134105) (xy 200.318352 -256.140205) (xy 200.262618 -256.138168)
			(xy 200.207775 -256.128038) (xy 200.154991 -256.110031) (xy 200.105391 -256.08453) (xy 200.060033 -256.052079)
			(xy 200.019884 -256.01337) (xy 199.985798 -255.969227) (xy 199.958502 -255.920592) (xy 199.938579 -255.868501)
			(xy 199.926453 -255.814064) (xy 199.922382 -255.758442) (xy 189.782051 -255.758442) (xy 189.78245 -255.780286)
			(xy 189.781941 -255.808172) (xy 189.773821 -255.863348) (xy 189.757753 -255.916755) (xy 189.734081 -255.967252)
			(xy 189.703308 -256.013765) (xy 189.666091 -256.055302) (xy 189.623223 -256.090977) (xy 189.575617 -256.120031)
			(xy 189.524288 -256.141843) (xy 189.470331 -256.155949) (xy 189.414894 -256.162049) (xy 189.35916 -256.160012)
			(xy 189.304317 -256.149882) (xy 189.251533 -256.131875) (xy 189.201933 -256.106374) (xy 189.156575 -256.073923)
			(xy 189.116426 -256.035214) (xy 189.08234 -255.991071) (xy 189.055044 -255.942436) (xy 189.035121 -255.890345)
			(xy 189.022995 -255.835908) (xy 189.018924 -255.780286) (xy 178.655146 -255.780286) (xy 178.649535 -255.789842)
			(xy 178.647598 -255.796034) (xy 178.321621 -256.947947) (xy 213.216524 -256.947947) (xy 213.216524 -256.893453)
			(xy 213.224279 -256.839512) (xy 213.239632 -256.787225) (xy 213.26227 -256.737654) (xy 213.291732 -256.69181)
			(xy 213.327418 -256.650625) (xy 213.368602 -256.614938) (xy 213.414445 -256.585475) (xy 213.464015 -256.562836)
			(xy 213.516302 -256.547482) (xy 213.570243 -256.539725) (xy 213.59749 -256.539238) (xy 213.62595 -256.53978)
			(xy 213.68224 -256.548229) (xy 213.736647 -256.564955) (xy 213.787961 -256.589586) (xy 213.835042 -256.621575)
			(xy 213.876842 -256.66021) (xy 213.912432 -256.704631) (xy 213.927182 -256.728976) (xy 213.933532 -256.739898)
			(xy 213.954614 -256.753106) (xy 214.063326 -256.761234) (xy 214.085932 -256.751582) (xy 214.09406 -256.741676)
			(xy 214.10073 -256.733532) (xy 214.114835 -256.717902) (xy 214.122254 -256.710434) (xy 214.130636 -256.702052)
			(xy 214.138256 -256.680462) (xy 214.12708 -256.5781) (xy 214.114888 -256.558542) (xy 214.104982 -256.552192)
			(xy 214.082005 -256.53711) (xy 214.040184 -256.50145) (xy 214.003918 -256.460153) (xy 213.97396 -256.414076)
			(xy 213.950929 -256.364174) (xy 213.935305 -256.311482) (xy 213.927409 -256.257092) (xy 213.926928 -256.229612)
			(xy 213.927414 -256.202361) (xy 213.93517 -256.148413) (xy 213.950525 -256.096118) (xy 213.973167 -256.046541)
			(xy 214.002633 -256.000691) (xy 214.038324 -255.9595) (xy 214.079515 -255.923809) (xy 214.125365 -255.894343)
			(xy 214.174942 -255.871701) (xy 214.227237 -255.856346) (xy 214.281185 -255.84859) (xy 214.335687 -255.84859)
			(xy 214.389635 -255.856346) (xy 214.44193 -255.871701) (xy 214.491507 -255.894343) (xy 214.537357 -255.923809)
			(xy 214.578548 -255.9595) (xy 214.614239 -256.000691) (xy 214.643705 -256.046541) (xy 214.666347 -256.096118)
			(xy 214.681702 -256.148413) (xy 214.689458 -256.202361) (xy 214.689944 -256.229612) (xy 214.689381 -256.259772)
			(xy 214.679876 -256.319338) (xy 214.661119 -256.376667) (xy 214.633578 -256.430333) (xy 214.597938 -256.478998)
			(xy 214.576914 -256.50063) (xy 214.568532 -256.509012) (xy 214.560912 -256.530602) (xy 214.572088 -256.632964)
			(xy 214.58428 -256.652522) (xy 214.594186 -256.658872) (xy 214.617208 -256.673889) (xy 214.659025 -256.709562)
			(xy 214.695285 -256.750871) (xy 214.725237 -256.796959) (xy 214.74826 -256.846871) (xy 214.763877 -256.899572)
			(xy 214.771763 -256.953969) (xy 214.77224 -256.981452) (xy 214.7717 -257.008702) (xy 214.763951 -257.062649)
			(xy 214.748602 -257.114943) (xy 214.725968 -257.164521) (xy 214.696508 -257.210373) (xy 214.660822 -257.251565)
			(xy 214.619637 -257.28726) (xy 214.573791 -257.316729) (xy 214.524218 -257.339374) (xy 214.471927 -257.354734)
			(xy 214.417982 -257.362494) (xy 214.390732 -257.36296) (xy 214.36227 -257.36248) (xy 214.305977 -257.35402)
			(xy 214.251569 -257.337283) (xy 214.200254 -257.312642) (xy 214.153174 -257.280643) (xy 214.111376 -257.242)
			(xy 214.075789 -257.197571) (xy 214.06104 -257.173222) (xy 214.05469 -257.1623) (xy 214.033608 -257.149092)
			(xy 213.924896 -257.140964) (xy 213.90229 -257.150616) (xy 213.894162 -257.160522) (xy 213.875924 -257.18222)
			(xy 213.834176 -257.220555) (xy 213.787215 -257.252291) (xy 213.736075 -257.276728) (xy 213.681882 -257.29333)
			(xy 213.625829 -257.30173) (xy 213.59749 -257.302254) (xy 213.570243 -257.301675) (xy 213.516302 -257.293918)
			(xy 213.464015 -257.278564) (xy 213.414445 -257.255925) (xy 213.368602 -257.226462) (xy 213.327418 -257.190775)
			(xy 213.291732 -257.14959) (xy 213.26227 -257.103746) (xy 213.239632 -257.054175) (xy 213.224279 -257.001888)
			(xy 213.216524 -256.947947) (xy 178.321621 -256.947947) (xy 177.767872 -258.90474) (xy 215.021922 -258.90474)
			(xy 215.022507 -258.875858) (xy 215.031222 -258.818755) (xy 215.048443 -258.763617) (xy 215.073777 -258.711705)
			(xy 215.106645 -258.664203) (xy 215.146296 -258.622198) (xy 215.168734 -258.604004) (xy 215.1761 -258.598162)
			(xy 215.185752 -258.582668) (xy 215.202008 -258.498594) (xy 215.19896 -258.480814) (xy 215.194134 -258.472686)
			(xy 215.181872 -258.450793) (xy 215.162588 -258.404465) (xy 215.149545 -258.356009) (xy 215.142968 -258.306261)
			(xy 215.142572 -258.28117) (xy 215.143058 -258.253919) (xy 215.150814 -258.199971) (xy 215.166169 -258.147676)
			(xy 215.188811 -258.098099) (xy 215.218277 -258.052249) (xy 215.253968 -258.011058) (xy 215.295159 -257.975367)
			(xy 215.341009 -257.945901) (xy 215.390586 -257.923259) (xy 215.442881 -257.907904) (xy 215.496829 -257.900148)
			(xy 215.551331 -257.900148) (xy 215.605279 -257.907904) (xy 215.657574 -257.923259) (xy 215.707151 -257.945901)
			(xy 215.753001 -257.975367) (xy 215.794192 -258.011058) (xy 215.829883 -258.052249) (xy 215.859349 -258.098099)
			(xy 215.881991 -258.147676) (xy 215.897346 -258.199971) (xy 215.905102 -258.253919) (xy 215.905588 -258.28117)
			(xy 215.905044 -258.310054) (xy 215.896326 -258.367161) (xy 215.879099 -258.4223) (xy 215.853757 -258.474214)
			(xy 215.82088 -258.521714) (xy 215.781219 -258.563715) (xy 215.758776 -258.581906) (xy 215.75141 -258.587748)
			(xy 215.741758 -258.603242) (xy 215.725502 -258.687316) (xy 215.72855 -258.705096) (xy 215.733376 -258.713224)
			(xy 215.745643 -258.735115) (xy 215.764926 -258.781443) (xy 215.777968 -258.8299) (xy 215.784542 -258.879649)
			(xy 215.784938 -258.90474) (xy 215.784443 -258.931788) (xy 215.776802 -258.985342) (xy 215.761678 -259.037281)
			(xy 215.739375 -259.086566) (xy 215.710339 -259.13221) (xy 215.675151 -259.173298) (xy 215.655144 -259.191506)
			(xy 215.646762 -259.198872) (xy 215.637872 -259.218684) (xy 215.638634 -259.318252) (xy 215.647778 -259.33781)
			(xy 215.656414 -259.345176) (xy 215.677148 -259.363406) (xy 215.713683 -259.404797) (xy 215.743871 -259.45102)
			(xy 215.767084 -259.501111) (xy 215.782835 -259.554025) (xy 215.790797 -259.608656) (xy 215.791288 -259.63626)
			(xy 215.790802 -259.663511) (xy 215.783046 -259.717459) (xy 215.767691 -259.769754) (xy 215.745049 -259.819331)
			(xy 215.715583 -259.865181) (xy 215.679892 -259.906372) (xy 215.638701 -259.942063) (xy 215.592851 -259.971529)
			(xy 215.543274 -259.994171) (xy 215.490979 -260.009526) (xy 215.437031 -260.017282) (xy 215.382529 -260.017282)
			(xy 215.328581 -260.009526) (xy 215.276286 -259.994171) (xy 215.226709 -259.971529) (xy 215.180859 -259.942063)
			(xy 215.139668 -259.906372) (xy 215.103977 -259.865181) (xy 215.074511 -259.819331) (xy 215.051869 -259.769754)
			(xy 215.036514 -259.717459) (xy 215.028758 -259.663511) (xy 215.028272 -259.63626) (xy 215.028797 -259.609213)
			(xy 215.036436 -259.555662) (xy 215.051556 -259.503724) (xy 215.073854 -259.45444) (xy 215.102883 -259.408796)
			(xy 215.138063 -259.367705) (xy 215.158066 -259.349494) (xy 215.166448 -259.342128) (xy 215.175338 -259.322316)
			(xy 215.174576 -259.222748) (xy 215.165432 -259.20319) (xy 215.156796 -259.195824) (xy 215.136064 -259.177591)
			(xy 215.099529 -259.136202) (xy 215.069339 -259.089979) (xy 215.046127 -259.039888) (xy 215.030375 -258.986975)
			(xy 215.022413 -258.932344) (xy 215.021922 -258.90474) (xy 177.767872 -258.90474) (xy 177.268509 -260.669351)
			(xy 200.037678 -260.669351) (xy 200.037678 -260.614849) (xy 200.045434 -260.560901) (xy 200.060789 -260.508606)
			(xy 200.083431 -260.459029) (xy 200.112897 -260.413179) (xy 200.148588 -260.371988) (xy 200.189779 -260.336297)
			(xy 200.235629 -260.306831) (xy 200.285206 -260.284189) (xy 200.337501 -260.268834) (xy 200.391449 -260.261078)
			(xy 200.4187 -260.260592) (xy 200.444345 -260.260996) (xy 200.495172 -260.267883) (xy 200.544617 -260.281519)
			(xy 200.591789 -260.301658) (xy 200.614026 -260.31444) (xy 200.622916 -260.31952) (xy 200.643236 -260.322568)
			(xy 200.73366 -260.298184) (xy 200.749662 -260.285484) (xy 200.754742 -260.27634) (xy 200.769319 -260.25127)
			(xy 200.804849 -260.205441) (xy 200.846905 -260.165516) (xy 200.894518 -260.132414) (xy 200.946592 -260.106899)
			(xy 201.001927 -260.089557) (xy 201.059249 -260.080789) (xy 201.088244 -260.080252) (xy 201.11549 -260.080821)
			(xy 201.169428 -260.088582) (xy 201.221711 -260.103939) (xy 201.271278 -260.126581) (xy 201.317118 -260.156045)
			(xy 201.358299 -260.191733) (xy 201.393982 -260.232917) (xy 201.423441 -260.278761) (xy 201.446076 -260.32833)
			(xy 201.461427 -260.380615) (xy 201.469182 -260.434554) (xy 201.469182 -260.46176) (xy 201.708256 -260.46176)
			(xy 201.712327 -260.406138) (xy 201.724453 -260.351701) (xy 201.744376 -260.29961) (xy 201.771672 -260.250975)
			(xy 201.805758 -260.206832) (xy 201.845907 -260.168123) (xy 201.891265 -260.135672) (xy 201.940865 -260.110171)
			(xy 201.993649 -260.092164) (xy 202.048492 -260.082034) (xy 202.104226 -260.079997) (xy 202.159663 -260.086097)
			(xy 202.21362 -260.100203) (xy 202.264949 -260.122015) (xy 202.312555 -260.151069) (xy 202.355423 -260.186744)
			(xy 202.39264 -260.228281) (xy 202.423413 -260.274794) (xy 202.447085 -260.325291) (xy 202.463153 -260.378698)
			(xy 202.471273 -260.433874) (xy 202.471782 -260.46176) (xy 202.724256 -260.46176) (xy 202.728327 -260.406138)
			(xy 202.740453 -260.351701) (xy 202.760376 -260.29961) (xy 202.787672 -260.250975) (xy 202.821758 -260.206832)
			(xy 202.861907 -260.168123) (xy 202.907265 -260.135672) (xy 202.956865 -260.110171) (xy 203.009649 -260.092164)
			(xy 203.064492 -260.082034) (xy 203.120226 -260.079997) (xy 203.175663 -260.086097) (xy 203.22962 -260.100203)
			(xy 203.280949 -260.122015) (xy 203.328555 -260.151069) (xy 203.371423 -260.186744) (xy 203.40864 -260.228281)
			(xy 203.439413 -260.274794) (xy 203.463085 -260.325291) (xy 203.479153 -260.378698) (xy 203.487273 -260.433874)
			(xy 203.487782 -260.46176) (xy 203.750924 -260.46176) (xy 203.754995 -260.406138) (xy 203.767121 -260.351701)
			(xy 203.787044 -260.29961) (xy 203.81434 -260.250975) (xy 203.848426 -260.206832) (xy 203.888575 -260.168123)
			(xy 203.933933 -260.135672) (xy 203.983533 -260.110171) (xy 204.036317 -260.092164) (xy 204.09116 -260.082034)
			(xy 204.146894 -260.079997) (xy 204.202331 -260.086097) (xy 204.256288 -260.100203) (xy 204.307617 -260.122015)
			(xy 204.355223 -260.151069) (xy 204.398091 -260.186744) (xy 204.435308 -260.228281) (xy 204.466081 -260.274794)
			(xy 204.489753 -260.325291) (xy 204.505821 -260.378698) (xy 204.513941 -260.433874) (xy 204.51445 -260.46176)
			(xy 204.513941 -260.489646) (xy 204.505821 -260.544822) (xy 204.489753 -260.598229) (xy 204.466081 -260.648726)
			(xy 204.435308 -260.695239) (xy 204.398091 -260.736776) (xy 204.355223 -260.772451) (xy 204.307617 -260.801505)
			(xy 204.256288 -260.823317) (xy 204.202331 -260.837423) (xy 204.146894 -260.843523) (xy 204.09116 -260.841486)
			(xy 204.036317 -260.831356) (xy 203.983533 -260.813349) (xy 203.933933 -260.787848) (xy 203.888575 -260.755397)
			(xy 203.848426 -260.716688) (xy 203.81434 -260.672545) (xy 203.787044 -260.62391) (xy 203.767121 -260.571819)
			(xy 203.754995 -260.517382) (xy 203.750924 -260.46176) (xy 203.487782 -260.46176) (xy 203.487273 -260.489646)
			(xy 203.479153 -260.544822) (xy 203.463085 -260.598229) (xy 203.439413 -260.648726) (xy 203.40864 -260.695239)
			(xy 203.371423 -260.736776) (xy 203.328555 -260.772451) (xy 203.280949 -260.801505) (xy 203.22962 -260.823317)
			(xy 203.175663 -260.837423) (xy 203.120226 -260.843523) (xy 203.064492 -260.841486) (xy 203.009649 -260.831356)
			(xy 202.956865 -260.813349) (xy 202.907265 -260.787848) (xy 202.861907 -260.755397) (xy 202.821758 -260.716688)
			(xy 202.787672 -260.672545) (xy 202.760376 -260.62391) (xy 202.740453 -260.571819) (xy 202.728327 -260.517382)
			(xy 202.724256 -260.46176) (xy 202.471782 -260.46176) (xy 202.471273 -260.489646) (xy 202.463153 -260.544822)
			(xy 202.447085 -260.598229) (xy 202.423413 -260.648726) (xy 202.39264 -260.695239) (xy 202.355423 -260.736776)
			(xy 202.312555 -260.772451) (xy 202.264949 -260.801505) (xy 202.21362 -260.823317) (xy 202.159663 -260.837423)
			(xy 202.104226 -260.843523) (xy 202.048492 -260.841486) (xy 201.993649 -260.831356) (xy 201.940865 -260.813349)
			(xy 201.891265 -260.787848) (xy 201.845907 -260.755397) (xy 201.805758 -260.716688) (xy 201.771672 -260.672545)
			(xy 201.744376 -260.62391) (xy 201.724453 -260.571819) (xy 201.712327 -260.517382) (xy 201.708256 -260.46176)
			(xy 201.469182 -260.46176) (xy 201.469182 -260.489046) (xy 201.461427 -260.542985) (xy 201.446076 -260.59527)
			(xy 201.423441 -260.644839) (xy 201.393982 -260.690683) (xy 201.358299 -260.731867) (xy 201.317118 -260.767555)
			(xy 201.271278 -260.797019) (xy 201.221711 -260.819661) (xy 201.169428 -260.835018) (xy 201.11549 -260.842779)
			(xy 201.088244 -260.843268) (xy 201.062599 -260.84285) (xy 201.011773 -260.835968) (xy 200.962327 -260.822336)
			(xy 200.915155 -260.8022) (xy 200.892918 -260.78942) (xy 200.884028 -260.78434) (xy 200.863708 -260.781292)
			(xy 200.773284 -260.805676) (xy 200.757282 -260.818376) (xy 200.752202 -260.82752) (xy 200.737649 -260.852605)
			(xy 200.702117 -260.898437) (xy 200.660058 -260.938363) (xy 200.612441 -260.971464) (xy 200.560362 -260.996976)
			(xy 200.505022 -261.014313) (xy 200.447696 -261.023075) (xy 200.4187 -261.023608) (xy 200.391449 -261.023122)
			(xy 200.337501 -261.015366) (xy 200.285206 -261.000011) (xy 200.235629 -260.977369) (xy 200.189779 -260.947903)
			(xy 200.148588 -260.912212) (xy 200.112897 -260.871021) (xy 200.083431 -260.825171) (xy 200.060789 -260.775594)
			(xy 200.045434 -260.723299) (xy 200.037678 -260.669351) (xy 177.268509 -260.669351) (xy 176.907698 -261.944358)
			(xy 176.905666 -261.958074) (xy 176.905666 -270.89989) (xy 200.998589 -270.89989) (xy 201.002595 -270.704835)
			(xy 201.014605 -270.510109) (xy 201.0346 -270.31604) (xy 201.062545 -270.122956) (xy 201.098394 -269.931181)
			(xy 201.142086 -269.741041) (xy 201.193547 -269.552854) (xy 201.252691 -269.366939) (xy 201.319418 -269.183608)
			(xy 201.393615 -269.003172) (xy 201.475157 -268.825934) (xy 201.563908 -268.652193) (xy 201.659716 -268.482242)
			(xy 201.762421 -268.316368) (xy 201.871849 -268.15485) (xy 201.987816 -267.997961) (xy 202.110127 -267.845966)
			(xy 202.238574 -267.69912) (xy 202.372942 -267.557671) (xy 202.513004 -267.421858) (xy 202.658523 -267.291909)
			(xy 202.809255 -267.168045) (xy 202.964945 -267.050473) (xy 203.125331 -266.939393) (xy 203.290142 -266.83499)
			(xy 203.4591 -266.737442) (xy 203.631921 -266.646913) (xy 203.808313 -266.563555) (xy 203.987978 -266.487509)
			(xy 204.170613 -266.418904) (xy 204.355912 -266.357854) (xy 204.54356 -266.304464) (xy 204.733242 -266.258822)
			(xy 204.924639 -266.221006) (xy 205.117426 -266.19108) (xy 205.311279 -266.169094) (xy 205.505872 -266.155085)
			(xy 205.700875 -266.149077) (xy 205.895961 -266.15108) (xy 206.0908 -266.161091) (xy 206.285064 -266.179092)
			(xy 206.478425 -266.205054) (xy 206.670558 -266.238932) (xy 206.861137 -266.280669) (xy 207.049842 -266.330196)
			(xy 207.236355 -266.387428) (xy 207.420361 -266.452269) (xy 207.601549 -266.52461) (xy 207.779615 -266.604328)
			(xy 207.954258 -266.69129) (xy 208.125184 -266.785349) (xy 208.292103 -266.886345) (xy 208.454736 -266.99411)
			(xy 208.612807 -267.10846) (xy 208.76605 -267.229203) (xy 208.914207 -267.356137) (xy 209.057028 -267.489045)
			(xy 209.194272 -267.627705) (xy 209.325708 -267.771883) (xy 209.451113 -267.921336) (xy 209.570277 -268.07581)
			(xy 209.682998 -268.235047) (xy 209.789087 -268.398778) (xy 209.888365 -268.566725) (xy 209.980663 -268.738608)
			(xy 210.065828 -268.914134) (xy 210.143714 -269.093009) (xy 210.214191 -269.274931) (xy 210.277139 -269.459593)
			(xy 210.332454 -269.646683) (xy 210.38004 -269.835887) (xy 210.419819 -270.026884) (xy 210.451723 -270.219354)
			(xy 210.475698 -270.412972) (xy 210.491704 -270.60741) (xy 210.499713 -270.802342) (xy 210.500214 -270.89989)
			(xy 210.499713 -270.997438) (xy 210.491704 -271.19237) (xy 210.475698 -271.386808) (xy 210.451723 -271.580426)
			(xy 210.419819 -271.772896) (xy 210.38004 -271.963893) (xy 210.332454 -272.153097) (xy 210.277139 -272.340187)
			(xy 210.214191 -272.524849) (xy 210.143714 -272.706771) (xy 210.09336 -272.822416) (xy 220.248988 -272.822416)
			(xy 220.249466 -272.795046) (xy 220.257282 -272.740868) (xy 220.272768 -272.688365) (xy 220.295607 -272.638618)
			(xy 220.325328 -272.59265) (xy 220.342968 -272.571718) (xy 220.349064 -272.564606) (xy 220.355414 -272.547588)
			(xy 220.355414 -272.462244) (xy 220.349064 -272.445226) (xy 220.342968 -272.438114) (xy 220.325317 -272.417192)
			(xy 220.295608 -272.371216) (xy 220.272775 -272.321466) (xy 220.257287 -272.268963) (xy 220.249461 -272.214786)
			(xy 220.248988 -272.187416) (xy 220.24947 -272.160164) (xy 220.257225 -272.106214) (xy 220.272579 -272.053916)
			(xy 220.295219 -272.004337) (xy 220.324685 -271.958484) (xy 220.360377 -271.917291) (xy 220.401568 -271.881597)
			(xy 220.447419 -271.852129) (xy 220.496998 -271.829486) (xy 220.549294 -271.814129) (xy 220.603244 -271.806372)
			(xy 220.630496 -271.805908) (xy 220.659235 -271.806432) (xy 220.716062 -271.815054) (xy 220.770953 -271.832104)
			(xy 220.822665 -271.857196) (xy 220.870027 -271.889761) (xy 220.891354 -271.909032) (xy 220.898466 -271.915636)
			(xy 220.915992 -271.922748) (xy 221.0054 -271.922748) (xy 221.022926 -271.915636) (xy 221.030038 -271.909032)
			(xy 221.051365 -271.889762) (xy 221.098728 -271.857197) (xy 221.150439 -271.832106) (xy 221.20533 -271.815056)
			(xy 221.262157 -271.806434) (xy 221.319635 -271.806434) (xy 221.376462 -271.815056) (xy 221.431353 -271.832106)
			(xy 221.483064 -271.857197) (xy 221.530427 -271.889762) (xy 221.551754 -271.909032) (xy 221.558866 -271.915636)
			(xy 221.576392 -271.922748) (xy 221.6658 -271.922748) (xy 221.683326 -271.915636) (xy 221.690438 -271.909032)
			(xy 221.711765 -271.889762) (xy 221.759128 -271.857197) (xy 221.810839 -271.832106) (xy 221.86573 -271.815056)
			(xy 221.922557 -271.806434) (xy 221.980035 -271.806434) (xy 222.036862 -271.815056) (xy 222.091753 -271.832106)
			(xy 222.143464 -271.857197) (xy 222.190827 -271.889762) (xy 222.212154 -271.909032) (xy 222.219266 -271.915636)
			(xy 222.236792 -271.922748) (xy 222.3262 -271.922748) (xy 222.343726 -271.915636) (xy 222.350838 -271.909032)
			(xy 222.372166 -271.889762) (xy 222.419528 -271.857196) (xy 222.471239 -271.832103) (xy 222.52613 -271.815053)
			(xy 222.582957 -271.806429) (xy 222.611696 -271.805908) (xy 222.638949 -271.806359) (xy 222.692902 -271.814116)
			(xy 222.745201 -271.829472) (xy 222.794782 -271.852115) (xy 222.840636 -271.881585) (xy 222.881829 -271.91728)
			(xy 222.917523 -271.958474) (xy 222.94699 -272.004329) (xy 222.969632 -272.053911) (xy 222.984987 -272.10621)
			(xy 222.992742 -272.160163) (xy 222.993204 -272.187416) (xy 222.992746 -272.214787) (xy 222.984926 -272.268966)
			(xy 222.969435 -272.321469) (xy 222.946592 -272.371216) (xy 222.916866 -272.417182) (xy 222.899224 -272.438114)
			(xy 222.893128 -272.445226) (xy 222.886778 -272.462244) (xy 222.886778 -272.547588) (xy 222.893128 -272.564606)
			(xy 222.899224 -272.571718) (xy 222.916842 -272.592667) (xy 222.946556 -272.638636) (xy 222.969396 -272.688379)
			(xy 222.984892 -272.740876) (xy 222.992726 -272.795048) (xy 222.993204 -272.822416) (xy 223.844358 -272.822416)
			(xy 223.844819 -272.795045) (xy 223.852636 -272.740866) (xy 223.868126 -272.688362) (xy 223.890969 -272.638615)
			(xy 223.920695 -272.592649) (xy 223.938338 -272.571718) (xy 223.944434 -272.564606) (xy 223.950784 -272.547588)
			(xy 223.950784 -272.462244) (xy 223.944434 -272.445226) (xy 223.938338 -272.438114) (xy 223.920698 -272.417183)
			(xy 223.890985 -272.37121) (xy 223.868149 -272.321463) (xy 223.852658 -272.268962) (xy 223.844831 -272.214785)
			(xy 223.844358 -272.187416) (xy 223.844893 -272.160167) (xy 223.852646 -272.106223) (xy 223.867998 -272.053931)
			(xy 223.890635 -272.004356) (xy 223.920096 -271.958507) (xy 223.955782 -271.917318) (xy 223.996967 -271.881626)
			(xy 224.042812 -271.852159) (xy 224.092384 -271.829515) (xy 224.144674 -271.814157) (xy 224.198617 -271.806397)
			(xy 224.225866 -271.805908) (xy 224.254607 -271.806389) (xy 224.311436 -271.815022) (xy 224.366327 -271.832082)
			(xy 224.418038 -271.857183) (xy 224.465399 -271.889757) (xy 224.486724 -271.909032) (xy 224.493836 -271.915636)
			(xy 224.511362 -271.922748) (xy 224.60077 -271.922748) (xy 224.618296 -271.915636) (xy 224.625408 -271.909032)
			(xy 224.646735 -271.889762) (xy 224.694098 -271.857197) (xy 224.745809 -271.832106) (xy 224.8007 -271.815056)
			(xy 224.857527 -271.806434) (xy 224.915005 -271.806434) (xy 224.971832 -271.815056) (xy 225.026723 -271.832106)
			(xy 225.078434 -271.857197) (xy 225.125797 -271.889762) (xy 225.147124 -271.909032) (xy 225.154236 -271.915636)
			(xy 225.171762 -271.922748) (xy 225.26117 -271.922748) (xy 225.278696 -271.915636) (xy 225.285808 -271.909032)
			(xy 225.307135 -271.889762) (xy 225.354498 -271.857197) (xy 225.406209 -271.832106) (xy 225.4611 -271.815056)
			(xy 225.517927 -271.806434) (xy 225.575405 -271.806434) (xy 225.632232 -271.815056) (xy 225.687123 -271.832106)
			(xy 225.738834 -271.857197) (xy 225.786197 -271.889762) (xy 225.807524 -271.909032) (xy 225.814636 -271.915636)
			(xy 225.832162 -271.922748) (xy 225.92157 -271.922748) (xy 225.939096 -271.915636) (xy 225.946208 -271.909032)
			(xy 225.967548 -271.889776) (xy 226.014907 -271.857208) (xy 226.066615 -271.832113) (xy 226.121503 -271.815059)
			(xy 226.178328 -271.806431) (xy 226.207066 -271.805908) (xy 226.234319 -271.806387) (xy 226.28827 -271.81414)
			(xy 226.340568 -271.829492) (xy 226.39015 -271.852132) (xy 226.436004 -271.881598) (xy 226.477197 -271.91729)
			(xy 226.512891 -271.958482) (xy 226.542359 -272.004335) (xy 226.565001 -272.053915) (xy 226.580356 -272.106212)
			(xy 226.588112 -272.160163) (xy 226.588574 -272.187416) (xy 226.588124 -272.214787) (xy 226.580303 -272.268967)
			(xy 226.564811 -272.32147) (xy 226.541965 -272.371217) (xy 226.512237 -272.417183) (xy 226.494594 -272.438114)
			(xy 226.488498 -272.445226) (xy 226.482148 -272.462244) (xy 226.482148 -272.547588) (xy 226.488498 -272.564606)
			(xy 226.494594 -272.571718) (xy 226.512207 -272.592671) (xy 226.541923 -272.638638) (xy 226.564764 -272.68838)
			(xy 226.580261 -272.740876) (xy 226.588096 -272.795048) (xy 226.588574 -272.822416) (xy 226.58816 -272.849671)
			(xy 226.5804 -272.903625) (xy 226.56504 -272.955926) (xy 226.542393 -273.005509) (xy 226.51292 -273.051363)
			(xy 226.477221 -273.092557) (xy 226.436023 -273.12825) (xy 226.390165 -273.157717) (xy 226.340579 -273.180358)
			(xy 226.288276 -273.195711) (xy 226.234321 -273.203463) (xy 226.207066 -273.203924) (xy 226.178327 -273.203415)
			(xy 226.121499 -273.194787) (xy 226.066608 -273.177734) (xy 226.014897 -273.152639) (xy 225.967535 -273.120072)
			(xy 225.946208 -273.1008) (xy 225.939096 -273.094196) (xy 225.92157 -273.087084) (xy 225.832162 -273.087084)
			(xy 225.814636 -273.094196) (xy 225.807524 -273.1008) (xy 225.786197 -273.12007) (xy 225.738834 -273.152635)
			(xy 225.687123 -273.177726) (xy 225.632232 -273.194776) (xy 225.575405 -273.203398) (xy 225.517927 -273.203398)
			(xy 225.4611 -273.194776) (xy 225.406209 -273.177726) (xy 225.354498 -273.152635) (xy 225.307135 -273.12007)
			(xy 225.285808 -273.1008) (xy 225.278696 -273.094196) (xy 225.26117 -273.087084) (xy 225.171762 -273.087084)
			(xy 225.154236 -273.094196) (xy 225.147124 -273.1008) (xy 225.125797 -273.12007) (xy 225.078434 -273.152635)
			(xy 225.026723 -273.177726) (xy 224.971832 -273.194776) (xy 224.915005 -273.203398) (xy 224.857527 -273.203398)
			(xy 224.8007 -273.194776) (xy 224.745809 -273.177726) (xy 224.694098 -273.152635) (xy 224.646735 -273.12007)
			(xy 224.625408 -273.1008) (xy 224.618296 -273.094196) (xy 224.60077 -273.087084) (xy 224.511362 -273.087084)
			(xy 224.493836 -273.094196) (xy 224.486724 -273.1008) (xy 224.465401 -273.120076) (xy 224.418039 -273.152644)
			(xy 224.366327 -273.177736) (xy 224.311434 -273.194785) (xy 224.254606 -273.203405) (xy 224.225866 -273.203924)
			(xy 224.198615 -273.203454) (xy 224.144667 -273.195693) (xy 224.092373 -273.180335) (xy 224.042797 -273.157691)
			(xy 223.996947 -273.128222) (xy 223.955758 -273.092529) (xy 223.920067 -273.051338) (xy 223.890601 -273.005487)
			(xy 223.867959 -272.95591) (xy 223.852603 -272.903615) (xy 223.844845 -272.849667) (xy 223.844358 -272.822416)
			(xy 222.993204 -272.822416) (xy 222.992737 -272.849668) (xy 222.984978 -272.903616) (xy 222.969621 -272.955912)
			(xy 222.946978 -273.005489) (xy 222.917509 -273.05134) (xy 222.881816 -273.09253) (xy 222.840624 -273.128221)
			(xy 222.794772 -273.157687) (xy 222.745193 -273.180328) (xy 222.692897 -273.195683) (xy 222.638948 -273.203439)
			(xy 222.611696 -273.203924) (xy 222.582957 -273.203396) (xy 222.52613 -273.194774) (xy 222.47124 -273.177724)
			(xy 222.419528 -273.152634) (xy 222.372165 -273.12007) (xy 222.350838 -273.1008) (xy 222.343726 -273.094196)
			(xy 222.3262 -273.087084) (xy 222.236792 -273.087084) (xy 222.219266 -273.094196) (xy 222.212154 -273.1008)
			(xy 222.190827 -273.12007) (xy 222.143464 -273.152635) (xy 222.091753 -273.177726) (xy 222.036862 -273.194776)
			(xy 221.980035 -273.203398) (xy 221.922557 -273.203398) (xy 221.86573 -273.194776) (xy 221.810839 -273.177726)
			(xy 221.759128 -273.152635) (xy 221.711765 -273.12007) (xy 221.690438 -273.1008) (xy 221.683326 -273.094196)
			(xy 221.6658 -273.087084) (xy 221.576392 -273.087084) (xy 221.558866 -273.094196) (xy 221.551754 -273.1008)
			(xy 221.530427 -273.12007) (xy 221.483064 -273.152635) (xy 221.431353 -273.177726) (xy 221.376462 -273.194776)
			(xy 221.319635 -273.203398) (xy 221.262157 -273.203398) (xy 221.20533 -273.194776) (xy 221.150439 -273.177726)
			(xy 221.098728 -273.152635) (xy 221.051365 -273.12007) (xy 221.030038 -273.1008) (xy 221.022926 -273.094196)
			(xy 221.0054 -273.087084) (xy 220.915992 -273.087084) (xy 220.898466 -273.094196) (xy 220.891354 -273.1008)
			(xy 220.870019 -273.120062) (xy 220.82266 -273.152632) (xy 220.770951 -273.177727) (xy 220.716061 -273.194779)
			(xy 220.659235 -273.203403) (xy 220.630496 -273.203924) (xy 220.603245 -273.203426) (xy 220.549299 -273.195669)
			(xy 220.497005 -273.180315) (xy 220.447429 -273.157674) (xy 220.40158 -273.128209) (xy 220.36039 -273.092519)
			(xy 220.324698 -273.05133) (xy 220.295232 -273.005481) (xy 220.27259 -272.955906) (xy 220.257233 -272.903613)
			(xy 220.249475 -272.849667) (xy 220.248988 -272.822416) (xy 210.09336 -272.822416) (xy 210.065828 -272.885646)
			(xy 209.980663 -273.061172) (xy 209.888365 -273.233055) (xy 209.789087 -273.401002) (xy 209.682998 -273.564733)
			(xy 209.570277 -273.72397) (xy 209.49414 -273.822668) (xy 227.662992 -273.822668) (xy 227.667063 -273.767046)
			(xy 227.679189 -273.712609) (xy 227.699112 -273.660518) (xy 227.726408 -273.611883) (xy 227.760494 -273.56774)
			(xy 227.800643 -273.529031) (xy 227.846001 -273.49658) (xy 227.895601 -273.471079) (xy 227.948385 -273.453072)
			(xy 228.003228 -273.442942) (xy 228.058962 -273.440905) (xy 228.114399 -273.447005) (xy 228.168356 -273.461111)
			(xy 228.219685 -273.482923) (xy 228.267291 -273.511977) (xy 228.310159 -273.547652) (xy 228.347376 -273.589189)
			(xy 228.378149 -273.635702) (xy 228.401821 -273.686199) (xy 228.417889 -273.739606) (xy 228.426009 -273.794782)
			(xy 228.426518 -273.822668) (xy 228.426393 -273.829526) (xy 228.564946 -273.829526) (xy 228.569017 -273.773904)
			(xy 228.581143 -273.719467) (xy 228.601066 -273.667376) (xy 228.628362 -273.618741) (xy 228.662448 -273.574598)
			(xy 228.702597 -273.535889) (xy 228.747955 -273.503438) (xy 228.797555 -273.477937) (xy 228.850339 -273.45993)
			(xy 228.905182 -273.4498) (xy 228.960916 -273.447763) (xy 229.016353 -273.453863) (xy 229.07031 -273.467969)
			(xy 229.121639 -273.489781) (xy 229.169245 -273.518835) (xy 229.212113 -273.55451) (xy 229.24933 -273.596047)
			(xy 229.280103 -273.64256) (xy 229.303775 -273.693057) (xy 229.319843 -273.746464) (xy 229.327963 -273.80164)
			(xy 229.328472 -273.829526) (xy 229.327963 -273.857412) (xy 229.319843 -273.912588) (xy 229.303775 -273.965995)
			(xy 229.280103 -274.016492) (xy 229.24933 -274.063005) (xy 229.212113 -274.104542) (xy 229.169245 -274.140217)
			(xy 229.121639 -274.169271) (xy 229.07031 -274.191083) (xy 229.016353 -274.205189) (xy 228.960916 -274.211289)
			(xy 228.905182 -274.209252) (xy 228.850339 -274.199122) (xy 228.797555 -274.181115) (xy 228.747955 -274.155614)
			(xy 228.702597 -274.123163) (xy 228.662448 -274.084454) (xy 228.628362 -274.040311) (xy 228.601066 -273.991676)
			(xy 228.581143 -273.939585) (xy 228.569017 -273.885148) (xy 228.564946 -273.829526) (xy 228.426393 -273.829526)
			(xy 228.426009 -273.850554) (xy 228.417889 -273.90573) (xy 228.401821 -273.959137) (xy 228.378149 -274.009634)
			(xy 228.347376 -274.056147) (xy 228.310159 -274.097684) (xy 228.267291 -274.133359) (xy 228.219685 -274.162413)
			(xy 228.168356 -274.184225) (xy 228.114399 -274.198331) (xy 228.058962 -274.204431) (xy 228.003228 -274.202394)
			(xy 227.948385 -274.192264) (xy 227.895601 -274.174257) (xy 227.846001 -274.148756) (xy 227.800643 -274.116305)
			(xy 227.760494 -274.077596) (xy 227.726408 -274.033453) (xy 227.699112 -273.984818) (xy 227.679189 -273.932727)
			(xy 227.667063 -273.87829) (xy 227.662992 -273.822668) (xy 209.49414 -273.822668) (xy 209.451113 -273.878444)
			(xy 209.325708 -274.027897) (xy 209.194272 -274.172075) (xy 209.057028 -274.310735) (xy 208.914207 -274.443643)
			(xy 208.76605 -274.570577) (xy 208.687239 -274.632674) (xy 226.694998 -274.632674) (xy 226.699069 -274.577052)
			(xy 226.711195 -274.522615) (xy 226.731118 -274.470524) (xy 226.758414 -274.421889) (xy 226.7925 -274.377746)
			(xy 226.832649 -274.339037) (xy 226.878007 -274.306586) (xy 226.927607 -274.281085) (xy 226.980391 -274.263078)
			(xy 227.035234 -274.252948) (xy 227.090968 -274.250911) (xy 227.146405 -274.257011) (xy 227.200362 -274.271117)
			(xy 227.251691 -274.292929) (xy 227.299297 -274.321983) (xy 227.342165 -274.357658) (xy 227.379382 -274.399195)
			(xy 227.410155 -274.445708) (xy 227.433827 -274.496205) (xy 227.449895 -274.549612) (xy 227.458015 -274.604788)
			(xy 227.458524 -274.632674) (xy 227.458015 -274.66056) (xy 227.449895 -274.715736) (xy 227.434154 -274.768056)
			(xy 228.824788 -274.768056) (xy 228.828859 -274.712434) (xy 228.840985 -274.657997) (xy 228.860908 -274.605906)
			(xy 228.888204 -274.557271) (xy 228.92229 -274.513128) (xy 228.962439 -274.474419) (xy 229.007797 -274.441968)
			(xy 229.057397 -274.416467) (xy 229.110181 -274.39846) (xy 229.165024 -274.38833) (xy 229.220758 -274.386293)
			(xy 229.276195 -274.392393) (xy 229.330152 -274.406499) (xy 229.381481 -274.428311) (xy 229.429087 -274.457365)
			(xy 229.471955 -274.49304) (xy 229.509172 -274.534577) (xy 229.539945 -274.58109) (xy 229.563617 -274.631587)
			(xy 229.579685 -274.684994) (xy 229.587805 -274.74017) (xy 229.588314 -274.768056) (xy 229.587805 -274.795942)
			(xy 229.579685 -274.851118) (xy 229.563617 -274.904525) (xy 229.539945 -274.955022) (xy 229.509172 -275.001535)
			(xy 229.471955 -275.043072) (xy 229.429087 -275.078747) (xy 229.381481 -275.107801) (xy 229.330152 -275.129613)
			(xy 229.276195 -275.143719) (xy 229.220758 -275.149819) (xy 229.165024 -275.147782) (xy 229.110181 -275.137652)
			(xy 229.057397 -275.119645) (xy 229.007797 -275.094144) (xy 228.962439 -275.061693) (xy 228.92229 -275.022984)
			(xy 228.888204 -274.978841) (xy 228.860908 -274.930206) (xy 228.840985 -274.878115) (xy 228.828859 -274.823678)
			(xy 228.824788 -274.768056) (xy 227.434154 -274.768056) (xy 227.433827 -274.769143) (xy 227.410155 -274.81964)
			(xy 227.379382 -274.866153) (xy 227.342165 -274.90769) (xy 227.299297 -274.943365) (xy 227.251691 -274.972419)
			(xy 227.200362 -274.994231) (xy 227.146405 -275.008337) (xy 227.090968 -275.014437) (xy 227.035234 -275.0124)
			(xy 226.980391 -275.00227) (xy 226.927607 -274.984263) (xy 226.878007 -274.958762) (xy 226.832649 -274.926311)
			(xy 226.7925 -274.887602) (xy 226.758414 -274.843459) (xy 226.731118 -274.794824) (xy 226.711195 -274.742733)
			(xy 226.699069 -274.688296) (xy 226.694998 -274.632674) (xy 208.687239 -274.632674) (xy 208.612807 -274.69132)
			(xy 208.454736 -274.80567) (xy 208.292103 -274.913435) (xy 208.125184 -275.014431) (xy 207.954258 -275.10849)
			(xy 207.779615 -275.195452) (xy 207.601549 -275.27517) (xy 207.420361 -275.347511) (xy 207.236355 -275.412352)
			(xy 207.049842 -275.469584) (xy 206.861137 -275.519111) (xy 206.800201 -275.532456) (xy 223.168119 -275.532456)
			(xy 223.168119 -275.477944) (xy 223.175877 -275.423987) (xy 223.191235 -275.371684) (xy 223.21388 -275.322098)
			(xy 223.243352 -275.27624) (xy 223.27905 -275.235043) (xy 223.320248 -275.199346) (xy 223.366107 -275.169876)
			(xy 223.415693 -275.147231) (xy 223.467997 -275.131875) (xy 223.521954 -275.124118) (xy 223.54921 -275.123656)
			(xy 223.576581 -275.124103) (xy 223.630762 -275.131923) (xy 223.683265 -275.147416) (xy 223.733012 -275.170262)
			(xy 223.778977 -275.199992) (xy 223.799908 -275.217636) (xy 223.80702 -275.223732) (xy 223.824038 -275.230082)
			(xy 223.909382 -275.230082) (xy 223.9264 -275.223732) (xy 223.933512 -275.217636) (xy 223.954471 -275.20003)
			(xy 224.000436 -275.170312) (xy 224.050176 -275.147469) (xy 224.102671 -275.13197) (xy 224.156843 -275.124134)
			(xy 224.18421 -275.123656) (xy 224.211458 -275.124215) (xy 224.2654 -275.131972) (xy 224.317688 -275.147326)
			(xy 224.367259 -275.169966) (xy 224.413104 -275.19943) (xy 224.419458 -275.204936) (xy 230.320594 -275.204936)
			(xy 230.324665 -275.149314) (xy 230.336791 -275.094877) (xy 230.356714 -275.042786) (xy 230.38401 -274.994151)
			(xy 230.418096 -274.950008) (xy 230.458245 -274.911299) (xy 230.503603 -274.878848) (xy 230.553203 -274.853347)
			(xy 230.605987 -274.83534) (xy 230.66083 -274.82521) (xy 230.716564 -274.823173) (xy 230.772001 -274.829273)
			(xy 230.825958 -274.843379) (xy 230.877287 -274.865191) (xy 230.924893 -274.894245) (xy 230.967761 -274.92992)
			(xy 231.004978 -274.971457) (xy 231.035751 -275.01797) (xy 231.059423 -275.068467) (xy 231.075491 -275.121874)
			(xy 231.083611 -275.17705) (xy 231.08412 -275.204936) (xy 231.083611 -275.232822) (xy 231.075491 -275.287998)
			(xy 231.059423 -275.341405) (xy 231.035751 -275.391902) (xy 231.004978 -275.438415) (xy 230.967761 -275.479952)
			(xy 230.924893 -275.515627) (xy 230.877287 -275.544681) (xy 230.825958 -275.566493) (xy 230.772001 -275.580599)
			(xy 230.716564 -275.586699) (xy 230.66083 -275.584662) (xy 230.605987 -275.574532) (xy 230.553203 -275.556525)
			(xy 230.503603 -275.531024) (xy 230.458245 -275.498573) (xy 230.418096 -275.459864) (xy 230.38401 -275.415721)
			(xy 230.356714 -275.367086) (xy 230.336791 -275.314995) (xy 230.324665 -275.260558) (xy 230.320594 -275.204936)
			(xy 224.419458 -275.204936) (xy 224.454289 -275.235118) (xy 224.489976 -275.276304) (xy 224.519439 -275.322149)
			(xy 224.542077 -275.371721) (xy 224.55743 -275.42401) (xy 224.565186 -275.477952) (xy 224.565186 -275.532448)
			(xy 224.55743 -275.58639) (xy 224.542077 -275.638679) (xy 224.519439 -275.688251) (xy 224.489976 -275.734096)
			(xy 224.454289 -275.775282) (xy 224.413104 -275.81097) (xy 224.367259 -275.840434) (xy 224.317688 -275.863074)
			(xy 224.2654 -275.878428) (xy 224.211458 -275.886185) (xy 224.18421 -275.886672) (xy 224.15684 -275.886207)
			(xy 224.10266 -275.87839) (xy 224.050157 -275.862901) (xy 224.00041 -275.840059) (xy 223.954443 -275.810334)
			(xy 223.933512 -275.792692) (xy 223.9264 -275.786596) (xy 223.909382 -275.780246) (xy 223.824038 -275.780246)
			(xy 223.80702 -275.786596) (xy 223.799908 -275.792692) (xy 223.778983 -275.81034) (xy 223.733008 -275.84005)
			(xy 223.683259 -275.862885) (xy 223.630757 -275.878374) (xy 223.57658 -275.886199) (xy 223.54921 -275.886672)
			(xy 223.521954 -275.886282) (xy 223.467997 -275.878525) (xy 223.415693 -275.863169) (xy 223.366107 -275.840524)
			(xy 223.320248 -275.811054) (xy 223.27905 -275.775357) (xy 223.243352 -275.73416) (xy 223.21388 -275.688302)
			(xy 223.191235 -275.638716) (xy 223.175877 -275.586413) (xy 223.168119 -275.532456) (xy 206.800201 -275.532456)
			(xy 206.670558 -275.560848) (xy 206.478425 -275.594726) (xy 206.285064 -275.620688) (xy 206.0908 -275.638689)
			(xy 205.895961 -275.6487) (xy 205.700875 -275.650703) (xy 205.505872 -275.644695) (xy 205.311279 -275.630686)
			(xy 205.117426 -275.6087) (xy 204.924639 -275.578774) (xy 204.733242 -275.540958) (xy 204.54356 -275.495316)
			(xy 204.355912 -275.441926) (xy 204.170613 -275.380876) (xy 203.987978 -275.312271) (xy 203.808313 -275.236225)
			(xy 203.631921 -275.152867) (xy 203.4591 -275.062338) (xy 203.290142 -274.96479) (xy 203.125331 -274.860387)
			(xy 202.964945 -274.749307) (xy 202.809255 -274.631735) (xy 202.658523 -274.507871) (xy 202.513004 -274.377922)
			(xy 202.372942 -274.242109) (xy 202.238574 -274.10066) (xy 202.110127 -273.953814) (xy 201.987816 -273.801819)
			(xy 201.871849 -273.64493) (xy 201.762421 -273.483412) (xy 201.659716 -273.317538) (xy 201.563908 -273.147587)
			(xy 201.475157 -272.973846) (xy 201.393615 -272.796608) (xy 201.319418 -272.616172) (xy 201.252691 -272.432841)
			(xy 201.193547 -272.246926) (xy 201.142086 -272.058739) (xy 201.098394 -271.868599) (xy 201.062545 -271.676824)
			(xy 201.0346 -271.48374) (xy 201.014605 -271.289671) (xy 201.002595 -271.094945) (xy 200.998589 -270.89989)
			(xy 176.905666 -270.89989) (xy 176.905666 -272.225008) (xy 176.90592 -272.228564) (xy 176.90592 -272.230088)
			(xy 176.907322 -272.24173) (xy 176.919098 -272.261977) (xy 176.928526 -272.26895) (xy 176.9745 -272.29943)
			(xy 176.975008 -272.29943) (xy 176.994058 -272.312384) (xy 177.000191 -272.316965) (xy 177.014398 -272.322643)
			(xy 177.021998 -272.32356) (xy 177.028348 -272.324068) (xy 177.040794 -272.32229) (xy 177.04689 -272.31975)
			(xy 177.067199 -272.311625) (xy 177.10942 -272.300195) (xy 177.152781 -272.29444) (xy 177.174652 -272.294096)
			(xy 177.174906 -272.294096) (xy 177.188497 -272.294265) (xy 177.215582 -272.296551) (xy 177.229008 -272.298668)
			(xy 177.2412 -272.300446) (xy 177.263552 -272.293588) (xy 177.340006 -272.220436) (xy 177.34788 -272.198338)
			(xy 177.34661 -272.186146) (xy 177.345555 -272.177039) (xy 177.344409 -272.158738) (xy 177.344324 -272.14957)
			(xy 177.344812 -272.124753) (xy 177.352847 -272.075773) (xy 177.368699 -272.028738) (xy 177.391951 -271.984887)
			(xy 177.421992 -271.945376) (xy 177.458028 -271.911245) (xy 177.499112 -271.883393) (xy 177.544159 -271.862554)
			(xy 177.591985 -271.849278) (xy 177.641329 -271.843913) (xy 177.69089 -271.846601) (xy 177.739364 -271.857272)
			(xy 177.785473 -271.875645) (xy 177.828002 -271.901234) (xy 177.865832 -271.933367) (xy 177.897965 -271.971196)
			(xy 177.923554 -272.013725) (xy 177.941927 -272.059834) (xy 177.952598 -272.108308) (xy 177.954837 -272.14957)
			(xy 179.244002 -272.14957) (xy 179.247962 -272.100516) (xy 179.259739 -272.052732) (xy 179.27903 -272.007456)
			(xy 179.305333 -271.96586) (xy 179.337968 -271.929023) (xy 179.376089 -271.897898) (xy 179.41871 -271.873291)
			(xy 179.464726 -271.855839) (xy 179.512945 -271.845995) (xy 179.56212 -271.844014) (xy 179.610975 -271.849946)
			(xy 179.658246 -271.863638) (xy 179.702708 -271.884736) (xy 179.743211 -271.912692) (xy 179.778704 -271.946784)
			(xy 179.808269 -271.986128) (xy 179.83114 -272.029705) (xy 179.846724 -272.076386) (xy 179.854619 -272.124963)
			(xy 179.855114 -272.14957) (xy 181.143922 -272.14957) (xy 181.147882 -272.100516) (xy 181.159659 -272.052732)
			(xy 181.17895 -272.007456) (xy 181.205253 -271.96586) (xy 181.237888 -271.929023) (xy 181.276009 -271.897898)
			(xy 181.31863 -271.873291) (xy 181.364646 -271.855839) (xy 181.412865 -271.845995) (xy 181.46204 -271.844014)
			(xy 181.510895 -271.849946) (xy 181.558166 -271.863638) (xy 181.602628 -271.884736) (xy 181.643131 -271.912692)
			(xy 181.678624 -271.946784) (xy 181.708189 -271.986128) (xy 181.73106 -272.029705) (xy 181.746644 -272.076386)
			(xy 181.754539 -272.124963) (xy 181.755034 -272.14957) (xy 183.043842 -272.14957) (xy 183.047802 -272.100516)
			(xy 183.059579 -272.052732) (xy 183.07887 -272.007456) (xy 183.105173 -271.96586) (xy 183.137808 -271.929023)
			(xy 183.175929 -271.897898) (xy 183.21855 -271.873291) (xy 183.264566 -271.855839) (xy 183.312785 -271.845995)
			(xy 183.36196 -271.844014) (xy 183.410815 -271.849946) (xy 183.458086 -271.863638) (xy 183.502548 -271.884736)
			(xy 183.543051 -271.912692) (xy 183.578544 -271.946784) (xy 183.608109 -271.986128) (xy 183.63098 -272.029705)
			(xy 183.646564 -272.076386) (xy 183.654459 -272.124963) (xy 183.654954 -272.14957) (xy 184.944016 -272.14957)
			(xy 184.947976 -272.100516) (xy 184.959753 -272.052732) (xy 184.979044 -272.007456) (xy 185.005347 -271.96586)
			(xy 185.037982 -271.929023) (xy 185.076103 -271.897898) (xy 185.118724 -271.873291) (xy 185.16474 -271.855839)
			(xy 185.212959 -271.845995) (xy 185.262134 -271.844014) (xy 185.310989 -271.849946) (xy 185.35826 -271.863638)
			(xy 185.402722 -271.884736) (xy 185.443225 -271.912692) (xy 185.478718 -271.946784) (xy 185.508283 -271.986128)
			(xy 185.531154 -272.029705) (xy 185.546738 -272.076386) (xy 185.554633 -272.124963) (xy 185.555128 -272.14957)
			(xy 186.843936 -272.14957) (xy 186.847896 -272.100516) (xy 186.859673 -272.052732) (xy 186.878964 -272.007456)
			(xy 186.905267 -271.96586) (xy 186.937902 -271.929023) (xy 186.976023 -271.897898) (xy 187.018644 -271.873291)
			(xy 187.06466 -271.855839) (xy 187.112879 -271.845995) (xy 187.162054 -271.844014) (xy 187.210909 -271.849946)
			(xy 187.25818 -271.863638) (xy 187.302642 -271.884736) (xy 187.343145 -271.912692) (xy 187.378638 -271.946784)
			(xy 187.408203 -271.986128) (xy 187.431074 -272.029705) (xy 187.446658 -272.076386) (xy 187.454553 -272.124963)
			(xy 187.455048 -272.14957) (xy 188.743856 -272.14957) (xy 188.747816 -272.100516) (xy 188.759593 -272.052732)
			(xy 188.778884 -272.007456) (xy 188.805187 -271.96586) (xy 188.837822 -271.929023) (xy 188.875943 -271.897898)
			(xy 188.918564 -271.873291) (xy 188.96458 -271.855839) (xy 189.012799 -271.845995) (xy 189.061974 -271.844014)
			(xy 189.110829 -271.849946) (xy 189.1581 -271.863638) (xy 189.202562 -271.884736) (xy 189.243065 -271.912692)
			(xy 189.278558 -271.946784) (xy 189.308123 -271.986128) (xy 189.330994 -272.029705) (xy 189.346578 -272.076386)
			(xy 189.354473 -272.124963) (xy 189.354968 -272.14957) (xy 190.64403 -272.14957) (xy 190.64799 -272.100516)
			(xy 190.659767 -272.052732) (xy 190.679058 -272.007456) (xy 190.705361 -271.96586) (xy 190.737996 -271.929023)
			(xy 190.776117 -271.897898) (xy 190.818738 -271.873291) (xy 190.864754 -271.855839) (xy 190.912973 -271.845995)
			(xy 190.962148 -271.844014) (xy 191.011003 -271.849946) (xy 191.058274 -271.863638) (xy 191.102736 -271.884736)
			(xy 191.143239 -271.912692) (xy 191.178732 -271.946784) (xy 191.208297 -271.986128) (xy 191.231168 -272.029705)
			(xy 191.246752 -272.076386) (xy 191.254647 -272.124963) (xy 191.255142 -272.14957) (xy 192.544204 -272.14957)
			(xy 192.548164 -272.100516) (xy 192.559941 -272.052732) (xy 192.579232 -272.007456) (xy 192.605535 -271.96586)
			(xy 192.63817 -271.929023) (xy 192.676291 -271.897898) (xy 192.718912 -271.873291) (xy 192.764928 -271.855839)
			(xy 192.813147 -271.845995) (xy 192.862322 -271.844014) (xy 192.911177 -271.849946) (xy 192.958448 -271.863638)
			(xy 193.00291 -271.884736) (xy 193.043413 -271.912692) (xy 193.078906 -271.946784) (xy 193.108471 -271.986128)
			(xy 193.131342 -272.029705) (xy 193.146926 -272.076386) (xy 193.154821 -272.124963) (xy 193.155316 -272.14957)
			(xy 194.444124 -272.14957) (xy 194.448084 -272.100516) (xy 194.459861 -272.052732) (xy 194.479152 -272.007456)
			(xy 194.505455 -271.96586) (xy 194.53809 -271.929023) (xy 194.576211 -271.897898) (xy 194.618832 -271.873291)
			(xy 194.664848 -271.855839) (xy 194.713067 -271.845995) (xy 194.762242 -271.844014) (xy 194.811097 -271.849946)
			(xy 194.858368 -271.863638) (xy 194.90283 -271.884736) (xy 194.943333 -271.912692) (xy 194.978826 -271.946784)
			(xy 195.008391 -271.986128) (xy 195.031262 -272.029705) (xy 195.046846 -272.076386) (xy 195.054741 -272.124963)
			(xy 195.055236 -272.14957) (xy 196.344044 -272.14957) (xy 196.348004 -272.100516) (xy 196.359781 -272.052732)
			(xy 196.379072 -272.007456) (xy 196.405375 -271.96586) (xy 196.43801 -271.929023) (xy 196.476131 -271.897898)
			(xy 196.518752 -271.873291) (xy 196.564768 -271.855839) (xy 196.612987 -271.845995) (xy 196.662162 -271.844014)
			(xy 196.711017 -271.849946) (xy 196.758288 -271.863638) (xy 196.80275 -271.884736) (xy 196.843253 -271.912692)
			(xy 196.878746 -271.946784) (xy 196.908311 -271.986128) (xy 196.931182 -272.029705) (xy 196.946766 -272.076386)
			(xy 196.954661 -272.124963) (xy 196.955156 -272.14957) (xy 196.954661 -272.174177) (xy 196.946766 -272.222754)
			(xy 196.931182 -272.269435) (xy 196.908311 -272.313012) (xy 196.878746 -272.352356) (xy 196.843253 -272.386448)
			(xy 196.80275 -272.414404) (xy 196.758288 -272.435502) (xy 196.711017 -272.449194) (xy 196.662162 -272.455126)
			(xy 196.612987 -272.453145) (xy 196.564768 -272.443301) (xy 196.518752 -272.425849) (xy 196.476131 -272.401242)
			(xy 196.43801 -272.370117) (xy 196.405375 -272.33328) (xy 196.379072 -272.291684) (xy 196.359781 -272.246408)
			(xy 196.348004 -272.198624) (xy 196.344044 -272.14957) (xy 195.055236 -272.14957) (xy 195.054741 -272.174177)
			(xy 195.046846 -272.222754) (xy 195.031262 -272.269435) (xy 195.008391 -272.313012) (xy 194.978826 -272.352356)
			(xy 194.943333 -272.386448) (xy 194.90283 -272.414404) (xy 194.858368 -272.435502) (xy 194.811097 -272.449194)
			(xy 194.762242 -272.455126) (xy 194.713067 -272.453145) (xy 194.664848 -272.443301) (xy 194.618832 -272.425849)
			(xy 194.576211 -272.401242) (xy 194.53809 -272.370117) (xy 194.505455 -272.33328) (xy 194.479152 -272.291684)
			(xy 194.459861 -272.246408) (xy 194.448084 -272.198624) (xy 194.444124 -272.14957) (xy 193.155316 -272.14957)
			(xy 193.154821 -272.174177) (xy 193.146926 -272.222754) (xy 193.131342 -272.269435) (xy 193.108471 -272.313012)
			(xy 193.078906 -272.352356) (xy 193.043413 -272.386448) (xy 193.00291 -272.414404) (xy 192.958448 -272.435502)
			(xy 192.911177 -272.449194) (xy 192.862322 -272.455126) (xy 192.813147 -272.453145) (xy 192.764928 -272.443301)
			(xy 192.718912 -272.425849) (xy 192.676291 -272.401242) (xy 192.63817 -272.370117) (xy 192.605535 -272.33328)
			(xy 192.579232 -272.291684) (xy 192.559941 -272.246408) (xy 192.548164 -272.198624) (xy 192.544204 -272.14957)
			(xy 191.255142 -272.14957) (xy 191.254647 -272.174177) (xy 191.246752 -272.222754) (xy 191.231168 -272.269435)
			(xy 191.208297 -272.313012) (xy 191.178732 -272.352356) (xy 191.143239 -272.386448) (xy 191.102736 -272.414404)
			(xy 191.058274 -272.435502) (xy 191.011003 -272.449194) (xy 190.962148 -272.455126) (xy 190.912973 -272.453145)
			(xy 190.864754 -272.443301) (xy 190.818738 -272.425849) (xy 190.776117 -272.401242) (xy 190.737996 -272.370117)
			(xy 190.705361 -272.33328) (xy 190.679058 -272.291684) (xy 190.659767 -272.246408) (xy 190.64799 -272.198624)
			(xy 190.64403 -272.14957) (xy 189.354968 -272.14957) (xy 189.354473 -272.174177) (xy 189.346578 -272.222754)
			(xy 189.330994 -272.269435) (xy 189.308123 -272.313012) (xy 189.278558 -272.352356) (xy 189.243065 -272.386448)
			(xy 189.202562 -272.414404) (xy 189.1581 -272.435502) (xy 189.110829 -272.449194) (xy 189.061974 -272.455126)
			(xy 189.012799 -272.453145) (xy 188.96458 -272.443301) (xy 188.918564 -272.425849) (xy 188.875943 -272.401242)
			(xy 188.837822 -272.370117) (xy 188.805187 -272.33328) (xy 188.778884 -272.291684) (xy 188.759593 -272.246408)
			(xy 188.747816 -272.198624) (xy 188.743856 -272.14957) (xy 187.455048 -272.14957) (xy 187.454553 -272.174177)
			(xy 187.446658 -272.222754) (xy 187.431074 -272.269435) (xy 187.408203 -272.313012) (xy 187.378638 -272.352356)
			(xy 187.343145 -272.386448) (xy 187.302642 -272.414404) (xy 187.25818 -272.435502) (xy 187.210909 -272.449194)
			(xy 187.162054 -272.455126) (xy 187.112879 -272.453145) (xy 187.06466 -272.443301) (xy 187.018644 -272.425849)
			(xy 186.976023 -272.401242) (xy 186.937902 -272.370117) (xy 186.905267 -272.33328) (xy 186.878964 -272.291684)
			(xy 186.859673 -272.246408) (xy 186.847896 -272.198624) (xy 186.843936 -272.14957) (xy 185.555128 -272.14957)
			(xy 185.554633 -272.174177) (xy 185.546738 -272.222754) (xy 185.531154 -272.269435) (xy 185.508283 -272.313012)
			(xy 185.478718 -272.352356) (xy 185.443225 -272.386448) (xy 185.402722 -272.414404) (xy 185.35826 -272.435502)
			(xy 185.310989 -272.449194) (xy 185.262134 -272.455126) (xy 185.212959 -272.453145) (xy 185.16474 -272.443301)
			(xy 185.118724 -272.425849) (xy 185.076103 -272.401242) (xy 185.037982 -272.370117) (xy 185.005347 -272.33328)
			(xy 184.979044 -272.291684) (xy 184.959753 -272.246408) (xy 184.947976 -272.198624) (xy 184.944016 -272.14957)
			(xy 183.654954 -272.14957) (xy 183.654459 -272.174177) (xy 183.646564 -272.222754) (xy 183.63098 -272.269435)
			(xy 183.608109 -272.313012) (xy 183.578544 -272.352356) (xy 183.543051 -272.386448) (xy 183.502548 -272.414404)
			(xy 183.458086 -272.435502) (xy 183.410815 -272.449194) (xy 183.36196 -272.455126) (xy 183.312785 -272.453145)
			(xy 183.264566 -272.443301) (xy 183.21855 -272.425849) (xy 183.175929 -272.401242) (xy 183.137808 -272.370117)
			(xy 183.105173 -272.33328) (xy 183.07887 -272.291684) (xy 183.059579 -272.246408) (xy 183.047802 -272.198624)
			(xy 183.043842 -272.14957) (xy 181.755034 -272.14957) (xy 181.754539 -272.174177) (xy 181.746644 -272.222754)
			(xy 181.73106 -272.269435) (xy 181.708189 -272.313012) (xy 181.678624 -272.352356) (xy 181.643131 -272.386448)
			(xy 181.602628 -272.414404) (xy 181.558166 -272.435502) (xy 181.510895 -272.449194) (xy 181.46204 -272.455126)
			(xy 181.412865 -272.453145) (xy 181.364646 -272.443301) (xy 181.31863 -272.425849) (xy 181.276009 -272.401242)
			(xy 181.237888 -272.370117) (xy 181.205253 -272.33328) (xy 181.17895 -272.291684) (xy 181.159659 -272.246408)
			(xy 181.147882 -272.198624) (xy 181.143922 -272.14957) (xy 179.855114 -272.14957) (xy 179.854619 -272.174177)
			(xy 179.846724 -272.222754) (xy 179.83114 -272.269435) (xy 179.808269 -272.313012) (xy 179.778704 -272.352356)
			(xy 179.743211 -272.386448) (xy 179.702708 -272.414404) (xy 179.658246 -272.435502) (xy 179.610975 -272.449194)
			(xy 179.56212 -272.455126) (xy 179.512945 -272.453145) (xy 179.464726 -272.443301) (xy 179.41871 -272.425849)
			(xy 179.376089 -272.401242) (xy 179.337968 -272.370117) (xy 179.305333 -272.33328) (xy 179.27903 -272.291684)
			(xy 179.259739 -272.246408) (xy 179.247962 -272.198624) (xy 179.244002 -272.14957) (xy 177.954837 -272.14957)
			(xy 177.955287 -272.157869) (xy 177.949923 -272.207213) (xy 177.936647 -272.255039) (xy 177.915808 -272.300087)
			(xy 177.887957 -272.34117) (xy 177.853826 -272.377207) (xy 177.814314 -272.407248) (xy 177.770464 -272.4305)
			(xy 177.723429 -272.446353) (xy 177.674449 -272.454388) (xy 177.649632 -272.454878) (xy 177.640528 -272.454779)
			(xy 177.622355 -272.453634) (xy 177.61331 -272.452592) (xy 177.601372 -272.451322) (xy 177.57902 -272.459196)
			(xy 177.506122 -272.53565) (xy 177.49901 -272.558256) (xy 177.501042 -272.570448) (xy 177.503173 -272.583936)
			(xy 177.50546 -272.611149) (xy 177.505614 -272.624804) (xy 177.505571 -272.634158) (xy 177.504554 -272.652838)
			(xy 177.503582 -272.662142) (xy 177.502312 -272.673572) (xy 177.509678 -272.695416) (xy 177.582068 -272.76806)
			(xy 177.603658 -272.775934) (xy 177.615088 -272.774664) (xy 177.649632 -272.772632) (xy 177.675339 -272.773138)
			(xy 177.72612 -272.781186) (xy 177.775018 -272.797078) (xy 177.820827 -272.820423) (xy 177.862421 -272.850646)
			(xy 177.898775 -272.887004) (xy 177.928994 -272.9286) (xy 177.952334 -272.974412) (xy 177.968221 -273.023311)
			(xy 177.976264 -273.074093) (xy 177.976264 -273.099784) (xy 178.294042 -273.099784) (xy 178.298002 -273.05073)
			(xy 178.309779 -273.002946) (xy 178.32907 -272.95767) (xy 178.355373 -272.916074) (xy 178.388008 -272.879237)
			(xy 178.426129 -272.848112) (xy 178.46875 -272.823505) (xy 178.514766 -272.806053) (xy 178.562985 -272.796209)
			(xy 178.61216 -272.794228) (xy 178.661015 -272.80016) (xy 178.708286 -272.813852) (xy 178.752748 -272.83495)
			(xy 178.793251 -272.862906) (xy 178.828744 -272.896998) (xy 178.858309 -272.936342) (xy 178.88118 -272.979919)
			(xy 178.896764 -273.0266) (xy 178.904659 -273.075177) (xy 178.905154 -273.099784) (xy 178.904659 -273.124391)
			(xy 178.90448 -273.125492) (xy 179.223158 -273.125492) (xy 179.223158 -273.074076) (xy 179.231201 -273.023294)
			(xy 179.247089 -272.974395) (xy 179.270432 -272.928583) (xy 179.300653 -272.886987) (xy 179.337009 -272.850631)
			(xy 179.378605 -272.82041) (xy 179.424417 -272.797067) (xy 179.473316 -272.781179) (xy 179.524098 -272.773136)
			(xy 179.575514 -272.773136) (xy 179.626296 -272.781179) (xy 179.675195 -272.797067) (xy 179.721007 -272.82041)
			(xy 179.762603 -272.850631) (xy 179.798959 -272.886987) (xy 179.82918 -272.928583) (xy 179.852523 -272.974395)
			(xy 179.868411 -273.023294) (xy 179.876454 -273.074076) (xy 179.876958 -273.099784) (xy 180.194216 -273.099784)
			(xy 180.198176 -273.05073) (xy 180.209953 -273.002946) (xy 180.229244 -272.95767) (xy 180.255547 -272.916074)
			(xy 180.288182 -272.879237) (xy 180.326303 -272.848112) (xy 180.368924 -272.823505) (xy 180.41494 -272.806053)
			(xy 180.463159 -272.796209) (xy 180.512334 -272.794228) (xy 180.561189 -272.80016) (xy 180.60846 -272.813852)
			(xy 180.652922 -272.83495) (xy 180.693425 -272.862906) (xy 180.728918 -272.896998) (xy 180.758483 -272.936342)
			(xy 180.781354 -272.979919) (xy 180.796938 -273.0266) (xy 180.804833 -273.075177) (xy 180.805328 -273.099784)
			(xy 180.804833 -273.124391) (xy 180.804654 -273.125492) (xy 181.123078 -273.125492) (xy 181.123078 -273.074076)
			(xy 181.131121 -273.023294) (xy 181.147009 -272.974395) (xy 181.170352 -272.928583) (xy 181.200573 -272.886987)
			(xy 181.236929 -272.850631) (xy 181.278525 -272.82041) (xy 181.324337 -272.797067) (xy 181.373236 -272.781179)
			(xy 181.424018 -272.773136) (xy 181.475434 -272.773136) (xy 181.526216 -272.781179) (xy 181.575115 -272.797067)
			(xy 181.620927 -272.82041) (xy 181.662523 -272.850631) (xy 181.698879 -272.886987) (xy 181.7291 -272.928583)
			(xy 181.752443 -272.974395) (xy 181.768331 -273.023294) (xy 181.776374 -273.074076) (xy 181.776878 -273.099784)
			(xy 182.094136 -273.099784) (xy 182.098096 -273.05073) (xy 182.109873 -273.002946) (xy 182.129164 -272.95767)
			(xy 182.155467 -272.916074) (xy 182.188102 -272.879237) (xy 182.226223 -272.848112) (xy 182.268844 -272.823505)
			(xy 182.31486 -272.806053) (xy 182.363079 -272.796209) (xy 182.412254 -272.794228) (xy 182.461109 -272.80016)
			(xy 182.50838 -272.813852) (xy 182.552842 -272.83495) (xy 182.593345 -272.862906) (xy 182.628838 -272.896998)
			(xy 182.658403 -272.936342) (xy 182.681274 -272.979919) (xy 182.696858 -273.0266) (xy 182.704753 -273.075177)
			(xy 182.705248 -273.099784) (xy 182.704753 -273.124391) (xy 182.704574 -273.125492) (xy 183.022998 -273.125492)
			(xy 183.022998 -273.074076) (xy 183.031041 -273.023294) (xy 183.046929 -272.974395) (xy 183.070272 -272.928583)
			(xy 183.100493 -272.886987) (xy 183.136849 -272.850631) (xy 183.178445 -272.82041) (xy 183.224257 -272.797067)
			(xy 183.273156 -272.781179) (xy 183.323938 -272.773136) (xy 183.375354 -272.773136) (xy 183.426136 -272.781179)
			(xy 183.475035 -272.797067) (xy 183.520847 -272.82041) (xy 183.562443 -272.850631) (xy 183.598799 -272.886987)
			(xy 183.62902 -272.928583) (xy 183.652363 -272.974395) (xy 183.668251 -273.023294) (xy 183.676294 -273.074076)
			(xy 183.676798 -273.099784) (xy 183.994056 -273.099784) (xy 183.998016 -273.05073) (xy 184.009793 -273.002946)
			(xy 184.029084 -272.95767) (xy 184.055387 -272.916074) (xy 184.088022 -272.879237) (xy 184.126143 -272.848112)
			(xy 184.168764 -272.823505) (xy 184.21478 -272.806053) (xy 184.262999 -272.796209) (xy 184.312174 -272.794228)
			(xy 184.361029 -272.80016) (xy 184.4083 -272.813852) (xy 184.452762 -272.83495) (xy 184.493265 -272.862906)
			(xy 184.528758 -272.896998) (xy 184.558323 -272.936342) (xy 184.581194 -272.979919) (xy 184.596778 -273.0266)
			(xy 184.604673 -273.075177) (xy 184.605168 -273.099784) (xy 184.604673 -273.124391) (xy 184.604494 -273.125492)
			(xy 184.923172 -273.125492) (xy 184.923172 -273.074076) (xy 184.931215 -273.023294) (xy 184.947103 -272.974395)
			(xy 184.970446 -272.928583) (xy 185.000667 -272.886987) (xy 185.037023 -272.850631) (xy 185.078619 -272.82041)
			(xy 185.124431 -272.797067) (xy 185.17333 -272.781179) (xy 185.224112 -272.773136) (xy 185.275528 -272.773136)
			(xy 185.32631 -272.781179) (xy 185.375209 -272.797067) (xy 185.421021 -272.82041) (xy 185.462617 -272.850631)
			(xy 185.498973 -272.886987) (xy 185.529194 -272.928583) (xy 185.552537 -272.974395) (xy 185.568425 -273.023294)
			(xy 185.576468 -273.074076) (xy 185.576972 -273.099784) (xy 185.89423 -273.099784) (xy 185.89819 -273.05073)
			(xy 185.909967 -273.002946) (xy 185.929258 -272.95767) (xy 185.955561 -272.916074) (xy 185.988196 -272.879237)
			(xy 186.026317 -272.848112) (xy 186.068938 -272.823505) (xy 186.114954 -272.806053) (xy 186.163173 -272.796209)
			(xy 186.212348 -272.794228) (xy 186.261203 -272.80016) (xy 186.308474 -272.813852) (xy 186.352936 -272.83495)
			(xy 186.393439 -272.862906) (xy 186.428932 -272.896998) (xy 186.458497 -272.936342) (xy 186.481368 -272.979919)
			(xy 186.496952 -273.0266) (xy 186.504847 -273.075177) (xy 186.505342 -273.099784) (xy 186.504847 -273.124391)
			(xy 186.504668 -273.125492) (xy 186.823092 -273.125492) (xy 186.823092 -273.074076) (xy 186.831135 -273.023294)
			(xy 186.847023 -272.974395) (xy 186.870366 -272.928583) (xy 186.900587 -272.886987) (xy 186.936943 -272.850631)
			(xy 186.978539 -272.82041) (xy 187.024351 -272.797067) (xy 187.07325 -272.781179) (xy 187.124032 -272.773136)
			(xy 187.175448 -272.773136) (xy 187.22623 -272.781179) (xy 187.275129 -272.797067) (xy 187.320941 -272.82041)
			(xy 187.362537 -272.850631) (xy 187.398893 -272.886987) (xy 187.429114 -272.928583) (xy 187.452457 -272.974395)
			(xy 187.468345 -273.023294) (xy 187.476388 -273.074076) (xy 187.476892 -273.099784) (xy 187.79415 -273.099784)
			(xy 187.79811 -273.05073) (xy 187.809887 -273.002946) (xy 187.829178 -272.95767) (xy 187.855481 -272.916074)
			(xy 187.888116 -272.879237) (xy 187.926237 -272.848112) (xy 187.968858 -272.823505) (xy 188.014874 -272.806053)
			(xy 188.063093 -272.796209) (xy 188.112268 -272.794228) (xy 188.161123 -272.80016) (xy 188.208394 -272.813852)
			(xy 188.252856 -272.83495) (xy 188.293359 -272.862906) (xy 188.328852 -272.896998) (xy 188.358417 -272.936342)
			(xy 188.381288 -272.979919) (xy 188.396872 -273.0266) (xy 188.404767 -273.075177) (xy 188.405262 -273.099784)
			(xy 188.404767 -273.124391) (xy 188.404588 -273.125492) (xy 188.723012 -273.125492) (xy 188.723012 -273.074076)
			(xy 188.731055 -273.023294) (xy 188.746943 -272.974395) (xy 188.770286 -272.928583) (xy 188.800507 -272.886987)
			(xy 188.836863 -272.850631) (xy 188.878459 -272.82041) (xy 188.924271 -272.797067) (xy 188.97317 -272.781179)
			(xy 189.023952 -272.773136) (xy 189.075368 -272.773136) (xy 189.12615 -272.781179) (xy 189.175049 -272.797067)
			(xy 189.220861 -272.82041) (xy 189.262457 -272.850631) (xy 189.298813 -272.886987) (xy 189.329034 -272.928583)
			(xy 189.352377 -272.974395) (xy 189.368265 -273.023294) (xy 189.376308 -273.074076) (xy 189.376812 -273.099784)
			(xy 189.69407 -273.099784) (xy 189.69803 -273.05073) (xy 189.709807 -273.002946) (xy 189.729098 -272.95767)
			(xy 189.755401 -272.916074) (xy 189.788036 -272.879237) (xy 189.826157 -272.848112) (xy 189.868778 -272.823505)
			(xy 189.914794 -272.806053) (xy 189.963013 -272.796209) (xy 190.012188 -272.794228) (xy 190.061043 -272.80016)
			(xy 190.108314 -272.813852) (xy 190.152776 -272.83495) (xy 190.193279 -272.862906) (xy 190.228772 -272.896998)
			(xy 190.258337 -272.936342) (xy 190.281208 -272.979919) (xy 190.296792 -273.0266) (xy 190.304687 -273.075177)
			(xy 190.305182 -273.099784) (xy 190.304687 -273.124391) (xy 190.304508 -273.125492) (xy 190.623186 -273.125492)
			(xy 190.623186 -273.074076) (xy 190.631229 -273.023294) (xy 190.647117 -272.974395) (xy 190.67046 -272.928583)
			(xy 190.700681 -272.886987) (xy 190.737037 -272.850631) (xy 190.778633 -272.82041) (xy 190.824445 -272.797067)
			(xy 190.873344 -272.781179) (xy 190.924126 -272.773136) (xy 190.975542 -272.773136) (xy 191.026324 -272.781179)
			(xy 191.075223 -272.797067) (xy 191.121035 -272.82041) (xy 191.162631 -272.850631) (xy 191.198987 -272.886987)
			(xy 191.229208 -272.928583) (xy 191.252551 -272.974395) (xy 191.268439 -273.023294) (xy 191.276482 -273.074076)
			(xy 191.276986 -273.099784) (xy 191.594244 -273.099784) (xy 191.598204 -273.05073) (xy 191.609981 -273.002946)
			(xy 191.629272 -272.95767) (xy 191.655575 -272.916074) (xy 191.68821 -272.879237) (xy 191.726331 -272.848112)
			(xy 191.768952 -272.823505) (xy 191.814968 -272.806053) (xy 191.863187 -272.796209) (xy 191.912362 -272.794228)
			(xy 191.961217 -272.80016) (xy 192.008488 -272.813852) (xy 192.05295 -272.83495) (xy 192.093453 -272.862906)
			(xy 192.128946 -272.896998) (xy 192.158511 -272.936342) (xy 192.181382 -272.979919) (xy 192.196966 -273.0266)
			(xy 192.204861 -273.075177) (xy 192.205356 -273.099784) (xy 192.204861 -273.124391) (xy 192.204682 -273.125492)
			(xy 192.523106 -273.125492) (xy 192.523106 -273.074076) (xy 192.531149 -273.023294) (xy 192.547037 -272.974395)
			(xy 192.57038 -272.928583) (xy 192.600601 -272.886987) (xy 192.636957 -272.850631) (xy 192.678553 -272.82041)
			(xy 192.724365 -272.797067) (xy 192.773264 -272.781179) (xy 192.824046 -272.773136) (xy 192.875462 -272.773136)
			(xy 192.926244 -272.781179) (xy 192.975143 -272.797067) (xy 193.020955 -272.82041) (xy 193.062551 -272.850631)
			(xy 193.098907 -272.886987) (xy 193.129128 -272.928583) (xy 193.152471 -272.974395) (xy 193.168359 -273.023294)
			(xy 193.176402 -273.074076) (xy 193.176906 -273.099784) (xy 193.494418 -273.099784) (xy 193.498378 -273.05073)
			(xy 193.510155 -273.002946) (xy 193.529446 -272.95767) (xy 193.555749 -272.916074) (xy 193.588384 -272.879237)
			(xy 193.626505 -272.848112) (xy 193.669126 -272.823505) (xy 193.715142 -272.806053) (xy 193.763361 -272.796209)
			(xy 193.812536 -272.794228) (xy 193.861391 -272.80016) (xy 193.908662 -272.813852) (xy 193.953124 -272.83495)
			(xy 193.993627 -272.862906) (xy 194.02912 -272.896998) (xy 194.058685 -272.936342) (xy 194.081556 -272.979919)
			(xy 194.09714 -273.0266) (xy 194.105035 -273.075177) (xy 194.10553 -273.099784) (xy 194.105035 -273.124391)
			(xy 194.104856 -273.125492) (xy 194.423026 -273.125492) (xy 194.423026 -273.074076) (xy 194.431069 -273.023294)
			(xy 194.446957 -272.974395) (xy 194.4703 -272.928583) (xy 194.500521 -272.886987) (xy 194.536877 -272.850631)
			(xy 194.578473 -272.82041) (xy 194.624285 -272.797067) (xy 194.673184 -272.781179) (xy 194.723966 -272.773136)
			(xy 194.775382 -272.773136) (xy 194.826164 -272.781179) (xy 194.875063 -272.797067) (xy 194.920875 -272.82041)
			(xy 194.962471 -272.850631) (xy 194.998827 -272.886987) (xy 195.029048 -272.928583) (xy 195.052391 -272.974395)
			(xy 195.068279 -273.023294) (xy 195.076322 -273.074076) (xy 195.076826 -273.099784) (xy 195.394338 -273.099784)
			(xy 195.398298 -273.05073) (xy 195.410075 -273.002946) (xy 195.429366 -272.95767) (xy 195.455669 -272.916074)
			(xy 195.488304 -272.879237) (xy 195.526425 -272.848112) (xy 195.569046 -272.823505) (xy 195.615062 -272.806053)
			(xy 195.663281 -272.796209) (xy 195.712456 -272.794228) (xy 195.761311 -272.80016) (xy 195.808582 -272.813852)
			(xy 195.853044 -272.83495) (xy 195.893547 -272.862906) (xy 195.92904 -272.896998) (xy 195.958605 -272.936342)
			(xy 195.981476 -272.979919) (xy 195.99706 -273.0266) (xy 196.004955 -273.075177) (xy 196.00545 -273.099784)
			(xy 196.004955 -273.124391) (xy 196.004776 -273.125492) (xy 196.322946 -273.125492) (xy 196.322946 -273.074076)
			(xy 196.330989 -273.023294) (xy 196.346877 -272.974395) (xy 196.37022 -272.928583) (xy 196.400441 -272.886987)
			(xy 196.436797 -272.850631) (xy 196.478393 -272.82041) (xy 196.524205 -272.797067) (xy 196.573104 -272.781179)
			(xy 196.623886 -272.773136) (xy 196.675302 -272.773136) (xy 196.726084 -272.781179) (xy 196.774983 -272.797067)
			(xy 196.820795 -272.82041) (xy 196.862391 -272.850631) (xy 196.898747 -272.886987) (xy 196.928968 -272.928583)
			(xy 196.952311 -272.974395) (xy 196.968199 -273.023294) (xy 196.976242 -273.074076) (xy 196.976746 -273.099784)
			(xy 197.294258 -273.099784) (xy 197.298218 -273.05073) (xy 197.309995 -273.002946) (xy 197.329286 -272.95767)
			(xy 197.355589 -272.916074) (xy 197.388224 -272.879237) (xy 197.426345 -272.848112) (xy 197.468966 -272.823505)
			(xy 197.514982 -272.806053) (xy 197.563201 -272.796209) (xy 197.612376 -272.794228) (xy 197.661231 -272.80016)
			(xy 197.708502 -272.813852) (xy 197.752964 -272.83495) (xy 197.793467 -272.862906) (xy 197.82896 -272.896998)
			(xy 197.858525 -272.936342) (xy 197.881396 -272.979919) (xy 197.89698 -273.0266) (xy 197.904875 -273.075177)
			(xy 197.90537 -273.099784) (xy 197.904875 -273.124391) (xy 197.89698 -273.172968) (xy 197.881396 -273.219649)
			(xy 197.858525 -273.263226) (xy 197.82896 -273.30257) (xy 197.793467 -273.336662) (xy 197.752964 -273.364618)
			(xy 197.708502 -273.385716) (xy 197.661231 -273.399408) (xy 197.612376 -273.40534) (xy 197.563201 -273.403359)
			(xy 197.514982 -273.393515) (xy 197.468966 -273.376063) (xy 197.426345 -273.351456) (xy 197.388224 -273.320331)
			(xy 197.355589 -273.283494) (xy 197.329286 -273.241898) (xy 197.309995 -273.196622) (xy 197.298218 -273.148838)
			(xy 197.294258 -273.099784) (xy 196.976746 -273.099784) (xy 196.976242 -273.125492) (xy 196.968199 -273.176274)
			(xy 196.952311 -273.225173) (xy 196.928968 -273.270985) (xy 196.898747 -273.312581) (xy 196.862391 -273.348937)
			(xy 196.820795 -273.379158) (xy 196.774983 -273.402501) (xy 196.726084 -273.418389) (xy 196.675302 -273.426432)
			(xy 196.623886 -273.426432) (xy 196.573104 -273.418389) (xy 196.524205 -273.402501) (xy 196.478393 -273.379158)
			(xy 196.436797 -273.348937) (xy 196.400441 -273.312581) (xy 196.37022 -273.270985) (xy 196.346877 -273.225173)
			(xy 196.330989 -273.176274) (xy 196.322946 -273.125492) (xy 196.004776 -273.125492) (xy 195.99706 -273.172968)
			(xy 195.981476 -273.219649) (xy 195.958605 -273.263226) (xy 195.92904 -273.30257) (xy 195.893547 -273.336662)
			(xy 195.853044 -273.364618) (xy 195.808582 -273.385716) (xy 195.761311 -273.399408) (xy 195.712456 -273.40534)
			(xy 195.663281 -273.403359) (xy 195.615062 -273.393515) (xy 195.569046 -273.376063) (xy 195.526425 -273.351456)
			(xy 195.488304 -273.320331) (xy 195.455669 -273.283494) (xy 195.429366 -273.241898) (xy 195.410075 -273.196622)
			(xy 195.398298 -273.148838) (xy 195.394338 -273.099784) (xy 195.076826 -273.099784) (xy 195.076322 -273.125492)
			(xy 195.068279 -273.176274) (xy 195.052391 -273.225173) (xy 195.029048 -273.270985) (xy 194.998827 -273.312581)
			(xy 194.962471 -273.348937) (xy 194.920875 -273.379158) (xy 194.875063 -273.402501) (xy 194.826164 -273.418389)
			(xy 194.775382 -273.426432) (xy 194.723966 -273.426432) (xy 194.673184 -273.418389) (xy 194.624285 -273.402501)
			(xy 194.578473 -273.379158) (xy 194.536877 -273.348937) (xy 194.500521 -273.312581) (xy 194.4703 -273.270985)
			(xy 194.446957 -273.225173) (xy 194.431069 -273.176274) (xy 194.423026 -273.125492) (xy 194.104856 -273.125492)
			(xy 194.09714 -273.172968) (xy 194.081556 -273.219649) (xy 194.058685 -273.263226) (xy 194.02912 -273.30257)
			(xy 193.993627 -273.336662) (xy 193.953124 -273.364618) (xy 193.908662 -273.385716) (xy 193.861391 -273.399408)
			(xy 193.812536 -273.40534) (xy 193.763361 -273.403359) (xy 193.715142 -273.393515) (xy 193.669126 -273.376063)
			(xy 193.626505 -273.351456) (xy 193.588384 -273.320331) (xy 193.555749 -273.283494) (xy 193.529446 -273.241898)
			(xy 193.510155 -273.196622) (xy 193.498378 -273.148838) (xy 193.494418 -273.099784) (xy 193.176906 -273.099784)
			(xy 193.176402 -273.125492) (xy 193.168359 -273.176274) (xy 193.152471 -273.225173) (xy 193.129128 -273.270985)
			(xy 193.098907 -273.312581) (xy 193.062551 -273.348937) (xy 193.020955 -273.379158) (xy 192.975143 -273.402501)
			(xy 192.926244 -273.418389) (xy 192.875462 -273.426432) (xy 192.824046 -273.426432) (xy 192.773264 -273.418389)
			(xy 192.724365 -273.402501) (xy 192.678553 -273.379158) (xy 192.636957 -273.348937) (xy 192.600601 -273.312581)
			(xy 192.57038 -273.270985) (xy 192.547037 -273.225173) (xy 192.531149 -273.176274) (xy 192.523106 -273.125492)
			(xy 192.204682 -273.125492) (xy 192.196966 -273.172968) (xy 192.181382 -273.219649) (xy 192.158511 -273.263226)
			(xy 192.128946 -273.30257) (xy 192.093453 -273.336662) (xy 192.05295 -273.364618) (xy 192.008488 -273.385716)
			(xy 191.961217 -273.399408) (xy 191.912362 -273.40534) (xy 191.863187 -273.403359) (xy 191.814968 -273.393515)
			(xy 191.768952 -273.376063) (xy 191.726331 -273.351456) (xy 191.68821 -273.320331) (xy 191.655575 -273.283494)
			(xy 191.629272 -273.241898) (xy 191.609981 -273.196622) (xy 191.598204 -273.148838) (xy 191.594244 -273.099784)
			(xy 191.276986 -273.099784) (xy 191.276482 -273.125492) (xy 191.268439 -273.176274) (xy 191.252551 -273.225173)
			(xy 191.229208 -273.270985) (xy 191.198987 -273.312581) (xy 191.162631 -273.348937) (xy 191.121035 -273.379158)
			(xy 191.075223 -273.402501) (xy 191.026324 -273.418389) (xy 190.975542 -273.426432) (xy 190.924126 -273.426432)
			(xy 190.873344 -273.418389) (xy 190.824445 -273.402501) (xy 190.778633 -273.379158) (xy 190.737037 -273.348937)
			(xy 190.700681 -273.312581) (xy 190.67046 -273.270985) (xy 190.647117 -273.225173) (xy 190.631229 -273.176274)
			(xy 190.623186 -273.125492) (xy 190.304508 -273.125492) (xy 190.296792 -273.172968) (xy 190.281208 -273.219649)
			(xy 190.258337 -273.263226) (xy 190.228772 -273.30257) (xy 190.193279 -273.336662) (xy 190.152776 -273.364618)
			(xy 190.108314 -273.385716) (xy 190.061043 -273.399408) (xy 190.012188 -273.40534) (xy 189.963013 -273.403359)
			(xy 189.914794 -273.393515) (xy 189.868778 -273.376063) (xy 189.826157 -273.351456) (xy 189.788036 -273.320331)
			(xy 189.755401 -273.283494) (xy 189.729098 -273.241898) (xy 189.709807 -273.196622) (xy 189.69803 -273.148838)
			(xy 189.69407 -273.099784) (xy 189.376812 -273.099784) (xy 189.376308 -273.125492) (xy 189.368265 -273.176274)
			(xy 189.352377 -273.225173) (xy 189.329034 -273.270985) (xy 189.298813 -273.312581) (xy 189.262457 -273.348937)
			(xy 189.220861 -273.379158) (xy 189.175049 -273.402501) (xy 189.12615 -273.418389) (xy 189.075368 -273.426432)
			(xy 189.023952 -273.426432) (xy 188.97317 -273.418389) (xy 188.924271 -273.402501) (xy 188.878459 -273.379158)
			(xy 188.836863 -273.348937) (xy 188.800507 -273.312581) (xy 188.770286 -273.270985) (xy 188.746943 -273.225173)
			(xy 188.731055 -273.176274) (xy 188.723012 -273.125492) (xy 188.404588 -273.125492) (xy 188.396872 -273.172968)
			(xy 188.381288 -273.219649) (xy 188.358417 -273.263226) (xy 188.328852 -273.30257) (xy 188.293359 -273.336662)
			(xy 188.252856 -273.364618) (xy 188.208394 -273.385716) (xy 188.161123 -273.399408) (xy 188.112268 -273.40534)
			(xy 188.063093 -273.403359) (xy 188.014874 -273.393515) (xy 187.968858 -273.376063) (xy 187.926237 -273.351456)
			(xy 187.888116 -273.320331) (xy 187.855481 -273.283494) (xy 187.829178 -273.241898) (xy 187.809887 -273.196622)
			(xy 187.79811 -273.148838) (xy 187.79415 -273.099784) (xy 187.476892 -273.099784) (xy 187.476388 -273.125492)
			(xy 187.468345 -273.176274) (xy 187.452457 -273.225173) (xy 187.429114 -273.270985) (xy 187.398893 -273.312581)
			(xy 187.362537 -273.348937) (xy 187.320941 -273.379158) (xy 187.275129 -273.402501) (xy 187.22623 -273.418389)
			(xy 187.175448 -273.426432) (xy 187.124032 -273.426432) (xy 187.07325 -273.418389) (xy 187.024351 -273.402501)
			(xy 186.978539 -273.379158) (xy 186.936943 -273.348937) (xy 186.900587 -273.312581) (xy 186.870366 -273.270985)
			(xy 186.847023 -273.225173) (xy 186.831135 -273.176274) (xy 186.823092 -273.125492) (xy 186.504668 -273.125492)
			(xy 186.496952 -273.172968) (xy 186.481368 -273.219649) (xy 186.458497 -273.263226) (xy 186.428932 -273.30257)
			(xy 186.393439 -273.336662) (xy 186.352936 -273.364618) (xy 186.308474 -273.385716) (xy 186.261203 -273.399408)
			(xy 186.212348 -273.40534) (xy 186.163173 -273.403359) (xy 186.114954 -273.393515) (xy 186.068938 -273.376063)
			(xy 186.026317 -273.351456) (xy 185.988196 -273.320331) (xy 185.955561 -273.283494) (xy 185.929258 -273.241898)
			(xy 185.909967 -273.196622) (xy 185.89819 -273.148838) (xy 185.89423 -273.099784) (xy 185.576972 -273.099784)
			(xy 185.576468 -273.125492) (xy 185.568425 -273.176274) (xy 185.552537 -273.225173) (xy 185.529194 -273.270985)
			(xy 185.498973 -273.312581) (xy 185.462617 -273.348937) (xy 185.421021 -273.379158) (xy 185.375209 -273.402501)
			(xy 185.32631 -273.418389) (xy 185.275528 -273.426432) (xy 185.224112 -273.426432) (xy 185.17333 -273.418389)
			(xy 185.124431 -273.402501) (xy 185.078619 -273.379158) (xy 185.037023 -273.348937) (xy 185.000667 -273.312581)
			(xy 184.970446 -273.270985) (xy 184.947103 -273.225173) (xy 184.931215 -273.176274) (xy 184.923172 -273.125492)
			(xy 184.604494 -273.125492) (xy 184.596778 -273.172968) (xy 184.581194 -273.219649) (xy 184.558323 -273.263226)
			(xy 184.528758 -273.30257) (xy 184.493265 -273.336662) (xy 184.452762 -273.364618) (xy 184.4083 -273.385716)
			(xy 184.361029 -273.399408) (xy 184.312174 -273.40534) (xy 184.262999 -273.403359) (xy 184.21478 -273.393515)
			(xy 184.168764 -273.376063) (xy 184.126143 -273.351456) (xy 184.088022 -273.320331) (xy 184.055387 -273.283494)
			(xy 184.029084 -273.241898) (xy 184.009793 -273.196622) (xy 183.998016 -273.148838) (xy 183.994056 -273.099784)
			(xy 183.676798 -273.099784) (xy 183.676294 -273.125492) (xy 183.668251 -273.176274) (xy 183.652363 -273.225173)
			(xy 183.62902 -273.270985) (xy 183.598799 -273.312581) (xy 183.562443 -273.348937) (xy 183.520847 -273.379158)
			(xy 183.475035 -273.402501) (xy 183.426136 -273.418389) (xy 183.375354 -273.426432) (xy 183.323938 -273.426432)
			(xy 183.273156 -273.418389) (xy 183.224257 -273.402501) (xy 183.178445 -273.379158) (xy 183.136849 -273.348937)
			(xy 183.100493 -273.312581) (xy 183.070272 -273.270985) (xy 183.046929 -273.225173) (xy 183.031041 -273.176274)
			(xy 183.022998 -273.125492) (xy 182.704574 -273.125492) (xy 182.696858 -273.172968) (xy 182.681274 -273.219649)
			(xy 182.658403 -273.263226) (xy 182.628838 -273.30257) (xy 182.593345 -273.336662) (xy 182.552842 -273.364618)
			(xy 182.50838 -273.385716) (xy 182.461109 -273.399408) (xy 182.412254 -273.40534) (xy 182.363079 -273.403359)
			(xy 182.31486 -273.393515) (xy 182.268844 -273.376063) (xy 182.226223 -273.351456) (xy 182.188102 -273.320331)
			(xy 182.155467 -273.283494) (xy 182.129164 -273.241898) (xy 182.109873 -273.196622) (xy 182.098096 -273.148838)
			(xy 182.094136 -273.099784) (xy 181.776878 -273.099784) (xy 181.776374 -273.125492) (xy 181.768331 -273.176274)
			(xy 181.752443 -273.225173) (xy 181.7291 -273.270985) (xy 181.698879 -273.312581) (xy 181.662523 -273.348937)
			(xy 181.620927 -273.379158) (xy 181.575115 -273.402501) (xy 181.526216 -273.418389) (xy 181.475434 -273.426432)
			(xy 181.424018 -273.426432) (xy 181.373236 -273.418389) (xy 181.324337 -273.402501) (xy 181.278525 -273.379158)
			(xy 181.236929 -273.348937) (xy 181.200573 -273.312581) (xy 181.170352 -273.270985) (xy 181.147009 -273.225173)
			(xy 181.131121 -273.176274) (xy 181.123078 -273.125492) (xy 180.804654 -273.125492) (xy 180.796938 -273.172968)
			(xy 180.781354 -273.219649) (xy 180.758483 -273.263226) (xy 180.728918 -273.30257) (xy 180.693425 -273.336662)
			(xy 180.652922 -273.364618) (xy 180.60846 -273.385716) (xy 180.561189 -273.399408) (xy 180.512334 -273.40534)
			(xy 180.463159 -273.403359) (xy 180.41494 -273.393515) (xy 180.368924 -273.376063) (xy 180.326303 -273.351456)
			(xy 180.288182 -273.320331) (xy 180.255547 -273.283494) (xy 180.229244 -273.241898) (xy 180.209953 -273.196622)
			(xy 180.198176 -273.148838) (xy 180.194216 -273.099784) (xy 179.876958 -273.099784) (xy 179.876454 -273.125492)
			(xy 179.868411 -273.176274) (xy 179.852523 -273.225173) (xy 179.82918 -273.270985) (xy 179.798959 -273.312581)
			(xy 179.762603 -273.348937) (xy 179.721007 -273.379158) (xy 179.675195 -273.402501) (xy 179.626296 -273.418389)
			(xy 179.575514 -273.426432) (xy 179.524098 -273.426432) (xy 179.473316 -273.418389) (xy 179.424417 -273.402501)
			(xy 179.378605 -273.379158) (xy 179.337009 -273.348937) (xy 179.300653 -273.312581) (xy 179.270432 -273.270985)
			(xy 179.247089 -273.225173) (xy 179.231201 -273.176274) (xy 179.223158 -273.125492) (xy 178.90448 -273.125492)
			(xy 178.896764 -273.172968) (xy 178.88118 -273.219649) (xy 178.858309 -273.263226) (xy 178.828744 -273.30257)
			(xy 178.793251 -273.336662) (xy 178.752748 -273.364618) (xy 178.708286 -273.385716) (xy 178.661015 -273.399408)
			(xy 178.61216 -273.40534) (xy 178.562985 -273.403359) (xy 178.514766 -273.393515) (xy 178.46875 -273.376063)
			(xy 178.426129 -273.351456) (xy 178.388008 -273.320331) (xy 178.355373 -273.283494) (xy 178.32907 -273.241898)
			(xy 178.309779 -273.196622) (xy 178.298002 -273.148838) (xy 178.294042 -273.099784) (xy 177.976264 -273.099784)
			(xy 177.976264 -273.125507) (xy 177.968221 -273.176289) (xy 177.952334 -273.225188) (xy 177.928994 -273.271)
			(xy 177.898775 -273.312596) (xy 177.862421 -273.348954) (xy 177.820827 -273.379177) (xy 177.775018 -273.402522)
			(xy 177.72612 -273.418414) (xy 177.675339 -273.426462) (xy 177.649632 -273.426936) (xy 177.615088 -273.424904)
			(xy 177.603658 -273.423634) (xy 177.582068 -273.431508) (xy 177.509678 -273.504152) (xy 177.502312 -273.525996)
			(xy 177.503582 -273.537426) (xy 177.50455 -273.54673) (xy 177.505566 -273.56541) (xy 177.505614 -273.574764)
			(xy 177.505572 -273.584118) (xy 177.504558 -273.602799) (xy 177.503582 -273.612102) (xy 177.502312 -273.623532)
			(xy 177.509678 -273.645376) (xy 177.582068 -273.71802) (xy 177.603658 -273.725894) (xy 177.615088 -273.724624)
			(xy 177.649632 -273.722592) (xy 177.675335 -273.723099) (xy 177.726106 -273.731145) (xy 177.774994 -273.747034)
			(xy 177.820795 -273.770374) (xy 177.862381 -273.800592) (xy 177.898729 -273.836943) (xy 177.928942 -273.878532)
			(xy 177.952278 -273.924335) (xy 177.968163 -273.973225) (xy 177.976204 -274.023997) (xy 177.976204 -274.049744)
			(xy 178.294042 -274.049744) (xy 178.298002 -274.00069) (xy 178.309779 -273.952906) (xy 178.32907 -273.90763)
			(xy 178.355373 -273.866034) (xy 178.388008 -273.829197) (xy 178.426129 -273.798072) (xy 178.46875 -273.773465)
			(xy 178.514766 -273.756013) (xy 178.562985 -273.746169) (xy 178.61216 -273.744188) (xy 178.661015 -273.75012)
			(xy 178.708286 -273.763812) (xy 178.752748 -273.78491) (xy 178.793251 -273.812866) (xy 178.828744 -273.846958)
			(xy 178.858309 -273.886302) (xy 178.88118 -273.929879) (xy 178.896764 -273.97656) (xy 178.904659 -274.025137)
			(xy 178.905154 -274.049744) (xy 178.904659 -274.074351) (xy 178.90448 -274.075452) (xy 179.223158 -274.075452)
			(xy 179.223158 -274.024036) (xy 179.231201 -273.973254) (xy 179.247089 -273.924355) (xy 179.270432 -273.878543)
			(xy 179.300653 -273.836947) (xy 179.337009 -273.800591) (xy 179.378605 -273.77037) (xy 179.424417 -273.747027)
			(xy 179.473316 -273.731139) (xy 179.524098 -273.723096) (xy 179.575514 -273.723096) (xy 179.626296 -273.731139)
			(xy 179.675195 -273.747027) (xy 179.721007 -273.77037) (xy 179.762603 -273.800591) (xy 179.798959 -273.836947)
			(xy 179.82918 -273.878543) (xy 179.852523 -273.924355) (xy 179.868411 -273.973254) (xy 179.876454 -274.024036)
			(xy 179.876958 -274.049744) (xy 180.194216 -274.049744) (xy 180.198176 -274.00069) (xy 180.209953 -273.952906)
			(xy 180.229244 -273.90763) (xy 180.255547 -273.866034) (xy 180.288182 -273.829197) (xy 180.326303 -273.798072)
			(xy 180.368924 -273.773465) (xy 180.41494 -273.756013) (xy 180.463159 -273.746169) (xy 180.512334 -273.744188)
			(xy 180.561189 -273.75012) (xy 180.60846 -273.763812) (xy 180.652922 -273.78491) (xy 180.693425 -273.812866)
			(xy 180.728918 -273.846958) (xy 180.758483 -273.886302) (xy 180.781354 -273.929879) (xy 180.796938 -273.97656)
			(xy 180.804833 -274.025137) (xy 180.805328 -274.049744) (xy 180.804833 -274.074351) (xy 180.804654 -274.075452)
			(xy 181.123078 -274.075452) (xy 181.123078 -274.024036) (xy 181.131121 -273.973254) (xy 181.147009 -273.924355)
			(xy 181.170352 -273.878543) (xy 181.200573 -273.836947) (xy 181.236929 -273.800591) (xy 181.278525 -273.77037)
			(xy 181.324337 -273.747027) (xy 181.373236 -273.731139) (xy 181.424018 -273.723096) (xy 181.475434 -273.723096)
			(xy 181.526216 -273.731139) (xy 181.575115 -273.747027) (xy 181.620927 -273.77037) (xy 181.662523 -273.800591)
			(xy 181.698879 -273.836947) (xy 181.7291 -273.878543) (xy 181.752443 -273.924355) (xy 181.768331 -273.973254)
			(xy 181.776374 -274.024036) (xy 181.776878 -274.049744) (xy 182.094136 -274.049744) (xy 182.098096 -274.00069)
			(xy 182.109873 -273.952906) (xy 182.129164 -273.90763) (xy 182.155467 -273.866034) (xy 182.188102 -273.829197)
			(xy 182.226223 -273.798072) (xy 182.268844 -273.773465) (xy 182.31486 -273.756013) (xy 182.363079 -273.746169)
			(xy 182.412254 -273.744188) (xy 182.461109 -273.75012) (xy 182.50838 -273.763812) (xy 182.552842 -273.78491)
			(xy 182.593345 -273.812866) (xy 182.628838 -273.846958) (xy 182.658403 -273.886302) (xy 182.681274 -273.929879)
			(xy 182.696858 -273.97656) (xy 182.704753 -274.025137) (xy 182.705248 -274.049744) (xy 182.704753 -274.074351)
			(xy 182.704574 -274.075452) (xy 183.022998 -274.075452) (xy 183.022998 -274.024036) (xy 183.031041 -273.973254)
			(xy 183.046929 -273.924355) (xy 183.070272 -273.878543) (xy 183.100493 -273.836947) (xy 183.136849 -273.800591)
			(xy 183.178445 -273.77037) (xy 183.224257 -273.747027) (xy 183.273156 -273.731139) (xy 183.323938 -273.723096)
			(xy 183.375354 -273.723096) (xy 183.426136 -273.731139) (xy 183.475035 -273.747027) (xy 183.520847 -273.77037)
			(xy 183.562443 -273.800591) (xy 183.598799 -273.836947) (xy 183.62902 -273.878543) (xy 183.652363 -273.924355)
			(xy 183.668251 -273.973254) (xy 183.676294 -274.024036) (xy 183.676798 -274.049744) (xy 183.994056 -274.049744)
			(xy 183.998016 -274.00069) (xy 184.009793 -273.952906) (xy 184.029084 -273.90763) (xy 184.055387 -273.866034)
			(xy 184.088022 -273.829197) (xy 184.126143 -273.798072) (xy 184.168764 -273.773465) (xy 184.21478 -273.756013)
			(xy 184.262999 -273.746169) (xy 184.312174 -273.744188) (xy 184.361029 -273.75012) (xy 184.4083 -273.763812)
			(xy 184.452762 -273.78491) (xy 184.493265 -273.812866) (xy 184.528758 -273.846958) (xy 184.558323 -273.886302)
			(xy 184.581194 -273.929879) (xy 184.596778 -273.97656) (xy 184.604673 -274.025137) (xy 184.605168 -274.049744)
			(xy 184.604673 -274.074351) (xy 184.604494 -274.075452) (xy 184.923172 -274.075452) (xy 184.923172 -274.024036)
			(xy 184.931215 -273.973254) (xy 184.947103 -273.924355) (xy 184.970446 -273.878543) (xy 185.000667 -273.836947)
			(xy 185.037023 -273.800591) (xy 185.078619 -273.77037) (xy 185.124431 -273.747027) (xy 185.17333 -273.731139)
			(xy 185.224112 -273.723096) (xy 185.275528 -273.723096) (xy 185.32631 -273.731139) (xy 185.375209 -273.747027)
			(xy 185.421021 -273.77037) (xy 185.462617 -273.800591) (xy 185.498973 -273.836947) (xy 185.529194 -273.878543)
			(xy 185.552537 -273.924355) (xy 185.568425 -273.973254) (xy 185.576468 -274.024036) (xy 185.576972 -274.049744)
			(xy 185.89423 -274.049744) (xy 185.89819 -274.00069) (xy 185.909967 -273.952906) (xy 185.929258 -273.90763)
			(xy 185.955561 -273.866034) (xy 185.988196 -273.829197) (xy 186.026317 -273.798072) (xy 186.068938 -273.773465)
			(xy 186.114954 -273.756013) (xy 186.163173 -273.746169) (xy 186.212348 -273.744188) (xy 186.261203 -273.75012)
			(xy 186.308474 -273.763812) (xy 186.352936 -273.78491) (xy 186.393439 -273.812866) (xy 186.428932 -273.846958)
			(xy 186.458497 -273.886302) (xy 186.481368 -273.929879) (xy 186.496952 -273.97656) (xy 186.504847 -274.025137)
			(xy 186.505342 -274.049744) (xy 186.504847 -274.074351) (xy 186.504668 -274.075452) (xy 186.823092 -274.075452)
			(xy 186.823092 -274.024036) (xy 186.831135 -273.973254) (xy 186.847023 -273.924355) (xy 186.870366 -273.878543)
			(xy 186.900587 -273.836947) (xy 186.936943 -273.800591) (xy 186.978539 -273.77037) (xy 187.024351 -273.747027)
			(xy 187.07325 -273.731139) (xy 187.124032 -273.723096) (xy 187.175448 -273.723096) (xy 187.22623 -273.731139)
			(xy 187.275129 -273.747027) (xy 187.320941 -273.77037) (xy 187.362537 -273.800591) (xy 187.398893 -273.836947)
			(xy 187.429114 -273.878543) (xy 187.452457 -273.924355) (xy 187.468345 -273.973254) (xy 187.476388 -274.024036)
			(xy 187.476892 -274.049744) (xy 187.79415 -274.049744) (xy 187.79811 -274.00069) (xy 187.809887 -273.952906)
			(xy 187.829178 -273.90763) (xy 187.855481 -273.866034) (xy 187.888116 -273.829197) (xy 187.926237 -273.798072)
			(xy 187.968858 -273.773465) (xy 188.014874 -273.756013) (xy 188.063093 -273.746169) (xy 188.112268 -273.744188)
			(xy 188.161123 -273.75012) (xy 188.208394 -273.763812) (xy 188.252856 -273.78491) (xy 188.293359 -273.812866)
			(xy 188.328852 -273.846958) (xy 188.358417 -273.886302) (xy 188.381288 -273.929879) (xy 188.396872 -273.97656)
			(xy 188.404767 -274.025137) (xy 188.405262 -274.049744) (xy 188.404767 -274.074351) (xy 188.404588 -274.075452)
			(xy 188.723012 -274.075452) (xy 188.723012 -274.024036) (xy 188.731055 -273.973254) (xy 188.746943 -273.924355)
			(xy 188.770286 -273.878543) (xy 188.800507 -273.836947) (xy 188.836863 -273.800591) (xy 188.878459 -273.77037)
			(xy 188.924271 -273.747027) (xy 188.97317 -273.731139) (xy 189.023952 -273.723096) (xy 189.075368 -273.723096)
			(xy 189.12615 -273.731139) (xy 189.175049 -273.747027) (xy 189.220861 -273.77037) (xy 189.262457 -273.800591)
			(xy 189.298813 -273.836947) (xy 189.329034 -273.878543) (xy 189.352377 -273.924355) (xy 189.368265 -273.973254)
			(xy 189.376308 -274.024036) (xy 189.376812 -274.049744) (xy 189.69407 -274.049744) (xy 189.69803 -274.00069)
			(xy 189.709807 -273.952906) (xy 189.729098 -273.90763) (xy 189.755401 -273.866034) (xy 189.788036 -273.829197)
			(xy 189.826157 -273.798072) (xy 189.868778 -273.773465) (xy 189.914794 -273.756013) (xy 189.963013 -273.746169)
			(xy 190.012188 -273.744188) (xy 190.061043 -273.75012) (xy 190.108314 -273.763812) (xy 190.152776 -273.78491)
			(xy 190.193279 -273.812866) (xy 190.228772 -273.846958) (xy 190.258337 -273.886302) (xy 190.281208 -273.929879)
			(xy 190.296792 -273.97656) (xy 190.304687 -274.025137) (xy 190.305182 -274.049744) (xy 190.304687 -274.074351)
			(xy 190.304508 -274.075452) (xy 190.623186 -274.075452) (xy 190.623186 -274.024036) (xy 190.631229 -273.973254)
			(xy 190.647117 -273.924355) (xy 190.67046 -273.878543) (xy 190.700681 -273.836947) (xy 190.737037 -273.800591)
			(xy 190.778633 -273.77037) (xy 190.824445 -273.747027) (xy 190.873344 -273.731139) (xy 190.924126 -273.723096)
			(xy 190.975542 -273.723096) (xy 191.026324 -273.731139) (xy 191.075223 -273.747027) (xy 191.121035 -273.77037)
			(xy 191.162631 -273.800591) (xy 191.198987 -273.836947) (xy 191.229208 -273.878543) (xy 191.252551 -273.924355)
			(xy 191.268439 -273.973254) (xy 191.276482 -274.024036) (xy 191.276986 -274.049744) (xy 191.594498 -274.049744)
			(xy 191.598458 -274.00069) (xy 191.610235 -273.952906) (xy 191.629526 -273.90763) (xy 191.655829 -273.866034)
			(xy 191.688464 -273.829197) (xy 191.726585 -273.798072) (xy 191.769206 -273.773465) (xy 191.815222 -273.756013)
			(xy 191.863441 -273.746169) (xy 191.912616 -273.744188) (xy 191.961471 -273.75012) (xy 192.008742 -273.763812)
			(xy 192.053204 -273.78491) (xy 192.093707 -273.812866) (xy 192.1292 -273.846958) (xy 192.158765 -273.886302)
			(xy 192.181636 -273.929879) (xy 192.19722 -273.97656) (xy 192.205115 -274.025137) (xy 192.20561 -274.049744)
			(xy 192.205115 -274.074351) (xy 192.204936 -274.075452) (xy 192.523106 -274.075452) (xy 192.523106 -274.024036)
			(xy 192.531149 -273.973254) (xy 192.547037 -273.924355) (xy 192.57038 -273.878543) (xy 192.600601 -273.836947)
			(xy 192.636957 -273.800591) (xy 192.678553 -273.77037) (xy 192.724365 -273.747027) (xy 192.773264 -273.731139)
			(xy 192.824046 -273.723096) (xy 192.875462 -273.723096) (xy 192.926244 -273.731139) (xy 192.975143 -273.747027)
			(xy 193.020955 -273.77037) (xy 193.062551 -273.800591) (xy 193.098907 -273.836947) (xy 193.129128 -273.878543)
			(xy 193.152471 -273.924355) (xy 193.168359 -273.973254) (xy 193.176402 -274.024036) (xy 193.176906 -274.049744)
			(xy 193.494418 -274.049744) (xy 193.498378 -274.00069) (xy 193.510155 -273.952906) (xy 193.529446 -273.90763)
			(xy 193.555749 -273.866034) (xy 193.588384 -273.829197) (xy 193.626505 -273.798072) (xy 193.669126 -273.773465)
			(xy 193.715142 -273.756013) (xy 193.763361 -273.746169) (xy 193.812536 -273.744188) (xy 193.861391 -273.75012)
			(xy 193.908662 -273.763812) (xy 193.953124 -273.78491) (xy 193.993627 -273.812866) (xy 194.02912 -273.846958)
			(xy 194.058685 -273.886302) (xy 194.081556 -273.929879) (xy 194.09714 -273.97656) (xy 194.105035 -274.025137)
			(xy 194.10553 -274.049744) (xy 194.105035 -274.074351) (xy 194.104856 -274.075452) (xy 194.423026 -274.075452)
			(xy 194.423026 -274.024036) (xy 194.431069 -273.973254) (xy 194.446957 -273.924355) (xy 194.4703 -273.878543)
			(xy 194.500521 -273.836947) (xy 194.536877 -273.800591) (xy 194.578473 -273.77037) (xy 194.624285 -273.747027)
			(xy 194.673184 -273.731139) (xy 194.723966 -273.723096) (xy 194.775382 -273.723096) (xy 194.826164 -273.731139)
			(xy 194.875063 -273.747027) (xy 194.920875 -273.77037) (xy 194.962471 -273.800591) (xy 194.998827 -273.836947)
			(xy 195.029048 -273.878543) (xy 195.052391 -273.924355) (xy 195.068279 -273.973254) (xy 195.076322 -274.024036)
			(xy 195.076826 -274.049744) (xy 195.394338 -274.049744) (xy 195.398298 -274.00069) (xy 195.410075 -273.952906)
			(xy 195.429366 -273.90763) (xy 195.455669 -273.866034) (xy 195.488304 -273.829197) (xy 195.526425 -273.798072)
			(xy 195.569046 -273.773465) (xy 195.615062 -273.756013) (xy 195.663281 -273.746169) (xy 195.712456 -273.744188)
			(xy 195.761311 -273.75012) (xy 195.808582 -273.763812) (xy 195.853044 -273.78491) (xy 195.893547 -273.812866)
			(xy 195.92904 -273.846958) (xy 195.958605 -273.886302) (xy 195.981476 -273.929879) (xy 195.99706 -273.97656)
			(xy 196.004955 -274.025137) (xy 196.00545 -274.049744) (xy 196.004955 -274.074351) (xy 196.004776 -274.075452)
			(xy 196.322946 -274.075452) (xy 196.322946 -274.024036) (xy 196.330989 -273.973254) (xy 196.346877 -273.924355)
			(xy 196.37022 -273.878543) (xy 196.400441 -273.836947) (xy 196.436797 -273.800591) (xy 196.478393 -273.77037)
			(xy 196.524205 -273.747027) (xy 196.573104 -273.731139) (xy 196.623886 -273.723096) (xy 196.675302 -273.723096)
			(xy 196.726084 -273.731139) (xy 196.774983 -273.747027) (xy 196.820795 -273.77037) (xy 196.862391 -273.800591)
			(xy 196.898747 -273.836947) (xy 196.928968 -273.878543) (xy 196.952311 -273.924355) (xy 196.968199 -273.973254)
			(xy 196.976242 -274.024036) (xy 196.976746 -274.049744) (xy 197.294258 -274.049744) (xy 197.298218 -274.00069)
			(xy 197.309995 -273.952906) (xy 197.329286 -273.90763) (xy 197.355589 -273.866034) (xy 197.388224 -273.829197)
			(xy 197.426345 -273.798072) (xy 197.468966 -273.773465) (xy 197.514982 -273.756013) (xy 197.563201 -273.746169)
			(xy 197.612376 -273.744188) (xy 197.661231 -273.75012) (xy 197.708502 -273.763812) (xy 197.752964 -273.78491)
			(xy 197.793467 -273.812866) (xy 197.82896 -273.846958) (xy 197.858525 -273.886302) (xy 197.881396 -273.929879)
			(xy 197.89698 -273.97656) (xy 197.904875 -274.025137) (xy 197.90537 -274.049744) (xy 198.244218 -274.049744)
			(xy 198.248178 -274.00069) (xy 198.259955 -273.952906) (xy 198.279246 -273.90763) (xy 198.305549 -273.866034)
			(xy 198.338184 -273.829197) (xy 198.376305 -273.798072) (xy 198.418926 -273.773465) (xy 198.464942 -273.756013)
			(xy 198.513161 -273.746169) (xy 198.562336 -273.744188) (xy 198.611191 -273.75012) (xy 198.658462 -273.763812)
			(xy 198.702924 -273.78491) (xy 198.743427 -273.812866) (xy 198.77892 -273.846958) (xy 198.808485 -273.886302)
			(xy 198.831356 -273.929879) (xy 198.84694 -273.97656) (xy 198.854835 -274.025137) (xy 198.85533 -274.049744)
			(xy 198.854835 -274.074351) (xy 198.84694 -274.122928) (xy 198.831356 -274.169609) (xy 198.808485 -274.213186)
			(xy 198.77892 -274.25253) (xy 198.743427 -274.286622) (xy 198.702924 -274.314578) (xy 198.658462 -274.335676)
			(xy 198.611191 -274.349368) (xy 198.562336 -274.3553) (xy 198.513161 -274.353319) (xy 198.464942 -274.343475)
			(xy 198.418926 -274.326023) (xy 198.376305 -274.301416) (xy 198.338184 -274.270291) (xy 198.305549 -274.233454)
			(xy 198.279246 -274.191858) (xy 198.259955 -274.146582) (xy 198.248178 -274.098798) (xy 198.244218 -274.049744)
			(xy 197.90537 -274.049744) (xy 197.904875 -274.074351) (xy 197.89698 -274.122928) (xy 197.881396 -274.169609)
			(xy 197.858525 -274.213186) (xy 197.82896 -274.25253) (xy 197.793467 -274.286622) (xy 197.752964 -274.314578)
			(xy 197.708502 -274.335676) (xy 197.661231 -274.349368) (xy 197.612376 -274.3553) (xy 197.563201 -274.353319)
			(xy 197.514982 -274.343475) (xy 197.468966 -274.326023) (xy 197.426345 -274.301416) (xy 197.388224 -274.270291)
			(xy 197.355589 -274.233454) (xy 197.329286 -274.191858) (xy 197.309995 -274.146582) (xy 197.298218 -274.098798)
			(xy 197.294258 -274.049744) (xy 196.976746 -274.049744) (xy 196.976242 -274.075452) (xy 196.968199 -274.126234)
			(xy 196.952311 -274.175133) (xy 196.928968 -274.220945) (xy 196.898747 -274.262541) (xy 196.862391 -274.298897)
			(xy 196.820795 -274.329118) (xy 196.774983 -274.352461) (xy 196.726084 -274.368349) (xy 196.675302 -274.376392)
			(xy 196.623886 -274.376392) (xy 196.573104 -274.368349) (xy 196.524205 -274.352461) (xy 196.478393 -274.329118)
			(xy 196.436797 -274.298897) (xy 196.400441 -274.262541) (xy 196.37022 -274.220945) (xy 196.346877 -274.175133)
			(xy 196.330989 -274.126234) (xy 196.322946 -274.075452) (xy 196.004776 -274.075452) (xy 195.99706 -274.122928)
			(xy 195.981476 -274.169609) (xy 195.958605 -274.213186) (xy 195.92904 -274.25253) (xy 195.893547 -274.286622)
			(xy 195.853044 -274.314578) (xy 195.808582 -274.335676) (xy 195.761311 -274.349368) (xy 195.712456 -274.3553)
			(xy 195.663281 -274.353319) (xy 195.615062 -274.343475) (xy 195.569046 -274.326023) (xy 195.526425 -274.301416)
			(xy 195.488304 -274.270291) (xy 195.455669 -274.233454) (xy 195.429366 -274.191858) (xy 195.410075 -274.146582)
			(xy 195.398298 -274.098798) (xy 195.394338 -274.049744) (xy 195.076826 -274.049744) (xy 195.076322 -274.075452)
			(xy 195.068279 -274.126234) (xy 195.052391 -274.175133) (xy 195.029048 -274.220945) (xy 194.998827 -274.262541)
			(xy 194.962471 -274.298897) (xy 194.920875 -274.329118) (xy 194.875063 -274.352461) (xy 194.826164 -274.368349)
			(xy 194.775382 -274.376392) (xy 194.723966 -274.376392) (xy 194.673184 -274.368349) (xy 194.624285 -274.352461)
			(xy 194.578473 -274.329118) (xy 194.536877 -274.298897) (xy 194.500521 -274.262541) (xy 194.4703 -274.220945)
			(xy 194.446957 -274.175133) (xy 194.431069 -274.126234) (xy 194.423026 -274.075452) (xy 194.104856 -274.075452)
			(xy 194.09714 -274.122928) (xy 194.081556 -274.169609) (xy 194.058685 -274.213186) (xy 194.02912 -274.25253)
			(xy 193.993627 -274.286622) (xy 193.953124 -274.314578) (xy 193.908662 -274.335676) (xy 193.861391 -274.349368)
			(xy 193.812536 -274.3553) (xy 193.763361 -274.353319) (xy 193.715142 -274.343475) (xy 193.669126 -274.326023)
			(xy 193.626505 -274.301416) (xy 193.588384 -274.270291) (xy 193.555749 -274.233454) (xy 193.529446 -274.191858)
			(xy 193.510155 -274.146582) (xy 193.498378 -274.098798) (xy 193.494418 -274.049744) (xy 193.176906 -274.049744)
			(xy 193.176402 -274.075452) (xy 193.168359 -274.126234) (xy 193.152471 -274.175133) (xy 193.129128 -274.220945)
			(xy 193.098907 -274.262541) (xy 193.062551 -274.298897) (xy 193.020955 -274.329118) (xy 192.975143 -274.352461)
			(xy 192.926244 -274.368349) (xy 192.875462 -274.376392) (xy 192.824046 -274.376392) (xy 192.773264 -274.368349)
			(xy 192.724365 -274.352461) (xy 192.678553 -274.329118) (xy 192.636957 -274.298897) (xy 192.600601 -274.262541)
			(xy 192.57038 -274.220945) (xy 192.547037 -274.175133) (xy 192.531149 -274.126234) (xy 192.523106 -274.075452)
			(xy 192.204936 -274.075452) (xy 192.19722 -274.122928) (xy 192.181636 -274.169609) (xy 192.158765 -274.213186)
			(xy 192.1292 -274.25253) (xy 192.093707 -274.286622) (xy 192.053204 -274.314578) (xy 192.008742 -274.335676)
			(xy 191.961471 -274.349368) (xy 191.912616 -274.3553) (xy 191.863441 -274.353319) (xy 191.815222 -274.343475)
			(xy 191.769206 -274.326023) (xy 191.726585 -274.301416) (xy 191.688464 -274.270291) (xy 191.655829 -274.233454)
			(xy 191.629526 -274.191858) (xy 191.610235 -274.146582) (xy 191.598458 -274.098798) (xy 191.594498 -274.049744)
			(xy 191.276986 -274.049744) (xy 191.276482 -274.075452) (xy 191.268439 -274.126234) (xy 191.252551 -274.175133)
			(xy 191.229208 -274.220945) (xy 191.198987 -274.262541) (xy 191.162631 -274.298897) (xy 191.121035 -274.329118)
			(xy 191.075223 -274.352461) (xy 191.026324 -274.368349) (xy 190.975542 -274.376392) (xy 190.924126 -274.376392)
			(xy 190.873344 -274.368349) (xy 190.824445 -274.352461) (xy 190.778633 -274.329118) (xy 190.737037 -274.298897)
			(xy 190.700681 -274.262541) (xy 190.67046 -274.220945) (xy 190.647117 -274.175133) (xy 190.631229 -274.126234)
			(xy 190.623186 -274.075452) (xy 190.304508 -274.075452) (xy 190.296792 -274.122928) (xy 190.281208 -274.169609)
			(xy 190.258337 -274.213186) (xy 190.228772 -274.25253) (xy 190.193279 -274.286622) (xy 190.152776 -274.314578)
			(xy 190.108314 -274.335676) (xy 190.061043 -274.349368) (xy 190.012188 -274.3553) (xy 189.963013 -274.353319)
			(xy 189.914794 -274.343475) (xy 189.868778 -274.326023) (xy 189.826157 -274.301416) (xy 189.788036 -274.270291)
			(xy 189.755401 -274.233454) (xy 189.729098 -274.191858) (xy 189.709807 -274.146582) (xy 189.69803 -274.098798)
			(xy 189.69407 -274.049744) (xy 189.376812 -274.049744) (xy 189.376308 -274.075452) (xy 189.368265 -274.126234)
			(xy 189.352377 -274.175133) (xy 189.329034 -274.220945) (xy 189.298813 -274.262541) (xy 189.262457 -274.298897)
			(xy 189.220861 -274.329118) (xy 189.175049 -274.352461) (xy 189.12615 -274.368349) (xy 189.075368 -274.376392)
			(xy 189.023952 -274.376392) (xy 188.97317 -274.368349) (xy 188.924271 -274.352461) (xy 188.878459 -274.329118)
			(xy 188.836863 -274.298897) (xy 188.800507 -274.262541) (xy 188.770286 -274.220945) (xy 188.746943 -274.175133)
			(xy 188.731055 -274.126234) (xy 188.723012 -274.075452) (xy 188.404588 -274.075452) (xy 188.396872 -274.122928)
			(xy 188.381288 -274.169609) (xy 188.358417 -274.213186) (xy 188.328852 -274.25253) (xy 188.293359 -274.286622)
			(xy 188.252856 -274.314578) (xy 188.208394 -274.335676) (xy 188.161123 -274.349368) (xy 188.112268 -274.3553)
			(xy 188.063093 -274.353319) (xy 188.014874 -274.343475) (xy 187.968858 -274.326023) (xy 187.926237 -274.301416)
			(xy 187.888116 -274.270291) (xy 187.855481 -274.233454) (xy 187.829178 -274.191858) (xy 187.809887 -274.146582)
			(xy 187.79811 -274.098798) (xy 187.79415 -274.049744) (xy 187.476892 -274.049744) (xy 187.476388 -274.075452)
			(xy 187.468345 -274.126234) (xy 187.452457 -274.175133) (xy 187.429114 -274.220945) (xy 187.398893 -274.262541)
			(xy 187.362537 -274.298897) (xy 187.320941 -274.329118) (xy 187.275129 -274.352461) (xy 187.22623 -274.368349)
			(xy 187.175448 -274.376392) (xy 187.124032 -274.376392) (xy 187.07325 -274.368349) (xy 187.024351 -274.352461)
			(xy 186.978539 -274.329118) (xy 186.936943 -274.298897) (xy 186.900587 -274.262541) (xy 186.870366 -274.220945)
			(xy 186.847023 -274.175133) (xy 186.831135 -274.126234) (xy 186.823092 -274.075452) (xy 186.504668 -274.075452)
			(xy 186.496952 -274.122928) (xy 186.481368 -274.169609) (xy 186.458497 -274.213186) (xy 186.428932 -274.25253)
			(xy 186.393439 -274.286622) (xy 186.352936 -274.314578) (xy 186.308474 -274.335676) (xy 186.261203 -274.349368)
			(xy 186.212348 -274.3553) (xy 186.163173 -274.353319) (xy 186.114954 -274.343475) (xy 186.068938 -274.326023)
			(xy 186.026317 -274.301416) (xy 185.988196 -274.270291) (xy 185.955561 -274.233454) (xy 185.929258 -274.191858)
			(xy 185.909967 -274.146582) (xy 185.89819 -274.098798) (xy 185.89423 -274.049744) (xy 185.576972 -274.049744)
			(xy 185.576468 -274.075452) (xy 185.568425 -274.126234) (xy 185.552537 -274.175133) (xy 185.529194 -274.220945)
			(xy 185.498973 -274.262541) (xy 185.462617 -274.298897) (xy 185.421021 -274.329118) (xy 185.375209 -274.352461)
			(xy 185.32631 -274.368349) (xy 185.275528 -274.376392) (xy 185.224112 -274.376392) (xy 185.17333 -274.368349)
			(xy 185.124431 -274.352461) (xy 185.078619 -274.329118) (xy 185.037023 -274.298897) (xy 185.000667 -274.262541)
			(xy 184.970446 -274.220945) (xy 184.947103 -274.175133) (xy 184.931215 -274.126234) (xy 184.923172 -274.075452)
			(xy 184.604494 -274.075452) (xy 184.596778 -274.122928) (xy 184.581194 -274.169609) (xy 184.558323 -274.213186)
			(xy 184.528758 -274.25253) (xy 184.493265 -274.286622) (xy 184.452762 -274.314578) (xy 184.4083 -274.335676)
			(xy 184.361029 -274.349368) (xy 184.312174 -274.3553) (xy 184.262999 -274.353319) (xy 184.21478 -274.343475)
			(xy 184.168764 -274.326023) (xy 184.126143 -274.301416) (xy 184.088022 -274.270291) (xy 184.055387 -274.233454)
			(xy 184.029084 -274.191858) (xy 184.009793 -274.146582) (xy 183.998016 -274.098798) (xy 183.994056 -274.049744)
			(xy 183.676798 -274.049744) (xy 183.676294 -274.075452) (xy 183.668251 -274.126234) (xy 183.652363 -274.175133)
			(xy 183.62902 -274.220945) (xy 183.598799 -274.262541) (xy 183.562443 -274.298897) (xy 183.520847 -274.329118)
			(xy 183.475035 -274.352461) (xy 183.426136 -274.368349) (xy 183.375354 -274.376392) (xy 183.323938 -274.376392)
			(xy 183.273156 -274.368349) (xy 183.224257 -274.352461) (xy 183.178445 -274.329118) (xy 183.136849 -274.298897)
			(xy 183.100493 -274.262541) (xy 183.070272 -274.220945) (xy 183.046929 -274.175133) (xy 183.031041 -274.126234)
			(xy 183.022998 -274.075452) (xy 182.704574 -274.075452) (xy 182.696858 -274.122928) (xy 182.681274 -274.169609)
			(xy 182.658403 -274.213186) (xy 182.628838 -274.25253) (xy 182.593345 -274.286622) (xy 182.552842 -274.314578)
			(xy 182.50838 -274.335676) (xy 182.461109 -274.349368) (xy 182.412254 -274.3553) (xy 182.363079 -274.353319)
			(xy 182.31486 -274.343475) (xy 182.268844 -274.326023) (xy 182.226223 -274.301416) (xy 182.188102 -274.270291)
			(xy 182.155467 -274.233454) (xy 182.129164 -274.191858) (xy 182.109873 -274.146582) (xy 182.098096 -274.098798)
			(xy 182.094136 -274.049744) (xy 181.776878 -274.049744) (xy 181.776374 -274.075452) (xy 181.768331 -274.126234)
			(xy 181.752443 -274.175133) (xy 181.7291 -274.220945) (xy 181.698879 -274.262541) (xy 181.662523 -274.298897)
			(xy 181.620927 -274.329118) (xy 181.575115 -274.352461) (xy 181.526216 -274.368349) (xy 181.475434 -274.376392)
			(xy 181.424018 -274.376392) (xy 181.373236 -274.368349) (xy 181.324337 -274.352461) (xy 181.278525 -274.329118)
			(xy 181.236929 -274.298897) (xy 181.200573 -274.262541) (xy 181.170352 -274.220945) (xy 181.147009 -274.175133)
			(xy 181.131121 -274.126234) (xy 181.123078 -274.075452) (xy 180.804654 -274.075452) (xy 180.796938 -274.122928)
			(xy 180.781354 -274.169609) (xy 180.758483 -274.213186) (xy 180.728918 -274.25253) (xy 180.693425 -274.286622)
			(xy 180.652922 -274.314578) (xy 180.60846 -274.335676) (xy 180.561189 -274.349368) (xy 180.512334 -274.3553)
			(xy 180.463159 -274.353319) (xy 180.41494 -274.343475) (xy 180.368924 -274.326023) (xy 180.326303 -274.301416)
			(xy 180.288182 -274.270291) (xy 180.255547 -274.233454) (xy 180.229244 -274.191858) (xy 180.209953 -274.146582)
			(xy 180.198176 -274.098798) (xy 180.194216 -274.049744) (xy 179.876958 -274.049744) (xy 179.876454 -274.075452)
			(xy 179.868411 -274.126234) (xy 179.852523 -274.175133) (xy 179.82918 -274.220945) (xy 179.798959 -274.262541)
			(xy 179.762603 -274.298897) (xy 179.721007 -274.329118) (xy 179.675195 -274.352461) (xy 179.626296 -274.368349)
			(xy 179.575514 -274.376392) (xy 179.524098 -274.376392) (xy 179.473316 -274.368349) (xy 179.424417 -274.352461)
			(xy 179.378605 -274.329118) (xy 179.337009 -274.298897) (xy 179.300653 -274.262541) (xy 179.270432 -274.220945)
			(xy 179.247089 -274.175133) (xy 179.231201 -274.126234) (xy 179.223158 -274.075452) (xy 178.90448 -274.075452)
			(xy 178.896764 -274.122928) (xy 178.88118 -274.169609) (xy 178.858309 -274.213186) (xy 178.828744 -274.25253)
			(xy 178.793251 -274.286622) (xy 178.752748 -274.314578) (xy 178.708286 -274.335676) (xy 178.661015 -274.349368)
			(xy 178.61216 -274.3553) (xy 178.562985 -274.353319) (xy 178.514766 -274.343475) (xy 178.46875 -274.326023)
			(xy 178.426129 -274.301416) (xy 178.388008 -274.270291) (xy 178.355373 -274.233454) (xy 178.32907 -274.191858)
			(xy 178.309779 -274.146582) (xy 178.298002 -274.098798) (xy 178.294042 -274.049744) (xy 177.976204 -274.049744)
			(xy 177.976204 -274.075403) (xy 177.968163 -274.126175) (xy 177.952278 -274.175065) (xy 177.928942 -274.220868)
			(xy 177.898729 -274.262457) (xy 177.862381 -274.298808) (xy 177.820795 -274.329026) (xy 177.774994 -274.352366)
			(xy 177.726106 -274.368255) (xy 177.675335 -274.376301) (xy 177.649632 -274.376896) (xy 177.615342 -274.374864)
			(xy 177.603658 -274.373848) (xy 177.582068 -274.381468) (xy 177.509932 -274.454366) (xy 177.502312 -274.475956)
			(xy 177.503836 -274.487386) (xy 177.504812 -274.496753) (xy 177.505829 -274.51556) (xy 177.505868 -274.524978)
			(xy 177.505868 -274.595336) (xy 177.506334 -274.605992) (xy 177.515021 -274.625453) (xy 177.522632 -274.632928)
			(xy 177.586894 -274.69084) (xy 177.607214 -274.697444) (xy 177.618136 -274.696428) (xy 177.649886 -274.69465)
			(xy 177.675148 -274.695142) (xy 177.724983 -274.703456) (xy 177.77277 -274.719859) (xy 177.817205 -274.743904)
			(xy 177.857076 -274.774936) (xy 177.891296 -274.812106) (xy 177.918931 -274.854403) (xy 177.939226 -274.900671)
			(xy 177.95163 -274.949649) (xy 177.955802 -275) (xy 177.953675 -275.025666) (xy 178.272944 -275.025666)
			(xy 178.272944 -274.97425) (xy 178.280987 -274.923468) (xy 178.296875 -274.874569) (xy 178.320218 -274.828757)
			(xy 178.350439 -274.787161) (xy 178.386795 -274.750805) (xy 178.428391 -274.720584) (xy 178.474203 -274.697241)
			(xy 178.523102 -274.681353) (xy 178.573884 -274.67331) (xy 178.6253 -274.67331) (xy 178.676082 -274.681353)
			(xy 178.724981 -274.697241) (xy 178.770793 -274.720584) (xy 178.812389 -274.750805) (xy 178.848745 -274.787161)
			(xy 178.878966 -274.828757) (xy 178.902309 -274.874569) (xy 178.918197 -274.923468) (xy 178.92624 -274.97425)
			(xy 178.926744 -274.999958) (xy 179.244256 -274.999958) (xy 179.248216 -274.950904) (xy 179.259993 -274.90312)
			(xy 179.279284 -274.857844) (xy 179.305587 -274.816248) (xy 179.338222 -274.779411) (xy 179.376343 -274.748286)
			(xy 179.418964 -274.723679) (xy 179.46498 -274.706227) (xy 179.513199 -274.696383) (xy 179.562374 -274.694402)
			(xy 179.611229 -274.700334) (xy 179.6585 -274.714026) (xy 179.702962 -274.735124) (xy 179.743465 -274.76308)
			(xy 179.778958 -274.797172) (xy 179.808523 -274.836516) (xy 179.831394 -274.880093) (xy 179.846978 -274.926774)
			(xy 179.854873 -274.975351) (xy 179.855368 -274.999958) (xy 179.854873 -275.024565) (xy 179.854735 -275.025412)
			(xy 180.173118 -275.025412) (xy 180.173118 -274.973996) (xy 180.181161 -274.923214) (xy 180.197049 -274.874315)
			(xy 180.220392 -274.828503) (xy 180.250613 -274.786907) (xy 180.286969 -274.750551) (xy 180.328565 -274.72033)
			(xy 180.374377 -274.696987) (xy 180.423276 -274.681099) (xy 180.474058 -274.673056) (xy 180.525474 -274.673056)
			(xy 180.576256 -274.681099) (xy 180.625155 -274.696987) (xy 180.670967 -274.72033) (xy 180.712563 -274.750551)
			(xy 180.748919 -274.786907) (xy 180.77914 -274.828503) (xy 180.802483 -274.874315) (xy 180.818371 -274.923214)
			(xy 180.826414 -274.973996) (xy 180.826918 -274.999704) (xy 180.826913 -274.999958) (xy 181.144176 -274.999958)
			(xy 181.148136 -274.950904) (xy 181.159913 -274.90312) (xy 181.179204 -274.857844) (xy 181.205507 -274.816248)
			(xy 181.238142 -274.779411) (xy 181.276263 -274.748286) (xy 181.318884 -274.723679) (xy 181.3649 -274.706227)
			(xy 181.413119 -274.696383) (xy 181.462294 -274.694402) (xy 181.511149 -274.700334) (xy 181.55842 -274.714026)
			(xy 181.602882 -274.735124) (xy 181.643385 -274.76308) (xy 181.678878 -274.797172) (xy 181.708443 -274.836516)
			(xy 181.731314 -274.880093) (xy 181.746898 -274.926774) (xy 181.754793 -274.975351) (xy 181.755288 -274.999958)
			(xy 181.754793 -275.024565) (xy 181.754614 -275.025666) (xy 182.073038 -275.025666) (xy 182.073038 -274.97425)
			(xy 182.081081 -274.923468) (xy 182.096969 -274.874569) (xy 182.120312 -274.828757) (xy 182.150533 -274.787161)
			(xy 182.186889 -274.750805) (xy 182.228485 -274.720584) (xy 182.274297 -274.697241) (xy 182.323196 -274.681353)
			(xy 182.373978 -274.67331) (xy 182.425394 -274.67331) (xy 182.476176 -274.681353) (xy 182.525075 -274.697241)
			(xy 182.570887 -274.720584) (xy 182.612483 -274.750805) (xy 182.648839 -274.787161) (xy 182.67906 -274.828757)
			(xy 182.702403 -274.874569) (xy 182.718291 -274.923468) (xy 182.726334 -274.97425) (xy 182.726838 -274.999958)
			(xy 183.044096 -274.999958) (xy 183.048056 -274.950904) (xy 183.059833 -274.90312) (xy 183.079124 -274.857844)
			(xy 183.105427 -274.816248) (xy 183.138062 -274.779411) (xy 183.176183 -274.748286) (xy 183.218804 -274.723679)
			(xy 183.26482 -274.706227) (xy 183.313039 -274.696383) (xy 183.362214 -274.694402) (xy 183.411069 -274.700334)
			(xy 183.45834 -274.714026) (xy 183.502802 -274.735124) (xy 183.543305 -274.76308) (xy 183.578798 -274.797172)
			(xy 183.608363 -274.836516) (xy 183.631234 -274.880093) (xy 183.646818 -274.926774) (xy 183.654713 -274.975351)
			(xy 183.655208 -274.999958) (xy 183.654713 -275.024565) (xy 183.654575 -275.025412) (xy 183.972958 -275.025412)
			(xy 183.972958 -274.973996) (xy 183.981001 -274.923214) (xy 183.996889 -274.874315) (xy 184.020232 -274.828503)
			(xy 184.050453 -274.786907) (xy 184.086809 -274.750551) (xy 184.128405 -274.72033) (xy 184.174217 -274.696987)
			(xy 184.223116 -274.681099) (xy 184.273898 -274.673056) (xy 184.325314 -274.673056) (xy 184.376096 -274.681099)
			(xy 184.424995 -274.696987) (xy 184.470807 -274.72033) (xy 184.512403 -274.750551) (xy 184.548759 -274.786907)
			(xy 184.57898 -274.828503) (xy 184.602323 -274.874315) (xy 184.618211 -274.923214) (xy 184.626254 -274.973996)
			(xy 184.626758 -274.999704) (xy 184.626753 -274.999958) (xy 184.94427 -274.999958) (xy 184.94823 -274.950904)
			(xy 184.960007 -274.90312) (xy 184.979298 -274.857844) (xy 185.005601 -274.816248) (xy 185.038236 -274.779411)
			(xy 185.076357 -274.748286) (xy 185.118978 -274.723679) (xy 185.164994 -274.706227) (xy 185.213213 -274.696383)
			(xy 185.262388 -274.694402) (xy 185.311243 -274.700334) (xy 185.358514 -274.714026) (xy 185.402976 -274.735124)
			(xy 185.443479 -274.76308) (xy 185.478972 -274.797172) (xy 185.508537 -274.836516) (xy 185.531408 -274.880093)
			(xy 185.546992 -274.926774) (xy 185.554887 -274.975351) (xy 185.555382 -274.999958) (xy 185.554887 -275.024565)
			(xy 185.554708 -275.025666) (xy 185.872878 -275.025666) (xy 185.872878 -274.97425) (xy 185.880921 -274.923468)
			(xy 185.896809 -274.874569) (xy 185.920152 -274.828757) (xy 185.950373 -274.787161) (xy 185.986729 -274.750805)
			(xy 186.028325 -274.720584) (xy 186.074137 -274.697241) (xy 186.123036 -274.681353) (xy 186.173818 -274.67331)
			(xy 186.225234 -274.67331) (xy 186.276016 -274.681353) (xy 186.324915 -274.697241) (xy 186.370727 -274.720584)
			(xy 186.412323 -274.750805) (xy 186.448679 -274.787161) (xy 186.4789 -274.828757) (xy 186.502243 -274.874569)
			(xy 186.518131 -274.923468) (xy 186.526174 -274.97425) (xy 186.526678 -274.999958) (xy 186.84419 -274.999958)
			(xy 186.84815 -274.950904) (xy 186.859927 -274.90312) (xy 186.879218 -274.857844) (xy 186.905521 -274.816248)
			(xy 186.938156 -274.779411) (xy 186.976277 -274.748286) (xy 187.018898 -274.723679) (xy 187.064914 -274.706227)
			(xy 187.113133 -274.696383) (xy 187.162308 -274.694402) (xy 187.211163 -274.700334) (xy 187.258434 -274.714026)
			(xy 187.302896 -274.735124) (xy 187.343399 -274.76308) (xy 187.378892 -274.797172) (xy 187.408457 -274.836516)
			(xy 187.431328 -274.880093) (xy 187.446912 -274.926774) (xy 187.454807 -274.975351) (xy 187.455302 -274.999958)
			(xy 187.454807 -275.024565) (xy 187.454669 -275.025412) (xy 187.773052 -275.025412) (xy 187.773052 -274.973996)
			(xy 187.781095 -274.923214) (xy 187.796983 -274.874315) (xy 187.820326 -274.828503) (xy 187.850547 -274.786907)
			(xy 187.886903 -274.750551) (xy 187.928499 -274.72033) (xy 187.974311 -274.696987) (xy 188.02321 -274.681099)
			(xy 188.073992 -274.673056) (xy 188.125408 -274.673056) (xy 188.17619 -274.681099) (xy 188.225089 -274.696987)
			(xy 188.270901 -274.72033) (xy 188.312497 -274.750551) (xy 188.348853 -274.786907) (xy 188.379074 -274.828503)
			(xy 188.402417 -274.874315) (xy 188.418305 -274.923214) (xy 188.426348 -274.973996) (xy 188.426852 -274.999704)
			(xy 188.426847 -274.999958) (xy 188.74411 -274.999958) (xy 188.74807 -274.950904) (xy 188.759847 -274.90312)
			(xy 188.779138 -274.857844) (xy 188.805441 -274.816248) (xy 188.838076 -274.779411) (xy 188.876197 -274.748286)
			(xy 188.918818 -274.723679) (xy 188.964834 -274.706227) (xy 189.013053 -274.696383) (xy 189.062228 -274.694402)
			(xy 189.111083 -274.700334) (xy 189.158354 -274.714026) (xy 189.202816 -274.735124) (xy 189.243319 -274.76308)
			(xy 189.278812 -274.797172) (xy 189.308377 -274.836516) (xy 189.331248 -274.880093) (xy 189.346832 -274.926774)
			(xy 189.354727 -274.975351) (xy 189.355222 -274.999958) (xy 189.354727 -275.024565) (xy 189.354548 -275.025666)
			(xy 189.672972 -275.025666) (xy 189.672972 -274.97425) (xy 189.681015 -274.923468) (xy 189.696903 -274.874569)
			(xy 189.720246 -274.828757) (xy 189.750467 -274.787161) (xy 189.786823 -274.750805) (xy 189.828419 -274.720584)
			(xy 189.874231 -274.697241) (xy 189.92313 -274.681353) (xy 189.973912 -274.67331) (xy 190.025328 -274.67331)
			(xy 190.07611 -274.681353) (xy 190.125009 -274.697241) (xy 190.170821 -274.720584) (xy 190.212417 -274.750805)
			(xy 190.248773 -274.787161) (xy 190.278994 -274.828757) (xy 190.302337 -274.874569) (xy 190.318225 -274.923468)
			(xy 190.326268 -274.97425) (xy 190.326772 -274.999958) (xy 190.64403 -274.999958) (xy 190.64799 -274.950904)
			(xy 190.659767 -274.90312) (xy 190.679058 -274.857844) (xy 190.705361 -274.816248) (xy 190.737996 -274.779411)
			(xy 190.776117 -274.748286) (xy 190.818738 -274.723679) (xy 190.864754 -274.706227) (xy 190.912973 -274.696383)
			(xy 190.962148 -274.694402) (xy 191.011003 -274.700334) (xy 191.058274 -274.714026) (xy 191.102736 -274.735124)
			(xy 191.143239 -274.76308) (xy 191.178732 -274.797172) (xy 191.208297 -274.836516) (xy 191.231168 -274.880093)
			(xy 191.246752 -274.926774) (xy 191.254647 -274.975351) (xy 191.255142 -274.999958) (xy 191.254647 -275.024565)
			(xy 191.254509 -275.025412) (xy 191.573146 -275.025412) (xy 191.573146 -274.973996) (xy 191.581189 -274.923214)
			(xy 191.597077 -274.874315) (xy 191.62042 -274.828503) (xy 191.650641 -274.786907) (xy 191.686997 -274.750551)
			(xy 191.728593 -274.72033) (xy 191.774405 -274.696987) (xy 191.823304 -274.681099) (xy 191.874086 -274.673056)
			(xy 191.925502 -274.673056) (xy 191.976284 -274.681099) (xy 192.025183 -274.696987) (xy 192.070995 -274.72033)
			(xy 192.112591 -274.750551) (xy 192.148947 -274.786907) (xy 192.179168 -274.828503) (xy 192.202511 -274.874315)
			(xy 192.218399 -274.923214) (xy 192.226442 -274.973996) (xy 192.226946 -274.999704) (xy 192.226941 -274.999958)
			(xy 192.54395 -274.999958) (xy 192.54791 -274.950904) (xy 192.559687 -274.90312) (xy 192.578978 -274.857844)
			(xy 192.605281 -274.816248) (xy 192.637916 -274.779411) (xy 192.676037 -274.748286) (xy 192.718658 -274.723679)
			(xy 192.764674 -274.706227) (xy 192.812893 -274.696383) (xy 192.862068 -274.694402) (xy 192.910923 -274.700334)
			(xy 192.958194 -274.714026) (xy 193.002656 -274.735124) (xy 193.043159 -274.76308) (xy 193.078652 -274.797172)
			(xy 193.108217 -274.836516) (xy 193.131088 -274.880093) (xy 193.146672 -274.926774) (xy 193.154567 -274.975351)
			(xy 193.155062 -274.999958) (xy 193.154567 -275.024565) (xy 193.154388 -275.025666) (xy 193.473066 -275.025666)
			(xy 193.473066 -274.97425) (xy 193.481109 -274.923468) (xy 193.496997 -274.874569) (xy 193.52034 -274.828757)
			(xy 193.550561 -274.787161) (xy 193.586917 -274.750805) (xy 193.628513 -274.720584) (xy 193.674325 -274.697241)
			(xy 193.723224 -274.681353) (xy 193.774006 -274.67331) (xy 193.825422 -274.67331) (xy 193.876204 -274.681353)
			(xy 193.925103 -274.697241) (xy 193.970915 -274.720584) (xy 194.012511 -274.750805) (xy 194.048867 -274.787161)
			(xy 194.079088 -274.828757) (xy 194.102431 -274.874569) (xy 194.118319 -274.923468) (xy 194.126362 -274.97425)
			(xy 194.126866 -274.999958) (xy 194.44387 -274.999958) (xy 194.44783 -274.950904) (xy 194.459607 -274.90312)
			(xy 194.478898 -274.857844) (xy 194.505201 -274.816248) (xy 194.537836 -274.779411) (xy 194.575957 -274.748286)
			(xy 194.618578 -274.723679) (xy 194.664594 -274.706227) (xy 194.712813 -274.696383) (xy 194.761988 -274.694402)
			(xy 194.810843 -274.700334) (xy 194.858114 -274.714026) (xy 194.902576 -274.735124) (xy 194.943079 -274.76308)
			(xy 194.978572 -274.797172) (xy 195.008137 -274.836516) (xy 195.031008 -274.880093) (xy 195.046592 -274.926774)
			(xy 195.054487 -274.975351) (xy 195.054982 -274.999958) (xy 195.054487 -275.024565) (xy 195.054308 -275.025666)
			(xy 195.372986 -275.025666) (xy 195.372986 -274.97425) (xy 195.381029 -274.923468) (xy 195.396917 -274.874569)
			(xy 195.42026 -274.828757) (xy 195.450481 -274.787161) (xy 195.486837 -274.750805) (xy 195.528433 -274.720584)
			(xy 195.574245 -274.697241) (xy 195.623144 -274.681353) (xy 195.673926 -274.67331) (xy 195.725342 -274.67331)
			(xy 195.776124 -274.681353) (xy 195.825023 -274.697241) (xy 195.870835 -274.720584) (xy 195.912431 -274.750805)
			(xy 195.948787 -274.787161) (xy 195.979008 -274.828757) (xy 196.002351 -274.874569) (xy 196.018239 -274.923468)
			(xy 196.026282 -274.97425) (xy 196.026786 -274.999958) (xy 196.344044 -274.999958) (xy 196.348004 -274.950904)
			(xy 196.359781 -274.90312) (xy 196.379072 -274.857844) (xy 196.405375 -274.816248) (xy 196.43801 -274.779411)
			(xy 196.476131 -274.748286) (xy 196.518752 -274.723679) (xy 196.564768 -274.706227) (xy 196.612987 -274.696383)
			(xy 196.662162 -274.694402) (xy 196.711017 -274.700334) (xy 196.758288 -274.714026) (xy 196.80275 -274.735124)
			(xy 196.843253 -274.76308) (xy 196.878746 -274.797172) (xy 196.908311 -274.836516) (xy 196.931182 -274.880093)
			(xy 196.946766 -274.926774) (xy 196.954661 -274.975351) (xy 196.955156 -274.999958) (xy 196.954661 -275.024565)
			(xy 196.954523 -275.025412) (xy 197.273414 -275.025412) (xy 197.273414 -274.973996) (xy 197.281457 -274.923214)
			(xy 197.297345 -274.874315) (xy 197.320688 -274.828503) (xy 197.350909 -274.786907) (xy 197.387265 -274.750551)
			(xy 197.428861 -274.72033) (xy 197.474673 -274.696987) (xy 197.523572 -274.681099) (xy 197.574354 -274.673056)
			(xy 197.62577 -274.673056) (xy 197.676552 -274.681099) (xy 197.725451 -274.696987) (xy 197.771263 -274.72033)
			(xy 197.812859 -274.750551) (xy 197.849215 -274.786907) (xy 197.879436 -274.828503) (xy 197.902779 -274.874315)
			(xy 197.918667 -274.923214) (xy 197.92671 -274.973996) (xy 197.927214 -274.999704) (xy 197.92671 -275.025412)
			(xy 198.223374 -275.025412) (xy 198.223374 -274.973996) (xy 198.231417 -274.923214) (xy 198.247305 -274.874315)
			(xy 198.270648 -274.828503) (xy 198.300869 -274.786907) (xy 198.337225 -274.750551) (xy 198.378821 -274.72033)
			(xy 198.424633 -274.696987) (xy 198.473532 -274.681099) (xy 198.524314 -274.673056) (xy 198.57573 -274.673056)
			(xy 198.626512 -274.681099) (xy 198.675411 -274.696987) (xy 198.721223 -274.72033) (xy 198.762819 -274.750551)
			(xy 198.799175 -274.786907) (xy 198.829396 -274.828503) (xy 198.852739 -274.874315) (xy 198.868627 -274.923214)
			(xy 198.87667 -274.973996) (xy 198.877174 -274.999704) (xy 198.877169 -274.999958) (xy 199.194432 -274.999958)
			(xy 199.198392 -274.950904) (xy 199.210169 -274.90312) (xy 199.22946 -274.857844) (xy 199.255763 -274.816248)
			(xy 199.288398 -274.779411) (xy 199.326519 -274.748286) (xy 199.36914 -274.723679) (xy 199.415156 -274.706227)
			(xy 199.463375 -274.696383) (xy 199.51255 -274.694402) (xy 199.561405 -274.700334) (xy 199.608676 -274.714026)
			(xy 199.653138 -274.735124) (xy 199.693641 -274.76308) (xy 199.729134 -274.797172) (xy 199.758699 -274.836516)
			(xy 199.78157 -274.880093) (xy 199.797154 -274.926774) (xy 199.805049 -274.975351) (xy 199.805544 -274.999958)
			(xy 199.805049 -275.024565) (xy 199.797154 -275.073142) (xy 199.78157 -275.119823) (xy 199.758699 -275.1634)
			(xy 199.729134 -275.202744) (xy 199.693641 -275.236836) (xy 199.653138 -275.264792) (xy 199.608676 -275.28589)
			(xy 199.561405 -275.299582) (xy 199.51255 -275.305514) (xy 199.463375 -275.303533) (xy 199.415156 -275.293689)
			(xy 199.36914 -275.276237) (xy 199.326519 -275.25163) (xy 199.288398 -275.220505) (xy 199.255763 -275.183668)
			(xy 199.22946 -275.142072) (xy 199.210169 -275.096796) (xy 199.198392 -275.049012) (xy 199.194432 -274.999958)
			(xy 198.877169 -274.999958) (xy 198.87667 -275.025412) (xy 198.868627 -275.076194) (xy 198.852739 -275.125093)
			(xy 198.829396 -275.170905) (xy 198.799175 -275.212501) (xy 198.762819 -275.248857) (xy 198.721223 -275.279078)
			(xy 198.675411 -275.302421) (xy 198.626512 -275.318309) (xy 198.57573 -275.326352) (xy 198.524314 -275.326352)
			(xy 198.473532 -275.318309) (xy 198.424633 -275.302421) (xy 198.378821 -275.279078) (xy 198.337225 -275.248857)
			(xy 198.300869 -275.212501) (xy 198.270648 -275.170905) (xy 198.247305 -275.125093) (xy 198.231417 -275.076194)
			(xy 198.223374 -275.025412) (xy 197.92671 -275.025412) (xy 197.918667 -275.076194) (xy 197.902779 -275.125093)
			(xy 197.879436 -275.170905) (xy 197.849215 -275.212501) (xy 197.812859 -275.248857) (xy 197.771263 -275.279078)
			(xy 197.725451 -275.302421) (xy 197.676552 -275.318309) (xy 197.62577 -275.326352) (xy 197.574354 -275.326352)
			(xy 197.523572 -275.318309) (xy 197.474673 -275.302421) (xy 197.428861 -275.279078) (xy 197.387265 -275.248857)
			(xy 197.350909 -275.212501) (xy 197.320688 -275.170905) (xy 197.297345 -275.125093) (xy 197.281457 -275.076194)
			(xy 197.273414 -275.025412) (xy 196.954523 -275.025412) (xy 196.946766 -275.073142) (xy 196.931182 -275.119823)
			(xy 196.908311 -275.1634) (xy 196.878746 -275.202744) (xy 196.843253 -275.236836) (xy 196.80275 -275.264792)
			(xy 196.758288 -275.28589) (xy 196.711017 -275.299582) (xy 196.662162 -275.305514) (xy 196.612987 -275.303533)
			(xy 196.564768 -275.293689) (xy 196.518752 -275.276237) (xy 196.476131 -275.25163) (xy 196.43801 -275.220505)
			(xy 196.405375 -275.183668) (xy 196.379072 -275.142072) (xy 196.359781 -275.096796) (xy 196.348004 -275.049012)
			(xy 196.344044 -274.999958) (xy 196.026786 -274.999958) (xy 196.026282 -275.025666) (xy 196.018239 -275.076448)
			(xy 196.002351 -275.125347) (xy 195.979008 -275.171159) (xy 195.948787 -275.212755) (xy 195.912431 -275.249111)
			(xy 195.870835 -275.279332) (xy 195.825023 -275.302675) (xy 195.776124 -275.318563) (xy 195.725342 -275.326606)
			(xy 195.673926 -275.326606) (xy 195.623144 -275.318563) (xy 195.574245 -275.302675) (xy 195.528433 -275.279332)
			(xy 195.486837 -275.249111) (xy 195.450481 -275.212755) (xy 195.42026 -275.171159) (xy 195.396917 -275.125347)
			(xy 195.381029 -275.076448) (xy 195.372986 -275.025666) (xy 195.054308 -275.025666) (xy 195.046592 -275.073142)
			(xy 195.031008 -275.119823) (xy 195.008137 -275.1634) (xy 194.978572 -275.202744) (xy 194.943079 -275.236836)
			(xy 194.902576 -275.264792) (xy 194.858114 -275.28589) (xy 194.810843 -275.299582) (xy 194.761988 -275.305514)
			(xy 194.712813 -275.303533) (xy 194.664594 -275.293689) (xy 194.618578 -275.276237) (xy 194.575957 -275.25163)
			(xy 194.537836 -275.220505) (xy 194.505201 -275.183668) (xy 194.478898 -275.142072) (xy 194.459607 -275.096796)
			(xy 194.44783 -275.049012) (xy 194.44387 -274.999958) (xy 194.126866 -274.999958) (xy 194.126362 -275.025666)
			(xy 194.118319 -275.076448) (xy 194.102431 -275.125347) (xy 194.079088 -275.171159) (xy 194.048867 -275.212755)
			(xy 194.012511 -275.249111) (xy 193.970915 -275.279332) (xy 193.925103 -275.302675) (xy 193.876204 -275.318563)
			(xy 193.825422 -275.326606) (xy 193.774006 -275.326606) (xy 193.723224 -275.318563) (xy 193.674325 -275.302675)
			(xy 193.628513 -275.279332) (xy 193.586917 -275.249111) (xy 193.550561 -275.212755) (xy 193.52034 -275.171159)
			(xy 193.496997 -275.125347) (xy 193.481109 -275.076448) (xy 193.473066 -275.025666) (xy 193.154388 -275.025666)
			(xy 193.146672 -275.073142) (xy 193.131088 -275.119823) (xy 193.108217 -275.1634) (xy 193.078652 -275.202744)
			(xy 193.043159 -275.236836) (xy 193.002656 -275.264792) (xy 192.958194 -275.28589) (xy 192.910923 -275.299582)
			(xy 192.862068 -275.305514) (xy 192.812893 -275.303533) (xy 192.764674 -275.293689) (xy 192.718658 -275.276237)
			(xy 192.676037 -275.25163) (xy 192.637916 -275.220505) (xy 192.605281 -275.183668) (xy 192.578978 -275.142072)
			(xy 192.559687 -275.096796) (xy 192.54791 -275.049012) (xy 192.54395 -274.999958) (xy 192.226941 -274.999958)
			(xy 192.226442 -275.025412) (xy 192.218399 -275.076194) (xy 192.202511 -275.125093) (xy 192.179168 -275.170905)
			(xy 192.148947 -275.212501) (xy 192.112591 -275.248857) (xy 192.070995 -275.279078) (xy 192.025183 -275.302421)
			(xy 191.976284 -275.318309) (xy 191.925502 -275.326352) (xy 191.874086 -275.326352) (xy 191.823304 -275.318309)
			(xy 191.774405 -275.302421) (xy 191.728593 -275.279078) (xy 191.686997 -275.248857) (xy 191.650641 -275.212501)
			(xy 191.62042 -275.170905) (xy 191.597077 -275.125093) (xy 191.581189 -275.076194) (xy 191.573146 -275.025412)
			(xy 191.254509 -275.025412) (xy 191.246752 -275.073142) (xy 191.231168 -275.119823) (xy 191.208297 -275.1634)
			(xy 191.178732 -275.202744) (xy 191.143239 -275.236836) (xy 191.102736 -275.264792) (xy 191.058274 -275.28589)
			(xy 191.011003 -275.299582) (xy 190.962148 -275.305514) (xy 190.912973 -275.303533) (xy 190.864754 -275.293689)
			(xy 190.818738 -275.276237) (xy 190.776117 -275.25163) (xy 190.737996 -275.220505) (xy 190.705361 -275.183668)
			(xy 190.679058 -275.142072) (xy 190.659767 -275.096796) (xy 190.64799 -275.049012) (xy 190.64403 -274.999958)
			(xy 190.326772 -274.999958) (xy 190.326268 -275.025666) (xy 190.318225 -275.076448) (xy 190.302337 -275.125347)
			(xy 190.278994 -275.171159) (xy 190.248773 -275.212755) (xy 190.212417 -275.249111) (xy 190.170821 -275.279332)
			(xy 190.125009 -275.302675) (xy 190.07611 -275.318563) (xy 190.025328 -275.326606) (xy 189.973912 -275.326606)
			(xy 189.92313 -275.318563) (xy 189.874231 -275.302675) (xy 189.828419 -275.279332) (xy 189.786823 -275.249111)
			(xy 189.750467 -275.212755) (xy 189.720246 -275.171159) (xy 189.696903 -275.125347) (xy 189.681015 -275.076448)
			(xy 189.672972 -275.025666) (xy 189.354548 -275.025666) (xy 189.346832 -275.073142) (xy 189.331248 -275.119823)
			(xy 189.308377 -275.1634) (xy 189.278812 -275.202744) (xy 189.243319 -275.236836) (xy 189.202816 -275.264792)
			(xy 189.158354 -275.28589) (xy 189.111083 -275.299582) (xy 189.062228 -275.305514) (xy 189.013053 -275.303533)
			(xy 188.964834 -275.293689) (xy 188.918818 -275.276237) (xy 188.876197 -275.25163) (xy 188.838076 -275.220505)
			(xy 188.805441 -275.183668) (xy 188.779138 -275.142072) (xy 188.759847 -275.096796) (xy 188.74807 -275.049012)
			(xy 188.74411 -274.999958) (xy 188.426847 -274.999958) (xy 188.426348 -275.025412) (xy 188.418305 -275.076194)
			(xy 188.402417 -275.125093) (xy 188.379074 -275.170905) (xy 188.348853 -275.212501) (xy 188.312497 -275.248857)
			(xy 188.270901 -275.279078) (xy 188.225089 -275.302421) (xy 188.17619 -275.318309) (xy 188.125408 -275.326352)
			(xy 188.073992 -275.326352) (xy 188.02321 -275.318309) (xy 187.974311 -275.302421) (xy 187.928499 -275.279078)
			(xy 187.886903 -275.248857) (xy 187.850547 -275.212501) (xy 187.820326 -275.170905) (xy 187.796983 -275.125093)
			(xy 187.781095 -275.076194) (xy 187.773052 -275.025412) (xy 187.454669 -275.025412) (xy 187.446912 -275.073142)
			(xy 187.431328 -275.119823) (xy 187.408457 -275.1634) (xy 187.378892 -275.202744) (xy 187.343399 -275.236836)
			(xy 187.302896 -275.264792) (xy 187.258434 -275.28589) (xy 187.211163 -275.299582) (xy 187.162308 -275.305514)
			(xy 187.113133 -275.303533) (xy 187.064914 -275.293689) (xy 187.018898 -275.276237) (xy 186.976277 -275.25163)
			(xy 186.938156 -275.220505) (xy 186.905521 -275.183668) (xy 186.879218 -275.142072) (xy 186.859927 -275.096796)
			(xy 186.84815 -275.049012) (xy 186.84419 -274.999958) (xy 186.526678 -274.999958) (xy 186.526174 -275.025666)
			(xy 186.518131 -275.076448) (xy 186.502243 -275.125347) (xy 186.4789 -275.171159) (xy 186.448679 -275.212755)
			(xy 186.412323 -275.249111) (xy 186.370727 -275.279332) (xy 186.324915 -275.302675) (xy 186.276016 -275.318563)
			(xy 186.225234 -275.326606) (xy 186.173818 -275.326606) (xy 186.123036 -275.318563) (xy 186.074137 -275.302675)
			(xy 186.028325 -275.279332) (xy 185.986729 -275.249111) (xy 185.950373 -275.212755) (xy 185.920152 -275.171159)
			(xy 185.896809 -275.125347) (xy 185.880921 -275.076448) (xy 185.872878 -275.025666) (xy 185.554708 -275.025666)
			(xy 185.546992 -275.073142) (xy 185.531408 -275.119823) (xy 185.508537 -275.1634) (xy 185.478972 -275.202744)
			(xy 185.443479 -275.236836) (xy 185.402976 -275.264792) (xy 185.358514 -275.28589) (xy 185.311243 -275.299582)
			(xy 185.262388 -275.305514) (xy 185.213213 -275.303533) (xy 185.164994 -275.293689) (xy 185.118978 -275.276237)
			(xy 185.076357 -275.25163) (xy 185.038236 -275.220505) (xy 185.005601 -275.183668) (xy 184.979298 -275.142072)
			(xy 184.960007 -275.096796) (xy 184.94823 -275.049012) (xy 184.94427 -274.999958) (xy 184.626753 -274.999958)
			(xy 184.626254 -275.025412) (xy 184.618211 -275.076194) (xy 184.602323 -275.125093) (xy 184.57898 -275.170905)
			(xy 184.548759 -275.212501) (xy 184.512403 -275.248857) (xy 184.470807 -275.279078) (xy 184.424995 -275.302421)
			(xy 184.376096 -275.318309) (xy 184.325314 -275.326352) (xy 184.273898 -275.326352) (xy 184.223116 -275.318309)
			(xy 184.174217 -275.302421) (xy 184.128405 -275.279078) (xy 184.086809 -275.248857) (xy 184.050453 -275.212501)
			(xy 184.020232 -275.170905) (xy 183.996889 -275.125093) (xy 183.981001 -275.076194) (xy 183.972958 -275.025412)
			(xy 183.654575 -275.025412) (xy 183.646818 -275.073142) (xy 183.631234 -275.119823) (xy 183.608363 -275.1634)
			(xy 183.578798 -275.202744) (xy 183.543305 -275.236836) (xy 183.502802 -275.264792) (xy 183.45834 -275.28589)
			(xy 183.411069 -275.299582) (xy 183.362214 -275.305514) (xy 183.313039 -275.303533) (xy 183.26482 -275.293689)
			(xy 183.218804 -275.276237) (xy 183.176183 -275.25163) (xy 183.138062 -275.220505) (xy 183.105427 -275.183668)
			(xy 183.079124 -275.142072) (xy 183.059833 -275.096796) (xy 183.048056 -275.049012) (xy 183.044096 -274.999958)
			(xy 182.726838 -274.999958) (xy 182.726334 -275.025666) (xy 182.718291 -275.076448) (xy 182.702403 -275.125347)
			(xy 182.67906 -275.171159) (xy 182.648839 -275.212755) (xy 182.612483 -275.249111) (xy 182.570887 -275.279332)
			(xy 182.525075 -275.302675) (xy 182.476176 -275.318563) (xy 182.425394 -275.326606) (xy 182.373978 -275.326606)
			(xy 182.323196 -275.318563) (xy 182.274297 -275.302675) (xy 182.228485 -275.279332) (xy 182.186889 -275.249111)
			(xy 182.150533 -275.212755) (xy 182.120312 -275.171159) (xy 182.096969 -275.125347) (xy 182.081081 -275.076448)
			(xy 182.073038 -275.025666) (xy 181.754614 -275.025666) (xy 181.746898 -275.073142) (xy 181.731314 -275.119823)
			(xy 181.708443 -275.1634) (xy 181.678878 -275.202744) (xy 181.643385 -275.236836) (xy 181.602882 -275.264792)
			(xy 181.55842 -275.28589) (xy 181.511149 -275.299582) (xy 181.462294 -275.305514) (xy 181.413119 -275.303533)
			(xy 181.3649 -275.293689) (xy 181.318884 -275.276237) (xy 181.276263 -275.25163) (xy 181.238142 -275.220505)
			(xy 181.205507 -275.183668) (xy 181.179204 -275.142072) (xy 181.159913 -275.096796) (xy 181.148136 -275.049012)
			(xy 181.144176 -274.999958) (xy 180.826913 -274.999958) (xy 180.826414 -275.025412) (xy 180.818371 -275.076194)
			(xy 180.802483 -275.125093) (xy 180.77914 -275.170905) (xy 180.748919 -275.212501) (xy 180.712563 -275.248857)
			(xy 180.670967 -275.279078) (xy 180.625155 -275.302421) (xy 180.576256 -275.318309) (xy 180.525474 -275.326352)
			(xy 180.474058 -275.326352) (xy 180.423276 -275.318309) (xy 180.374377 -275.302421) (xy 180.328565 -275.279078)
			(xy 180.286969 -275.248857) (xy 180.250613 -275.212501) (xy 180.220392 -275.170905) (xy 180.197049 -275.125093)
			(xy 180.181161 -275.076194) (xy 180.173118 -275.025412) (xy 179.854735 -275.025412) (xy 179.846978 -275.073142)
			(xy 179.831394 -275.119823) (xy 179.808523 -275.1634) (xy 179.778958 -275.202744) (xy 179.743465 -275.236836)
			(xy 179.702962 -275.264792) (xy 179.6585 -275.28589) (xy 179.611229 -275.299582) (xy 179.562374 -275.305514)
			(xy 179.513199 -275.303533) (xy 179.46498 -275.293689) (xy 179.418964 -275.276237) (xy 179.376343 -275.25163)
			(xy 179.338222 -275.220505) (xy 179.305587 -275.183668) (xy 179.279284 -275.142072) (xy 179.259993 -275.096796)
			(xy 179.248216 -275.049012) (xy 179.244256 -274.999958) (xy 178.926744 -274.999958) (xy 178.92624 -275.025666)
			(xy 178.918197 -275.076448) (xy 178.902309 -275.125347) (xy 178.878966 -275.171159) (xy 178.848745 -275.212755)
			(xy 178.812389 -275.249111) (xy 178.770793 -275.279332) (xy 178.724981 -275.302675) (xy 178.676082 -275.318563)
			(xy 178.6253 -275.326606) (xy 178.573884 -275.326606) (xy 178.523102 -275.318563) (xy 178.474203 -275.302675)
			(xy 178.428391 -275.279332) (xy 178.386795 -275.249111) (xy 178.350439 -275.212755) (xy 178.320218 -275.171159)
			(xy 178.296875 -275.125347) (xy 178.280987 -275.076448) (xy 178.272944 -275.025666) (xy 177.953675 -275.025666)
			(xy 177.95163 -275.050351) (xy 177.939226 -275.099329) (xy 177.918931 -275.145597) (xy 177.891296 -275.187894)
			(xy 177.857076 -275.225064) (xy 177.817205 -275.256096) (xy 177.77277 -275.280141) (xy 177.724983 -275.296544)
			(xy 177.675148 -275.304858) (xy 177.649886 -275.305266) (xy 177.618136 -275.303488) (xy 177.607214 -275.302472)
			(xy 177.586894 -275.309076) (xy 177.522632 -275.366988) (xy 177.515122 -275.374532) (xy 177.506459 -275.393952)
			(xy 177.505868 -275.40458) (xy 177.505868 -275.4757) (xy 177.505614 -275.490432) (xy 177.50536 -275.495004)
			(xy 177.50409 -275.50999) (xy 177.501595 -275.530448) (xy 177.492166 -275.57057) (xy 177.485294 -275.59)
			(xy 177.483008 -275.595842) (xy 177.479885 -275.605033) (xy 177.480051 -275.624427) (xy 177.487397 -275.642378)
			(xy 177.500876 -275.656323) (xy 177.518566 -275.664276) (xy 177.537944 -275.665101) (xy 177.54727 -275.66239)
			(xy 177.572109 -275.654094) (xy 177.623704 -275.645157) (xy 177.649886 -275.64461) (xy 177.675143 -275.645102)
			(xy 177.724968 -275.653414) (xy 177.772746 -275.669814) (xy 177.817172 -275.693854) (xy 177.857036 -275.72488)
			(xy 177.891249 -275.762043) (xy 177.918878 -275.804331) (xy 177.93917 -275.85059) (xy 177.95157 -275.899559)
			(xy 177.955742 -275.9499) (xy 177.95361 -275.975626) (xy 178.272944 -275.975626) (xy 178.272944 -275.92421)
			(xy 178.280987 -275.873428) (xy 178.296875 -275.824529) (xy 178.320218 -275.778717) (xy 178.350439 -275.737121)
			(xy 178.386795 -275.700765) (xy 178.428391 -275.670544) (xy 178.474203 -275.647201) (xy 178.523102 -275.631313)
			(xy 178.573884 -275.62327) (xy 178.6253 -275.62327) (xy 178.676082 -275.631313) (xy 178.724981 -275.647201)
			(xy 178.770793 -275.670544) (xy 178.812389 -275.700765) (xy 178.848745 -275.737121) (xy 178.878966 -275.778717)
			(xy 178.902309 -275.824529) (xy 178.918197 -275.873428) (xy 178.92624 -275.92421) (xy 178.926744 -275.949918)
			(xy 179.244256 -275.949918) (xy 179.248216 -275.900864) (xy 179.259993 -275.85308) (xy 179.279284 -275.807804)
			(xy 179.305587 -275.766208) (xy 179.338222 -275.729371) (xy 179.376343 -275.698246) (xy 179.418964 -275.673639)
			(xy 179.46498 -275.656187) (xy 179.513199 -275.646343) (xy 179.562374 -275.644362) (xy 179.611229 -275.650294)
			(xy 179.6585 -275.663986) (xy 179.702962 -275.685084) (xy 179.743465 -275.71304) (xy 179.778958 -275.747132)
			(xy 179.808523 -275.786476) (xy 179.831394 -275.830053) (xy 179.846978 -275.876734) (xy 179.854873 -275.925311)
			(xy 179.855368 -275.949918) (xy 179.854873 -275.974525) (xy 179.854735 -275.975372) (xy 180.173118 -275.975372)
			(xy 180.173118 -275.923956) (xy 180.181161 -275.873174) (xy 180.197049 -275.824275) (xy 180.220392 -275.778463)
			(xy 180.250613 -275.736867) (xy 180.286969 -275.700511) (xy 180.328565 -275.67029) (xy 180.374377 -275.646947)
			(xy 180.423276 -275.631059) (xy 180.474058 -275.623016) (xy 180.525474 -275.623016) (xy 180.576256 -275.631059)
			(xy 180.625155 -275.646947) (xy 180.670967 -275.67029) (xy 180.712563 -275.700511) (xy 180.748919 -275.736867)
			(xy 180.77914 -275.778463) (xy 180.802483 -275.824275) (xy 180.818371 -275.873174) (xy 180.826414 -275.923956)
			(xy 180.826918 -275.949664) (xy 180.826913 -275.949918) (xy 181.144176 -275.949918) (xy 181.148136 -275.900864)
			(xy 181.159913 -275.85308) (xy 181.179204 -275.807804) (xy 181.205507 -275.766208) (xy 181.238142 -275.729371)
			(xy 181.276263 -275.698246) (xy 181.318884 -275.673639) (xy 181.3649 -275.656187) (xy 181.413119 -275.646343)
			(xy 181.462294 -275.644362) (xy 181.511149 -275.650294) (xy 181.55842 -275.663986) (xy 181.602882 -275.685084)
			(xy 181.643385 -275.71304) (xy 181.678878 -275.747132) (xy 181.708443 -275.786476) (xy 181.731314 -275.830053)
			(xy 181.746898 -275.876734) (xy 181.754793 -275.925311) (xy 181.755288 -275.949918) (xy 181.754793 -275.974525)
			(xy 181.754614 -275.975626) (xy 182.073038 -275.975626) (xy 182.073038 -275.92421) (xy 182.081081 -275.873428)
			(xy 182.096969 -275.824529) (xy 182.120312 -275.778717) (xy 182.150533 -275.737121) (xy 182.186889 -275.700765)
			(xy 182.228485 -275.670544) (xy 182.274297 -275.647201) (xy 182.323196 -275.631313) (xy 182.373978 -275.62327)
			(xy 182.425394 -275.62327) (xy 182.476176 -275.631313) (xy 182.525075 -275.647201) (xy 182.570887 -275.670544)
			(xy 182.612483 -275.700765) (xy 182.648839 -275.737121) (xy 182.67906 -275.778717) (xy 182.702403 -275.824529)
			(xy 182.718291 -275.873428) (xy 182.726334 -275.92421) (xy 182.726838 -275.949918) (xy 183.044096 -275.949918)
			(xy 183.048056 -275.900864) (xy 183.059833 -275.85308) (xy 183.079124 -275.807804) (xy 183.105427 -275.766208)
			(xy 183.138062 -275.729371) (xy 183.176183 -275.698246) (xy 183.218804 -275.673639) (xy 183.26482 -275.656187)
			(xy 183.313039 -275.646343) (xy 183.362214 -275.644362) (xy 183.411069 -275.650294) (xy 183.45834 -275.663986)
			(xy 183.502802 -275.685084) (xy 183.543305 -275.71304) (xy 183.578798 -275.747132) (xy 183.608363 -275.786476)
			(xy 183.631234 -275.830053) (xy 183.646818 -275.876734) (xy 183.654713 -275.925311) (xy 183.655208 -275.949918)
			(xy 183.654713 -275.974525) (xy 183.654575 -275.975372) (xy 183.972958 -275.975372) (xy 183.972958 -275.923956)
			(xy 183.981001 -275.873174) (xy 183.996889 -275.824275) (xy 184.020232 -275.778463) (xy 184.050453 -275.736867)
			(xy 184.086809 -275.700511) (xy 184.128405 -275.67029) (xy 184.174217 -275.646947) (xy 184.223116 -275.631059)
			(xy 184.273898 -275.623016) (xy 184.325314 -275.623016) (xy 184.376096 -275.631059) (xy 184.424995 -275.646947)
			(xy 184.470807 -275.67029) (xy 184.512403 -275.700511) (xy 184.548759 -275.736867) (xy 184.57898 -275.778463)
			(xy 184.602323 -275.824275) (xy 184.618211 -275.873174) (xy 184.626254 -275.923956) (xy 184.626758 -275.949664)
			(xy 184.626753 -275.949918) (xy 184.94427 -275.949918) (xy 184.94823 -275.900864) (xy 184.960007 -275.85308)
			(xy 184.979298 -275.807804) (xy 185.005601 -275.766208) (xy 185.038236 -275.729371) (xy 185.076357 -275.698246)
			(xy 185.118978 -275.673639) (xy 185.164994 -275.656187) (xy 185.213213 -275.646343) (xy 185.262388 -275.644362)
			(xy 185.311243 -275.650294) (xy 185.358514 -275.663986) (xy 185.402976 -275.685084) (xy 185.443479 -275.71304)
			(xy 185.478972 -275.747132) (xy 185.508537 -275.786476) (xy 185.531408 -275.830053) (xy 185.546992 -275.876734)
			(xy 185.554887 -275.925311) (xy 185.555382 -275.949918) (xy 185.554887 -275.974525) (xy 185.554708 -275.975626)
			(xy 185.872878 -275.975626) (xy 185.872878 -275.92421) (xy 185.880921 -275.873428) (xy 185.896809 -275.824529)
			(xy 185.920152 -275.778717) (xy 185.950373 -275.737121) (xy 185.986729 -275.700765) (xy 186.028325 -275.670544)
			(xy 186.074137 -275.647201) (xy 186.123036 -275.631313) (xy 186.173818 -275.62327) (xy 186.225234 -275.62327)
			(xy 186.276016 -275.631313) (xy 186.324915 -275.647201) (xy 186.370727 -275.670544) (xy 186.412323 -275.700765)
			(xy 186.448679 -275.737121) (xy 186.4789 -275.778717) (xy 186.502243 -275.824529) (xy 186.518131 -275.873428)
			(xy 186.526174 -275.92421) (xy 186.526678 -275.949918) (xy 186.84419 -275.949918) (xy 186.84815 -275.900864)
			(xy 186.859927 -275.85308) (xy 186.879218 -275.807804) (xy 186.905521 -275.766208) (xy 186.938156 -275.729371)
			(xy 186.976277 -275.698246) (xy 187.018898 -275.673639) (xy 187.064914 -275.656187) (xy 187.113133 -275.646343)
			(xy 187.162308 -275.644362) (xy 187.211163 -275.650294) (xy 187.258434 -275.663986) (xy 187.302896 -275.685084)
			(xy 187.343399 -275.71304) (xy 187.378892 -275.747132) (xy 187.408457 -275.786476) (xy 187.431328 -275.830053)
			(xy 187.446912 -275.876734) (xy 187.454807 -275.925311) (xy 187.455302 -275.949918) (xy 187.454807 -275.974525)
			(xy 187.454669 -275.975372) (xy 187.773052 -275.975372) (xy 187.773052 -275.923956) (xy 187.781095 -275.873174)
			(xy 187.796983 -275.824275) (xy 187.820326 -275.778463) (xy 187.850547 -275.736867) (xy 187.886903 -275.700511)
			(xy 187.928499 -275.67029) (xy 187.974311 -275.646947) (xy 188.02321 -275.631059) (xy 188.073992 -275.623016)
			(xy 188.125408 -275.623016) (xy 188.17619 -275.631059) (xy 188.225089 -275.646947) (xy 188.270901 -275.67029)
			(xy 188.312497 -275.700511) (xy 188.348853 -275.736867) (xy 188.379074 -275.778463) (xy 188.402417 -275.824275)
			(xy 188.418305 -275.873174) (xy 188.426348 -275.923956) (xy 188.426852 -275.949664) (xy 188.426847 -275.949918)
			(xy 188.74411 -275.949918) (xy 188.74807 -275.900864) (xy 188.759847 -275.85308) (xy 188.779138 -275.807804)
			(xy 188.805441 -275.766208) (xy 188.838076 -275.729371) (xy 188.876197 -275.698246) (xy 188.918818 -275.673639)
			(xy 188.964834 -275.656187) (xy 189.013053 -275.646343) (xy 189.062228 -275.644362) (xy 189.111083 -275.650294)
			(xy 189.158354 -275.663986) (xy 189.202816 -275.685084) (xy 189.243319 -275.71304) (xy 189.278812 -275.747132)
			(xy 189.308377 -275.786476) (xy 189.331248 -275.830053) (xy 189.346832 -275.876734) (xy 189.354727 -275.925311)
			(xy 189.355222 -275.949918) (xy 189.354727 -275.974525) (xy 189.354548 -275.975626) (xy 189.672972 -275.975626)
			(xy 189.672972 -275.92421) (xy 189.681015 -275.873428) (xy 189.696903 -275.824529) (xy 189.720246 -275.778717)
			(xy 189.750467 -275.737121) (xy 189.786823 -275.700765) (xy 189.828419 -275.670544) (xy 189.874231 -275.647201)
			(xy 189.92313 -275.631313) (xy 189.973912 -275.62327) (xy 190.025328 -275.62327) (xy 190.07611 -275.631313)
			(xy 190.125009 -275.647201) (xy 190.170821 -275.670544) (xy 190.212417 -275.700765) (xy 190.248773 -275.737121)
			(xy 190.278994 -275.778717) (xy 190.302337 -275.824529) (xy 190.318225 -275.873428) (xy 190.326268 -275.92421)
			(xy 190.326772 -275.949918) (xy 190.644284 -275.949918) (xy 190.648244 -275.900864) (xy 190.660021 -275.85308)
			(xy 190.679312 -275.807804) (xy 190.705615 -275.766208) (xy 190.73825 -275.729371) (xy 190.776371 -275.698246)
			(xy 190.818992 -275.673639) (xy 190.865008 -275.656187) (xy 190.913227 -275.646343) (xy 190.962402 -275.644362)
			(xy 191.011257 -275.650294) (xy 191.058528 -275.663986) (xy 191.10299 -275.685084) (xy 191.143493 -275.71304)
			(xy 191.178986 -275.747132) (xy 191.208551 -275.786476) (xy 191.231422 -275.830053) (xy 191.247006 -275.876734)
			(xy 191.254901 -275.925311) (xy 191.255396 -275.949918) (xy 191.254901 -275.974525) (xy 191.254763 -275.975372)
			(xy 191.573146 -275.975372) (xy 191.573146 -275.923956) (xy 191.581189 -275.873174) (xy 191.597077 -275.824275)
			(xy 191.62042 -275.778463) (xy 191.650641 -275.736867) (xy 191.686997 -275.700511) (xy 191.728593 -275.67029)
			(xy 191.774405 -275.646947) (xy 191.823304 -275.631059) (xy 191.874086 -275.623016) (xy 191.925502 -275.623016)
			(xy 191.976284 -275.631059) (xy 192.025183 -275.646947) (xy 192.070995 -275.67029) (xy 192.112591 -275.700511)
			(xy 192.148947 -275.736867) (xy 192.179168 -275.778463) (xy 192.202511 -275.824275) (xy 192.218399 -275.873174)
			(xy 192.226442 -275.923956) (xy 192.226946 -275.949664) (xy 192.226941 -275.949918) (xy 192.544204 -275.949918)
			(xy 192.548164 -275.900864) (xy 192.559941 -275.85308) (xy 192.579232 -275.807804) (xy 192.605535 -275.766208)
			(xy 192.63817 -275.729371) (xy 192.676291 -275.698246) (xy 192.718912 -275.673639) (xy 192.764928 -275.656187)
			(xy 192.813147 -275.646343) (xy 192.862322 -275.644362) (xy 192.911177 -275.650294) (xy 192.958448 -275.663986)
			(xy 193.00291 -275.685084) (xy 193.043413 -275.71304) (xy 193.078906 -275.747132) (xy 193.108471 -275.786476)
			(xy 193.131342 -275.830053) (xy 193.146926 -275.876734) (xy 193.154821 -275.925311) (xy 193.155316 -275.949918)
			(xy 193.154821 -275.974525) (xy 193.154642 -275.975626) (xy 193.473066 -275.975626) (xy 193.473066 -275.92421)
			(xy 193.481109 -275.873428) (xy 193.496997 -275.824529) (xy 193.52034 -275.778717) (xy 193.550561 -275.737121)
			(xy 193.586917 -275.700765) (xy 193.628513 -275.670544) (xy 193.674325 -275.647201) (xy 193.723224 -275.631313)
			(xy 193.774006 -275.62327) (xy 193.825422 -275.62327) (xy 193.876204 -275.631313) (xy 193.925103 -275.647201)
			(xy 193.970915 -275.670544) (xy 194.012511 -275.700765) (xy 194.048867 -275.737121) (xy 194.079088 -275.778717)
			(xy 194.102431 -275.824529) (xy 194.118319 -275.873428) (xy 194.126362 -275.92421) (xy 194.126866 -275.949918)
			(xy 194.444124 -275.949918) (xy 194.448084 -275.900864) (xy 194.459861 -275.85308) (xy 194.479152 -275.807804)
			(xy 194.505455 -275.766208) (xy 194.53809 -275.729371) (xy 194.576211 -275.698246) (xy 194.618832 -275.673639)
			(xy 194.664848 -275.656187) (xy 194.713067 -275.646343) (xy 194.762242 -275.644362) (xy 194.811097 -275.650294)
			(xy 194.858368 -275.663986) (xy 194.90283 -275.685084) (xy 194.943333 -275.71304) (xy 194.978826 -275.747132)
			(xy 195.008391 -275.786476) (xy 195.031262 -275.830053) (xy 195.046846 -275.876734) (xy 195.054741 -275.925311)
			(xy 195.055236 -275.949918) (xy 195.054741 -275.974525) (xy 195.054562 -275.975626) (xy 195.372986 -275.975626)
			(xy 195.372986 -275.92421) (xy 195.381029 -275.873428) (xy 195.396917 -275.824529) (xy 195.42026 -275.778717)
			(xy 195.450481 -275.737121) (xy 195.486837 -275.700765) (xy 195.528433 -275.670544) (xy 195.574245 -275.647201)
			(xy 195.623144 -275.631313) (xy 195.673926 -275.62327) (xy 195.725342 -275.62327) (xy 195.776124 -275.631313)
			(xy 195.825023 -275.647201) (xy 195.870835 -275.670544) (xy 195.912431 -275.700765) (xy 195.948787 -275.737121)
			(xy 195.979008 -275.778717) (xy 196.002351 -275.824529) (xy 196.018239 -275.873428) (xy 196.026282 -275.92421)
			(xy 196.026786 -275.949918) (xy 196.344298 -275.949918) (xy 196.348258 -275.900864) (xy 196.360035 -275.85308)
			(xy 196.379326 -275.807804) (xy 196.405629 -275.766208) (xy 196.438264 -275.729371) (xy 196.476385 -275.698246)
			(xy 196.519006 -275.673639) (xy 196.565022 -275.656187) (xy 196.613241 -275.646343) (xy 196.662416 -275.644362)
			(xy 196.711271 -275.650294) (xy 196.758542 -275.663986) (xy 196.803004 -275.685084) (xy 196.843507 -275.71304)
			(xy 196.879 -275.747132) (xy 196.908565 -275.786476) (xy 196.931436 -275.830053) (xy 196.94702 -275.876734)
			(xy 196.954915 -275.925311) (xy 196.95541 -275.949918) (xy 197.294258 -275.949918) (xy 197.298218 -275.900864)
			(xy 197.309995 -275.85308) (xy 197.329286 -275.807804) (xy 197.355589 -275.766208) (xy 197.388224 -275.729371)
			(xy 197.426345 -275.698246) (xy 197.468966 -275.673639) (xy 197.514982 -275.656187) (xy 197.563201 -275.646343)
			(xy 197.612376 -275.644362) (xy 197.661231 -275.650294) (xy 197.708502 -275.663986) (xy 197.752964 -275.685084)
			(xy 197.793467 -275.71304) (xy 197.82896 -275.747132) (xy 197.858525 -275.786476) (xy 197.881396 -275.830053)
			(xy 197.89698 -275.876734) (xy 197.904875 -275.925311) (xy 197.90537 -275.949918) (xy 198.244218 -275.949918)
			(xy 198.248178 -275.900864) (xy 198.259955 -275.85308) (xy 198.279246 -275.807804) (xy 198.305549 -275.766208)
			(xy 198.338184 -275.729371) (xy 198.376305 -275.698246) (xy 198.418926 -275.673639) (xy 198.464942 -275.656187)
			(xy 198.513161 -275.646343) (xy 198.562336 -275.644362) (xy 198.611191 -275.650294) (xy 198.658462 -275.663986)
			(xy 198.702924 -275.685084) (xy 198.743427 -275.71304) (xy 198.77892 -275.747132) (xy 198.808485 -275.786476)
			(xy 198.831356 -275.830053) (xy 198.84694 -275.876734) (xy 198.854835 -275.925311) (xy 198.85533 -275.949918)
			(xy 198.854835 -275.974525) (xy 198.84694 -276.023102) (xy 198.831356 -276.069783) (xy 198.808485 -276.11336)
			(xy 198.77892 -276.152704) (xy 198.743427 -276.186796) (xy 198.702924 -276.214752) (xy 198.658462 -276.23585)
			(xy 198.611191 -276.249542) (xy 198.562336 -276.255474) (xy 198.513161 -276.253493) (xy 198.464942 -276.243649)
			(xy 198.418926 -276.226197) (xy 198.376305 -276.20159) (xy 198.338184 -276.170465) (xy 198.305549 -276.133628)
			(xy 198.279246 -276.092032) (xy 198.259955 -276.046756) (xy 198.248178 -275.998972) (xy 198.244218 -275.949918)
			(xy 197.90537 -275.949918) (xy 197.904875 -275.974525) (xy 197.89698 -276.023102) (xy 197.881396 -276.069783)
			(xy 197.858525 -276.11336) (xy 197.82896 -276.152704) (xy 197.793467 -276.186796) (xy 197.752964 -276.214752)
			(xy 197.708502 -276.23585) (xy 197.661231 -276.249542) (xy 197.612376 -276.255474) (xy 197.563201 -276.253493)
			(xy 197.514982 -276.243649) (xy 197.468966 -276.226197) (xy 197.426345 -276.20159) (xy 197.388224 -276.170465)
			(xy 197.355589 -276.133628) (xy 197.329286 -276.092032) (xy 197.309995 -276.046756) (xy 197.298218 -275.998972)
			(xy 197.294258 -275.949918) (xy 196.95541 -275.949918) (xy 196.954915 -275.974525) (xy 196.94702 -276.023102)
			(xy 196.931436 -276.069783) (xy 196.908565 -276.11336) (xy 196.879 -276.152704) (xy 196.843507 -276.186796)
			(xy 196.803004 -276.214752) (xy 196.758542 -276.23585) (xy 196.711271 -276.249542) (xy 196.662416 -276.255474)
			(xy 196.613241 -276.253493) (xy 196.565022 -276.243649) (xy 196.519006 -276.226197) (xy 196.476385 -276.20159)
			(xy 196.438264 -276.170465) (xy 196.405629 -276.133628) (xy 196.379326 -276.092032) (xy 196.360035 -276.046756)
			(xy 196.348258 -275.998972) (xy 196.344298 -275.949918) (xy 196.026786 -275.949918) (xy 196.026282 -275.975626)
			(xy 196.018239 -276.026408) (xy 196.002351 -276.075307) (xy 195.979008 -276.121119) (xy 195.948787 -276.162715)
			(xy 195.912431 -276.199071) (xy 195.870835 -276.229292) (xy 195.825023 -276.252635) (xy 195.776124 -276.268523)
			(xy 195.725342 -276.276566) (xy 195.673926 -276.276566) (xy 195.623144 -276.268523) (xy 195.574245 -276.252635)
			(xy 195.528433 -276.229292) (xy 195.486837 -276.199071) (xy 195.450481 -276.162715) (xy 195.42026 -276.121119)
			(xy 195.396917 -276.075307) (xy 195.381029 -276.026408) (xy 195.372986 -275.975626) (xy 195.054562 -275.975626)
			(xy 195.046846 -276.023102) (xy 195.031262 -276.069783) (xy 195.008391 -276.11336) (xy 194.978826 -276.152704)
			(xy 194.943333 -276.186796) (xy 194.90283 -276.214752) (xy 194.858368 -276.23585) (xy 194.811097 -276.249542)
			(xy 194.762242 -276.255474) (xy 194.713067 -276.253493) (xy 194.664848 -276.243649) (xy 194.618832 -276.226197)
			(xy 194.576211 -276.20159) (xy 194.53809 -276.170465) (xy 194.505455 -276.133628) (xy 194.479152 -276.092032)
			(xy 194.459861 -276.046756) (xy 194.448084 -275.998972) (xy 194.444124 -275.949918) (xy 194.126866 -275.949918)
			(xy 194.126362 -275.975626) (xy 194.118319 -276.026408) (xy 194.102431 -276.075307) (xy 194.079088 -276.121119)
			(xy 194.048867 -276.162715) (xy 194.012511 -276.199071) (xy 193.970915 -276.229292) (xy 193.925103 -276.252635)
			(xy 193.876204 -276.268523) (xy 193.825422 -276.276566) (xy 193.774006 -276.276566) (xy 193.723224 -276.268523)
			(xy 193.674325 -276.252635) (xy 193.628513 -276.229292) (xy 193.586917 -276.199071) (xy 193.550561 -276.162715)
			(xy 193.52034 -276.121119) (xy 193.496997 -276.075307) (xy 193.481109 -276.026408) (xy 193.473066 -275.975626)
			(xy 193.154642 -275.975626) (xy 193.146926 -276.023102) (xy 193.131342 -276.069783) (xy 193.108471 -276.11336)
			(xy 193.078906 -276.152704) (xy 193.043413 -276.186796) (xy 193.00291 -276.214752) (xy 192.958448 -276.23585)
			(xy 192.911177 -276.249542) (xy 192.862322 -276.255474) (xy 192.813147 -276.253493) (xy 192.764928 -276.243649)
			(xy 192.718912 -276.226197) (xy 192.676291 -276.20159) (xy 192.63817 -276.170465) (xy 192.605535 -276.133628)
			(xy 192.579232 -276.092032) (xy 192.559941 -276.046756) (xy 192.548164 -275.998972) (xy 192.544204 -275.949918)
			(xy 192.226941 -275.949918) (xy 192.226442 -275.975372) (xy 192.218399 -276.026154) (xy 192.202511 -276.075053)
			(xy 192.179168 -276.120865) (xy 192.148947 -276.162461) (xy 192.112591 -276.198817) (xy 192.070995 -276.229038)
			(xy 192.025183 -276.252381) (xy 191.976284 -276.268269) (xy 191.925502 -276.276312) (xy 191.874086 -276.276312)
			(xy 191.823304 -276.268269) (xy 191.774405 -276.252381) (xy 191.728593 -276.229038) (xy 191.686997 -276.198817)
			(xy 191.650641 -276.162461) (xy 191.62042 -276.120865) (xy 191.597077 -276.075053) (xy 191.581189 -276.026154)
			(xy 191.573146 -275.975372) (xy 191.254763 -275.975372) (xy 191.247006 -276.023102) (xy 191.231422 -276.069783)
			(xy 191.208551 -276.11336) (xy 191.178986 -276.152704) (xy 191.143493 -276.186796) (xy 191.10299 -276.214752)
			(xy 191.058528 -276.23585) (xy 191.011257 -276.249542) (xy 190.962402 -276.255474) (xy 190.913227 -276.253493)
			(xy 190.865008 -276.243649) (xy 190.818992 -276.226197) (xy 190.776371 -276.20159) (xy 190.73825 -276.170465)
			(xy 190.705615 -276.133628) (xy 190.679312 -276.092032) (xy 190.660021 -276.046756) (xy 190.648244 -275.998972)
			(xy 190.644284 -275.949918) (xy 190.326772 -275.949918) (xy 190.326268 -275.975626) (xy 190.318225 -276.026408)
			(xy 190.302337 -276.075307) (xy 190.278994 -276.121119) (xy 190.248773 -276.162715) (xy 190.212417 -276.199071)
			(xy 190.170821 -276.229292) (xy 190.125009 -276.252635) (xy 190.07611 -276.268523) (xy 190.025328 -276.276566)
			(xy 189.973912 -276.276566) (xy 189.92313 -276.268523) (xy 189.874231 -276.252635) (xy 189.828419 -276.229292)
			(xy 189.786823 -276.199071) (xy 189.750467 -276.162715) (xy 189.720246 -276.121119) (xy 189.696903 -276.075307)
			(xy 189.681015 -276.026408) (xy 189.672972 -275.975626) (xy 189.354548 -275.975626) (xy 189.346832 -276.023102)
			(xy 189.331248 -276.069783) (xy 189.308377 -276.11336) (xy 189.278812 -276.152704) (xy 189.243319 -276.186796)
			(xy 189.202816 -276.214752) (xy 189.158354 -276.23585) (xy 189.111083 -276.249542) (xy 189.062228 -276.255474)
			(xy 189.013053 -276.253493) (xy 188.964834 -276.243649) (xy 188.918818 -276.226197) (xy 188.876197 -276.20159)
			(xy 188.838076 -276.170465) (xy 188.805441 -276.133628) (xy 188.779138 -276.092032) (xy 188.759847 -276.046756)
			(xy 188.74807 -275.998972) (xy 188.74411 -275.949918) (xy 188.426847 -275.949918) (xy 188.426348 -275.975372)
			(xy 188.418305 -276.026154) (xy 188.402417 -276.075053) (xy 188.379074 -276.120865) (xy 188.348853 -276.162461)
			(xy 188.312497 -276.198817) (xy 188.270901 -276.229038) (xy 188.225089 -276.252381) (xy 188.17619 -276.268269)
			(xy 188.125408 -276.276312) (xy 188.073992 -276.276312) (xy 188.02321 -276.268269) (xy 187.974311 -276.252381)
			(xy 187.928499 -276.229038) (xy 187.886903 -276.198817) (xy 187.850547 -276.162461) (xy 187.820326 -276.120865)
			(xy 187.796983 -276.075053) (xy 187.781095 -276.026154) (xy 187.773052 -275.975372) (xy 187.454669 -275.975372)
			(xy 187.446912 -276.023102) (xy 187.431328 -276.069783) (xy 187.408457 -276.11336) (xy 187.378892 -276.152704)
			(xy 187.343399 -276.186796) (xy 187.302896 -276.214752) (xy 187.258434 -276.23585) (xy 187.211163 -276.249542)
			(xy 187.162308 -276.255474) (xy 187.113133 -276.253493) (xy 187.064914 -276.243649) (xy 187.018898 -276.226197)
			(xy 186.976277 -276.20159) (xy 186.938156 -276.170465) (xy 186.905521 -276.133628) (xy 186.879218 -276.092032)
			(xy 186.859927 -276.046756) (xy 186.84815 -275.998972) (xy 186.84419 -275.949918) (xy 186.526678 -275.949918)
			(xy 186.526174 -275.975626) (xy 186.518131 -276.026408) (xy 186.502243 -276.075307) (xy 186.4789 -276.121119)
			(xy 186.448679 -276.162715) (xy 186.412323 -276.199071) (xy 186.370727 -276.229292) (xy 186.324915 -276.252635)
			(xy 186.276016 -276.268523) (xy 186.225234 -276.276566) (xy 186.173818 -276.276566) (xy 186.123036 -276.268523)
			(xy 186.074137 -276.252635) (xy 186.028325 -276.229292) (xy 185.986729 -276.199071) (xy 185.950373 -276.162715)
			(xy 185.920152 -276.121119) (xy 185.896809 -276.075307) (xy 185.880921 -276.026408) (xy 185.872878 -275.975626)
			(xy 185.554708 -275.975626) (xy 185.546992 -276.023102) (xy 185.531408 -276.069783) (xy 185.508537 -276.11336)
			(xy 185.478972 -276.152704) (xy 185.443479 -276.186796) (xy 185.402976 -276.214752) (xy 185.358514 -276.23585)
			(xy 185.311243 -276.249542) (xy 185.262388 -276.255474) (xy 185.213213 -276.253493) (xy 185.164994 -276.243649)
			(xy 185.118978 -276.226197) (xy 185.076357 -276.20159) (xy 185.038236 -276.170465) (xy 185.005601 -276.133628)
			(xy 184.979298 -276.092032) (xy 184.960007 -276.046756) (xy 184.94823 -275.998972) (xy 184.94427 -275.949918)
			(xy 184.626753 -275.949918) (xy 184.626254 -275.975372) (xy 184.618211 -276.026154) (xy 184.602323 -276.075053)
			(xy 184.57898 -276.120865) (xy 184.548759 -276.162461) (xy 184.512403 -276.198817) (xy 184.470807 -276.229038)
			(xy 184.424995 -276.252381) (xy 184.376096 -276.268269) (xy 184.325314 -276.276312) (xy 184.273898 -276.276312)
			(xy 184.223116 -276.268269) (xy 184.174217 -276.252381) (xy 184.128405 -276.229038) (xy 184.086809 -276.198817)
			(xy 184.050453 -276.162461) (xy 184.020232 -276.120865) (xy 183.996889 -276.075053) (xy 183.981001 -276.026154)
			(xy 183.972958 -275.975372) (xy 183.654575 -275.975372) (xy 183.646818 -276.023102) (xy 183.631234 -276.069783)
			(xy 183.608363 -276.11336) (xy 183.578798 -276.152704) (xy 183.543305 -276.186796) (xy 183.502802 -276.214752)
			(xy 183.45834 -276.23585) (xy 183.411069 -276.249542) (xy 183.362214 -276.255474) (xy 183.313039 -276.253493)
			(xy 183.26482 -276.243649) (xy 183.218804 -276.226197) (xy 183.176183 -276.20159) (xy 183.138062 -276.170465)
			(xy 183.105427 -276.133628) (xy 183.079124 -276.092032) (xy 183.059833 -276.046756) (xy 183.048056 -275.998972)
			(xy 183.044096 -275.949918) (xy 182.726838 -275.949918) (xy 182.726334 -275.975626) (xy 182.718291 -276.026408)
			(xy 182.702403 -276.075307) (xy 182.67906 -276.121119) (xy 182.648839 -276.162715) (xy 182.612483 -276.199071)
			(xy 182.570887 -276.229292) (xy 182.525075 -276.252635) (xy 182.476176 -276.268523) (xy 182.425394 -276.276566)
			(xy 182.373978 -276.276566) (xy 182.323196 -276.268523) (xy 182.274297 -276.252635) (xy 182.228485 -276.229292)
			(xy 182.186889 -276.199071) (xy 182.150533 -276.162715) (xy 182.120312 -276.121119) (xy 182.096969 -276.075307)
			(xy 182.081081 -276.026408) (xy 182.073038 -275.975626) (xy 181.754614 -275.975626) (xy 181.746898 -276.023102)
			(xy 181.731314 -276.069783) (xy 181.708443 -276.11336) (xy 181.678878 -276.152704) (xy 181.643385 -276.186796)
			(xy 181.602882 -276.214752) (xy 181.55842 -276.23585) (xy 181.511149 -276.249542) (xy 181.462294 -276.255474)
			(xy 181.413119 -276.253493) (xy 181.3649 -276.243649) (xy 181.318884 -276.226197) (xy 181.276263 -276.20159)
			(xy 181.238142 -276.170465) (xy 181.205507 -276.133628) (xy 181.179204 -276.092032) (xy 181.159913 -276.046756)
			(xy 181.148136 -275.998972) (xy 181.144176 -275.949918) (xy 180.826913 -275.949918) (xy 180.826414 -275.975372)
			(xy 180.818371 -276.026154) (xy 180.802483 -276.075053) (xy 180.77914 -276.120865) (xy 180.748919 -276.162461)
			(xy 180.712563 -276.198817) (xy 180.670967 -276.229038) (xy 180.625155 -276.252381) (xy 180.576256 -276.268269)
			(xy 180.525474 -276.276312) (xy 180.474058 -276.276312) (xy 180.423276 -276.268269) (xy 180.374377 -276.252381)
			(xy 180.328565 -276.229038) (xy 180.286969 -276.198817) (xy 180.250613 -276.162461) (xy 180.220392 -276.120865)
			(xy 180.197049 -276.075053) (xy 180.181161 -276.026154) (xy 180.173118 -275.975372) (xy 179.854735 -275.975372)
			(xy 179.846978 -276.023102) (xy 179.831394 -276.069783) (xy 179.808523 -276.11336) (xy 179.778958 -276.152704)
			(xy 179.743465 -276.186796) (xy 179.702962 -276.214752) (xy 179.6585 -276.23585) (xy 179.611229 -276.249542)
			(xy 179.562374 -276.255474) (xy 179.513199 -276.253493) (xy 179.46498 -276.243649) (xy 179.418964 -276.226197)
			(xy 179.376343 -276.20159) (xy 179.338222 -276.170465) (xy 179.305587 -276.133628) (xy 179.279284 -276.092032)
			(xy 179.259993 -276.046756) (xy 179.248216 -275.998972) (xy 179.244256 -275.949918) (xy 178.926744 -275.949918)
			(xy 178.92624 -275.975626) (xy 178.918197 -276.026408) (xy 178.902309 -276.075307) (xy 178.878966 -276.121119)
			(xy 178.848745 -276.162715) (xy 178.812389 -276.199071) (xy 178.770793 -276.229292) (xy 178.724981 -276.252635)
			(xy 178.676082 -276.268523) (xy 178.6253 -276.276566) (xy 178.573884 -276.276566) (xy 178.523102 -276.268523)
			(xy 178.474203 -276.252635) (xy 178.428391 -276.229292) (xy 178.386795 -276.199071) (xy 178.350439 -276.162715)
			(xy 178.320218 -276.121119) (xy 178.296875 -276.075307) (xy 178.280987 -276.026408) (xy 178.272944 -275.975626)
			(xy 177.95361 -275.975626) (xy 177.95157 -276.000241) (xy 177.93917 -276.04921) (xy 177.918878 -276.095469)
			(xy 177.891249 -276.137757) (xy 177.857036 -276.17492) (xy 177.817172 -276.205946) (xy 177.772746 -276.229986)
			(xy 177.724968 -276.246386) (xy 177.675143 -276.254698) (xy 177.649886 -276.255226) (xy 177.640782 -276.255129)
			(xy 177.622608 -276.253987) (xy 177.613564 -276.25294) (xy 177.601372 -276.25167) (xy 177.57902 -276.259544)
			(xy 177.506122 -276.335998) (xy 177.49901 -276.358604) (xy 177.501042 -276.370542) (xy 177.503176 -276.38403)
			(xy 177.505468 -276.411243) (xy 177.505614 -276.424898) (xy 177.505451 -276.438552) (xy 177.503159 -276.465764)
			(xy 177.501042 -276.479254) (xy 177.49901 -276.491192) (xy 177.506122 -276.513798) (xy 177.57902 -276.590252)
			(xy 177.601372 -276.598126) (xy 177.613564 -276.596856) (xy 177.622608 -276.595807) (xy 177.640782 -276.594663)
			(xy 177.649886 -276.59457) (xy 177.674709 -276.595055) (xy 177.723702 -276.603085) (xy 177.77075 -276.618935)
			(xy 177.814614 -276.642189) (xy 177.854139 -276.672232) (xy 177.888281 -276.708274) (xy 177.916143 -276.749366)
			(xy 177.93699 -276.794423) (xy 177.950273 -276.84226) (xy 177.955641 -276.891615) (xy 177.955193 -276.899878)
			(xy 178.294042 -276.899878) (xy 178.298002 -276.850824) (xy 178.309779 -276.80304) (xy 178.32907 -276.757764)
			(xy 178.355373 -276.716168) (xy 178.388008 -276.679331) (xy 178.426129 -276.648206) (xy 178.46875 -276.623599)
			(xy 178.514766 -276.606147) (xy 178.562985 -276.596303) (xy 178.61216 -276.594322) (xy 178.661015 -276.600254)
			(xy 178.708286 -276.613946) (xy 178.752748 -276.635044) (xy 178.793251 -276.663) (xy 178.828744 -276.697092)
			(xy 178.858309 -276.736436) (xy 178.88118 -276.780013) (xy 178.896764 -276.826694) (xy 178.904659 -276.875271)
			(xy 178.905154 -276.899878) (xy 179.244256 -276.899878) (xy 179.248216 -276.850824) (xy 179.259993 -276.80304)
			(xy 179.279284 -276.757764) (xy 179.305587 -276.716168) (xy 179.338222 -276.679331) (xy 179.376343 -276.648206)
			(xy 179.418964 -276.623599) (xy 179.46498 -276.606147) (xy 179.513199 -276.596303) (xy 179.562374 -276.594322)
			(xy 179.611229 -276.600254) (xy 179.6585 -276.613946) (xy 179.702962 -276.635044) (xy 179.743465 -276.663)
			(xy 179.778958 -276.697092) (xy 179.808523 -276.736436) (xy 179.831394 -276.780013) (xy 179.846978 -276.826694)
			(xy 179.854873 -276.875271) (xy 179.855368 -276.899878) (xy 180.194216 -276.899878) (xy 180.198176 -276.850824)
			(xy 180.209953 -276.80304) (xy 180.229244 -276.757764) (xy 180.255547 -276.716168) (xy 180.288182 -276.679331)
			(xy 180.326303 -276.648206) (xy 180.368924 -276.623599) (xy 180.41494 -276.606147) (xy 180.463159 -276.596303)
			(xy 180.512334 -276.594322) (xy 180.561189 -276.600254) (xy 180.60846 -276.613946) (xy 180.652922 -276.635044)
			(xy 180.693425 -276.663) (xy 180.728918 -276.697092) (xy 180.758483 -276.736436) (xy 180.781354 -276.780013)
			(xy 180.796938 -276.826694) (xy 180.804833 -276.875271) (xy 180.805328 -276.899878) (xy 181.144176 -276.899878)
			(xy 181.148136 -276.850824) (xy 181.159913 -276.80304) (xy 181.179204 -276.757764) (xy 181.205507 -276.716168)
			(xy 181.238142 -276.679331) (xy 181.276263 -276.648206) (xy 181.318884 -276.623599) (xy 181.3649 -276.606147)
			(xy 181.413119 -276.596303) (xy 181.462294 -276.594322) (xy 181.511149 -276.600254) (xy 181.55842 -276.613946)
			(xy 181.602882 -276.635044) (xy 181.643385 -276.663) (xy 181.678878 -276.697092) (xy 181.708443 -276.736436)
			(xy 181.731314 -276.780013) (xy 181.746898 -276.826694) (xy 181.754793 -276.875271) (xy 181.755288 -276.899878)
			(xy 182.094136 -276.899878) (xy 182.098096 -276.850824) (xy 182.109873 -276.80304) (xy 182.129164 -276.757764)
			(xy 182.155467 -276.716168) (xy 182.188102 -276.679331) (xy 182.226223 -276.648206) (xy 182.268844 -276.623599)
			(xy 182.31486 -276.606147) (xy 182.363079 -276.596303) (xy 182.412254 -276.594322) (xy 182.461109 -276.600254)
			(xy 182.50838 -276.613946) (xy 182.552842 -276.635044) (xy 182.593345 -276.663) (xy 182.628838 -276.697092)
			(xy 182.658403 -276.736436) (xy 182.681274 -276.780013) (xy 182.696858 -276.826694) (xy 182.704753 -276.875271)
			(xy 182.705248 -276.899878) (xy 183.044096 -276.899878) (xy 183.048056 -276.850824) (xy 183.059833 -276.80304)
			(xy 183.079124 -276.757764) (xy 183.105427 -276.716168) (xy 183.138062 -276.679331) (xy 183.176183 -276.648206)
			(xy 183.218804 -276.623599) (xy 183.26482 -276.606147) (xy 183.313039 -276.596303) (xy 183.362214 -276.594322)
			(xy 183.411069 -276.600254) (xy 183.45834 -276.613946) (xy 183.502802 -276.635044) (xy 183.543305 -276.663)
			(xy 183.578798 -276.697092) (xy 183.608363 -276.736436) (xy 183.631234 -276.780013) (xy 183.646818 -276.826694)
			(xy 183.654713 -276.875271) (xy 183.655208 -276.899878) (xy 183.994056 -276.899878) (xy 183.998016 -276.850824)
			(xy 184.009793 -276.80304) (xy 184.029084 -276.757764) (xy 184.055387 -276.716168) (xy 184.088022 -276.679331)
			(xy 184.126143 -276.648206) (xy 184.168764 -276.623599) (xy 184.21478 -276.606147) (xy 184.262999 -276.596303)
			(xy 184.312174 -276.594322) (xy 184.361029 -276.600254) (xy 184.4083 -276.613946) (xy 184.452762 -276.635044)
			(xy 184.493265 -276.663) (xy 184.528758 -276.697092) (xy 184.558323 -276.736436) (xy 184.581194 -276.780013)
			(xy 184.596778 -276.826694) (xy 184.604673 -276.875271) (xy 184.605168 -276.899878) (xy 184.94427 -276.899878)
			(xy 184.94823 -276.850824) (xy 184.960007 -276.80304) (xy 184.979298 -276.757764) (xy 185.005601 -276.716168)
			(xy 185.038236 -276.679331) (xy 185.076357 -276.648206) (xy 185.118978 -276.623599) (xy 185.164994 -276.606147)
			(xy 185.213213 -276.596303) (xy 185.262388 -276.594322) (xy 185.311243 -276.600254) (xy 185.358514 -276.613946)
			(xy 185.402976 -276.635044) (xy 185.443479 -276.663) (xy 185.478972 -276.697092) (xy 185.508537 -276.736436)
			(xy 185.531408 -276.780013) (xy 185.546992 -276.826694) (xy 185.554887 -276.875271) (xy 185.555382 -276.899878)
			(xy 185.89423 -276.899878) (xy 185.89819 -276.850824) (xy 185.909967 -276.80304) (xy 185.929258 -276.757764)
			(xy 185.955561 -276.716168) (xy 185.988196 -276.679331) (xy 186.026317 -276.648206) (xy 186.068938 -276.623599)
			(xy 186.114954 -276.606147) (xy 186.163173 -276.596303) (xy 186.212348 -276.594322) (xy 186.261203 -276.600254)
			(xy 186.308474 -276.613946) (xy 186.352936 -276.635044) (xy 186.393439 -276.663) (xy 186.428932 -276.697092)
			(xy 186.458497 -276.736436) (xy 186.481368 -276.780013) (xy 186.496952 -276.826694) (xy 186.504847 -276.875271)
			(xy 186.505342 -276.899878) (xy 186.84419 -276.899878) (xy 186.84815 -276.850824) (xy 186.859927 -276.80304)
			(xy 186.879218 -276.757764) (xy 186.905521 -276.716168) (xy 186.938156 -276.679331) (xy 186.976277 -276.648206)
			(xy 187.018898 -276.623599) (xy 187.064914 -276.606147) (xy 187.113133 -276.596303) (xy 187.162308 -276.594322)
			(xy 187.211163 -276.600254) (xy 187.258434 -276.613946) (xy 187.302896 -276.635044) (xy 187.343399 -276.663)
			(xy 187.378892 -276.697092) (xy 187.408457 -276.736436) (xy 187.431328 -276.780013) (xy 187.446912 -276.826694)
			(xy 187.454807 -276.875271) (xy 187.455302 -276.899878) (xy 187.79415 -276.899878) (xy 187.79811 -276.850824)
			(xy 187.809887 -276.80304) (xy 187.829178 -276.757764) (xy 187.855481 -276.716168) (xy 187.888116 -276.679331)
			(xy 187.926237 -276.648206) (xy 187.968858 -276.623599) (xy 188.014874 -276.606147) (xy 188.063093 -276.596303)
			(xy 188.112268 -276.594322) (xy 188.161123 -276.600254) (xy 188.208394 -276.613946) (xy 188.252856 -276.635044)
			(xy 188.293359 -276.663) (xy 188.328852 -276.697092) (xy 188.358417 -276.736436) (xy 188.381288 -276.780013)
			(xy 188.396872 -276.826694) (xy 188.404767 -276.875271) (xy 188.405262 -276.899878) (xy 188.74411 -276.899878)
			(xy 188.74807 -276.850824) (xy 188.759847 -276.80304) (xy 188.779138 -276.757764) (xy 188.805441 -276.716168)
			(xy 188.838076 -276.679331) (xy 188.876197 -276.648206) (xy 188.918818 -276.623599) (xy 188.964834 -276.606147)
			(xy 189.013053 -276.596303) (xy 189.062228 -276.594322) (xy 189.111083 -276.600254) (xy 189.158354 -276.613946)
			(xy 189.202816 -276.635044) (xy 189.243319 -276.663) (xy 189.278812 -276.697092) (xy 189.308377 -276.736436)
			(xy 189.331248 -276.780013) (xy 189.346832 -276.826694) (xy 189.354727 -276.875271) (xy 189.355222 -276.899878)
			(xy 189.693816 -276.899878) (xy 189.697776 -276.850824) (xy 189.709553 -276.80304) (xy 189.728844 -276.757764)
			(xy 189.755147 -276.716168) (xy 189.787782 -276.679331) (xy 189.825903 -276.648206) (xy 189.868524 -276.623599)
			(xy 189.91454 -276.606147) (xy 189.962759 -276.596303) (xy 190.011934 -276.594322) (xy 190.060789 -276.600254)
			(xy 190.10806 -276.613946) (xy 190.152522 -276.635044) (xy 190.193025 -276.663) (xy 190.228518 -276.697092)
			(xy 190.258083 -276.736436) (xy 190.280954 -276.780013) (xy 190.296538 -276.826694) (xy 190.304433 -276.875271)
			(xy 190.304928 -276.899878) (xy 190.64403 -276.899878) (xy 190.64799 -276.850824) (xy 190.659767 -276.80304)
			(xy 190.679058 -276.757764) (xy 190.705361 -276.716168) (xy 190.737996 -276.679331) (xy 190.776117 -276.648206)
			(xy 190.818738 -276.623599) (xy 190.864754 -276.606147) (xy 190.912973 -276.596303) (xy 190.962148 -276.594322)
			(xy 191.011003 -276.600254) (xy 191.058274 -276.613946) (xy 191.102736 -276.635044) (xy 191.143239 -276.663)
			(xy 191.178732 -276.697092) (xy 191.208297 -276.736436) (xy 191.231168 -276.780013) (xy 191.246752 -276.826694)
			(xy 191.254647 -276.875271) (xy 191.255142 -276.899878) (xy 191.59399 -276.899878) (xy 191.59795 -276.850824)
			(xy 191.609727 -276.80304) (xy 191.629018 -276.757764) (xy 191.655321 -276.716168) (xy 191.687956 -276.679331)
			(xy 191.726077 -276.648206) (xy 191.768698 -276.623599) (xy 191.814714 -276.606147) (xy 191.862933 -276.596303)
			(xy 191.912108 -276.594322) (xy 191.960963 -276.600254) (xy 192.008234 -276.613946) (xy 192.052696 -276.635044)
			(xy 192.093199 -276.663) (xy 192.128692 -276.697092) (xy 192.158257 -276.736436) (xy 192.181128 -276.780013)
			(xy 192.196712 -276.826694) (xy 192.204607 -276.875271) (xy 192.205102 -276.899878) (xy 192.54395 -276.899878)
			(xy 192.54791 -276.850824) (xy 192.559687 -276.80304) (xy 192.578978 -276.757764) (xy 192.605281 -276.716168)
			(xy 192.637916 -276.679331) (xy 192.676037 -276.648206) (xy 192.718658 -276.623599) (xy 192.764674 -276.606147)
			(xy 192.812893 -276.596303) (xy 192.862068 -276.594322) (xy 192.910923 -276.600254) (xy 192.958194 -276.613946)
			(xy 193.002656 -276.635044) (xy 193.043159 -276.663) (xy 193.078652 -276.697092) (xy 193.108217 -276.736436)
			(xy 193.131088 -276.780013) (xy 193.146672 -276.826694) (xy 193.154567 -276.875271) (xy 193.155062 -276.899878)
			(xy 193.49391 -276.899878) (xy 193.49787 -276.850824) (xy 193.509647 -276.80304) (xy 193.528938 -276.757764)
			(xy 193.555241 -276.716168) (xy 193.587876 -276.679331) (xy 193.625997 -276.648206) (xy 193.668618 -276.623599)
			(xy 193.714634 -276.606147) (xy 193.762853 -276.596303) (xy 193.812028 -276.594322) (xy 193.860883 -276.600254)
			(xy 193.908154 -276.613946) (xy 193.952616 -276.635044) (xy 193.993119 -276.663) (xy 194.028612 -276.697092)
			(xy 194.058177 -276.736436) (xy 194.081048 -276.780013) (xy 194.096632 -276.826694) (xy 194.104527 -276.875271)
			(xy 194.105022 -276.899878) (xy 194.44387 -276.899878) (xy 194.44783 -276.850824) (xy 194.459607 -276.80304)
			(xy 194.478898 -276.757764) (xy 194.505201 -276.716168) (xy 194.537836 -276.679331) (xy 194.575957 -276.648206)
			(xy 194.618578 -276.623599) (xy 194.664594 -276.606147) (xy 194.712813 -276.596303) (xy 194.761988 -276.594322)
			(xy 194.810843 -276.600254) (xy 194.858114 -276.613946) (xy 194.902576 -276.635044) (xy 194.943079 -276.663)
			(xy 194.978572 -276.697092) (xy 195.008137 -276.736436) (xy 195.031008 -276.780013) (xy 195.046592 -276.826694)
			(xy 195.054487 -276.875271) (xy 195.054982 -276.899878) (xy 195.39383 -276.899878) (xy 195.39779 -276.850824)
			(xy 195.409567 -276.80304) (xy 195.428858 -276.757764) (xy 195.455161 -276.716168) (xy 195.487796 -276.679331)
			(xy 195.525917 -276.648206) (xy 195.568538 -276.623599) (xy 195.614554 -276.606147) (xy 195.662773 -276.596303)
			(xy 195.711948 -276.594322) (xy 195.760803 -276.600254) (xy 195.808074 -276.613946) (xy 195.852536 -276.635044)
			(xy 195.893039 -276.663) (xy 195.928532 -276.697092) (xy 195.958097 -276.736436) (xy 195.980968 -276.780013)
			(xy 195.996552 -276.826694) (xy 196.004447 -276.875271) (xy 196.004942 -276.899878) (xy 196.344044 -276.899878)
			(xy 196.348004 -276.850824) (xy 196.359781 -276.80304) (xy 196.379072 -276.757764) (xy 196.405375 -276.716168)
			(xy 196.43801 -276.679331) (xy 196.476131 -276.648206) (xy 196.518752 -276.623599) (xy 196.564768 -276.606147)
			(xy 196.612987 -276.596303) (xy 196.662162 -276.594322) (xy 196.711017 -276.600254) (xy 196.758288 -276.613946)
			(xy 196.80275 -276.635044) (xy 196.843253 -276.663) (xy 196.878746 -276.697092) (xy 196.908311 -276.736436)
			(xy 196.931182 -276.780013) (xy 196.946766 -276.826694) (xy 196.954661 -276.875271) (xy 196.955156 -276.899878)
			(xy 197.294258 -276.899878) (xy 197.298218 -276.850824) (xy 197.309995 -276.80304) (xy 197.329286 -276.757764)
			(xy 197.355589 -276.716168) (xy 197.388224 -276.679331) (xy 197.426345 -276.648206) (xy 197.468966 -276.623599)
			(xy 197.514982 -276.606147) (xy 197.563201 -276.596303) (xy 197.612376 -276.594322) (xy 197.661231 -276.600254)
			(xy 197.708502 -276.613946) (xy 197.752964 -276.635044) (xy 197.793467 -276.663) (xy 197.82896 -276.697092)
			(xy 197.858525 -276.736436) (xy 197.881396 -276.780013) (xy 197.89698 -276.826694) (xy 197.904875 -276.875271)
			(xy 197.90537 -276.899878) (xy 198.244218 -276.899878) (xy 198.248178 -276.850824) (xy 198.259955 -276.80304)
			(xy 198.279246 -276.757764) (xy 198.305549 -276.716168) (xy 198.338184 -276.679331) (xy 198.376305 -276.648206)
			(xy 198.418926 -276.623599) (xy 198.464942 -276.606147) (xy 198.513161 -276.596303) (xy 198.562336 -276.594322)
			(xy 198.611191 -276.600254) (xy 198.658462 -276.613946) (xy 198.702924 -276.635044) (xy 198.743427 -276.663)
			(xy 198.77892 -276.697092) (xy 198.808485 -276.736436) (xy 198.831356 -276.780013) (xy 198.84694 -276.826694)
			(xy 198.854835 -276.875271) (xy 198.85533 -276.899878) (xy 198.855325 -276.900132) (xy 199.194432 -276.900132)
			(xy 199.198392 -276.851078) (xy 199.210169 -276.803294) (xy 199.22946 -276.758018) (xy 199.255763 -276.716422)
			(xy 199.288398 -276.679585) (xy 199.326519 -276.64846) (xy 199.36914 -276.623853) (xy 199.415156 -276.606401)
			(xy 199.463375 -276.596557) (xy 199.51255 -276.594576) (xy 199.561405 -276.600508) (xy 199.608676 -276.6142)
			(xy 199.653138 -276.635298) (xy 199.693641 -276.663254) (xy 199.729134 -276.697346) (xy 199.758699 -276.73669)
			(xy 199.78157 -276.780267) (xy 199.797154 -276.826948) (xy 199.805049 -276.875525) (xy 199.805544 -276.900132)
			(xy 199.805049 -276.924739) (xy 199.797154 -276.973316) (xy 199.78157 -277.019997) (xy 199.758699 -277.063574)
			(xy 199.729134 -277.102918) (xy 199.698293 -277.132542) (xy 215.516966 -277.132542) (xy 215.521037 -277.07692)
			(xy 215.533163 -277.022483) (xy 215.553086 -276.970392) (xy 215.580382 -276.921757) (xy 215.614468 -276.877614)
			(xy 215.654617 -276.838905) (xy 215.699975 -276.806454) (xy 215.749575 -276.780953) (xy 215.802359 -276.762946)
			(xy 215.857202 -276.752816) (xy 215.912936 -276.750779) (xy 215.968373 -276.756879) (xy 216.02233 -276.770985)
			(xy 216.073659 -276.792797) (xy 216.121265 -276.821851) (xy 216.164133 -276.857526) (xy 216.20135 -276.899063)
			(xy 216.232123 -276.945576) (xy 216.255795 -276.996073) (xy 216.271863 -277.04948) (xy 216.279983 -277.104656)
			(xy 216.280492 -277.132542) (xy 216.279983 -277.160428) (xy 216.271863 -277.215604) (xy 216.256275 -277.267416)
			(xy 219.95257 -277.267416) (xy 219.953028 -277.240045) (xy 219.960845 -277.185865) (xy 219.976335 -277.133361)
			(xy 219.999179 -277.083615) (xy 220.028907 -277.037649) (xy 220.04655 -277.016718) (xy 220.052646 -277.009606)
			(xy 220.058996 -276.992588) (xy 220.058996 -276.907244) (xy 220.052646 -276.890226) (xy 220.04655 -276.883114)
			(xy 220.028912 -276.862181) (xy 219.999198 -276.816209) (xy 219.976361 -276.766462) (xy 219.96087 -276.713961)
			(xy 219.953043 -276.659785) (xy 219.95257 -276.632416) (xy 219.953093 -276.605166) (xy 219.960847 -276.551221)
			(xy 219.976199 -276.498928) (xy 219.998836 -276.449353) (xy 220.028299 -276.403503) (xy 220.063987 -276.362314)
			(xy 220.105173 -276.326622) (xy 220.151019 -276.297155) (xy 220.200593 -276.274512) (xy 220.252884 -276.259155)
			(xy 220.306828 -276.251396) (xy 220.334078 -276.250908) (xy 220.362816 -276.251443) (xy 220.419643 -276.260063)
			(xy 220.474534 -276.27711) (xy 220.526246 -276.302199) (xy 220.573609 -276.334762) (xy 220.594936 -276.354032)
			(xy 220.602048 -276.360636) (xy 220.619574 -276.367748) (xy 220.708982 -276.367748) (xy 220.726508 -276.360636)
			(xy 220.73362 -276.354032) (xy 220.754947 -276.334762) (xy 220.80231 -276.302197) (xy 220.854021 -276.277106)
			(xy 220.908912 -276.260056) (xy 220.965739 -276.251434) (xy 221.023217 -276.251434) (xy 221.080044 -276.260056)
			(xy 221.134935 -276.277106) (xy 221.186646 -276.302197) (xy 221.234009 -276.334762) (xy 221.255336 -276.354032)
			(xy 221.262448 -276.360636) (xy 221.279974 -276.367748) (xy 221.369382 -276.367748) (xy 221.386908 -276.360636)
			(xy 221.39402 -276.354032) (xy 221.415347 -276.334762) (xy 221.46271 -276.302197) (xy 221.514421 -276.277106)
			(xy 221.569312 -276.260056) (xy 221.626139 -276.251434) (xy 221.683617 -276.251434) (xy 221.740444 -276.260056)
			(xy 221.795335 -276.277106) (xy 221.847046 -276.302197) (xy 221.894409 -276.334762) (xy 221.915736 -276.354032)
			(xy 221.922848 -276.360636) (xy 221.940374 -276.367748) (xy 222.029782 -276.367748) (xy 222.047308 -276.360636)
			(xy 222.05442 -276.354032) (xy 222.075755 -276.334771) (xy 222.123115 -276.302203) (xy 222.174825 -276.277109)
			(xy 222.229714 -276.260056) (xy 222.28654 -276.251431) (xy 222.315278 -276.250908) (xy 222.342531 -276.251376)
			(xy 222.396483 -276.25913) (xy 222.448781 -276.274484) (xy 222.498362 -276.297125) (xy 222.544216 -276.326593)
			(xy 222.58541 -276.362286) (xy 222.591243 -276.369018) (xy 225.13493 -276.369018) (xy 225.139001 -276.313396)
			(xy 225.151127 -276.258959) (xy 225.17105 -276.206868) (xy 225.198346 -276.158233) (xy 225.232432 -276.11409)
			(xy 225.272581 -276.075381) (xy 225.317939 -276.04293) (xy 225.367539 -276.017429) (xy 225.420323 -275.999422)
			(xy 225.475166 -275.989292) (xy 225.5309 -275.987255) (xy 225.586337 -275.993355) (xy 225.640294 -276.007461)
			(xy 225.691623 -276.029273) (xy 225.739229 -276.058327) (xy 225.782097 -276.094002) (xy 225.819314 -276.135539)
			(xy 225.850087 -276.182052) (xy 225.873759 -276.232549) (xy 225.889827 -276.285956) (xy 225.897947 -276.341132)
			(xy 225.898456 -276.369018) (xy 225.897947 -276.396904) (xy 225.889827 -276.45208) (xy 225.873759 -276.505487)
			(xy 225.867243 -276.519386) (xy 230.452928 -276.519386) (xy 230.456999 -276.463764) (xy 230.469125 -276.409327)
			(xy 230.489048 -276.357236) (xy 230.516344 -276.308601) (xy 230.55043 -276.264458) (xy 230.590579 -276.225749)
			(xy 230.635937 -276.193298) (xy 230.685537 -276.167797) (xy 230.738321 -276.14979) (xy 230.793164 -276.13966)
			(xy 230.848898 -276.137623) (xy 230.904335 -276.143723) (xy 230.958292 -276.157829) (xy 231.009621 -276.179641)
			(xy 231.057227 -276.208695) (xy 231.100095 -276.24437) (xy 231.137312 -276.285907) (xy 231.168085 -276.33242)
			(xy 231.191757 -276.382917) (xy 231.207825 -276.436324) (xy 231.215945 -276.4915) (xy 231.216454 -276.519386)
			(xy 231.215945 -276.547272) (xy 231.207825 -276.602448) (xy 231.191757 -276.655855) (xy 231.168085 -276.706352)
			(xy 231.137312 -276.752865) (xy 231.100095 -276.794402) (xy 231.057227 -276.830077) (xy 231.009621 -276.859131)
			(xy 230.958292 -276.880943) (xy 230.904335 -276.895049) (xy 230.848898 -276.901149) (xy 230.793164 -276.899112)
			(xy 230.738321 -276.888982) (xy 230.685537 -276.870975) (xy 230.635937 -276.845474) (xy 230.590579 -276.813023)
			(xy 230.55043 -276.774314) (xy 230.516344 -276.730171) (xy 230.489048 -276.681536) (xy 230.469125 -276.629445)
			(xy 230.456999 -276.575008) (xy 230.452928 -276.519386) (xy 225.867243 -276.519386) (xy 225.850087 -276.555984)
			(xy 225.819314 -276.602497) (xy 225.782097 -276.644034) (xy 225.739229 -276.679709) (xy 225.691623 -276.708763)
			(xy 225.640294 -276.730575) (xy 225.586337 -276.744681) (xy 225.5309 -276.750781) (xy 225.475166 -276.748744)
			(xy 225.420323 -276.738614) (xy 225.367539 -276.720607) (xy 225.317939 -276.695106) (xy 225.272581 -276.662655)
			(xy 225.232432 -276.623946) (xy 225.198346 -276.579803) (xy 225.17105 -276.531168) (xy 225.151127 -276.479077)
			(xy 225.139001 -276.42464) (xy 225.13493 -276.369018) (xy 222.591243 -276.369018) (xy 222.621104 -276.403479)
			(xy 222.650572 -276.449332) (xy 222.673214 -276.498913) (xy 222.688568 -276.551211) (xy 222.696324 -276.605163)
			(xy 222.696786 -276.632416) (xy 222.696333 -276.659787) (xy 222.688512 -276.713966) (xy 222.67302 -276.76647)
			(xy 222.650176 -276.816217) (xy 222.620449 -276.862183) (xy 222.602806 -276.883114) (xy 222.59671 -276.890226)
			(xy 222.59036 -276.907244) (xy 222.59036 -276.992588) (xy 222.59671 -277.009606) (xy 222.602806 -277.016718)
			(xy 222.620421 -277.037669) (xy 222.650136 -277.083637) (xy 222.672977 -277.13338) (xy 222.688474 -277.185876)
			(xy 222.692442 -277.213314) (xy 227.470206 -277.213314) (xy 227.474277 -277.157692) (xy 227.486403 -277.103255)
			(xy 227.506326 -277.051164) (xy 227.533622 -277.002529) (xy 227.567708 -276.958386) (xy 227.607857 -276.919677)
			(xy 227.653215 -276.887226) (xy 227.702815 -276.861725) (xy 227.755599 -276.843718) (xy 227.810442 -276.833588)
			(xy 227.866176 -276.831551) (xy 227.921613 -276.837651) (xy 227.97557 -276.851757) (xy 228.026899 -276.873569)
			(xy 228.074505 -276.902623) (xy 228.117373 -276.938298) (xy 228.15459 -276.979835) (xy 228.185363 -277.026348)
			(xy 228.209035 -277.076845) (xy 228.225103 -277.130252) (xy 228.233223 -277.185428) (xy 228.233523 -277.201884)
			(xy 228.659688 -277.201884) (xy 228.663759 -277.146262) (xy 228.675885 -277.091825) (xy 228.695808 -277.039734)
			(xy 228.723104 -276.991099) (xy 228.75719 -276.946956) (xy 228.797339 -276.908247) (xy 228.842697 -276.875796)
			(xy 228.892297 -276.850295) (xy 228.945081 -276.832288) (xy 228.999924 -276.822158) (xy 229.055658 -276.820121)
			(xy 229.111095 -276.826221) (xy 229.165052 -276.840327) (xy 229.216381 -276.862139) (xy 229.263987 -276.891193)
			(xy 229.306855 -276.926868) (xy 229.344072 -276.968405) (xy 229.374845 -277.014918) (xy 229.398517 -277.065415)
			(xy 229.414585 -277.118822) (xy 229.422705 -277.173998) (xy 229.423214 -277.201884) (xy 229.422705 -277.22977)
			(xy 229.414585 -277.284946) (xy 229.398517 -277.338353) (xy 229.374845 -277.38885) (xy 229.344072 -277.435363)
			(xy 229.306855 -277.4769) (xy 229.263987 -277.512575) (xy 229.216381 -277.541629) (xy 229.165052 -277.563441)
			(xy 229.111095 -277.577547) (xy 229.055658 -277.583647) (xy 228.999924 -277.58161) (xy 228.945081 -277.57148)
			(xy 228.892297 -277.553473) (xy 228.842697 -277.527972) (xy 228.797339 -277.495521) (xy 228.75719 -277.456812)
			(xy 228.723104 -277.412669) (xy 228.695808 -277.364034) (xy 228.675885 -277.311943) (xy 228.663759 -277.257506)
			(xy 228.659688 -277.201884) (xy 228.233523 -277.201884) (xy 228.233732 -277.213314) (xy 228.233223 -277.2412)
			(xy 228.225103 -277.296376) (xy 228.209035 -277.349783) (xy 228.185363 -277.40028) (xy 228.15459 -277.446793)
			(xy 228.117373 -277.48833) (xy 228.074505 -277.524005) (xy 228.026899 -277.553059) (xy 227.97557 -277.574871)
			(xy 227.921613 -277.588977) (xy 227.866176 -277.595077) (xy 227.810442 -277.59304) (xy 227.755599 -277.58291)
			(xy 227.702815 -277.564903) (xy 227.653215 -277.539402) (xy 227.607857 -277.506951) (xy 227.567708 -277.468242)
			(xy 227.533622 -277.424099) (xy 227.506326 -277.375464) (xy 227.486403 -277.323373) (xy 227.474277 -277.268936)
			(xy 227.470206 -277.213314) (xy 222.692442 -277.213314) (xy 222.696308 -277.240048) (xy 222.696786 -277.267416)
			(xy 222.69636 -277.29467) (xy 222.6886 -277.348624) (xy 222.673241 -277.400924) (xy 222.650595 -277.450505)
			(xy 222.621123 -277.49636) (xy 222.585426 -277.537553) (xy 222.544229 -277.573246) (xy 222.498372 -277.602713)
			(xy 222.448788 -277.625354) (xy 222.396487 -277.640708) (xy 222.342532 -277.648463) (xy 222.315278 -277.648924)
			(xy 222.286539 -277.648407) (xy 222.229712 -277.639782) (xy 222.174821 -277.62273) (xy 222.123109 -277.597637)
			(xy 222.075747 -277.565071) (xy 222.05442 -277.5458) (xy 222.047308 -277.539196) (xy 222.029782 -277.532084)
			(xy 221.940374 -277.532084) (xy 221.922848 -277.539196) (xy 221.915736 -277.5458) (xy 221.894409 -277.56507)
			(xy 221.847046 -277.597635) (xy 221.795335 -277.622726) (xy 221.740444 -277.639776) (xy 221.683617 -277.648398)
			(xy 221.626139 -277.648398) (xy 221.569312 -277.639776) (xy 221.514421 -277.622726) (xy 221.46271 -277.597635)
			(xy 221.415347 -277.56507) (xy 221.39402 -277.5458) (xy 221.386908 -277.539196) (xy 221.369382 -277.532084)
			(xy 221.279974 -277.532084) (xy 221.262448 -277.539196) (xy 221.255336 -277.5458) (xy 221.234009 -277.56507)
			(xy 221.186646 -277.597635) (xy 221.134935 -277.622726) (xy 221.080044 -277.639776) (xy 221.023217 -277.648398)
			(xy 220.965739 -277.648398) (xy 220.908912 -277.639776) (xy 220.854021 -277.622726) (xy 220.80231 -277.597635)
			(xy 220.754947 -277.56507) (xy 220.73362 -277.5458) (xy 220.726508 -277.539196) (xy 220.708982 -277.532084)
			(xy 220.619574 -277.532084) (xy 220.602048 -277.539196) (xy 220.594936 -277.5458) (xy 220.573609 -277.565071)
			(xy 220.526248 -277.597639) (xy 220.474536 -277.622733) (xy 220.419645 -277.639783) (xy 220.362817 -277.648404)
			(xy 220.334078 -277.648924) (xy 220.306827 -277.648443) (xy 220.25288 -277.640684) (xy 220.200586 -277.625327)
			(xy 220.15101 -277.602684) (xy 220.10516 -277.573217) (xy 220.063971 -277.537525) (xy 220.02828 -277.496335)
			(xy 219.998813 -277.450485) (xy 219.976171 -277.400908) (xy 219.960815 -277.348614) (xy 219.953057 -277.294667)
			(xy 219.95257 -277.267416) (xy 216.256275 -277.267416) (xy 216.255795 -277.269011) (xy 216.232123 -277.319508)
			(xy 216.20135 -277.366021) (xy 216.164133 -277.407558) (xy 216.121265 -277.443233) (xy 216.073659 -277.472287)
			(xy 216.02233 -277.494099) (xy 215.968373 -277.508205) (xy 215.912936 -277.514305) (xy 215.857202 -277.512268)
			(xy 215.802359 -277.502138) (xy 215.749575 -277.484131) (xy 215.699975 -277.45863) (xy 215.654617 -277.426179)
			(xy 215.614468 -277.38747) (xy 215.580382 -277.343327) (xy 215.553086 -277.294692) (xy 215.533163 -277.242601)
			(xy 215.521037 -277.188164) (xy 215.516966 -277.132542) (xy 199.698293 -277.132542) (xy 199.693641 -277.13701)
			(xy 199.653138 -277.164966) (xy 199.608676 -277.186064) (xy 199.561405 -277.199756) (xy 199.51255 -277.205688)
			(xy 199.463375 -277.203707) (xy 199.415156 -277.193863) (xy 199.36914 -277.176411) (xy 199.326519 -277.151804)
			(xy 199.288398 -277.120679) (xy 199.255763 -277.083842) (xy 199.22946 -277.042246) (xy 199.210169 -276.99697)
			(xy 199.198392 -276.949186) (xy 199.194432 -276.900132) (xy 198.855325 -276.900132) (xy 198.854835 -276.924485)
			(xy 198.84694 -276.973062) (xy 198.831356 -277.019743) (xy 198.808485 -277.06332) (xy 198.77892 -277.102664)
			(xy 198.743427 -277.136756) (xy 198.702924 -277.164712) (xy 198.658462 -277.18581) (xy 198.611191 -277.199502)
			(xy 198.562336 -277.205434) (xy 198.513161 -277.203453) (xy 198.464942 -277.193609) (xy 198.418926 -277.176157)
			(xy 198.376305 -277.15155) (xy 198.338184 -277.120425) (xy 198.305549 -277.083588) (xy 198.279246 -277.041992)
			(xy 198.259955 -276.996716) (xy 198.248178 -276.948932) (xy 198.244218 -276.899878) (xy 197.90537 -276.899878)
			(xy 197.904875 -276.924485) (xy 197.89698 -276.973062) (xy 197.881396 -277.019743) (xy 197.858525 -277.06332)
			(xy 197.82896 -277.102664) (xy 197.793467 -277.136756) (xy 197.752964 -277.164712) (xy 197.708502 -277.18581)
			(xy 197.661231 -277.199502) (xy 197.612376 -277.205434) (xy 197.563201 -277.203453) (xy 197.514982 -277.193609)
			(xy 197.468966 -277.176157) (xy 197.426345 -277.15155) (xy 197.388224 -277.120425) (xy 197.355589 -277.083588)
			(xy 197.329286 -277.041992) (xy 197.309995 -276.996716) (xy 197.298218 -276.948932) (xy 197.294258 -276.899878)
			(xy 196.955156 -276.899878) (xy 196.954661 -276.924485) (xy 196.946766 -276.973062) (xy 196.931182 -277.019743)
			(xy 196.908311 -277.06332) (xy 196.878746 -277.102664) (xy 196.843253 -277.136756) (xy 196.80275 -277.164712)
			(xy 196.758288 -277.18581) (xy 196.711017 -277.199502) (xy 196.662162 -277.205434) (xy 196.612987 -277.203453)
			(xy 196.564768 -277.193609) (xy 196.518752 -277.176157) (xy 196.476131 -277.15155) (xy 196.43801 -277.120425)
			(xy 196.405375 -277.083588) (xy 196.379072 -277.041992) (xy 196.359781 -276.996716) (xy 196.348004 -276.948932)
			(xy 196.344044 -276.899878) (xy 196.004942 -276.899878) (xy 196.004447 -276.924485) (xy 195.996552 -276.973062)
			(xy 195.980968 -277.019743) (xy 195.958097 -277.06332) (xy 195.928532 -277.102664) (xy 195.893039 -277.136756)
			(xy 195.852536 -277.164712) (xy 195.808074 -277.18581) (xy 195.760803 -277.199502) (xy 195.711948 -277.205434)
			(xy 195.662773 -277.203453) (xy 195.614554 -277.193609) (xy 195.568538 -277.176157) (xy 195.525917 -277.15155)
			(xy 195.487796 -277.120425) (xy 195.455161 -277.083588) (xy 195.428858 -277.041992) (xy 195.409567 -276.996716)
			(xy 195.39779 -276.948932) (xy 195.39383 -276.899878) (xy 195.054982 -276.899878) (xy 195.054487 -276.924485)
			(xy 195.046592 -276.973062) (xy 195.031008 -277.019743) (xy 195.008137 -277.06332) (xy 194.978572 -277.102664)
			(xy 194.943079 -277.136756) (xy 194.902576 -277.164712) (xy 194.858114 -277.18581) (xy 194.810843 -277.199502)
			(xy 194.761988 -277.205434) (xy 194.712813 -277.203453) (xy 194.664594 -277.193609) (xy 194.618578 -277.176157)
			(xy 194.575957 -277.15155) (xy 194.537836 -277.120425) (xy 194.505201 -277.083588) (xy 194.478898 -277.041992)
			(xy 194.459607 -276.996716) (xy 194.44783 -276.948932) (xy 194.44387 -276.899878) (xy 194.105022 -276.899878)
			(xy 194.104527 -276.924485) (xy 194.096632 -276.973062) (xy 194.081048 -277.019743) (xy 194.058177 -277.06332)
			(xy 194.028612 -277.102664) (xy 193.993119 -277.136756) (xy 193.952616 -277.164712) (xy 193.908154 -277.18581)
			(xy 193.860883 -277.199502) (xy 193.812028 -277.205434) (xy 193.762853 -277.203453) (xy 193.714634 -277.193609)
			(xy 193.668618 -277.176157) (xy 193.625997 -277.15155) (xy 193.587876 -277.120425) (xy 193.555241 -277.083588)
			(xy 193.528938 -277.041992) (xy 193.509647 -276.996716) (xy 193.49787 -276.948932) (xy 193.49391 -276.899878)
			(xy 193.155062 -276.899878) (xy 193.154567 -276.924485) (xy 193.146672 -276.973062) (xy 193.131088 -277.019743)
			(xy 193.108217 -277.06332) (xy 193.078652 -277.102664) (xy 193.043159 -277.136756) (xy 193.002656 -277.164712)
			(xy 192.958194 -277.18581) (xy 192.910923 -277.199502) (xy 192.862068 -277.205434) (xy 192.812893 -277.203453)
			(xy 192.764674 -277.193609) (xy 192.718658 -277.176157) (xy 192.676037 -277.15155) (xy 192.637916 -277.120425)
			(xy 192.605281 -277.083588) (xy 192.578978 -277.041992) (xy 192.559687 -276.996716) (xy 192.54791 -276.948932)
			(xy 192.54395 -276.899878) (xy 192.205102 -276.899878) (xy 192.204607 -276.924485) (xy 192.196712 -276.973062)
			(xy 192.181128 -277.019743) (xy 192.158257 -277.06332) (xy 192.128692 -277.102664) (xy 192.093199 -277.136756)
			(xy 192.052696 -277.164712) (xy 192.008234 -277.18581) (xy 191.960963 -277.199502) (xy 191.912108 -277.205434)
			(xy 191.862933 -277.203453) (xy 191.814714 -277.193609) (xy 191.768698 -277.176157) (xy 191.726077 -277.15155)
			(xy 191.687956 -277.120425) (xy 191.655321 -277.083588) (xy 191.629018 -277.041992) (xy 191.609727 -276.996716)
			(xy 191.59795 -276.948932) (xy 191.59399 -276.899878) (xy 191.255142 -276.899878) (xy 191.254647 -276.924485)
			(xy 191.246752 -276.973062) (xy 191.231168 -277.019743) (xy 191.208297 -277.06332) (xy 191.178732 -277.102664)
			(xy 191.143239 -277.136756) (xy 191.102736 -277.164712) (xy 191.058274 -277.18581) (xy 191.011003 -277.199502)
			(xy 190.962148 -277.205434) (xy 190.912973 -277.203453) (xy 190.864754 -277.193609) (xy 190.818738 -277.176157)
			(xy 190.776117 -277.15155) (xy 190.737996 -277.120425) (xy 190.705361 -277.083588) (xy 190.679058 -277.041992)
			(xy 190.659767 -276.996716) (xy 190.64799 -276.948932) (xy 190.64403 -276.899878) (xy 190.304928 -276.899878)
			(xy 190.304433 -276.924485) (xy 190.296538 -276.973062) (xy 190.280954 -277.019743) (xy 190.258083 -277.06332)
			(xy 190.228518 -277.102664) (xy 190.193025 -277.136756) (xy 190.152522 -277.164712) (xy 190.10806 -277.18581)
			(xy 190.060789 -277.199502) (xy 190.011934 -277.205434) (xy 189.962759 -277.203453) (xy 189.91454 -277.193609)
			(xy 189.868524 -277.176157) (xy 189.825903 -277.15155) (xy 189.787782 -277.120425) (xy 189.755147 -277.083588)
			(xy 189.728844 -277.041992) (xy 189.709553 -276.996716) (xy 189.697776 -276.948932) (xy 189.693816 -276.899878)
			(xy 189.355222 -276.899878) (xy 189.354727 -276.924485) (xy 189.346832 -276.973062) (xy 189.331248 -277.019743)
			(xy 189.308377 -277.06332) (xy 189.278812 -277.102664) (xy 189.243319 -277.136756) (xy 189.202816 -277.164712)
			(xy 189.158354 -277.18581) (xy 189.111083 -277.199502) (xy 189.062228 -277.205434) (xy 189.013053 -277.203453)
			(xy 188.964834 -277.193609) (xy 188.918818 -277.176157) (xy 188.876197 -277.15155) (xy 188.838076 -277.120425)
			(xy 188.805441 -277.083588) (xy 188.779138 -277.041992) (xy 188.759847 -276.996716) (xy 188.74807 -276.948932)
			(xy 188.74411 -276.899878) (xy 188.405262 -276.899878) (xy 188.404767 -276.924485) (xy 188.396872 -276.973062)
			(xy 188.381288 -277.019743) (xy 188.358417 -277.06332) (xy 188.328852 -277.102664) (xy 188.293359 -277.136756)
			(xy 188.252856 -277.164712) (xy 188.208394 -277.18581) (xy 188.161123 -277.199502) (xy 188.112268 -277.205434)
			(xy 188.063093 -277.203453) (xy 188.014874 -277.193609) (xy 187.968858 -277.176157) (xy 187.926237 -277.15155)
			(xy 187.888116 -277.120425) (xy 187.855481 -277.083588) (xy 187.829178 -277.041992) (xy 187.809887 -276.996716)
			(xy 187.79811 -276.948932) (xy 187.79415 -276.899878) (xy 187.455302 -276.899878) (xy 187.454807 -276.924485)
			(xy 187.446912 -276.973062) (xy 187.431328 -277.019743) (xy 187.408457 -277.06332) (xy 187.378892 -277.102664)
			(xy 187.343399 -277.136756) (xy 187.302896 -277.164712) (xy 187.258434 -277.18581) (xy 187.211163 -277.199502)
			(xy 187.162308 -277.205434) (xy 187.113133 -277.203453) (xy 187.064914 -277.193609) (xy 187.018898 -277.176157)
			(xy 186.976277 -277.15155) (xy 186.938156 -277.120425) (xy 186.905521 -277.083588) (xy 186.879218 -277.041992)
			(xy 186.859927 -276.996716) (xy 186.84815 -276.948932) (xy 186.84419 -276.899878) (xy 186.505342 -276.899878)
			(xy 186.504847 -276.924485) (xy 186.496952 -276.973062) (xy 186.481368 -277.019743) (xy 186.458497 -277.06332)
			(xy 186.428932 -277.102664) (xy 186.393439 -277.136756) (xy 186.352936 -277.164712) (xy 186.308474 -277.18581)
			(xy 186.261203 -277.199502) (xy 186.212348 -277.205434) (xy 186.163173 -277.203453) (xy 186.114954 -277.193609)
			(xy 186.068938 -277.176157) (xy 186.026317 -277.15155) (xy 185.988196 -277.120425) (xy 185.955561 -277.083588)
			(xy 185.929258 -277.041992) (xy 185.909967 -276.996716) (xy 185.89819 -276.948932) (xy 185.89423 -276.899878)
			(xy 185.555382 -276.899878) (xy 185.554887 -276.924485) (xy 185.546992 -276.973062) (xy 185.531408 -277.019743)
			(xy 185.508537 -277.06332) (xy 185.478972 -277.102664) (xy 185.443479 -277.136756) (xy 185.402976 -277.164712)
			(xy 185.358514 -277.18581) (xy 185.311243 -277.199502) (xy 185.262388 -277.205434) (xy 185.213213 -277.203453)
			(xy 185.164994 -277.193609) (xy 185.118978 -277.176157) (xy 185.076357 -277.15155) (xy 185.038236 -277.120425)
			(xy 185.005601 -277.083588) (xy 184.979298 -277.041992) (xy 184.960007 -276.996716) (xy 184.94823 -276.948932)
			(xy 184.94427 -276.899878) (xy 184.605168 -276.899878) (xy 184.604673 -276.924485) (xy 184.596778 -276.973062)
			(xy 184.581194 -277.019743) (xy 184.558323 -277.06332) (xy 184.528758 -277.102664) (xy 184.493265 -277.136756)
			(xy 184.452762 -277.164712) (xy 184.4083 -277.18581) (xy 184.361029 -277.199502) (xy 184.312174 -277.205434)
			(xy 184.262999 -277.203453) (xy 184.21478 -277.193609) (xy 184.168764 -277.176157) (xy 184.126143 -277.15155)
			(xy 184.088022 -277.120425) (xy 184.055387 -277.083588) (xy 184.029084 -277.041992) (xy 184.009793 -276.996716)
			(xy 183.998016 -276.948932) (xy 183.994056 -276.899878) (xy 183.655208 -276.899878) (xy 183.654713 -276.924485)
			(xy 183.646818 -276.973062) (xy 183.631234 -277.019743) (xy 183.608363 -277.06332) (xy 183.578798 -277.102664)
			(xy 183.543305 -277.136756) (xy 183.502802 -277.164712) (xy 183.45834 -277.18581) (xy 183.411069 -277.199502)
			(xy 183.362214 -277.205434) (xy 183.313039 -277.203453) (xy 183.26482 -277.193609) (xy 183.218804 -277.176157)
			(xy 183.176183 -277.15155) (xy 183.138062 -277.120425) (xy 183.105427 -277.083588) (xy 183.079124 -277.041992)
			(xy 183.059833 -276.996716) (xy 183.048056 -276.948932) (xy 183.044096 -276.899878) (xy 182.705248 -276.899878)
			(xy 182.704753 -276.924485) (xy 182.696858 -276.973062) (xy 182.681274 -277.019743) (xy 182.658403 -277.06332)
			(xy 182.628838 -277.102664) (xy 182.593345 -277.136756) (xy 182.552842 -277.164712) (xy 182.50838 -277.18581)
			(xy 182.461109 -277.199502) (xy 182.412254 -277.205434) (xy 182.363079 -277.203453) (xy 182.31486 -277.193609)
			(xy 182.268844 -277.176157) (xy 182.226223 -277.15155) (xy 182.188102 -277.120425) (xy 182.155467 -277.083588)
			(xy 182.129164 -277.041992) (xy 182.109873 -276.996716) (xy 182.098096 -276.948932) (xy 182.094136 -276.899878)
			(xy 181.755288 -276.899878) (xy 181.754793 -276.924485) (xy 181.746898 -276.973062) (xy 181.731314 -277.019743)
			(xy 181.708443 -277.06332) (xy 181.678878 -277.102664) (xy 181.643385 -277.136756) (xy 181.602882 -277.164712)
			(xy 181.55842 -277.18581) (xy 181.511149 -277.199502) (xy 181.462294 -277.205434) (xy 181.413119 -277.203453)
			(xy 181.3649 -277.193609) (xy 181.318884 -277.176157) (xy 181.276263 -277.15155) (xy 181.238142 -277.120425)
			(xy 181.205507 -277.083588) (xy 181.179204 -277.041992) (xy 181.159913 -276.996716) (xy 181.148136 -276.948932)
			(xy 181.144176 -276.899878) (xy 180.805328 -276.899878) (xy 180.804833 -276.924485) (xy 180.796938 -276.973062)
			(xy 180.781354 -277.019743) (xy 180.758483 -277.06332) (xy 180.728918 -277.102664) (xy 180.693425 -277.136756)
			(xy 180.652922 -277.164712) (xy 180.60846 -277.18581) (xy 180.561189 -277.199502) (xy 180.512334 -277.205434)
			(xy 180.463159 -277.203453) (xy 180.41494 -277.193609) (xy 180.368924 -277.176157) (xy 180.326303 -277.15155)
			(xy 180.288182 -277.120425) (xy 180.255547 -277.083588) (xy 180.229244 -277.041992) (xy 180.209953 -276.996716)
			(xy 180.198176 -276.948932) (xy 180.194216 -276.899878) (xy 179.855368 -276.899878) (xy 179.854873 -276.924485)
			(xy 179.846978 -276.973062) (xy 179.831394 -277.019743) (xy 179.808523 -277.06332) (xy 179.778958 -277.102664)
			(xy 179.743465 -277.136756) (xy 179.702962 -277.164712) (xy 179.6585 -277.18581) (xy 179.611229 -277.199502)
			(xy 179.562374 -277.205434) (xy 179.513199 -277.203453) (xy 179.46498 -277.193609) (xy 179.418964 -277.176157)
			(xy 179.376343 -277.15155) (xy 179.338222 -277.120425) (xy 179.305587 -277.083588) (xy 179.279284 -277.041992)
			(xy 179.259993 -276.996716) (xy 179.248216 -276.948932) (xy 179.244256 -276.899878) (xy 178.905154 -276.899878)
			(xy 178.904659 -276.924485) (xy 178.896764 -276.973062) (xy 178.88118 -277.019743) (xy 178.858309 -277.06332)
			(xy 178.828744 -277.102664) (xy 178.793251 -277.136756) (xy 178.752748 -277.164712) (xy 178.708286 -277.18581)
			(xy 178.661015 -277.199502) (xy 178.61216 -277.205434) (xy 178.562985 -277.203453) (xy 178.514766 -277.193609)
			(xy 178.46875 -277.176157) (xy 178.426129 -277.15155) (xy 178.388008 -277.120425) (xy 178.355373 -277.083588)
			(xy 178.32907 -277.041992) (xy 178.309779 -276.996716) (xy 178.298002 -276.948932) (xy 178.294042 -276.899878)
			(xy 177.955193 -276.899878) (xy 177.952953 -276.941189) (xy 177.942281 -276.989675) (xy 177.923905 -277.035795)
			(xy 177.898309 -277.078335) (xy 177.866168 -277.116174) (xy 177.828329 -277.148313) (xy 177.785788 -277.173908)
			(xy 177.739667 -277.192283) (xy 177.691181 -277.202954) (xy 177.641607 -277.205641) (xy 177.592252 -277.200271)
			(xy 177.544416 -277.186987) (xy 177.499359 -277.166139) (xy 177.458268 -277.138276) (xy 177.422227 -277.104133)
			(xy 177.392184 -277.064608) (xy 177.368932 -277.020743) (xy 177.353083 -276.973694) (xy 177.345054 -276.924701)
			(xy 177.344578 -276.899878) (xy 177.344675 -276.890774) (xy 177.345818 -276.8726) (xy 177.346864 -276.863556)
			(xy 177.348134 -276.851364) (xy 177.34026 -276.829012) (xy 177.263806 -276.756114) (xy 177.2412 -276.749002)
			(xy 177.229262 -276.751034) (xy 177.215774 -276.753165) (xy 177.188561 -276.755454) (xy 177.174906 -276.755606)
			(xy 177.161252 -276.755443) (xy 177.13404 -276.753152) (xy 177.12055 -276.751034) (xy 177.108612 -276.749002)
			(xy 177.086006 -276.756114) (xy 177.009552 -276.829012) (xy 177.001678 -276.851364) (xy 177.002948 -276.863556)
			(xy 177.003997 -276.8726) (xy 177.005142 -276.890774) (xy 177.005234 -276.899878) (xy 177.004712 -276.925133)
			(xy 176.996399 -276.974955) (xy 176.979998 -277.022729) (xy 176.955957 -277.067152) (xy 176.924933 -277.107012)
			(xy 176.887771 -277.141222) (xy 176.845485 -277.168848) (xy 176.799229 -277.189138) (xy 176.750264 -277.201538)
			(xy 176.699926 -277.205709) (xy 176.649588 -277.201538) (xy 176.600623 -277.189138) (xy 176.554367 -277.168848)
			(xy 176.512081 -277.141222) (xy 176.474919 -277.107012) (xy 176.443895 -277.067152) (xy 176.419854 -277.022729)
			(xy 176.403453 -276.974955) (xy 176.39514 -276.925133) (xy 176.394618 -276.899878) (xy 176.394715 -276.890774)
			(xy 176.395858 -276.8726) (xy 176.396904 -276.863556) (xy 176.398174 -276.851364) (xy 176.3903 -276.829012)
			(xy 176.313846 -276.756114) (xy 176.29124 -276.749002) (xy 176.279302 -276.751034) (xy 176.265814 -276.753167)
			(xy 176.238601 -276.755459) (xy 176.224946 -276.755606) (xy 176.211292 -276.755445) (xy 176.184079 -276.753156)
			(xy 176.17059 -276.751034) (xy 176.158652 -276.749002) (xy 176.136046 -276.756114) (xy 176.059592 -276.829012)
			(xy 176.051718 -276.851364) (xy 176.052988 -276.863556) (xy 176.054037 -276.8726) (xy 176.055182 -276.890774)
			(xy 176.055274 -276.899878) (xy 176.054829 -276.923871) (xy 176.047325 -276.971267) (xy 176.032498 -277.016906)
			(xy 176.010713 -277.059663) (xy 175.982508 -277.098484) (xy 175.948575 -277.132415) (xy 175.909752 -277.16062)
			(xy 175.866995 -277.182403) (xy 175.821356 -277.197228) (xy 175.773959 -277.20473) (xy 175.749966 -277.205186)
			(xy 175.723579 -277.204626) (xy 175.67159 -277.195548) (xy 175.621936 -277.177669) (xy 175.576094 -277.15152)
			(xy 175.53543 -277.11788) (xy 175.501153 -277.077751) (xy 175.474285 -277.032328) (xy 175.46447 -277.007828)
			(xy 175.459644 -276.995636) (xy 175.440594 -276.979126) (xy 175.344074 -276.958298) (xy 175.335749 -276.956822)
			(xy 175.318975 -276.958854) (xy 175.303788 -276.966261) (xy 175.297592 -276.972014) (xy 174.93488 -277.334726)
			(xy 174.927484 -277.341577) (xy 174.908885 -277.349316) (xy 174.898812 -277.349712) (xy 174.706026 -277.349712)
			(xy 174.696441 -277.350124) (xy 174.678605 -277.357149) (xy 174.664565 -277.370202) (xy 174.660052 -277.378668)
			(xy 174.655734 -277.388066) (xy 174.654972 -277.397718) (xy 174.654972 -277.397972) (xy 174.651162 -277.429214)
			(xy 174.649384 -277.441152) (xy 174.656242 -277.463758) (xy 174.72914 -277.540212) (xy 174.751492 -277.548086)
			(xy 174.763684 -277.546816) (xy 174.772728 -277.545768) (xy 174.790902 -277.544625) (xy 174.800006 -277.54453)
			(xy 174.824823 -277.545016) (xy 174.873803 -277.553047) (xy 174.920839 -277.568895) (xy 174.964691 -277.592145)
			(xy 175.004204 -277.622182) (xy 175.038338 -277.658216) (xy 175.066192 -277.699297) (xy 175.087034 -277.744343)
			(xy 175.100313 -277.792168) (xy 175.105681 -277.841511) (xy 175.10523 -277.849838) (xy 175.443908 -277.849838)
			(xy 175.447868 -277.800784) (xy 175.459645 -277.753) (xy 175.478936 -277.707724) (xy 175.505239 -277.666128)
			(xy 175.537874 -277.629291) (xy 175.575995 -277.598166) (xy 175.618616 -277.573559) (xy 175.664632 -277.556107)
			(xy 175.712851 -277.546263) (xy 175.762026 -277.544282) (xy 175.810881 -277.550214) (xy 175.858152 -277.563906)
			(xy 175.902614 -277.585004) (xy 175.943117 -277.61296) (xy 175.97861 -277.647052) (xy 176.008175 -277.686396)
			(xy 176.031046 -277.729973) (xy 176.04663 -277.776654) (xy 176.054525 -277.825231) (xy 176.05502 -277.849838)
			(xy 176.394122 -277.849838) (xy 176.398082 -277.800784) (xy 176.409859 -277.753) (xy 176.42915 -277.707724)
			(xy 176.455453 -277.666128) (xy 176.488088 -277.629291) (xy 176.526209 -277.598166) (xy 176.56883 -277.573559)
			(xy 176.614846 -277.556107) (xy 176.663065 -277.546263) (xy 176.71224 -277.544282) (xy 176.761095 -277.550214)
			(xy 176.808366 -277.563906) (xy 176.852828 -277.585004) (xy 176.893331 -277.61296) (xy 176.928824 -277.647052)
			(xy 176.958389 -277.686396) (xy 176.98126 -277.729973) (xy 176.996844 -277.776654) (xy 177.004739 -277.825231)
			(xy 177.005234 -277.849838) (xy 177.343828 -277.849838) (xy 177.347788 -277.800784) (xy 177.359565 -277.753)
			(xy 177.378856 -277.707724) (xy 177.405159 -277.666128) (xy 177.437794 -277.629291) (xy 177.475915 -277.598166)
			(xy 177.518536 -277.573559) (xy 177.564552 -277.556107) (xy 177.612771 -277.546263) (xy 177.661946 -277.544282)
			(xy 177.710801 -277.550214) (xy 177.758072 -277.563906) (xy 177.802534 -277.585004) (xy 177.843037 -277.61296)
			(xy 177.87853 -277.647052) (xy 177.908095 -277.686396) (xy 177.930966 -277.729973) (xy 177.94655 -277.776654)
			(xy 177.954445 -277.825231) (xy 177.95494 -277.849838) (xy 178.294042 -277.849838) (xy 178.298002 -277.800784)
			(xy 178.309779 -277.753) (xy 178.32907 -277.707724) (xy 178.355373 -277.666128) (xy 178.388008 -277.629291)
			(xy 178.426129 -277.598166) (xy 178.46875 -277.573559) (xy 178.514766 -277.556107) (xy 178.562985 -277.546263)
			(xy 178.61216 -277.544282) (xy 178.661015 -277.550214) (xy 178.708286 -277.563906) (xy 178.752748 -277.585004)
			(xy 178.793251 -277.61296) (xy 178.828744 -277.647052) (xy 178.858309 -277.686396) (xy 178.88118 -277.729973)
			(xy 178.896764 -277.776654) (xy 178.904659 -277.825231) (xy 178.905154 -277.849838) (xy 179.244002 -277.849838)
			(xy 179.247962 -277.800784) (xy 179.259739 -277.753) (xy 179.27903 -277.707724) (xy 179.305333 -277.666128)
			(xy 179.337968 -277.629291) (xy 179.376089 -277.598166) (xy 179.41871 -277.573559) (xy 179.464726 -277.556107)
			(xy 179.512945 -277.546263) (xy 179.56212 -277.544282) (xy 179.610975 -277.550214) (xy 179.658246 -277.563906)
			(xy 179.702708 -277.585004) (xy 179.743211 -277.61296) (xy 179.778704 -277.647052) (xy 179.808269 -277.686396)
			(xy 179.83114 -277.729973) (xy 179.846724 -277.776654) (xy 179.854619 -277.825231) (xy 179.855114 -277.849838)
			(xy 180.194216 -277.849838) (xy 180.198176 -277.800784) (xy 180.209953 -277.753) (xy 180.229244 -277.707724)
			(xy 180.255547 -277.666128) (xy 180.288182 -277.629291) (xy 180.326303 -277.598166) (xy 180.368924 -277.573559)
			(xy 180.41494 -277.556107) (xy 180.463159 -277.546263) (xy 180.512334 -277.544282) (xy 180.561189 -277.550214)
			(xy 180.60846 -277.563906) (xy 180.652922 -277.585004) (xy 180.693425 -277.61296) (xy 180.728918 -277.647052)
			(xy 180.758483 -277.686396) (xy 180.781354 -277.729973) (xy 180.796938 -277.776654) (xy 180.804833 -277.825231)
			(xy 180.805328 -277.849838) (xy 181.143922 -277.849838) (xy 181.147882 -277.800784) (xy 181.159659 -277.753)
			(xy 181.17895 -277.707724) (xy 181.205253 -277.666128) (xy 181.237888 -277.629291) (xy 181.276009 -277.598166)
			(xy 181.31863 -277.573559) (xy 181.364646 -277.556107) (xy 181.412865 -277.546263) (xy 181.46204 -277.544282)
			(xy 181.510895 -277.550214) (xy 181.558166 -277.563906) (xy 181.602628 -277.585004) (xy 181.643131 -277.61296)
			(xy 181.678624 -277.647052) (xy 181.708189 -277.686396) (xy 181.73106 -277.729973) (xy 181.746644 -277.776654)
			(xy 181.754539 -277.825231) (xy 181.755034 -277.849838) (xy 182.094136 -277.849838) (xy 182.098096 -277.800784)
			(xy 182.109873 -277.753) (xy 182.129164 -277.707724) (xy 182.155467 -277.666128) (xy 182.188102 -277.629291)
			(xy 182.226223 -277.598166) (xy 182.268844 -277.573559) (xy 182.31486 -277.556107) (xy 182.363079 -277.546263)
			(xy 182.412254 -277.544282) (xy 182.461109 -277.550214) (xy 182.50838 -277.563906) (xy 182.552842 -277.585004)
			(xy 182.593345 -277.61296) (xy 182.628838 -277.647052) (xy 182.658403 -277.686396) (xy 182.681274 -277.729973)
			(xy 182.696858 -277.776654) (xy 182.704753 -277.825231) (xy 182.705248 -277.849838) (xy 183.043842 -277.849838)
			(xy 183.047802 -277.800784) (xy 183.059579 -277.753) (xy 183.07887 -277.707724) (xy 183.105173 -277.666128)
			(xy 183.137808 -277.629291) (xy 183.175929 -277.598166) (xy 183.21855 -277.573559) (xy 183.264566 -277.556107)
			(xy 183.312785 -277.546263) (xy 183.36196 -277.544282) (xy 183.410815 -277.550214) (xy 183.458086 -277.563906)
			(xy 183.502548 -277.585004) (xy 183.543051 -277.61296) (xy 183.578544 -277.647052) (xy 183.608109 -277.686396)
			(xy 183.63098 -277.729973) (xy 183.646564 -277.776654) (xy 183.654459 -277.825231) (xy 183.654954 -277.849838)
			(xy 183.994056 -277.849838) (xy 183.998016 -277.800784) (xy 184.009793 -277.753) (xy 184.029084 -277.707724)
			(xy 184.055387 -277.666128) (xy 184.088022 -277.629291) (xy 184.126143 -277.598166) (xy 184.168764 -277.573559)
			(xy 184.21478 -277.556107) (xy 184.262999 -277.546263) (xy 184.312174 -277.544282) (xy 184.361029 -277.550214)
			(xy 184.4083 -277.563906) (xy 184.452762 -277.585004) (xy 184.493265 -277.61296) (xy 184.528758 -277.647052)
			(xy 184.558323 -277.686396) (xy 184.581194 -277.729973) (xy 184.596778 -277.776654) (xy 184.604673 -277.825231)
			(xy 184.605168 -277.849838) (xy 184.944016 -277.849838) (xy 184.947976 -277.800784) (xy 184.959753 -277.753)
			(xy 184.979044 -277.707724) (xy 185.005347 -277.666128) (xy 185.037982 -277.629291) (xy 185.076103 -277.598166)
			(xy 185.118724 -277.573559) (xy 185.16474 -277.556107) (xy 185.212959 -277.546263) (xy 185.262134 -277.544282)
			(xy 185.310989 -277.550214) (xy 185.35826 -277.563906) (xy 185.402722 -277.585004) (xy 185.443225 -277.61296)
			(xy 185.478718 -277.647052) (xy 185.508283 -277.686396) (xy 185.531154 -277.729973) (xy 185.546738 -277.776654)
			(xy 185.554633 -277.825231) (xy 185.555128 -277.849838) (xy 185.89423 -277.849838) (xy 185.89819 -277.800784)
			(xy 185.909967 -277.753) (xy 185.929258 -277.707724) (xy 185.955561 -277.666128) (xy 185.988196 -277.629291)
			(xy 186.026317 -277.598166) (xy 186.068938 -277.573559) (xy 186.114954 -277.556107) (xy 186.163173 -277.546263)
			(xy 186.212348 -277.544282) (xy 186.261203 -277.550214) (xy 186.308474 -277.563906) (xy 186.352936 -277.585004)
			(xy 186.393439 -277.61296) (xy 186.428932 -277.647052) (xy 186.458497 -277.686396) (xy 186.481368 -277.729973)
			(xy 186.496952 -277.776654) (xy 186.504847 -277.825231) (xy 186.505342 -277.849838) (xy 186.843936 -277.849838)
			(xy 186.847896 -277.800784) (xy 186.859673 -277.753) (xy 186.878964 -277.707724) (xy 186.905267 -277.666128)
			(xy 186.937902 -277.629291) (xy 186.976023 -277.598166) (xy 187.018644 -277.573559) (xy 187.06466 -277.556107)
			(xy 187.112879 -277.546263) (xy 187.162054 -277.544282) (xy 187.210909 -277.550214) (xy 187.25818 -277.563906)
			(xy 187.302642 -277.585004) (xy 187.343145 -277.61296) (xy 187.378638 -277.647052) (xy 187.408203 -277.686396)
			(xy 187.431074 -277.729973) (xy 187.446658 -277.776654) (xy 187.454553 -277.825231) (xy 187.455048 -277.849838)
			(xy 187.79415 -277.849838) (xy 187.79811 -277.800784) (xy 187.809887 -277.753) (xy 187.829178 -277.707724)
			(xy 187.855481 -277.666128) (xy 187.888116 -277.629291) (xy 187.926237 -277.598166) (xy 187.968858 -277.573559)
			(xy 188.014874 -277.556107) (xy 188.063093 -277.546263) (xy 188.112268 -277.544282) (xy 188.161123 -277.550214)
			(xy 188.208394 -277.563906) (xy 188.252856 -277.585004) (xy 188.293359 -277.61296) (xy 188.328852 -277.647052)
			(xy 188.358417 -277.686396) (xy 188.381288 -277.729973) (xy 188.396872 -277.776654) (xy 188.404767 -277.825231)
			(xy 188.405262 -277.849838) (xy 188.743856 -277.849838) (xy 188.747816 -277.800784) (xy 188.759593 -277.753)
			(xy 188.778884 -277.707724) (xy 188.805187 -277.666128) (xy 188.837822 -277.629291) (xy 188.875943 -277.598166)
			(xy 188.918564 -277.573559) (xy 188.96458 -277.556107) (xy 189.012799 -277.546263) (xy 189.061974 -277.544282)
			(xy 189.110829 -277.550214) (xy 189.1581 -277.563906) (xy 189.202562 -277.585004) (xy 189.243065 -277.61296)
			(xy 189.278558 -277.647052) (xy 189.308123 -277.686396) (xy 189.330994 -277.729973) (xy 189.346578 -277.776654)
			(xy 189.354473 -277.825231) (xy 189.354968 -277.849838) (xy 189.69407 -277.849838) (xy 189.69803 -277.800784)
			(xy 189.709807 -277.753) (xy 189.729098 -277.707724) (xy 189.755401 -277.666128) (xy 189.788036 -277.629291)
			(xy 189.826157 -277.598166) (xy 189.868778 -277.573559) (xy 189.914794 -277.556107) (xy 189.963013 -277.546263)
			(xy 190.012188 -277.544282) (xy 190.061043 -277.550214) (xy 190.108314 -277.563906) (xy 190.152776 -277.585004)
			(xy 190.193279 -277.61296) (xy 190.228772 -277.647052) (xy 190.258337 -277.686396) (xy 190.281208 -277.729973)
			(xy 190.296792 -277.776654) (xy 190.304687 -277.825231) (xy 190.305182 -277.849838) (xy 190.64403 -277.849838)
			(xy 190.64799 -277.800784) (xy 190.659767 -277.753) (xy 190.679058 -277.707724) (xy 190.705361 -277.666128)
			(xy 190.737996 -277.629291) (xy 190.776117 -277.598166) (xy 190.818738 -277.573559) (xy 190.864754 -277.556107)
			(xy 190.912973 -277.546263) (xy 190.962148 -277.544282) (xy 191.011003 -277.550214) (xy 191.058274 -277.563906)
			(xy 191.102736 -277.585004) (xy 191.143239 -277.61296) (xy 191.178732 -277.647052) (xy 191.208297 -277.686396)
			(xy 191.231168 -277.729973) (xy 191.246752 -277.776654) (xy 191.254647 -277.825231) (xy 191.255142 -277.849838)
			(xy 191.594244 -277.849838) (xy 191.598204 -277.800784) (xy 191.609981 -277.753) (xy 191.629272 -277.707724)
			(xy 191.655575 -277.666128) (xy 191.68821 -277.629291) (xy 191.726331 -277.598166) (xy 191.768952 -277.573559)
			(xy 191.814968 -277.556107) (xy 191.863187 -277.546263) (xy 191.912362 -277.544282) (xy 191.961217 -277.550214)
			(xy 192.008488 -277.563906) (xy 192.05295 -277.585004) (xy 192.093453 -277.61296) (xy 192.128946 -277.647052)
			(xy 192.158511 -277.686396) (xy 192.181382 -277.729973) (xy 192.196966 -277.776654) (xy 192.204861 -277.825231)
			(xy 192.205356 -277.849838) (xy 192.54395 -277.849838) (xy 192.54791 -277.800784) (xy 192.559687 -277.753)
			(xy 192.578978 -277.707724) (xy 192.605281 -277.666128) (xy 192.637916 -277.629291) (xy 192.676037 -277.598166)
			(xy 192.718658 -277.573559) (xy 192.764674 -277.556107) (xy 192.812893 -277.546263) (xy 192.862068 -277.544282)
			(xy 192.910923 -277.550214) (xy 192.958194 -277.563906) (xy 193.002656 -277.585004) (xy 193.043159 -277.61296)
			(xy 193.078652 -277.647052) (xy 193.108217 -277.686396) (xy 193.131088 -277.729973) (xy 193.146672 -277.776654)
			(xy 193.154567 -277.825231) (xy 193.155062 -277.849838) (xy 193.494164 -277.849838) (xy 193.498124 -277.800784)
			(xy 193.509901 -277.753) (xy 193.529192 -277.707724) (xy 193.555495 -277.666128) (xy 193.58813 -277.629291)
			(xy 193.626251 -277.598166) (xy 193.668872 -277.573559) (xy 193.714888 -277.556107) (xy 193.763107 -277.546263)
			(xy 193.812282 -277.544282) (xy 193.861137 -277.550214) (xy 193.908408 -277.563906) (xy 193.95287 -277.585004)
			(xy 193.993373 -277.61296) (xy 194.028866 -277.647052) (xy 194.058431 -277.686396) (xy 194.081302 -277.729973)
			(xy 194.096886 -277.776654) (xy 194.104781 -277.825231) (xy 194.105276 -277.849838) (xy 194.44387 -277.849838)
			(xy 194.44783 -277.800784) (xy 194.459607 -277.753) (xy 194.478898 -277.707724) (xy 194.505201 -277.666128)
			(xy 194.537836 -277.629291) (xy 194.575957 -277.598166) (xy 194.618578 -277.573559) (xy 194.664594 -277.556107)
			(xy 194.712813 -277.546263) (xy 194.761988 -277.544282) (xy 194.810843 -277.550214) (xy 194.858114 -277.563906)
			(xy 194.902576 -277.585004) (xy 194.943079 -277.61296) (xy 194.978572 -277.647052) (xy 195.008137 -277.686396)
			(xy 195.031008 -277.729973) (xy 195.046592 -277.776654) (xy 195.054487 -277.825231) (xy 195.054982 -277.849838)
			(xy 195.394084 -277.849838) (xy 195.398044 -277.800784) (xy 195.409821 -277.753) (xy 195.429112 -277.707724)
			(xy 195.455415 -277.666128) (xy 195.48805 -277.629291) (xy 195.526171 -277.598166) (xy 195.568792 -277.573559)
			(xy 195.614808 -277.556107) (xy 195.663027 -277.546263) (xy 195.712202 -277.544282) (xy 195.761057 -277.550214)
			(xy 195.808328 -277.563906) (xy 195.85279 -277.585004) (xy 195.893293 -277.61296) (xy 195.928786 -277.647052)
			(xy 195.958351 -277.686396) (xy 195.981222 -277.729973) (xy 195.996806 -277.776654) (xy 196.004701 -277.825231)
			(xy 196.005196 -277.849838) (xy 196.344044 -277.849838) (xy 196.348004 -277.800784) (xy 196.359781 -277.753)
			(xy 196.379072 -277.707724) (xy 196.405375 -277.666128) (xy 196.43801 -277.629291) (xy 196.476131 -277.598166)
			(xy 196.518752 -277.573559) (xy 196.564768 -277.556107) (xy 196.612987 -277.546263) (xy 196.662162 -277.544282)
			(xy 196.711017 -277.550214) (xy 196.758288 -277.563906) (xy 196.80275 -277.585004) (xy 196.843253 -277.61296)
			(xy 196.878746 -277.647052) (xy 196.908311 -277.686396) (xy 196.931182 -277.729973) (xy 196.946766 -277.776654)
			(xy 196.954661 -277.825231) (xy 196.955156 -277.849838) (xy 197.294258 -277.849838) (xy 197.298218 -277.800784)
			(xy 197.309995 -277.753) (xy 197.329286 -277.707724) (xy 197.355589 -277.666128) (xy 197.388224 -277.629291)
			(xy 197.426345 -277.598166) (xy 197.468966 -277.573559) (xy 197.514982 -277.556107) (xy 197.563201 -277.546263)
			(xy 197.612376 -277.544282) (xy 197.661231 -277.550214) (xy 197.708502 -277.563906) (xy 197.752964 -277.585004)
			(xy 197.793467 -277.61296) (xy 197.82896 -277.647052) (xy 197.858525 -277.686396) (xy 197.881396 -277.729973)
			(xy 197.89698 -277.776654) (xy 197.904875 -277.825231) (xy 197.90537 -277.849838) (xy 198.244218 -277.849838)
			(xy 198.248178 -277.800784) (xy 198.259955 -277.753) (xy 198.279246 -277.707724) (xy 198.305549 -277.666128)
			(xy 198.338184 -277.629291) (xy 198.376305 -277.598166) (xy 198.418926 -277.573559) (xy 198.464942 -277.556107)
			(xy 198.513161 -277.546263) (xy 198.562336 -277.544282) (xy 198.611191 -277.550214) (xy 198.658462 -277.563906)
			(xy 198.702924 -277.585004) (xy 198.743427 -277.61296) (xy 198.77892 -277.647052) (xy 198.808485 -277.686396)
			(xy 198.831356 -277.729973) (xy 198.84694 -277.776654) (xy 198.854835 -277.825231) (xy 198.85533 -277.849838)
			(xy 198.854835 -277.874445) (xy 198.84694 -277.923022) (xy 198.831356 -277.969703) (xy 198.808485 -278.01328)
			(xy 198.77892 -278.052624) (xy 198.743427 -278.086716) (xy 198.702924 -278.114672) (xy 198.658462 -278.13577)
			(xy 198.611191 -278.149462) (xy 198.562336 -278.155394) (xy 198.513161 -278.153413) (xy 198.464942 -278.143569)
			(xy 198.418926 -278.126117) (xy 198.376305 -278.10151) (xy 198.338184 -278.070385) (xy 198.305549 -278.033548)
			(xy 198.279246 -277.991952) (xy 198.259955 -277.946676) (xy 198.248178 -277.898892) (xy 198.244218 -277.849838)
			(xy 197.90537 -277.849838) (xy 197.904875 -277.874445) (xy 197.89698 -277.923022) (xy 197.881396 -277.969703)
			(xy 197.858525 -278.01328) (xy 197.82896 -278.052624) (xy 197.793467 -278.086716) (xy 197.752964 -278.114672)
			(xy 197.708502 -278.13577) (xy 197.661231 -278.149462) (xy 197.612376 -278.155394) (xy 197.563201 -278.153413)
			(xy 197.514982 -278.143569) (xy 197.468966 -278.126117) (xy 197.426345 -278.10151) (xy 197.388224 -278.070385)
			(xy 197.355589 -278.033548) (xy 197.329286 -277.991952) (xy 197.309995 -277.946676) (xy 197.298218 -277.898892)
			(xy 197.294258 -277.849838) (xy 196.955156 -277.849838) (xy 196.954661 -277.874445) (xy 196.946766 -277.923022)
			(xy 196.931182 -277.969703) (xy 196.908311 -278.01328) (xy 196.878746 -278.052624) (xy 196.843253 -278.086716)
			(xy 196.80275 -278.114672) (xy 196.758288 -278.13577) (xy 196.711017 -278.149462) (xy 196.662162 -278.155394)
			(xy 196.612987 -278.153413) (xy 196.564768 -278.143569) (xy 196.518752 -278.126117) (xy 196.476131 -278.10151)
			(xy 196.43801 -278.070385) (xy 196.405375 -278.033548) (xy 196.379072 -277.991952) (xy 196.359781 -277.946676)
			(xy 196.348004 -277.898892) (xy 196.344044 -277.849838) (xy 196.005196 -277.849838) (xy 196.004701 -277.874445)
			(xy 195.996806 -277.923022) (xy 195.981222 -277.969703) (xy 195.958351 -278.01328) (xy 195.928786 -278.052624)
			(xy 195.893293 -278.086716) (xy 195.85279 -278.114672) (xy 195.808328 -278.13577) (xy 195.761057 -278.149462)
			(xy 195.712202 -278.155394) (xy 195.663027 -278.153413) (xy 195.614808 -278.143569) (xy 195.568792 -278.126117)
			(xy 195.526171 -278.10151) (xy 195.48805 -278.070385) (xy 195.455415 -278.033548) (xy 195.429112 -277.991952)
			(xy 195.409821 -277.946676) (xy 195.398044 -277.898892) (xy 195.394084 -277.849838) (xy 195.054982 -277.849838)
			(xy 195.054487 -277.874445) (xy 195.046592 -277.923022) (xy 195.031008 -277.969703) (xy 195.008137 -278.01328)
			(xy 194.978572 -278.052624) (xy 194.943079 -278.086716) (xy 194.902576 -278.114672) (xy 194.858114 -278.13577)
			(xy 194.810843 -278.149462) (xy 194.761988 -278.155394) (xy 194.712813 -278.153413) (xy 194.664594 -278.143569)
			(xy 194.618578 -278.126117) (xy 194.575957 -278.10151) (xy 194.537836 -278.070385) (xy 194.505201 -278.033548)
			(xy 194.478898 -277.991952) (xy 194.459607 -277.946676) (xy 194.44783 -277.898892) (xy 194.44387 -277.849838)
			(xy 194.105276 -277.849838) (xy 194.104781 -277.874445) (xy 194.096886 -277.923022) (xy 194.081302 -277.969703)
			(xy 194.058431 -278.01328) (xy 194.028866 -278.052624) (xy 193.993373 -278.086716) (xy 193.95287 -278.114672)
			(xy 193.908408 -278.13577) (xy 193.861137 -278.149462) (xy 193.812282 -278.155394) (xy 193.763107 -278.153413)
			(xy 193.714888 -278.143569) (xy 193.668872 -278.126117) (xy 193.626251 -278.10151) (xy 193.58813 -278.070385)
			(xy 193.555495 -278.033548) (xy 193.529192 -277.991952) (xy 193.509901 -277.946676) (xy 193.498124 -277.898892)
			(xy 193.494164 -277.849838) (xy 193.155062 -277.849838) (xy 193.154567 -277.874445) (xy 193.146672 -277.923022)
			(xy 193.131088 -277.969703) (xy 193.108217 -278.01328) (xy 193.078652 -278.052624) (xy 193.043159 -278.086716)
			(xy 193.002656 -278.114672) (xy 192.958194 -278.13577) (xy 192.910923 -278.149462) (xy 192.862068 -278.155394)
			(xy 192.812893 -278.153413) (xy 192.764674 -278.143569) (xy 192.718658 -278.126117) (xy 192.676037 -278.10151)
			(xy 192.637916 -278.070385) (xy 192.605281 -278.033548) (xy 192.578978 -277.991952) (xy 192.559687 -277.946676)
			(xy 192.54791 -277.898892) (xy 192.54395 -277.849838) (xy 192.205356 -277.849838) (xy 192.204861 -277.874445)
			(xy 192.196966 -277.923022) (xy 192.181382 -277.969703) (xy 192.158511 -278.01328) (xy 192.128946 -278.052624)
			(xy 192.093453 -278.086716) (xy 192.05295 -278.114672) (xy 192.008488 -278.13577) (xy 191.961217 -278.149462)
			(xy 191.912362 -278.155394) (xy 191.863187 -278.153413) (xy 191.814968 -278.143569) (xy 191.768952 -278.126117)
			(xy 191.726331 -278.10151) (xy 191.68821 -278.070385) (xy 191.655575 -278.033548) (xy 191.629272 -277.991952)
			(xy 191.609981 -277.946676) (xy 191.598204 -277.898892) (xy 191.594244 -277.849838) (xy 191.255142 -277.849838)
			(xy 191.254647 -277.874445) (xy 191.246752 -277.923022) (xy 191.231168 -277.969703) (xy 191.208297 -278.01328)
			(xy 191.178732 -278.052624) (xy 191.143239 -278.086716) (xy 191.102736 -278.114672) (xy 191.058274 -278.13577)
			(xy 191.011003 -278.149462) (xy 190.962148 -278.155394) (xy 190.912973 -278.153413) (xy 190.864754 -278.143569)
			(xy 190.818738 -278.126117) (xy 190.776117 -278.10151) (xy 190.737996 -278.070385) (xy 190.705361 -278.033548)
			(xy 190.679058 -277.991952) (xy 190.659767 -277.946676) (xy 190.64799 -277.898892) (xy 190.64403 -277.849838)
			(xy 190.305182 -277.849838) (xy 190.304687 -277.874445) (xy 190.296792 -277.923022) (xy 190.281208 -277.969703)
			(xy 190.258337 -278.01328) (xy 190.228772 -278.052624) (xy 190.193279 -278.086716) (xy 190.152776 -278.114672)
			(xy 190.108314 -278.13577) (xy 190.061043 -278.149462) (xy 190.012188 -278.155394) (xy 189.963013 -278.153413)
			(xy 189.914794 -278.143569) (xy 189.868778 -278.126117) (xy 189.826157 -278.10151) (xy 189.788036 -278.070385)
			(xy 189.755401 -278.033548) (xy 189.729098 -277.991952) (xy 189.709807 -277.946676) (xy 189.69803 -277.898892)
			(xy 189.69407 -277.849838) (xy 189.354968 -277.849838) (xy 189.354473 -277.874445) (xy 189.346578 -277.923022)
			(xy 189.330994 -277.969703) (xy 189.308123 -278.01328) (xy 189.278558 -278.052624) (xy 189.243065 -278.086716)
			(xy 189.202562 -278.114672) (xy 189.1581 -278.13577) (xy 189.110829 -278.149462) (xy 189.061974 -278.155394)
			(xy 189.012799 -278.153413) (xy 188.96458 -278.143569) (xy 188.918564 -278.126117) (xy 188.875943 -278.10151)
			(xy 188.837822 -278.070385) (xy 188.805187 -278.033548) (xy 188.778884 -277.991952) (xy 188.759593 -277.946676)
			(xy 188.747816 -277.898892) (xy 188.743856 -277.849838) (xy 188.405262 -277.849838) (xy 188.404767 -277.874445)
			(xy 188.396872 -277.923022) (xy 188.381288 -277.969703) (xy 188.358417 -278.01328) (xy 188.328852 -278.052624)
			(xy 188.293359 -278.086716) (xy 188.252856 -278.114672) (xy 188.208394 -278.13577) (xy 188.161123 -278.149462)
			(xy 188.112268 -278.155394) (xy 188.063093 -278.153413) (xy 188.014874 -278.143569) (xy 187.968858 -278.126117)
			(xy 187.926237 -278.10151) (xy 187.888116 -278.070385) (xy 187.855481 -278.033548) (xy 187.829178 -277.991952)
			(xy 187.809887 -277.946676) (xy 187.79811 -277.898892) (xy 187.79415 -277.849838) (xy 187.455048 -277.849838)
			(xy 187.454553 -277.874445) (xy 187.446658 -277.923022) (xy 187.431074 -277.969703) (xy 187.408203 -278.01328)
			(xy 187.378638 -278.052624) (xy 187.343145 -278.086716) (xy 187.302642 -278.114672) (xy 187.25818 -278.13577)
			(xy 187.210909 -278.149462) (xy 187.162054 -278.155394) (xy 187.112879 -278.153413) (xy 187.06466 -278.143569)
			(xy 187.018644 -278.126117) (xy 186.976023 -278.10151) (xy 186.937902 -278.070385) (xy 186.905267 -278.033548)
			(xy 186.878964 -277.991952) (xy 186.859673 -277.946676) (xy 186.847896 -277.898892) (xy 186.843936 -277.849838)
			(xy 186.505342 -277.849838) (xy 186.504847 -277.874445) (xy 186.496952 -277.923022) (xy 186.481368 -277.969703)
			(xy 186.458497 -278.01328) (xy 186.428932 -278.052624) (xy 186.393439 -278.086716) (xy 186.352936 -278.114672)
			(xy 186.308474 -278.13577) (xy 186.261203 -278.149462) (xy 186.212348 -278.155394) (xy 186.163173 -278.153413)
			(xy 186.114954 -278.143569) (xy 186.068938 -278.126117) (xy 186.026317 -278.10151) (xy 185.988196 -278.070385)
			(xy 185.955561 -278.033548) (xy 185.929258 -277.991952) (xy 185.909967 -277.946676) (xy 185.89819 -277.898892)
			(xy 185.89423 -277.849838) (xy 185.555128 -277.849838) (xy 185.554633 -277.874445) (xy 185.546738 -277.923022)
			(xy 185.531154 -277.969703) (xy 185.508283 -278.01328) (xy 185.478718 -278.052624) (xy 185.443225 -278.086716)
			(xy 185.402722 -278.114672) (xy 185.35826 -278.13577) (xy 185.310989 -278.149462) (xy 185.262134 -278.155394)
			(xy 185.212959 -278.153413) (xy 185.16474 -278.143569) (xy 185.118724 -278.126117) (xy 185.076103 -278.10151)
			(xy 185.037982 -278.070385) (xy 185.005347 -278.033548) (xy 184.979044 -277.991952) (xy 184.959753 -277.946676)
			(xy 184.947976 -277.898892) (xy 184.944016 -277.849838) (xy 184.605168 -277.849838) (xy 184.604673 -277.874445)
			(xy 184.596778 -277.923022) (xy 184.581194 -277.969703) (xy 184.558323 -278.01328) (xy 184.528758 -278.052624)
			(xy 184.493265 -278.086716) (xy 184.452762 -278.114672) (xy 184.4083 -278.13577) (xy 184.361029 -278.149462)
			(xy 184.312174 -278.155394) (xy 184.262999 -278.153413) (xy 184.21478 -278.143569) (xy 184.168764 -278.126117)
			(xy 184.126143 -278.10151) (xy 184.088022 -278.070385) (xy 184.055387 -278.033548) (xy 184.029084 -277.991952)
			(xy 184.009793 -277.946676) (xy 183.998016 -277.898892) (xy 183.994056 -277.849838) (xy 183.654954 -277.849838)
			(xy 183.654459 -277.874445) (xy 183.646564 -277.923022) (xy 183.63098 -277.969703) (xy 183.608109 -278.01328)
			(xy 183.578544 -278.052624) (xy 183.543051 -278.086716) (xy 183.502548 -278.114672) (xy 183.458086 -278.13577)
			(xy 183.410815 -278.149462) (xy 183.36196 -278.155394) (xy 183.312785 -278.153413) (xy 183.264566 -278.143569)
			(xy 183.21855 -278.126117) (xy 183.175929 -278.10151) (xy 183.137808 -278.070385) (xy 183.105173 -278.033548)
			(xy 183.07887 -277.991952) (xy 183.059579 -277.946676) (xy 183.047802 -277.898892) (xy 183.043842 -277.849838)
			(xy 182.705248 -277.849838) (xy 182.704753 -277.874445) (xy 182.696858 -277.923022) (xy 182.681274 -277.969703)
			(xy 182.658403 -278.01328) (xy 182.628838 -278.052624) (xy 182.593345 -278.086716) (xy 182.552842 -278.114672)
			(xy 182.50838 -278.13577) (xy 182.461109 -278.149462) (xy 182.412254 -278.155394) (xy 182.363079 -278.153413)
			(xy 182.31486 -278.143569) (xy 182.268844 -278.126117) (xy 182.226223 -278.10151) (xy 182.188102 -278.070385)
			(xy 182.155467 -278.033548) (xy 182.129164 -277.991952) (xy 182.109873 -277.946676) (xy 182.098096 -277.898892)
			(xy 182.094136 -277.849838) (xy 181.755034 -277.849838) (xy 181.754539 -277.874445) (xy 181.746644 -277.923022)
			(xy 181.73106 -277.969703) (xy 181.708189 -278.01328) (xy 181.678624 -278.052624) (xy 181.643131 -278.086716)
			(xy 181.602628 -278.114672) (xy 181.558166 -278.13577) (xy 181.510895 -278.149462) (xy 181.46204 -278.155394)
			(xy 181.412865 -278.153413) (xy 181.364646 -278.143569) (xy 181.31863 -278.126117) (xy 181.276009 -278.10151)
			(xy 181.237888 -278.070385) (xy 181.205253 -278.033548) (xy 181.17895 -277.991952) (xy 181.159659 -277.946676)
			(xy 181.147882 -277.898892) (xy 181.143922 -277.849838) (xy 180.805328 -277.849838) (xy 180.804833 -277.874445)
			(xy 180.796938 -277.923022) (xy 180.781354 -277.969703) (xy 180.758483 -278.01328) (xy 180.728918 -278.052624)
			(xy 180.693425 -278.086716) (xy 180.652922 -278.114672) (xy 180.60846 -278.13577) (xy 180.561189 -278.149462)
			(xy 180.512334 -278.155394) (xy 180.463159 -278.153413) (xy 180.41494 -278.143569) (xy 180.368924 -278.126117)
			(xy 180.326303 -278.10151) (xy 180.288182 -278.070385) (xy 180.255547 -278.033548) (xy 180.229244 -277.991952)
			(xy 180.209953 -277.946676) (xy 180.198176 -277.898892) (xy 180.194216 -277.849838) (xy 179.855114 -277.849838)
			(xy 179.854619 -277.874445) (xy 179.846724 -277.923022) (xy 179.83114 -277.969703) (xy 179.808269 -278.01328)
			(xy 179.778704 -278.052624) (xy 179.743211 -278.086716) (xy 179.702708 -278.114672) (xy 179.658246 -278.13577)
			(xy 179.610975 -278.149462) (xy 179.56212 -278.155394) (xy 179.512945 -278.153413) (xy 179.464726 -278.143569)
			(xy 179.41871 -278.126117) (xy 179.376089 -278.10151) (xy 179.337968 -278.070385) (xy 179.305333 -278.033548)
			(xy 179.27903 -277.991952) (xy 179.259739 -277.946676) (xy 179.247962 -277.898892) (xy 179.244002 -277.849838)
			(xy 178.905154 -277.849838) (xy 178.904659 -277.874445) (xy 178.896764 -277.923022) (xy 178.88118 -277.969703)
			(xy 178.858309 -278.01328) (xy 178.828744 -278.052624) (xy 178.793251 -278.086716) (xy 178.752748 -278.114672)
			(xy 178.708286 -278.13577) (xy 178.661015 -278.149462) (xy 178.61216 -278.155394) (xy 178.562985 -278.153413)
			(xy 178.514766 -278.143569) (xy 178.46875 -278.126117) (xy 178.426129 -278.10151) (xy 178.388008 -278.070385)
			(xy 178.355373 -278.033548) (xy 178.32907 -277.991952) (xy 178.309779 -277.946676) (xy 178.298002 -277.898892)
			(xy 178.294042 -277.849838) (xy 177.95494 -277.849838) (xy 177.954445 -277.874445) (xy 177.94655 -277.923022)
			(xy 177.930966 -277.969703) (xy 177.908095 -278.01328) (xy 177.87853 -278.052624) (xy 177.843037 -278.086716)
			(xy 177.802534 -278.114672) (xy 177.758072 -278.13577) (xy 177.710801 -278.149462) (xy 177.661946 -278.155394)
			(xy 177.612771 -278.153413) (xy 177.564552 -278.143569) (xy 177.518536 -278.126117) (xy 177.475915 -278.10151)
			(xy 177.437794 -278.070385) (xy 177.405159 -278.033548) (xy 177.378856 -277.991952) (xy 177.359565 -277.946676)
			(xy 177.347788 -277.898892) (xy 177.343828 -277.849838) (xy 177.005234 -277.849838) (xy 177.004739 -277.874445)
			(xy 176.996844 -277.923022) (xy 176.98126 -277.969703) (xy 176.958389 -278.01328) (xy 176.928824 -278.052624)
			(xy 176.893331 -278.086716) (xy 176.852828 -278.114672) (xy 176.808366 -278.13577) (xy 176.761095 -278.149462)
			(xy 176.71224 -278.155394) (xy 176.663065 -278.153413) (xy 176.614846 -278.143569) (xy 176.56883 -278.126117)
			(xy 176.526209 -278.10151) (xy 176.488088 -278.070385) (xy 176.455453 -278.033548) (xy 176.42915 -277.991952)
			(xy 176.409859 -277.946676) (xy 176.398082 -277.898892) (xy 176.394122 -277.849838) (xy 176.05502 -277.849838)
			(xy 176.054525 -277.874445) (xy 176.04663 -277.923022) (xy 176.031046 -277.969703) (xy 176.008175 -278.01328)
			(xy 175.97861 -278.052624) (xy 175.943117 -278.086716) (xy 175.902614 -278.114672) (xy 175.858152 -278.13577)
			(xy 175.810881 -278.149462) (xy 175.762026 -278.155394) (xy 175.712851 -278.153413) (xy 175.664632 -278.143569)
			(xy 175.618616 -278.126117) (xy 175.575995 -278.10151) (xy 175.537874 -278.070385) (xy 175.505239 -278.033548)
			(xy 175.478936 -277.991952) (xy 175.459645 -277.946676) (xy 175.447868 -277.898892) (xy 175.443908 -277.849838)
			(xy 175.10523 -277.849838) (xy 175.102995 -277.891072) (xy 175.092327 -277.939546) (xy 175.073957 -277.985656)
			(xy 175.04837 -278.028186) (xy 175.01624 -278.066017) (xy 174.978412 -278.098151) (xy 174.935884 -278.123743)
			(xy 174.889777 -278.142117) (xy 174.841304 -278.152791) (xy 174.791743 -278.155482) (xy 174.742399 -278.150119)
			(xy 174.694573 -278.136845) (xy 174.649525 -278.116008) (xy 174.608441 -278.088158) (xy 174.572403 -278.054028)
			(xy 174.542362 -278.014518) (xy 174.519108 -277.970668) (xy 174.503255 -277.923634) (xy 174.495219 -277.874655)
			(xy 174.494698 -277.849838) (xy 174.494796 -277.840734) (xy 174.495941 -277.822561) (xy 174.496984 -277.813516)
			(xy 174.498254 -277.801324) (xy 174.49038 -277.778972) (xy 174.413926 -277.706074) (xy 174.39132 -277.699216)
			(xy 174.379382 -277.700994) (xy 174.352344 -277.704931) (xy 174.297708 -277.704931) (xy 174.27067 -277.700994)
			(xy 174.258732 -277.699216) (xy 174.236126 -277.706074) (xy 174.159672 -277.778972) (xy 174.151798 -277.801324)
			(xy 174.153068 -277.813516) (xy 174.154115 -277.82256) (xy 174.155256 -277.840734) (xy 174.155354 -277.849838)
			(xy 174.154881 -277.873829) (xy 174.14737 -277.921218) (xy 174.13254 -277.96685) (xy 174.110755 -278.009601)
			(xy 174.082552 -278.048418) (xy 174.048624 -278.082347) (xy 174.009808 -278.110551) (xy 173.967058 -278.132337)
			(xy 173.921426 -278.147168) (xy 173.874037 -278.15468) (xy 173.850046 -278.155146) (xy 173.817788 -278.153368)
			(xy 173.806866 -278.152352) (xy 173.786546 -278.158956) (xy 173.768145 -278.175466) (xy 215.523824 -278.175466)
			(xy 215.527895 -278.119844) (xy 215.540021 -278.065407) (xy 215.559944 -278.013316) (xy 215.58724 -277.964681)
			(xy 215.621326 -277.920538) (xy 215.661475 -277.881829) (xy 215.706833 -277.849378) (xy 215.756433 -277.823877)
			(xy 215.809217 -277.80587) (xy 215.86406 -277.79574) (xy 215.919794 -277.793703) (xy 215.975231 -277.799803)
			(xy 216.029188 -277.813909) (xy 216.080517 -277.835721) (xy 216.128123 -277.864775) (xy 216.170991 -277.90045)
			(xy 216.208208 -277.941987) (xy 216.238981 -277.9885) (xy 216.262653 -278.038997) (xy 216.278721 -278.092404)
			(xy 216.286841 -278.14758) (xy 216.28735 -278.175466) (xy 216.286841 -278.203352) (xy 216.282422 -278.233378)
			(xy 225.945952 -278.233378) (xy 225.950023 -278.177756) (xy 225.962149 -278.123319) (xy 225.982072 -278.071228)
			(xy 226.009368 -278.022593) (xy 226.043454 -277.97845) (xy 226.083603 -277.939741) (xy 226.128961 -277.90729)
			(xy 226.178561 -277.881789) (xy 226.231345 -277.863782) (xy 226.286188 -277.853652) (xy 226.341922 -277.851615)
			(xy 226.397359 -277.857715) (xy 226.451316 -277.871821) (xy 226.502645 -277.893633) (xy 226.550251 -277.922687)
			(xy 226.593119 -277.958362) (xy 226.630336 -277.999899) (xy 226.661109 -278.046412) (xy 226.684781 -278.096909)
			(xy 226.700849 -278.150316) (xy 226.708969 -278.205492) (xy 226.709478 -278.233378) (xy 226.708969 -278.261264)
			(xy 226.700849 -278.31644) (xy 226.684781 -278.369847) (xy 226.680051 -278.379936) (xy 227.470206 -278.379936)
			(xy 227.474277 -278.324314) (xy 227.486403 -278.269877) (xy 227.506326 -278.217786) (xy 227.533622 -278.169151)
			(xy 227.567708 -278.125008) (xy 227.607857 -278.086299) (xy 227.653215 -278.053848) (xy 227.702815 -278.028347)
			(xy 227.755599 -278.01034) (xy 227.810442 -278.00021) (xy 227.866176 -277.998173) (xy 227.921613 -278.004273)
			(xy 227.97557 -278.018379) (xy 228.026899 -278.040191) (xy 228.074505 -278.069245) (xy 228.117373 -278.10492)
			(xy 228.15459 -278.146457) (xy 228.185363 -278.19297) (xy 228.209035 -278.243467) (xy 228.225103 -278.296874)
			(xy 228.233223 -278.35205) (xy 228.233528 -278.36876) (xy 228.648258 -278.36876) (xy 228.652329 -278.313138)
			(xy 228.664455 -278.258701) (xy 228.684378 -278.20661) (xy 228.711674 -278.157975) (xy 228.74576 -278.113832)
			(xy 228.785909 -278.075123) (xy 228.831267 -278.042672) (xy 228.880867 -278.017171) (xy 228.933651 -277.999164)
			(xy 228.988494 -277.989034) (xy 229.044228 -277.986997) (xy 229.099665 -277.993097) (xy 229.153622 -278.007203)
			(xy 229.204951 -278.029015) (xy 229.252557 -278.058069) (xy 229.295425 -278.093744) (xy 229.332642 -278.135281)
			(xy 229.363415 -278.181794) (xy 229.387087 -278.232291) (xy 229.403155 -278.285698) (xy 229.411275 -278.340874)
			(xy 229.411784 -278.36876) (xy 229.411275 -278.396646) (xy 229.403155 -278.451822) (xy 229.387087 -278.505229)
			(xy 229.36545 -278.551386) (xy 230.453438 -278.551386) (xy 230.454004 -278.522471) (xy 230.462721 -278.465301)
			(xy 230.479969 -278.410103) (xy 230.505351 -278.35814) (xy 230.538287 -278.310605) (xy 230.578022 -278.268587)
			(xy 230.600504 -278.250396) (xy 230.609264 -278.242832) (xy 230.619448 -278.222075) (xy 230.620062 -278.210518)
			(xy 230.620062 -278.130254) (xy 230.619474 -278.118688) (xy 230.609293 -278.097916) (xy 230.600504 -278.090376)
			(xy 230.57801 -278.072198) (xy 230.538275 -278.030175) (xy 230.505337 -277.982638) (xy 230.479951 -277.930674)
			(xy 230.462697 -277.875474) (xy 230.453971 -277.818303) (xy 230.453438 -277.789386) (xy 230.453924 -277.762135)
			(xy 230.46168 -277.708187) (xy 230.477035 -277.655892) (xy 230.499677 -277.606315) (xy 230.529143 -277.560465)
			(xy 230.564834 -277.519274) (xy 230.606025 -277.483583) (xy 230.651875 -277.454117) (xy 230.701452 -277.431475)
			(xy 230.753747 -277.41612) (xy 230.807695 -277.408364) (xy 230.862197 -277.408364) (xy 230.916145 -277.41612)
			(xy 230.96844 -277.431475) (xy 231.018017 -277.454117) (xy 231.063867 -277.483583) (xy 231.105058 -277.519274)
			(xy 231.140749 -277.560465) (xy 231.170215 -277.606315) (xy 231.192857 -277.655892) (xy 231.208212 -277.708187)
			(xy 231.215968 -277.762135) (xy 231.216454 -277.789386) (xy 231.215943 -277.818303) (xy 231.207215 -277.875476)
			(xy 231.189957 -277.930675) (xy 231.164564 -277.982638) (xy 231.131618 -278.030171) (xy 231.091875 -278.072187)
			(xy 231.069388 -278.090376) (xy 231.060639 -278.097951) (xy 231.050449 -278.1187) (xy 231.04983 -278.130254)
			(xy 231.04983 -278.210518) (xy 231.05038 -278.222089) (xy 231.060588 -278.24286) (xy 231.069388 -278.250396)
			(xy 231.091867 -278.268592) (xy 231.131603 -278.310611) (xy 231.164543 -278.358144) (xy 231.189932 -278.410105)
			(xy 231.207189 -278.465301) (xy 231.215919 -278.52247) (xy 231.216454 -278.551386) (xy 231.215968 -278.578637)
			(xy 231.208212 -278.632585) (xy 231.192857 -278.68488) (xy 231.170215 -278.734457) (xy 231.140749 -278.780307)
			(xy 231.105058 -278.821498) (xy 231.063867 -278.857189) (xy 231.018017 -278.886655) (xy 230.96844 -278.909297)
			(xy 230.916145 -278.924652) (xy 230.862197 -278.932408) (xy 230.807695 -278.932408) (xy 230.753747 -278.924652)
			(xy 230.701452 -278.909297) (xy 230.651875 -278.886655) (xy 230.606025 -278.857189) (xy 230.564834 -278.821498)
			(xy 230.529143 -278.780307) (xy 230.499677 -278.734457) (xy 230.477035 -278.68488) (xy 230.46168 -278.632585)
			(xy 230.453924 -278.578637) (xy 230.453438 -278.551386) (xy 229.36545 -278.551386) (xy 229.363415 -278.555726)
			(xy 229.332642 -278.602239) (xy 229.295425 -278.643776) (xy 229.252557 -278.679451) (xy 229.204951 -278.708505)
			(xy 229.153622 -278.730317) (xy 229.099665 -278.744423) (xy 229.044228 -278.750523) (xy 228.988494 -278.748486)
			(xy 228.933651 -278.738356) (xy 228.880867 -278.720349) (xy 228.831267 -278.694848) (xy 228.785909 -278.662397)
			(xy 228.74576 -278.623688) (xy 228.711674 -278.579545) (xy 228.684378 -278.53091) (xy 228.664455 -278.478819)
			(xy 228.652329 -278.424382) (xy 228.648258 -278.36876) (xy 228.233528 -278.36876) (xy 228.233732 -278.379936)
			(xy 228.233223 -278.407822) (xy 228.225103 -278.462998) (xy 228.209035 -278.516405) (xy 228.185363 -278.566902)
			(xy 228.15459 -278.613415) (xy 228.117373 -278.654952) (xy 228.074505 -278.690627) (xy 228.026899 -278.719681)
			(xy 227.97557 -278.741493) (xy 227.921613 -278.755599) (xy 227.866176 -278.761699) (xy 227.810442 -278.759662)
			(xy 227.755599 -278.749532) (xy 227.702815 -278.731525) (xy 227.653215 -278.706024) (xy 227.607857 -278.673573)
			(xy 227.567708 -278.634864) (xy 227.533622 -278.590721) (xy 227.506326 -278.542086) (xy 227.486403 -278.489995)
			(xy 227.474277 -278.435558) (xy 227.470206 -278.379936) (xy 226.680051 -278.379936) (xy 226.661109 -278.420344)
			(xy 226.630336 -278.466857) (xy 226.593119 -278.508394) (xy 226.550251 -278.544069) (xy 226.502645 -278.573123)
			(xy 226.451316 -278.594935) (xy 226.397359 -278.609041) (xy 226.341922 -278.615141) (xy 226.286188 -278.613104)
			(xy 226.231345 -278.602974) (xy 226.178561 -278.584967) (xy 226.128961 -278.559466) (xy 226.083603 -278.527015)
			(xy 226.043454 -278.488306) (xy 226.009368 -278.444163) (xy 225.982072 -278.395528) (xy 225.962149 -278.343437)
			(xy 225.950023 -278.289) (xy 225.945952 -278.233378) (xy 216.282422 -278.233378) (xy 216.278721 -278.258528)
			(xy 216.262653 -278.311935) (xy 216.238981 -278.362432) (xy 216.208208 -278.408945) (xy 216.170991 -278.450482)
			(xy 216.128123 -278.486157) (xy 216.080517 -278.515211) (xy 216.029188 -278.537023) (xy 215.975231 -278.551129)
			(xy 215.919794 -278.557229) (xy 215.86406 -278.555192) (xy 215.809217 -278.545062) (xy 215.756433 -278.527055)
			(xy 215.706833 -278.501554) (xy 215.661475 -278.469103) (xy 215.621326 -278.430394) (xy 215.58724 -278.386251)
			(xy 215.559944 -278.337616) (xy 215.540021 -278.285525) (xy 215.527895 -278.231088) (xy 215.523824 -278.175466)
			(xy 173.768145 -278.175466) (xy 173.722284 -278.216614) (xy 173.714621 -278.224129) (xy 173.705935 -278.243735)
			(xy 173.70552 -278.25446) (xy 173.70552 -278.31415) (xy 173.705774 -278.324818) (xy 173.705614 -278.338472)
			(xy 173.703329 -278.365685) (xy 173.701202 -278.379174) (xy 173.69917 -278.391112) (xy 173.706282 -278.413718)
			(xy 173.77918 -278.490172) (xy 173.801532 -278.498046) (xy 173.813724 -278.496776) (xy 173.822768 -278.495729)
			(xy 173.840942 -278.494588) (xy 173.850046 -278.49449) (xy 173.874866 -278.49498) (xy 173.923852 -278.503018)
			(xy 173.970891 -278.518875) (xy 174.014746 -278.542133) (xy 174.054261 -278.572179) (xy 174.088394 -278.608222)
			(xy 174.116247 -278.649312) (xy 174.137085 -278.694367) (xy 174.15036 -278.7422) (xy 174.155722 -278.79155)
			(xy 174.155274 -278.799798) (xy 174.494202 -278.799798) (xy 174.498162 -278.750744) (xy 174.509939 -278.70296)
			(xy 174.52923 -278.657684) (xy 174.555533 -278.616088) (xy 174.588168 -278.579251) (xy 174.626289 -278.548126)
			(xy 174.66891 -278.523519) (xy 174.714926 -278.506067) (xy 174.763145 -278.496223) (xy 174.81232 -278.494242)
			(xy 174.861175 -278.500174) (xy 174.908446 -278.513866) (xy 174.952908 -278.534964) (xy 174.993411 -278.56292)
			(xy 175.028904 -278.597012) (xy 175.058469 -278.636356) (xy 175.08134 -278.679933) (xy 175.096924 -278.726614)
			(xy 175.104819 -278.775191) (xy 175.105314 -278.799798) (xy 175.443908 -278.799798) (xy 175.447868 -278.750744)
			(xy 175.459645 -278.70296) (xy 175.478936 -278.657684) (xy 175.505239 -278.616088) (xy 175.537874 -278.579251)
			(xy 175.575995 -278.548126) (xy 175.618616 -278.523519) (xy 175.664632 -278.506067) (xy 175.712851 -278.496223)
			(xy 175.762026 -278.494242) (xy 175.810881 -278.500174) (xy 175.858152 -278.513866) (xy 175.902614 -278.534964)
			(xy 175.943117 -278.56292) (xy 175.97861 -278.597012) (xy 176.008175 -278.636356) (xy 176.031046 -278.679933)
			(xy 176.04663 -278.726614) (xy 176.054525 -278.775191) (xy 176.05502 -278.799798) (xy 176.394122 -278.799798)
			(xy 176.398082 -278.750744) (xy 176.409859 -278.70296) (xy 176.42915 -278.657684) (xy 176.455453 -278.616088)
			(xy 176.488088 -278.579251) (xy 176.526209 -278.548126) (xy 176.56883 -278.523519) (xy 176.614846 -278.506067)
			(xy 176.663065 -278.496223) (xy 176.71224 -278.494242) (xy 176.761095 -278.500174) (xy 176.808366 -278.513866)
			(xy 176.852828 -278.534964) (xy 176.893331 -278.56292) (xy 176.928824 -278.597012) (xy 176.958389 -278.636356)
			(xy 176.98126 -278.679933) (xy 176.996844 -278.726614) (xy 177.004739 -278.775191) (xy 177.005234 -278.799798)
			(xy 177.343828 -278.799798) (xy 177.347788 -278.750744) (xy 177.359565 -278.70296) (xy 177.378856 -278.657684)
			(xy 177.405159 -278.616088) (xy 177.437794 -278.579251) (xy 177.475915 -278.548126) (xy 177.518536 -278.523519)
			(xy 177.564552 -278.506067) (xy 177.612771 -278.496223) (xy 177.661946 -278.494242) (xy 177.710801 -278.500174)
			(xy 177.758072 -278.513866) (xy 177.802534 -278.534964) (xy 177.843037 -278.56292) (xy 177.87853 -278.597012)
			(xy 177.908095 -278.636356) (xy 177.930966 -278.679933) (xy 177.94655 -278.726614) (xy 177.954445 -278.775191)
			(xy 177.95494 -278.799798) (xy 178.294042 -278.799798) (xy 178.298002 -278.750744) (xy 178.309779 -278.70296)
			(xy 178.32907 -278.657684) (xy 178.355373 -278.616088) (xy 178.388008 -278.579251) (xy 178.426129 -278.548126)
			(xy 178.46875 -278.523519) (xy 178.514766 -278.506067) (xy 178.562985 -278.496223) (xy 178.61216 -278.494242)
			(xy 178.661015 -278.500174) (xy 178.708286 -278.513866) (xy 178.752748 -278.534964) (xy 178.793251 -278.56292)
			(xy 178.828744 -278.597012) (xy 178.858309 -278.636356) (xy 178.88118 -278.679933) (xy 178.896764 -278.726614)
			(xy 178.904659 -278.775191) (xy 178.905154 -278.799798) (xy 179.244002 -278.799798) (xy 179.247962 -278.750744)
			(xy 179.259739 -278.70296) (xy 179.27903 -278.657684) (xy 179.305333 -278.616088) (xy 179.337968 -278.579251)
			(xy 179.376089 -278.548126) (xy 179.41871 -278.523519) (xy 179.464726 -278.506067) (xy 179.512945 -278.496223)
			(xy 179.56212 -278.494242) (xy 179.610975 -278.500174) (xy 179.658246 -278.513866) (xy 179.702708 -278.534964)
			(xy 179.743211 -278.56292) (xy 179.778704 -278.597012) (xy 179.808269 -278.636356) (xy 179.83114 -278.679933)
			(xy 179.846724 -278.726614) (xy 179.854619 -278.775191) (xy 179.855114 -278.799798) (xy 180.194216 -278.799798)
			(xy 180.198176 -278.750744) (xy 180.209953 -278.70296) (xy 180.229244 -278.657684) (xy 180.255547 -278.616088)
			(xy 180.288182 -278.579251) (xy 180.326303 -278.548126) (xy 180.368924 -278.523519) (xy 180.41494 -278.506067)
			(xy 180.463159 -278.496223) (xy 180.512334 -278.494242) (xy 180.561189 -278.500174) (xy 180.60846 -278.513866)
			(xy 180.652922 -278.534964) (xy 180.693425 -278.56292) (xy 180.728918 -278.597012) (xy 180.758483 -278.636356)
			(xy 180.781354 -278.679933) (xy 180.796938 -278.726614) (xy 180.804833 -278.775191) (xy 180.805328 -278.799798)
			(xy 181.143922 -278.799798) (xy 181.147882 -278.750744) (xy 181.159659 -278.70296) (xy 181.17895 -278.657684)
			(xy 181.205253 -278.616088) (xy 181.237888 -278.579251) (xy 181.276009 -278.548126) (xy 181.31863 -278.523519)
			(xy 181.364646 -278.506067) (xy 181.412865 -278.496223) (xy 181.46204 -278.494242) (xy 181.510895 -278.500174)
			(xy 181.558166 -278.513866) (xy 181.602628 -278.534964) (xy 181.643131 -278.56292) (xy 181.678624 -278.597012)
			(xy 181.708189 -278.636356) (xy 181.73106 -278.679933) (xy 181.746644 -278.726614) (xy 181.754539 -278.775191)
			(xy 181.755034 -278.799798) (xy 182.094136 -278.799798) (xy 182.098096 -278.750744) (xy 182.109873 -278.70296)
			(xy 182.129164 -278.657684) (xy 182.155467 -278.616088) (xy 182.188102 -278.579251) (xy 182.226223 -278.548126)
			(xy 182.268844 -278.523519) (xy 182.31486 -278.506067) (xy 182.363079 -278.496223) (xy 182.412254 -278.494242)
			(xy 182.461109 -278.500174) (xy 182.50838 -278.513866) (xy 182.552842 -278.534964) (xy 182.593345 -278.56292)
			(xy 182.628838 -278.597012) (xy 182.658403 -278.636356) (xy 182.681274 -278.679933) (xy 182.696858 -278.726614)
			(xy 182.704753 -278.775191) (xy 182.705248 -278.799798) (xy 183.043842 -278.799798) (xy 183.047802 -278.750744)
			(xy 183.059579 -278.70296) (xy 183.07887 -278.657684) (xy 183.105173 -278.616088) (xy 183.137808 -278.579251)
			(xy 183.175929 -278.548126) (xy 183.21855 -278.523519) (xy 183.264566 -278.506067) (xy 183.312785 -278.496223)
			(xy 183.36196 -278.494242) (xy 183.410815 -278.500174) (xy 183.458086 -278.513866) (xy 183.502548 -278.534964)
			(xy 183.543051 -278.56292) (xy 183.578544 -278.597012) (xy 183.608109 -278.636356) (xy 183.63098 -278.679933)
			(xy 183.646564 -278.726614) (xy 183.654459 -278.775191) (xy 183.654954 -278.799798) (xy 183.994056 -278.799798)
			(xy 183.998016 -278.750744) (xy 184.009793 -278.70296) (xy 184.029084 -278.657684) (xy 184.055387 -278.616088)
			(xy 184.088022 -278.579251) (xy 184.126143 -278.548126) (xy 184.168764 -278.523519) (xy 184.21478 -278.506067)
			(xy 184.262999 -278.496223) (xy 184.312174 -278.494242) (xy 184.361029 -278.500174) (xy 184.4083 -278.513866)
			(xy 184.452762 -278.534964) (xy 184.493265 -278.56292) (xy 184.528758 -278.597012) (xy 184.558323 -278.636356)
			(xy 184.581194 -278.679933) (xy 184.596778 -278.726614) (xy 184.604673 -278.775191) (xy 184.605168 -278.799798)
			(xy 184.944016 -278.799798) (xy 184.947976 -278.750744) (xy 184.959753 -278.70296) (xy 184.979044 -278.657684)
			(xy 185.005347 -278.616088) (xy 185.037982 -278.579251) (xy 185.076103 -278.548126) (xy 185.118724 -278.523519)
			(xy 185.16474 -278.506067) (xy 185.212959 -278.496223) (xy 185.262134 -278.494242) (xy 185.310989 -278.500174)
			(xy 185.35826 -278.513866) (xy 185.402722 -278.534964) (xy 185.443225 -278.56292) (xy 185.478718 -278.597012)
			(xy 185.508283 -278.636356) (xy 185.531154 -278.679933) (xy 185.546738 -278.726614) (xy 185.554633 -278.775191)
			(xy 185.555128 -278.799798) (xy 185.89423 -278.799798) (xy 185.89819 -278.750744) (xy 185.909967 -278.70296)
			(xy 185.929258 -278.657684) (xy 185.955561 -278.616088) (xy 185.988196 -278.579251) (xy 186.026317 -278.548126)
			(xy 186.068938 -278.523519) (xy 186.114954 -278.506067) (xy 186.163173 -278.496223) (xy 186.212348 -278.494242)
			(xy 186.261203 -278.500174) (xy 186.308474 -278.513866) (xy 186.352936 -278.534964) (xy 186.393439 -278.56292)
			(xy 186.428932 -278.597012) (xy 186.458497 -278.636356) (xy 186.481368 -278.679933) (xy 186.496952 -278.726614)
			(xy 186.504847 -278.775191) (xy 186.505342 -278.799798) (xy 186.843936 -278.799798) (xy 186.847896 -278.750744)
			(xy 186.859673 -278.70296) (xy 186.878964 -278.657684) (xy 186.905267 -278.616088) (xy 186.937902 -278.579251)
			(xy 186.976023 -278.548126) (xy 187.018644 -278.523519) (xy 187.06466 -278.506067) (xy 187.112879 -278.496223)
			(xy 187.162054 -278.494242) (xy 187.210909 -278.500174) (xy 187.25818 -278.513866) (xy 187.302642 -278.534964)
			(xy 187.343145 -278.56292) (xy 187.378638 -278.597012) (xy 187.408203 -278.636356) (xy 187.431074 -278.679933)
			(xy 187.446658 -278.726614) (xy 187.454553 -278.775191) (xy 187.455048 -278.799798) (xy 187.79415 -278.799798)
			(xy 187.79811 -278.750744) (xy 187.809887 -278.70296) (xy 187.829178 -278.657684) (xy 187.855481 -278.616088)
			(xy 187.888116 -278.579251) (xy 187.926237 -278.548126) (xy 187.968858 -278.523519) (xy 188.014874 -278.506067)
			(xy 188.063093 -278.496223) (xy 188.112268 -278.494242) (xy 188.161123 -278.500174) (xy 188.208394 -278.513866)
			(xy 188.252856 -278.534964) (xy 188.293359 -278.56292) (xy 188.328852 -278.597012) (xy 188.358417 -278.636356)
			(xy 188.381288 -278.679933) (xy 188.396872 -278.726614) (xy 188.404767 -278.775191) (xy 188.405262 -278.799798)
			(xy 188.743856 -278.799798) (xy 188.747816 -278.750744) (xy 188.759593 -278.70296) (xy 188.778884 -278.657684)
			(xy 188.805187 -278.616088) (xy 188.837822 -278.579251) (xy 188.875943 -278.548126) (xy 188.918564 -278.523519)
			(xy 188.96458 -278.506067) (xy 189.012799 -278.496223) (xy 189.061974 -278.494242) (xy 189.110829 -278.500174)
			(xy 189.1581 -278.513866) (xy 189.202562 -278.534964) (xy 189.243065 -278.56292) (xy 189.278558 -278.597012)
			(xy 189.308123 -278.636356) (xy 189.330994 -278.679933) (xy 189.346578 -278.726614) (xy 189.354473 -278.775191)
			(xy 189.354968 -278.799798) (xy 189.69407 -278.799798) (xy 189.69803 -278.750744) (xy 189.709807 -278.70296)
			(xy 189.729098 -278.657684) (xy 189.755401 -278.616088) (xy 189.788036 -278.579251) (xy 189.826157 -278.548126)
			(xy 189.868778 -278.523519) (xy 189.914794 -278.506067) (xy 189.963013 -278.496223) (xy 190.012188 -278.494242)
			(xy 190.061043 -278.500174) (xy 190.108314 -278.513866) (xy 190.152776 -278.534964) (xy 190.193279 -278.56292)
			(xy 190.228772 -278.597012) (xy 190.258337 -278.636356) (xy 190.281208 -278.679933) (xy 190.296792 -278.726614)
			(xy 190.304687 -278.775191) (xy 190.305182 -278.799798) (xy 190.64403 -278.799798) (xy 190.64799 -278.750744)
			(xy 190.659767 -278.70296) (xy 190.679058 -278.657684) (xy 190.705361 -278.616088) (xy 190.737996 -278.579251)
			(xy 190.776117 -278.548126) (xy 190.818738 -278.523519) (xy 190.864754 -278.506067) (xy 190.912973 -278.496223)
			(xy 190.962148 -278.494242) (xy 191.011003 -278.500174) (xy 191.058274 -278.513866) (xy 191.102736 -278.534964)
			(xy 191.143239 -278.56292) (xy 191.178732 -278.597012) (xy 191.208297 -278.636356) (xy 191.231168 -278.679933)
			(xy 191.246752 -278.726614) (xy 191.254647 -278.775191) (xy 191.255142 -278.799798) (xy 191.594244 -278.799798)
			(xy 191.598204 -278.750744) (xy 191.609981 -278.70296) (xy 191.629272 -278.657684) (xy 191.655575 -278.616088)
			(xy 191.68821 -278.579251) (xy 191.726331 -278.548126) (xy 191.768952 -278.523519) (xy 191.814968 -278.506067)
			(xy 191.863187 -278.496223) (xy 191.912362 -278.494242) (xy 191.961217 -278.500174) (xy 192.008488 -278.513866)
			(xy 192.05295 -278.534964) (xy 192.093453 -278.56292) (xy 192.128946 -278.597012) (xy 192.158511 -278.636356)
			(xy 192.181382 -278.679933) (xy 192.196966 -278.726614) (xy 192.204861 -278.775191) (xy 192.205356 -278.799798)
			(xy 192.54395 -278.799798) (xy 192.54791 -278.750744) (xy 192.559687 -278.70296) (xy 192.578978 -278.657684)
			(xy 192.605281 -278.616088) (xy 192.637916 -278.579251) (xy 192.676037 -278.548126) (xy 192.718658 -278.523519)
			(xy 192.764674 -278.506067) (xy 192.812893 -278.496223) (xy 192.862068 -278.494242) (xy 192.910923 -278.500174)
			(xy 192.958194 -278.513866) (xy 193.002656 -278.534964) (xy 193.043159 -278.56292) (xy 193.078652 -278.597012)
			(xy 193.108217 -278.636356) (xy 193.131088 -278.679933) (xy 193.146672 -278.726614) (xy 193.154567 -278.775191)
			(xy 193.155062 -278.799798) (xy 193.494164 -278.799798) (xy 193.498124 -278.750744) (xy 193.509901 -278.70296)
			(xy 193.529192 -278.657684) (xy 193.555495 -278.616088) (xy 193.58813 -278.579251) (xy 193.626251 -278.548126)
			(xy 193.668872 -278.523519) (xy 193.714888 -278.506067) (xy 193.763107 -278.496223) (xy 193.812282 -278.494242)
			(xy 193.861137 -278.500174) (xy 193.908408 -278.513866) (xy 193.95287 -278.534964) (xy 193.993373 -278.56292)
			(xy 194.028866 -278.597012) (xy 194.058431 -278.636356) (xy 194.081302 -278.679933) (xy 194.096886 -278.726614)
			(xy 194.104781 -278.775191) (xy 194.105276 -278.799798) (xy 194.44387 -278.799798) (xy 194.44783 -278.750744)
			(xy 194.459607 -278.70296) (xy 194.478898 -278.657684) (xy 194.505201 -278.616088) (xy 194.537836 -278.579251)
			(xy 194.575957 -278.548126) (xy 194.618578 -278.523519) (xy 194.664594 -278.506067) (xy 194.712813 -278.496223)
			(xy 194.761988 -278.494242) (xy 194.810843 -278.500174) (xy 194.858114 -278.513866) (xy 194.902576 -278.534964)
			(xy 194.943079 -278.56292) (xy 194.978572 -278.597012) (xy 195.008137 -278.636356) (xy 195.031008 -278.679933)
			(xy 195.046592 -278.726614) (xy 195.054487 -278.775191) (xy 195.054982 -278.799798) (xy 195.394084 -278.799798)
			(xy 195.398044 -278.750744) (xy 195.409821 -278.70296) (xy 195.429112 -278.657684) (xy 195.455415 -278.616088)
			(xy 195.48805 -278.579251) (xy 195.526171 -278.548126) (xy 195.568792 -278.523519) (xy 195.614808 -278.506067)
			(xy 195.663027 -278.496223) (xy 195.712202 -278.494242) (xy 195.761057 -278.500174) (xy 195.808328 -278.513866)
			(xy 195.85279 -278.534964) (xy 195.893293 -278.56292) (xy 195.928786 -278.597012) (xy 195.958351 -278.636356)
			(xy 195.981222 -278.679933) (xy 195.996806 -278.726614) (xy 196.004701 -278.775191) (xy 196.005196 -278.799798)
			(xy 196.344044 -278.799798) (xy 196.348004 -278.750744) (xy 196.359781 -278.70296) (xy 196.379072 -278.657684)
			(xy 196.405375 -278.616088) (xy 196.43801 -278.579251) (xy 196.476131 -278.548126) (xy 196.518752 -278.523519)
			(xy 196.564768 -278.506067) (xy 196.612987 -278.496223) (xy 196.662162 -278.494242) (xy 196.711017 -278.500174)
			(xy 196.758288 -278.513866) (xy 196.80275 -278.534964) (xy 196.843253 -278.56292) (xy 196.878746 -278.597012)
			(xy 196.908311 -278.636356) (xy 196.931182 -278.679933) (xy 196.946766 -278.726614) (xy 196.954661 -278.775191)
			(xy 196.955156 -278.799798) (xy 197.294258 -278.799798) (xy 197.298218 -278.750744) (xy 197.309995 -278.70296)
			(xy 197.329286 -278.657684) (xy 197.355589 -278.616088) (xy 197.388224 -278.579251) (xy 197.426345 -278.548126)
			(xy 197.468966 -278.523519) (xy 197.514982 -278.506067) (xy 197.563201 -278.496223) (xy 197.612376 -278.494242)
			(xy 197.661231 -278.500174) (xy 197.708502 -278.513866) (xy 197.752964 -278.534964) (xy 197.793467 -278.56292)
			(xy 197.82896 -278.597012) (xy 197.858525 -278.636356) (xy 197.881396 -278.679933) (xy 197.89698 -278.726614)
			(xy 197.904875 -278.775191) (xy 197.90537 -278.799798) (xy 198.244218 -278.799798) (xy 198.248178 -278.750744)
			(xy 198.259955 -278.70296) (xy 198.279246 -278.657684) (xy 198.305549 -278.616088) (xy 198.338184 -278.579251)
			(xy 198.376305 -278.548126) (xy 198.418926 -278.523519) (xy 198.464942 -278.506067) (xy 198.513161 -278.496223)
			(xy 198.562336 -278.494242) (xy 198.611191 -278.500174) (xy 198.658462 -278.513866) (xy 198.702924 -278.534964)
			(xy 198.743427 -278.56292) (xy 198.77892 -278.597012) (xy 198.808485 -278.636356) (xy 198.831356 -278.679933)
			(xy 198.84694 -278.726614) (xy 198.854835 -278.775191) (xy 198.85533 -278.799798) (xy 198.854835 -278.824405)
			(xy 198.84694 -278.872982) (xy 198.831356 -278.919663) (xy 198.808485 -278.96324) (xy 198.77892 -279.002584)
			(xy 198.743427 -279.036676) (xy 198.702924 -279.064632) (xy 198.679186 -279.075896) (xy 224.380042 -279.075896)
			(xy 224.384113 -279.020274) (xy 224.396239 -278.965837) (xy 224.416162 -278.913746) (xy 224.443458 -278.865111)
			(xy 224.477544 -278.820968) (xy 224.517693 -278.782259) (xy 224.563051 -278.749808) (xy 224.612651 -278.724307)
			(xy 224.665435 -278.7063) (xy 224.720278 -278.69617) (xy 224.776012 -278.694133) (xy 224.831449 -278.700233)
			(xy 224.885406 -278.714339) (xy 224.936735 -278.736151) (xy 224.984341 -278.765205) (xy 225.027209 -278.80088)
			(xy 225.064426 -278.842417) (xy 225.095199 -278.88893) (xy 225.118871 -278.939427) (xy 225.134939 -278.992834)
			(xy 225.143059 -279.04801) (xy 225.143568 -279.075896) (xy 225.143059 -279.103782) (xy 225.134939 -279.158958)
			(xy 225.118871 -279.212365) (xy 225.095199 -279.262862) (xy 225.064426 -279.309375) (xy 225.027209 -279.350912)
			(xy 224.984341 -279.386587) (xy 224.936735 -279.415641) (xy 224.885406 -279.437453) (xy 224.831449 -279.451559)
			(xy 224.776012 -279.457659) (xy 224.720278 -279.455622) (xy 224.665435 -279.445492) (xy 224.612651 -279.427485)
			(xy 224.563051 -279.401984) (xy 224.517693 -279.369533) (xy 224.477544 -279.330824) (xy 224.443458 -279.286681)
			(xy 224.416162 -279.238046) (xy 224.396239 -279.185955) (xy 224.384113 -279.131518) (xy 224.380042 -279.075896)
			(xy 198.679186 -279.075896) (xy 198.658462 -279.08573) (xy 198.611191 -279.099422) (xy 198.562336 -279.105354)
			(xy 198.513161 -279.103373) (xy 198.464942 -279.093529) (xy 198.418926 -279.076077) (xy 198.376305 -279.05147)
			(xy 198.338184 -279.020345) (xy 198.305549 -278.983508) (xy 198.279246 -278.941912) (xy 198.259955 -278.896636)
			(xy 198.248178 -278.848852) (xy 198.244218 -278.799798) (xy 197.90537 -278.799798) (xy 197.904875 -278.824405)
			(xy 197.89698 -278.872982) (xy 197.881396 -278.919663) (xy 197.858525 -278.96324) (xy 197.82896 -279.002584)
			(xy 197.793467 -279.036676) (xy 197.752964 -279.064632) (xy 197.708502 -279.08573) (xy 197.661231 -279.099422)
			(xy 197.612376 -279.105354) (xy 197.563201 -279.103373) (xy 197.514982 -279.093529) (xy 197.468966 -279.076077)
			(xy 197.426345 -279.05147) (xy 197.388224 -279.020345) (xy 197.355589 -278.983508) (xy 197.329286 -278.941912)
			(xy 197.309995 -278.896636) (xy 197.298218 -278.848852) (xy 197.294258 -278.799798) (xy 196.955156 -278.799798)
			(xy 196.954661 -278.824405) (xy 196.946766 -278.872982) (xy 196.931182 -278.919663) (xy 196.908311 -278.96324)
			(xy 196.878746 -279.002584) (xy 196.843253 -279.036676) (xy 196.80275 -279.064632) (xy 196.758288 -279.08573)
			(xy 196.711017 -279.099422) (xy 196.662162 -279.105354) (xy 196.612987 -279.103373) (xy 196.564768 -279.093529)
			(xy 196.518752 -279.076077) (xy 196.476131 -279.05147) (xy 196.43801 -279.020345) (xy 196.405375 -278.983508)
			(xy 196.379072 -278.941912) (xy 196.359781 -278.896636) (xy 196.348004 -278.848852) (xy 196.344044 -278.799798)
			(xy 196.005196 -278.799798) (xy 196.004701 -278.824405) (xy 195.996806 -278.872982) (xy 195.981222 -278.919663)
			(xy 195.958351 -278.96324) (xy 195.928786 -279.002584) (xy 195.893293 -279.036676) (xy 195.85279 -279.064632)
			(xy 195.808328 -279.08573) (xy 195.761057 -279.099422) (xy 195.712202 -279.105354) (xy 195.663027 -279.103373)
			(xy 195.614808 -279.093529) (xy 195.568792 -279.076077) (xy 195.526171 -279.05147) (xy 195.48805 -279.020345)
			(xy 195.455415 -278.983508) (xy 195.429112 -278.941912) (xy 195.409821 -278.896636) (xy 195.398044 -278.848852)
			(xy 195.394084 -278.799798) (xy 195.054982 -278.799798) (xy 195.054487 -278.824405) (xy 195.046592 -278.872982)
			(xy 195.031008 -278.919663) (xy 195.008137 -278.96324) (xy 194.978572 -279.002584) (xy 194.943079 -279.036676)
			(xy 194.902576 -279.064632) (xy 194.858114 -279.08573) (xy 194.810843 -279.099422) (xy 194.761988 -279.105354)
			(xy 194.712813 -279.103373) (xy 194.664594 -279.093529) (xy 194.618578 -279.076077) (xy 194.575957 -279.05147)
			(xy 194.537836 -279.020345) (xy 194.505201 -278.983508) (xy 194.478898 -278.941912) (xy 194.459607 -278.896636)
			(xy 194.44783 -278.848852) (xy 194.44387 -278.799798) (xy 194.105276 -278.799798) (xy 194.104781 -278.824405)
			(xy 194.096886 -278.872982) (xy 194.081302 -278.919663) (xy 194.058431 -278.96324) (xy 194.028866 -279.002584)
			(xy 193.993373 -279.036676) (xy 193.95287 -279.064632) (xy 193.908408 -279.08573) (xy 193.861137 -279.099422)
			(xy 193.812282 -279.105354) (xy 193.763107 -279.103373) (xy 193.714888 -279.093529) (xy 193.668872 -279.076077)
			(xy 193.626251 -279.05147) (xy 193.58813 -279.020345) (xy 193.555495 -278.983508) (xy 193.529192 -278.941912)
			(xy 193.509901 -278.896636) (xy 193.498124 -278.848852) (xy 193.494164 -278.799798) (xy 193.155062 -278.799798)
			(xy 193.154567 -278.824405) (xy 193.146672 -278.872982) (xy 193.131088 -278.919663) (xy 193.108217 -278.96324)
			(xy 193.078652 -279.002584) (xy 193.043159 -279.036676) (xy 193.002656 -279.064632) (xy 192.958194 -279.08573)
			(xy 192.910923 -279.099422) (xy 192.862068 -279.105354) (xy 192.812893 -279.103373) (xy 192.764674 -279.093529)
			(xy 192.718658 -279.076077) (xy 192.676037 -279.05147) (xy 192.637916 -279.020345) (xy 192.605281 -278.983508)
			(xy 192.578978 -278.941912) (xy 192.559687 -278.896636) (xy 192.54791 -278.848852) (xy 192.54395 -278.799798)
			(xy 192.205356 -278.799798) (xy 192.204861 -278.824405) (xy 192.196966 -278.872982) (xy 192.181382 -278.919663)
			(xy 192.158511 -278.96324) (xy 192.128946 -279.002584) (xy 192.093453 -279.036676) (xy 192.05295 -279.064632)
			(xy 192.008488 -279.08573) (xy 191.961217 -279.099422) (xy 191.912362 -279.105354) (xy 191.863187 -279.103373)
			(xy 191.814968 -279.093529) (xy 191.768952 -279.076077) (xy 191.726331 -279.05147) (xy 191.68821 -279.020345)
			(xy 191.655575 -278.983508) (xy 191.629272 -278.941912) (xy 191.609981 -278.896636) (xy 191.598204 -278.848852)
			(xy 191.594244 -278.799798) (xy 191.255142 -278.799798) (xy 191.254647 -278.824405) (xy 191.246752 -278.872982)
			(xy 191.231168 -278.919663) (xy 191.208297 -278.96324) (xy 191.178732 -279.002584) (xy 191.143239 -279.036676)
			(xy 191.102736 -279.064632) (xy 191.058274 -279.08573) (xy 191.011003 -279.099422) (xy 190.962148 -279.105354)
			(xy 190.912973 -279.103373) (xy 190.864754 -279.093529) (xy 190.818738 -279.076077) (xy 190.776117 -279.05147)
			(xy 190.737996 -279.020345) (xy 190.705361 -278.983508) (xy 190.679058 -278.941912) (xy 190.659767 -278.896636)
			(xy 190.64799 -278.848852) (xy 190.64403 -278.799798) (xy 190.305182 -278.799798) (xy 190.304687 -278.824405)
			(xy 190.296792 -278.872982) (xy 190.281208 -278.919663) (xy 190.258337 -278.96324) (xy 190.228772 -279.002584)
			(xy 190.193279 -279.036676) (xy 190.152776 -279.064632) (xy 190.108314 -279.08573) (xy 190.061043 -279.099422)
			(xy 190.012188 -279.105354) (xy 189.963013 -279.103373) (xy 189.914794 -279.093529) (xy 189.868778 -279.076077)
			(xy 189.826157 -279.05147) (xy 189.788036 -279.020345) (xy 189.755401 -278.983508) (xy 189.729098 -278.941912)
			(xy 189.709807 -278.896636) (xy 189.69803 -278.848852) (xy 189.69407 -278.799798) (xy 189.354968 -278.799798)
			(xy 189.354473 -278.824405) (xy 189.346578 -278.872982) (xy 189.330994 -278.919663) (xy 189.308123 -278.96324)
			(xy 189.278558 -279.002584) (xy 189.243065 -279.036676) (xy 189.202562 -279.064632) (xy 189.1581 -279.08573)
			(xy 189.110829 -279.099422) (xy 189.061974 -279.105354) (xy 189.012799 -279.103373) (xy 188.96458 -279.093529)
			(xy 188.918564 -279.076077) (xy 188.875943 -279.05147) (xy 188.837822 -279.020345) (xy 188.805187 -278.983508)
			(xy 188.778884 -278.941912) (xy 188.759593 -278.896636) (xy 188.747816 -278.848852) (xy 188.743856 -278.799798)
			(xy 188.405262 -278.799798) (xy 188.404767 -278.824405) (xy 188.396872 -278.872982) (xy 188.381288 -278.919663)
			(xy 188.358417 -278.96324) (xy 188.328852 -279.002584) (xy 188.293359 -279.036676) (xy 188.252856 -279.064632)
			(xy 188.208394 -279.08573) (xy 188.161123 -279.099422) (xy 188.112268 -279.105354) (xy 188.063093 -279.103373)
			(xy 188.014874 -279.093529) (xy 187.968858 -279.076077) (xy 187.926237 -279.05147) (xy 187.888116 -279.020345)
			(xy 187.855481 -278.983508) (xy 187.829178 -278.941912) (xy 187.809887 -278.896636) (xy 187.79811 -278.848852)
			(xy 187.79415 -278.799798) (xy 187.455048 -278.799798) (xy 187.454553 -278.824405) (xy 187.446658 -278.872982)
			(xy 187.431074 -278.919663) (xy 187.408203 -278.96324) (xy 187.378638 -279.002584) (xy 187.343145 -279.036676)
			(xy 187.302642 -279.064632) (xy 187.25818 -279.08573) (xy 187.210909 -279.099422) (xy 187.162054 -279.105354)
			(xy 187.112879 -279.103373) (xy 187.06466 -279.093529) (xy 187.018644 -279.076077) (xy 186.976023 -279.05147)
			(xy 186.937902 -279.020345) (xy 186.905267 -278.983508) (xy 186.878964 -278.941912) (xy 186.859673 -278.896636)
			(xy 186.847896 -278.848852) (xy 186.843936 -278.799798) (xy 186.505342 -278.799798) (xy 186.504847 -278.824405)
			(xy 186.496952 -278.872982) (xy 186.481368 -278.919663) (xy 186.458497 -278.96324) (xy 186.428932 -279.002584)
			(xy 186.393439 -279.036676) (xy 186.352936 -279.064632) (xy 186.308474 -279.08573) (xy 186.261203 -279.099422)
			(xy 186.212348 -279.105354) (xy 186.163173 -279.103373) (xy 186.114954 -279.093529) (xy 186.068938 -279.076077)
			(xy 186.026317 -279.05147) (xy 185.988196 -279.020345) (xy 185.955561 -278.983508) (xy 185.929258 -278.941912)
			(xy 185.909967 -278.896636) (xy 185.89819 -278.848852) (xy 185.89423 -278.799798) (xy 185.555128 -278.799798)
			(xy 185.554633 -278.824405) (xy 185.546738 -278.872982) (xy 185.531154 -278.919663) (xy 185.508283 -278.96324)
			(xy 185.478718 -279.002584) (xy 185.443225 -279.036676) (xy 185.402722 -279.064632) (xy 185.35826 -279.08573)
			(xy 185.310989 -279.099422) (xy 185.262134 -279.105354) (xy 185.212959 -279.103373) (xy 185.16474 -279.093529)
			(xy 185.118724 -279.076077) (xy 185.076103 -279.05147) (xy 185.037982 -279.020345) (xy 185.005347 -278.983508)
			(xy 184.979044 -278.941912) (xy 184.959753 -278.896636) (xy 184.947976 -278.848852) (xy 184.944016 -278.799798)
			(xy 184.605168 -278.799798) (xy 184.604673 -278.824405) (xy 184.596778 -278.872982) (xy 184.581194 -278.919663)
			(xy 184.558323 -278.96324) (xy 184.528758 -279.002584) (xy 184.493265 -279.036676) (xy 184.452762 -279.064632)
			(xy 184.4083 -279.08573) (xy 184.361029 -279.099422) (xy 184.312174 -279.105354) (xy 184.262999 -279.103373)
			(xy 184.21478 -279.093529) (xy 184.168764 -279.076077) (xy 184.126143 -279.05147) (xy 184.088022 -279.020345)
			(xy 184.055387 -278.983508) (xy 184.029084 -278.941912) (xy 184.009793 -278.896636) (xy 183.998016 -278.848852)
			(xy 183.994056 -278.799798) (xy 183.654954 -278.799798) (xy 183.654459 -278.824405) (xy 183.646564 -278.872982)
			(xy 183.63098 -278.919663) (xy 183.608109 -278.96324) (xy 183.578544 -279.002584) (xy 183.543051 -279.036676)
			(xy 183.502548 -279.064632) (xy 183.458086 -279.08573) (xy 183.410815 -279.099422) (xy 183.36196 -279.105354)
			(xy 183.312785 -279.103373) (xy 183.264566 -279.093529) (xy 183.21855 -279.076077) (xy 183.175929 -279.05147)
			(xy 183.137808 -279.020345) (xy 183.105173 -278.983508) (xy 183.07887 -278.941912) (xy 183.059579 -278.896636)
			(xy 183.047802 -278.848852) (xy 183.043842 -278.799798) (xy 182.705248 -278.799798) (xy 182.704753 -278.824405)
			(xy 182.696858 -278.872982) (xy 182.681274 -278.919663) (xy 182.658403 -278.96324) (xy 182.628838 -279.002584)
			(xy 182.593345 -279.036676) (xy 182.552842 -279.064632) (xy 182.50838 -279.08573) (xy 182.461109 -279.099422)
			(xy 182.412254 -279.105354) (xy 182.363079 -279.103373) (xy 182.31486 -279.093529) (xy 182.268844 -279.076077)
			(xy 182.226223 -279.05147) (xy 182.188102 -279.020345) (xy 182.155467 -278.983508) (xy 182.129164 -278.941912)
			(xy 182.109873 -278.896636) (xy 182.098096 -278.848852) (xy 182.094136 -278.799798) (xy 181.755034 -278.799798)
			(xy 181.754539 -278.824405) (xy 181.746644 -278.872982) (xy 181.73106 -278.919663) (xy 181.708189 -278.96324)
			(xy 181.678624 -279.002584) (xy 181.643131 -279.036676) (xy 181.602628 -279.064632) (xy 181.558166 -279.08573)
			(xy 181.510895 -279.099422) (xy 181.46204 -279.105354) (xy 181.412865 -279.103373) (xy 181.364646 -279.093529)
			(xy 181.31863 -279.076077) (xy 181.276009 -279.05147) (xy 181.237888 -279.020345) (xy 181.205253 -278.983508)
			(xy 181.17895 -278.941912) (xy 181.159659 -278.896636) (xy 181.147882 -278.848852) (xy 181.143922 -278.799798)
			(xy 180.805328 -278.799798) (xy 180.804833 -278.824405) (xy 180.796938 -278.872982) (xy 180.781354 -278.919663)
			(xy 180.758483 -278.96324) (xy 180.728918 -279.002584) (xy 180.693425 -279.036676) (xy 180.652922 -279.064632)
			(xy 180.60846 -279.08573) (xy 180.561189 -279.099422) (xy 180.512334 -279.105354) (xy 180.463159 -279.103373)
			(xy 180.41494 -279.093529) (xy 180.368924 -279.076077) (xy 180.326303 -279.05147) (xy 180.288182 -279.020345)
			(xy 180.255547 -278.983508) (xy 180.229244 -278.941912) (xy 180.209953 -278.896636) (xy 180.198176 -278.848852)
			(xy 180.194216 -278.799798) (xy 179.855114 -278.799798) (xy 179.854619 -278.824405) (xy 179.846724 -278.872982)
			(xy 179.83114 -278.919663) (xy 179.808269 -278.96324) (xy 179.778704 -279.002584) (xy 179.743211 -279.036676)
			(xy 179.702708 -279.064632) (xy 179.658246 -279.08573) (xy 179.610975 -279.099422) (xy 179.56212 -279.105354)
			(xy 179.512945 -279.103373) (xy 179.464726 -279.093529) (xy 179.41871 -279.076077) (xy 179.376089 -279.05147)
			(xy 179.337968 -279.020345) (xy 179.305333 -278.983508) (xy 179.27903 -278.941912) (xy 179.259739 -278.896636)
			(xy 179.247962 -278.848852) (xy 179.244002 -278.799798) (xy 178.905154 -278.799798) (xy 178.904659 -278.824405)
			(xy 178.896764 -278.872982) (xy 178.88118 -278.919663) (xy 178.858309 -278.96324) (xy 178.828744 -279.002584)
			(xy 178.793251 -279.036676) (xy 178.752748 -279.064632) (xy 178.708286 -279.08573) (xy 178.661015 -279.099422)
			(xy 178.61216 -279.105354) (xy 178.562985 -279.103373) (xy 178.514766 -279.093529) (xy 178.46875 -279.076077)
			(xy 178.426129 -279.05147) (xy 178.388008 -279.020345) (xy 178.355373 -278.983508) (xy 178.32907 -278.941912)
			(xy 178.309779 -278.896636) (xy 178.298002 -278.848852) (xy 178.294042 -278.799798) (xy 177.95494 -278.799798)
			(xy 177.954445 -278.824405) (xy 177.94655 -278.872982) (xy 177.930966 -278.919663) (xy 177.908095 -278.96324)
			(xy 177.87853 -279.002584) (xy 177.843037 -279.036676) (xy 177.802534 -279.064632) (xy 177.758072 -279.08573)
			(xy 177.710801 -279.099422) (xy 177.661946 -279.105354) (xy 177.612771 -279.103373) (xy 177.564552 -279.093529)
			(xy 177.518536 -279.076077) (xy 177.475915 -279.05147) (xy 177.437794 -279.020345) (xy 177.405159 -278.983508)
			(xy 177.378856 -278.941912) (xy 177.359565 -278.896636) (xy 177.347788 -278.848852) (xy 177.343828 -278.799798)
			(xy 177.005234 -278.799798) (xy 177.004739 -278.824405) (xy 176.996844 -278.872982) (xy 176.98126 -278.919663)
			(xy 176.958389 -278.96324) (xy 176.928824 -279.002584) (xy 176.893331 -279.036676) (xy 176.852828 -279.064632)
			(xy 176.808366 -279.08573) (xy 176.761095 -279.099422) (xy 176.71224 -279.105354) (xy 176.663065 -279.103373)
			(xy 176.614846 -279.093529) (xy 176.56883 -279.076077) (xy 176.526209 -279.05147) (xy 176.488088 -279.020345)
			(xy 176.455453 -278.983508) (xy 176.42915 -278.941912) (xy 176.409859 -278.896636) (xy 176.398082 -278.848852)
			(xy 176.394122 -278.799798) (xy 176.05502 -278.799798) (xy 176.054525 -278.824405) (xy 176.04663 -278.872982)
			(xy 176.031046 -278.919663) (xy 176.008175 -278.96324) (xy 175.97861 -279.002584) (xy 175.943117 -279.036676)
			(xy 175.902614 -279.064632) (xy 175.858152 -279.08573) (xy 175.810881 -279.099422) (xy 175.762026 -279.105354)
			(xy 175.712851 -279.103373) (xy 175.664632 -279.093529) (xy 175.618616 -279.076077) (xy 175.575995 -279.05147)
			(xy 175.537874 -279.020345) (xy 175.505239 -278.983508) (xy 175.478936 -278.941912) (xy 175.459645 -278.896636)
			(xy 175.447868 -278.848852) (xy 175.443908 -278.799798) (xy 175.105314 -278.799798) (xy 175.104819 -278.824405)
			(xy 175.096924 -278.872982) (xy 175.08134 -278.919663) (xy 175.058469 -278.96324) (xy 175.028904 -279.002584)
			(xy 174.993411 -279.036676) (xy 174.952908 -279.064632) (xy 174.908446 -279.08573) (xy 174.861175 -279.099422)
			(xy 174.81232 -279.105354) (xy 174.763145 -279.103373) (xy 174.714926 -279.093529) (xy 174.66891 -279.076077)
			(xy 174.626289 -279.05147) (xy 174.588168 -279.020345) (xy 174.555533 -278.983508) (xy 174.52923 -278.941912)
			(xy 174.509939 -278.896636) (xy 174.498162 -278.848852) (xy 174.494202 -278.799798) (xy 174.155274 -278.799798)
			(xy 174.153029 -278.841117) (xy 174.142353 -278.889596) (xy 174.123975 -278.935709) (xy 174.098379 -278.978242)
			(xy 174.06624 -279.016074) (xy 174.028403 -279.048207) (xy 173.985866 -279.073797) (xy 173.93975 -279.092167)
			(xy 173.89127 -279.102836) (xy 173.841702 -279.10552) (xy 173.792353 -279.100151) (xy 173.744522 -279.086868)
			(xy 173.69947 -279.066023) (xy 173.658384 -279.038164) (xy 173.622347 -279.004025) (xy 173.592307 -278.964506)
			(xy 173.569056 -278.920647) (xy 173.553206 -278.873605) (xy 173.545176 -278.824618) (xy 173.544738 -278.799798)
			(xy 173.54526 -278.773552) (xy 173.5542 -278.721827) (xy 173.562518 -278.696928) (xy 173.565368 -278.687642)
			(xy 173.564614 -278.668248) (xy 173.556703 -278.650524) (xy 173.54277 -278.637013) (xy 173.524812 -278.629651)
			(xy 173.505404 -278.629494) (xy 173.496224 -278.632666) (xy 173.486747 -278.636296) (xy 173.467429 -278.642525)
			(xy 173.457616 -278.645112) (xy 173.437211 -278.65008) (xy 173.395556 -278.655427) (xy 173.374558 -278.65578)
			(xy 173.361036 -278.655662) (xy 173.334078 -278.653501) (xy 173.32071 -278.651462) (xy 173.308772 -278.64943)
			(xy 173.286166 -278.656288) (xy 173.209712 -278.729186) (xy 173.201838 -278.751538) (xy 173.203362 -278.76373)
			(xy 173.204346 -278.772714) (xy 173.205365 -278.79076) (xy 173.205394 -278.799798) (xy 173.204908 -278.824618)
			(xy 173.196878 -278.873603) (xy 173.181029 -278.920643) (xy 173.157778 -278.9645) (xy 173.127738 -279.004018)
			(xy 173.091701 -279.038155) (xy 173.050615 -279.066013) (xy 173.005565 -279.086856) (xy 172.957735 -279.100137)
			(xy 172.908387 -279.105505) (xy 172.858821 -279.102818) (xy 172.810342 -279.092148) (xy 172.764228 -279.073776)
			(xy 172.721694 -279.048186) (xy 172.68386 -279.016051) (xy 172.651724 -278.978219) (xy 172.626131 -278.935686)
			(xy 172.607756 -278.889573) (xy 172.597084 -278.841095) (xy 172.594395 -278.791529) (xy 172.59976 -278.742181)
			(xy 172.613038 -278.69435) (xy 172.63388 -278.649298) (xy 172.661735 -278.608212) (xy 172.69587 -278.572173)
			(xy 172.735386 -278.542131) (xy 172.779242 -278.518878) (xy 172.826282 -278.503026) (xy 172.875267 -278.494993)
			(xy 172.900086 -278.49449) (xy 172.90906 -278.494532) (xy 172.926979 -278.495551) (xy 172.9359 -278.496522)
			(xy 172.948092 -278.498046) (xy 172.97019 -278.489918) (xy 173.043088 -278.413718) (xy 173.049946 -278.391112)
			(xy 173.048168 -278.379174) (xy 173.046037 -278.365686) (xy 173.043746 -278.338473) (xy 173.043596 -278.324818)
			(xy 173.043596 -278.25446) (xy 173.043148 -278.243796) (xy 173.03448 -278.224311) (xy 173.026832 -278.216868)
			(xy 172.96257 -278.158956) (xy 172.942504 -278.152352) (xy 172.931582 -278.153622) (xy 172.900086 -278.155146)
			(xy 172.876094 -278.154674) (xy 172.828702 -278.147167) (xy 172.783068 -278.132339) (xy 172.740314 -278.110555)
			(xy 172.701494 -278.082352) (xy 172.667564 -278.048424) (xy 172.639358 -278.009606) (xy 172.617571 -277.966855)
			(xy 172.602739 -277.921221) (xy 172.595228 -277.87383) (xy 172.594778 -277.849838) (xy 172.594876 -277.840734)
			(xy 172.596021 -277.822561) (xy 172.597064 -277.813516) (xy 172.598334 -277.801324) (xy 172.59046 -277.778972)
			(xy 172.514006 -277.706074) (xy 172.4914 -277.698962) (xy 172.479462 -277.700994) (xy 172.45236 -277.704933)
			(xy 172.397598 -277.704933) (xy 172.370496 -277.700994) (xy 172.358558 -277.699216) (xy 172.335952 -277.706074)
			(xy 172.259498 -277.778972) (xy 172.251624 -277.801324) (xy 172.252894 -277.813516) (xy 172.253941 -277.82256)
			(xy 172.255083 -277.840734) (xy 172.25518 -277.849838) (xy 172.254707 -277.873826) (xy 172.247196 -277.921212)
			(xy 172.232364 -277.966839) (xy 172.210578 -278.009584) (xy 172.182374 -278.048396) (xy 172.148445 -278.082317)
			(xy 172.109628 -278.110513) (xy 172.066878 -278.13229) (xy 172.021248 -278.147111) (xy 171.973861 -278.154612)
			(xy 171.949872 -278.155146) (xy 171.91736 -278.153368) (xy 171.906692 -278.152352) (xy 171.886372 -278.158956)
			(xy 171.821856 -278.216614) (xy 171.814196 -278.224131) (xy 171.805515 -278.243736) (xy 171.805092 -278.25446)
			(xy 171.805092 -278.30653) (xy 171.805346 -278.308562) (xy 171.805346 -278.31415) (xy 171.8056 -278.324818)
			(xy 171.80544 -278.338472) (xy 171.803155 -278.365685) (xy 171.801028 -278.379174) (xy 171.798996 -278.391112)
			(xy 171.806108 -278.413718) (xy 171.879006 -278.490172) (xy 171.901358 -278.498046) (xy 171.91355 -278.496776)
			(xy 171.922594 -278.495727) (xy 171.940768 -278.494581) (xy 171.949872 -278.49449) (xy 171.974694 -278.494974)
			(xy 172.023683 -278.503001) (xy 172.070729 -278.518848) (xy 172.114591 -278.542097) (xy 172.154114 -278.572137)
			(xy 172.188256 -278.608175) (xy 172.216118 -278.649262) (xy 172.236966 -278.694316) (xy 172.25025 -278.742148)
			(xy 172.25562 -278.7915) (xy 172.252936 -278.84107) (xy 172.242266 -278.889553) (xy 172.223894 -278.935672)
			(xy 172.198302 -278.97821) (xy 172.166166 -279.016047) (xy 172.128331 -279.048187) (xy 172.085795 -279.073782)
			(xy 172.039678 -279.092159) (xy 171.991196 -279.102832) (xy 171.941626 -279.105521) (xy 171.892274 -279.100155)
			(xy 171.84444 -279.086875) (xy 171.799385 -279.066031) (xy 171.758295 -279.038173) (xy 171.722254 -279.004034)
			(xy 171.692211 -278.964513) (xy 171.668958 -278.920653) (xy 171.653107 -278.873609) (xy 171.645076 -278.82462)
			(xy 171.644564 -278.799798) (xy 171.645106 -278.773616) (xy 171.654048 -278.722021) (xy 171.662344 -278.697182)
			(xy 171.665249 -278.687852) (xy 171.66455 -278.66834) (xy 171.656621 -278.650498) (xy 171.642607 -278.636904)
			(xy 171.624533 -278.629521) (xy 171.605009 -278.629416) (xy 171.595796 -278.632666) (xy 171.586652 -278.636222)
			(xy 171.56003 -278.645161) (xy 171.504742 -278.654984) (xy 171.47667 -278.65578) (xy 171.473622 -278.65578)
			(xy 171.453048 -278.655272) (xy 171.450254 -278.655018) (xy 171.449746 -278.655018) (xy 171.420536 -278.651462)
			(xy 171.408598 -278.64943) (xy 171.385992 -278.656542) (xy 171.309538 -278.72944) (xy 171.301664 -278.751792)
			(xy 171.303188 -278.76373) (xy 171.304172 -278.772714) (xy 171.305191 -278.79076) (xy 171.30522 -278.799798)
			(xy 171.304734 -278.82462) (xy 171.296703 -278.87361) (xy 171.280852 -278.920656) (xy 171.257598 -278.964517)
			(xy 171.227555 -279.004038) (xy 171.191513 -279.038179) (xy 171.150423 -279.066038) (xy 171.105367 -279.086883)
			(xy 171.057533 -279.100164) (xy 171.008179 -279.105531) (xy 170.958608 -279.102843) (xy 170.910125 -279.09217)
			(xy 170.864007 -279.073794) (xy 170.821469 -279.0482) (xy 170.783633 -279.01606) (xy 170.751495 -278.978223)
			(xy 170.725901 -278.935684) (xy 170.707527 -278.889566) (xy 170.696856 -278.841082) (xy 170.694169 -278.791511)
			(xy 170.699538 -278.742158) (xy 170.712821 -278.694323) (xy 170.733667 -278.649268) (xy 170.761528 -278.608179)
			(xy 170.795669 -278.572139) (xy 170.835191 -278.542097) (xy 170.879053 -278.518844) (xy 170.926099 -278.502995)
			(xy 170.97509 -278.494965) (xy 170.999912 -278.49449) (xy 171.008949 -278.494538) (xy 171.026994 -278.495557)
			(xy 171.03598 -278.496522) (xy 171.047918 -278.498046) (xy 171.07027 -278.490172) (xy 171.143168 -278.413718)
			(xy 171.150026 -278.391112) (xy 171.147994 -278.379174) (xy 171.145944 -278.365807) (xy 171.143779 -278.338849)
			(xy 171.143676 -278.325326) (xy 171.143676 -278.25446) (xy 171.143228 -278.243796) (xy 171.134557 -278.224313)
			(xy 171.126912 -278.216868) (xy 171.06265 -278.158956) (xy 171.04233 -278.152352) (xy 171.031662 -278.153622)
			(xy 170.999912 -278.155146) (xy 170.975919 -278.154676) (xy 170.928524 -278.147172) (xy 170.882886 -278.132346)
			(xy 170.840129 -278.110564) (xy 170.801305 -278.082361) (xy 170.767371 -278.048433) (xy 170.739162 -278.009614)
			(xy 170.717373 -277.966861) (xy 170.70254 -277.921225) (xy 170.695028 -277.873831) (xy 170.694604 -277.849838)
			(xy 170.694702 -277.840734) (xy 170.695847 -277.822561) (xy 170.69689 -277.813516) (xy 170.69816 -277.801324)
			(xy 170.690286 -277.778972) (xy 170.613832 -277.706074) (xy 170.591226 -277.699216) (xy 170.579288 -277.700994)
			(xy 170.55225 -277.704931) (xy 170.497614 -277.704931) (xy 170.470576 -277.700994) (xy 170.458638 -277.699216)
			(xy 170.436032 -277.706074) (xy 170.359578 -277.778972) (xy 170.351704 -277.801324) (xy 170.352974 -277.813516)
			(xy 170.354021 -277.82256) (xy 170.355162 -277.840734) (xy 170.35526 -277.849838) (xy 170.354811 -277.873828)
			(xy 170.347299 -277.921216) (xy 170.332467 -277.966845) (xy 170.310679 -278.009593) (xy 170.282471 -278.048405)
			(xy 170.24854 -278.082327) (xy 170.209719 -278.110524) (xy 170.166966 -278.1323) (xy 170.121332 -278.147119)
			(xy 170.073942 -278.154618) (xy 170.049952 -278.155146) (xy 170.01744 -278.153368) (xy 170.006772 -278.152352)
			(xy 169.986452 -278.158956) (xy 169.921936 -278.216614) (xy 169.914279 -278.224132) (xy 169.905601 -278.243737)
			(xy 169.905172 -278.25446) (xy 169.905172 -278.314912) (xy 169.90568 -278.324818) (xy 169.90568 -278.325072)
			(xy 169.905508 -278.338662) (xy 169.903217 -278.365747) (xy 169.901108 -278.379174) (xy 169.899076 -278.391112)
			(xy 169.906188 -278.413718) (xy 169.979086 -278.490172) (xy 170.001438 -278.498046) (xy 170.01363 -278.496776)
			(xy 170.022674 -278.495726) (xy 170.040848 -278.49458) (xy 170.049952 -278.49449) (xy 170.074774 -278.494972)
			(xy 170.123765 -278.502996) (xy 170.170812 -278.518841) (xy 170.214676 -278.542088) (xy 170.254202 -278.572126)
			(xy 170.288346 -278.608162) (xy 170.316211 -278.649249) (xy 170.337061 -278.694302) (xy 170.350347 -278.742134)
			(xy 170.35572 -278.791487) (xy 170.353037 -278.841058) (xy 170.34237 -278.889542) (xy 170.323999 -278.935661)
			(xy 170.298409 -278.978201) (xy 170.266273 -279.01604) (xy 170.228439 -279.048182) (xy 170.185903 -279.073779)
			(xy 170.139786 -279.092156) (xy 170.091303 -279.102831) (xy 170.041733 -279.105521) (xy 169.99238 -279.100156)
			(xy 169.944545 -279.086877) (xy 169.899489 -279.066033) (xy 169.858398 -279.038175) (xy 169.822357 -279.004036)
			(xy 169.792313 -278.964515) (xy 169.769059 -278.920655) (xy 169.753207 -278.87361) (xy 169.745176 -278.82462)
			(xy 169.744644 -278.799798) (xy 169.745166 -278.773552) (xy 169.754106 -278.721827) (xy 169.762424 -278.696928)
			(xy 169.765275 -278.687641) (xy 169.76452 -278.668246) (xy 169.756609 -278.650522) (xy 169.742675 -278.637009)
			(xy 169.724716 -278.629646) (xy 169.705307 -278.629487) (xy 169.69613 -278.632666) (xy 169.680008 -278.638742)
			(xy 169.646794 -278.647907) (xy 169.629836 -278.650954) (xy 169.616038 -278.65319) (xy 169.588187 -278.655603)
			(xy 169.57421 -278.65578) (xy 169.560751 -278.655654) (xy 169.533921 -278.653494) (xy 169.520616 -278.651462)
			(xy 169.508424 -278.64943) (xy 169.485818 -278.656288) (xy 169.409618 -278.72944) (xy 169.401744 -278.751538)
			(xy 169.403268 -278.76373) (xy 169.404252 -278.772714) (xy 169.405271 -278.79076) (xy 169.4053 -278.799798)
			(xy 169.404814 -278.824618) (xy 169.396784 -278.873604) (xy 169.380934 -278.920646) (xy 169.357682 -278.964504)
			(xy 169.327642 -279.004023) (xy 169.291604 -279.038161) (xy 169.250517 -279.066018) (xy 169.205465 -279.086862)
			(xy 169.157635 -279.100143) (xy 169.108285 -279.105511) (xy 169.058718 -279.102824) (xy 169.010238 -279.092153)
			(xy 168.964123 -279.07378) (xy 168.921588 -279.048189) (xy 168.883754 -279.016053) (xy 168.851617 -278.97822)
			(xy 168.826024 -278.935686) (xy 168.80765 -278.889571) (xy 168.796977 -278.841092) (xy 168.794289 -278.791525)
			(xy 168.799655 -278.742175) (xy 168.812934 -278.694344) (xy 168.833777 -278.649291) (xy 168.861633 -278.608204)
			(xy 168.89577 -278.572165) (xy 168.935287 -278.542123) (xy 168.979145 -278.51887) (xy 169.026186 -278.503019)
			(xy 169.075172 -278.494986) (xy 169.099992 -278.49449) (xy 169.108902 -278.494538) (xy 169.126694 -278.495556)
			(xy 169.135552 -278.496522) (xy 169.147744 -278.498046) (xy 169.169842 -278.489918) (xy 169.24274 -278.413718)
			(xy 169.249598 -278.391112) (xy 169.24782 -278.37892) (xy 169.245704 -278.365494) (xy 169.243418 -278.338409)
			(xy 169.243248 -278.324818) (xy 169.243248 -278.254714) (xy 169.24282 -278.243995) (xy 169.234119 -278.224408)
			(xy 169.226484 -278.216868) (xy 169.162476 -278.158956) (xy 169.142156 -278.152352) (xy 169.131234 -278.153622)
			(xy 169.099992 -278.155146) (xy 169.076 -278.154675) (xy 169.028607 -278.147168) (xy 168.982972 -278.13234)
			(xy 168.940217 -278.110557) (xy 168.901397 -278.082354) (xy 168.867465 -278.048426) (xy 168.839259 -278.009608)
			(xy 168.817471 -277.966856) (xy 168.802639 -277.921222) (xy 168.795128 -277.87383) (xy 168.794684 -277.849838)
			(xy 168.794782 -277.840734) (xy 168.795928 -277.822561) (xy 168.79697 -277.813516) (xy 168.79824 -277.801324)
			(xy 168.790366 -277.778972) (xy 168.713912 -277.706074) (xy 168.691306 -277.699216) (xy 168.679368 -277.700994)
			(xy 168.65233 -277.704931) (xy 168.597694 -277.704931) (xy 168.570656 -277.700994) (xy 168.558718 -277.699216)
			(xy 168.536112 -277.706074) (xy 168.459658 -277.778972) (xy 168.451784 -277.801324) (xy 168.453054 -277.813516)
			(xy 168.454101 -277.82256) (xy 168.455243 -277.840734) (xy 168.45534 -277.849838) (xy 168.454867 -277.873828)
			(xy 168.447356 -277.921217) (xy 168.432526 -277.966848) (xy 168.410741 -278.009598) (xy 168.382537 -278.048414)
			(xy 168.348609 -278.082341) (xy 168.309793 -278.110544) (xy 168.267043 -278.132328) (xy 168.221411 -278.147157)
			(xy 168.174022 -278.154667) (xy 168.150032 -278.155146) (xy 168.11752 -278.153368) (xy 168.106852 -278.152352)
			(xy 168.086532 -278.158956) (xy 168.022016 -278.216614) (xy 168.014361 -278.224133) (xy 168.005688 -278.243738)
			(xy 168.005252 -278.25446) (xy 168.005252 -278.314912) (xy 168.00576 -278.324818) (xy 168.00576 -278.325072)
			(xy 168.005588 -278.338662) (xy 168.003296 -278.365747) (xy 168.001188 -278.379174) (xy 167.999156 -278.391112)
			(xy 168.006268 -278.413718) (xy 168.079166 -278.490172) (xy 168.101518 -278.498046) (xy 168.11371 -278.496776)
			(xy 168.122754 -278.495729) (xy 168.140928 -278.494587) (xy 168.150032 -278.49449) (xy 168.174852 -278.494978)
			(xy 168.223839 -278.503014) (xy 168.27088 -278.518869) (xy 168.314736 -278.542126) (xy 168.354252 -278.572171)
			(xy 168.388387 -278.608213) (xy 168.416241 -278.649303) (xy 168.437081 -278.694357) (xy 168.450358 -278.74219)
			(xy 168.455721 -278.79154) (xy 168.45303 -278.841108) (xy 168.442356 -278.889588) (xy 168.423979 -278.935702)
			(xy 168.398384 -278.978236) (xy 168.366245 -279.016069) (xy 168.328408 -279.048203) (xy 168.285872 -279.073794)
			(xy 168.239756 -279.092166) (xy 168.191275 -279.102835) (xy 168.141706 -279.105521) (xy 168.092357 -279.100152)
			(xy 168.044525 -279.08687) (xy 167.999473 -279.066024) (xy 167.958387 -279.038166) (xy 167.922348 -279.004027)
			(xy 167.892308 -278.964507) (xy 167.869056 -278.920648) (xy 167.853206 -278.873606) (xy 167.845176 -278.824619)
			(xy 167.844724 -278.799798) (xy 167.845247 -278.773552) (xy 167.854189 -278.721828) (xy 167.862504 -278.696928)
			(xy 167.865355 -278.687643) (xy 167.864602 -278.668251) (xy 167.856691 -278.65053) (xy 167.842758 -278.637021)
			(xy 167.8248 -278.629662) (xy 167.805394 -278.629509) (xy 167.79621 -278.632666) (xy 167.780088 -278.638742)
			(xy 167.746873 -278.647904) (xy 167.729916 -278.650954) (xy 167.716118 -278.653194) (xy 167.688267 -278.655613)
			(xy 167.67429 -278.65578) (xy 167.660831 -278.655654) (xy 167.634001 -278.653491) (xy 167.620696 -278.651462)
			(xy 167.608504 -278.64943) (xy 167.585898 -278.656288) (xy 167.509698 -278.72944) (xy 167.501824 -278.751538)
			(xy 167.503348 -278.76373) (xy 167.504332 -278.772714) (xy 167.505351 -278.79076) (xy 167.50538 -278.799798)
			(xy 167.504894 -278.824616) (xy 167.496865 -278.873599) (xy 167.481016 -278.920637) (xy 167.457767 -278.964491)
			(xy 167.427729 -279.004007) (xy 167.391694 -279.038143) (xy 167.350611 -279.065999) (xy 167.305563 -279.086842)
			(xy 167.257737 -279.100122) (xy 167.208391 -279.105491) (xy 167.158828 -279.102805) (xy 167.110352 -279.092137)
			(xy 167.06424 -279.073766) (xy 167.021708 -279.048178) (xy 166.983875 -279.016046) (xy 166.951739 -278.978217)
			(xy 166.926147 -278.935687) (xy 166.907772 -278.889577) (xy 166.897099 -278.841102) (xy 166.894409 -278.791539)
			(xy 166.899772 -278.742193) (xy 166.913048 -278.694365) (xy 166.933886 -278.649315) (xy 166.961739 -278.608229)
			(xy 166.995871 -278.572191) (xy 167.035383 -278.542149) (xy 167.079236 -278.518896) (xy 167.126272 -278.503043)
			(xy 167.175254 -278.495008) (xy 167.200072 -278.49449) (xy 167.208982 -278.494537) (xy 167.226774 -278.495554)
			(xy 167.235632 -278.496522) (xy 167.247824 -278.498046) (xy 167.269922 -278.489918) (xy 167.34282 -278.413718)
			(xy 167.349678 -278.391112) (xy 167.3479 -278.37892) (xy 167.345784 -278.365494) (xy 167.343499 -278.338409)
			(xy 167.343328 -278.324818) (xy 167.343328 -278.254714) (xy 167.342902 -278.243993) (xy 167.334211 -278.224396)
			(xy 167.326564 -278.216868) (xy 167.262556 -278.158956) (xy 167.242236 -278.152352) (xy 167.231314 -278.153622)
			(xy 167.200072 -278.155146) (xy 167.176081 -278.154673) (xy 167.128691 -278.147164) (xy 167.083058 -278.132335)
			(xy 167.040306 -278.11055) (xy 167.001488 -278.082347) (xy 166.96756 -278.048419) (xy 166.939355 -278.009602)
			(xy 166.917569 -277.966851) (xy 166.902738 -277.921219) (xy 166.895227 -277.873829) (xy 166.894764 -277.849838)
			(xy 166.894862 -277.840734) (xy 166.896007 -277.822561) (xy 166.89705 -277.813516) (xy 166.89832 -277.801324)
			(xy 166.890446 -277.778972) (xy 166.813992 -277.706074) (xy 166.791386 -277.699216) (xy 166.779448 -277.700994)
			(xy 166.752346 -277.704933) (xy 166.697584 -277.704933) (xy 166.670482 -277.700994) (xy 166.658544 -277.698962)
			(xy 166.635938 -277.706074) (xy 166.559484 -277.778972) (xy 166.55161 -277.801324) (xy 166.55288 -277.813516)
			(xy 166.553927 -277.82256) (xy 166.555068 -277.840734) (xy 166.555166 -277.849838) (xy 166.554717 -277.873828)
			(xy 166.547205 -277.921216) (xy 166.532373 -277.966846) (xy 166.510585 -278.009594) (xy 166.482378 -278.048407)
			(xy 166.448446 -278.08233) (xy 166.409626 -278.110527) (xy 166.366872 -278.132303) (xy 166.321239 -278.147124)
			(xy 166.273848 -278.154623) (xy 166.249858 -278.155146) (xy 166.2176 -278.153368) (xy 166.206678 -278.152352)
			(xy 166.186358 -278.158956) (xy 166.122096 -278.216614) (xy 166.114443 -278.224134) (xy 166.105773 -278.243739)
			(xy 166.105332 -278.25446) (xy 166.105332 -278.31415) (xy 166.105586 -278.324818) (xy 166.105426 -278.338472)
			(xy 166.103141 -278.365685) (xy 166.101014 -278.379174) (xy 166.098982 -278.391112) (xy 166.106094 -278.413718)
			(xy 166.178992 -278.490172) (xy 166.201344 -278.498046) (xy 166.213536 -278.496776) (xy 166.22258 -278.495726)
			(xy 166.240754 -278.49458) (xy 166.249858 -278.49449) (xy 166.27468 -278.494973) (xy 166.32367 -278.502997)
			(xy 166.370717 -278.518843) (xy 166.414581 -278.542091) (xy 166.454105 -278.572129) (xy 166.488249 -278.608166)
			(xy 166.516113 -278.649253) (xy 166.536962 -278.694306) (xy 166.550248 -278.742139) (xy 166.55562 -278.791491)
			(xy 166.552937 -278.841062) (xy 166.542269 -278.889545) (xy 166.523898 -278.935665) (xy 166.498307 -278.978204)
			(xy 166.466171 -279.016042) (xy 166.428336 -279.048183) (xy 166.3858 -279.07378) (xy 166.339684 -279.092157)
			(xy 166.291201 -279.102831) (xy 166.241631 -279.105521) (xy 166.192278 -279.100156) (xy 166.144443 -279.086876)
			(xy 166.099388 -279.066033) (xy 166.058298 -279.038174) (xy 166.022256 -279.004035) (xy 165.992212 -278.964515)
			(xy 165.968959 -278.920654) (xy 165.953107 -278.873609) (xy 165.945076 -278.82462) (xy 165.94455 -278.799798)
			(xy 165.945072 -278.773552) (xy 165.954013 -278.721827) (xy 165.96233 -278.696928) (xy 165.96518 -278.687641)
			(xy 165.964426 -278.668245) (xy 165.956514 -278.650519) (xy 165.94258 -278.637006) (xy 165.924621 -278.629641)
			(xy 165.905211 -278.62948) (xy 165.896036 -278.632666) (xy 165.886559 -278.636296) (xy 165.867242 -278.642526)
			(xy 165.857428 -278.645112) (xy 165.837023 -278.650081) (xy 165.795368 -278.655429) (xy 165.77437 -278.65578)
			(xy 165.760848 -278.655662) (xy 165.73389 -278.653502) (xy 165.720522 -278.651462) (xy 165.708584 -278.64943)
			(xy 165.685978 -278.656288) (xy 165.609524 -278.729186) (xy 165.60165 -278.751538) (xy 165.603174 -278.76373)
			(xy 165.604158 -278.772714) (xy 165.605177 -278.79076) (xy 165.605206 -278.799798) (xy 165.60472 -278.824619)
			(xy 165.59669 -278.873606) (xy 165.580839 -278.920649) (xy 165.557587 -278.964508) (xy 165.527546 -279.004027)
			(xy 165.491506 -279.038166) (xy 165.450419 -279.066024) (xy 165.405366 -279.086869) (xy 165.357534 -279.100149)
			(xy 165.308184 -279.105517) (xy 165.258615 -279.10283) (xy 165.210134 -279.092158) (xy 165.164018 -279.073785)
			(xy 165.121483 -279.048192) (xy 165.083648 -279.016055) (xy 165.05151 -278.978221) (xy 165.025917 -278.935685)
			(xy 165.007543 -278.88957) (xy 164.996871 -278.841089) (xy 164.994183 -278.79152) (xy 164.99955 -278.74217)
			(xy 165.01283 -278.694338) (xy 165.033674 -278.649284) (xy 165.061532 -278.608197) (xy 165.09567 -278.572157)
			(xy 165.135189 -278.542115) (xy 165.179047 -278.518862) (xy 165.22609 -278.503011) (xy 165.275077 -278.49498)
			(xy 165.299898 -278.49449) (xy 165.308872 -278.494529) (xy 165.326791 -278.495543) (xy 165.335712 -278.496522)
			(xy 165.347904 -278.498046) (xy 165.370002 -278.489918) (xy 165.4429 -278.413718) (xy 165.449758 -278.391112)
			(xy 165.44798 -278.379174) (xy 165.445849 -278.365686) (xy 165.443558 -278.338473) (xy 165.443408 -278.324818)
			(xy 165.443408 -278.25446) (xy 165.442961 -278.243795) (xy 165.434294 -278.224309) (xy 165.426644 -278.216868)
			(xy 165.362382 -278.158956) (xy 165.342316 -278.152352) (xy 165.331394 -278.153622) (xy 165.299898 -278.155146)
			(xy 165.275906 -278.154675) (xy 165.228512 -278.147169) (xy 165.182876 -278.132342) (xy 165.140121 -278.110559)
			(xy 165.101299 -278.082356) (xy 165.067367 -278.048428) (xy 165.03916 -278.00961) (xy 165.017372 -277.966857)
			(xy 165.002539 -277.921223) (xy 164.995028 -277.87383) (xy 164.99459 -277.849838) (xy 164.994688 -277.840734)
			(xy 164.995833 -277.822561) (xy 164.996876 -277.813516) (xy 164.998146 -277.801324) (xy 164.990272 -277.778972)
			(xy 164.913818 -277.706074) (xy 164.891212 -277.698962) (xy 164.879274 -277.700994) (xy 164.865786 -277.703125)
			(xy 164.838573 -277.705414) (xy 164.824918 -277.705566) (xy 164.823902 -277.705566) (xy 164.810507 -277.705431)
			(xy 164.783805 -277.703267) (xy 164.770562 -277.701248) (xy 164.75837 -277.699216) (xy 164.735764 -277.706074)
			(xy 164.659564 -277.779226) (xy 164.65169 -277.801324) (xy 164.65296 -277.813516) (xy 164.654007 -277.82256)
			(xy 164.655148 -277.840734) (xy 164.655246 -277.849838) (xy 164.654792 -277.873888) (xy 164.647245 -277.921393)
			(xy 164.632343 -277.967126) (xy 164.610455 -278.009958) (xy 164.582123 -278.048828) (xy 164.548046 -278.082776)
			(xy 164.509069 -278.110961) (xy 164.466154 -278.132686) (xy 164.420364 -278.147415) (xy 164.396674 -278.15159)
			(xy 164.378132 -278.154384) (xy 164.353748 -278.182832) (xy 164.353748 -278.466804) (xy 164.378132 -278.495252)
			(xy 164.396674 -278.498046) (xy 164.420374 -278.502176) (xy 164.466169 -278.516907) (xy 164.509087 -278.538637)
			(xy 164.548067 -278.566827) (xy 164.582145 -278.60078) (xy 164.610478 -278.639657) (xy 164.632365 -278.682496)
			(xy 164.647264 -278.728236) (xy 164.654807 -278.775747) (xy 164.654807 -278.823853) (xy 164.647264 -278.871363)
			(xy 164.632365 -278.917104) (xy 164.610479 -278.959942) (xy 164.582146 -278.998819) (xy 164.548068 -279.032773)
			(xy 164.509087 -279.060963) (xy 164.466169 -279.082693) (xy 164.420375 -279.097424) (xy 164.396674 -279.10155)
			(xy 164.378132 -279.104344) (xy 164.353748 -279.132792) (xy 164.353748 -279.416764) (xy 164.378132 -279.445212)
			(xy 164.396674 -279.448006) (xy 164.420377 -279.452135) (xy 164.466178 -279.466868) (xy 164.509103 -279.488599)
			(xy 164.548089 -279.516792) (xy 164.582172 -279.55075) (xy 164.610509 -279.589631) (xy 164.6324 -279.632475)
			(xy 164.647302 -279.678221) (xy 164.654846 -279.725738) (xy 164.654846 -279.749504) (xy 164.994094 -279.749504)
			(xy 164.998054 -279.70045) (xy 165.009831 -279.652666) (xy 165.029122 -279.60739) (xy 165.055425 -279.565794)
			(xy 165.08806 -279.528957) (xy 165.126181 -279.497832) (xy 165.168802 -279.473225) (xy 165.214818 -279.455773)
			(xy 165.263037 -279.445929) (xy 165.312212 -279.443948) (xy 165.361067 -279.44988) (xy 165.408338 -279.463572)
			(xy 165.4528 -279.48467) (xy 165.493303 -279.512626) (xy 165.528796 -279.546718) (xy 165.558361 -279.586062)
			(xy 165.581232 -279.629639) (xy 165.596816 -279.67632) (xy 165.604711 -279.724897) (xy 165.605206 -279.749504)
			(xy 165.605201 -279.749758) (xy 165.944054 -279.749758) (xy 165.948014 -279.700704) (xy 165.959791 -279.65292)
			(xy 165.979082 -279.607644) (xy 166.005385 -279.566048) (xy 166.03802 -279.529211) (xy 166.076141 -279.498086)
			(xy 166.118762 -279.473479) (xy 166.164778 -279.456027) (xy 166.212997 -279.446183) (xy 166.262172 -279.444202)
			(xy 166.311027 -279.450134) (xy 166.358298 -279.463826) (xy 166.40276 -279.484924) (xy 166.443263 -279.51288)
			(xy 166.478756 -279.546972) (xy 166.508321 -279.586316) (xy 166.531192 -279.629893) (xy 166.546776 -279.676574)
			(xy 166.554671 -279.725151) (xy 166.555161 -279.749504) (xy 166.894268 -279.749504) (xy 166.898228 -279.70045)
			(xy 166.910005 -279.652666) (xy 166.929296 -279.60739) (xy 166.955599 -279.565794) (xy 166.988234 -279.528957)
			(xy 167.026355 -279.497832) (xy 167.068976 -279.473225) (xy 167.114992 -279.455773) (xy 167.163211 -279.445929)
			(xy 167.212386 -279.443948) (xy 167.261241 -279.44988) (xy 167.308512 -279.463572) (xy 167.352974 -279.48467)
			(xy 167.393477 -279.512626) (xy 167.42897 -279.546718) (xy 167.458535 -279.586062) (xy 167.481406 -279.629639)
			(xy 167.49699 -279.67632) (xy 167.504885 -279.724897) (xy 167.50538 -279.749504) (xy 167.505375 -279.749758)
			(xy 167.844228 -279.749758) (xy 167.848188 -279.700704) (xy 167.859965 -279.65292) (xy 167.879256 -279.607644)
			(xy 167.905559 -279.566048) (xy 167.938194 -279.529211) (xy 167.976315 -279.498086) (xy 168.018936 -279.473479)
			(xy 168.064952 -279.456027) (xy 168.113171 -279.446183) (xy 168.162346 -279.444202) (xy 168.211201 -279.450134)
			(xy 168.258472 -279.463826) (xy 168.302934 -279.484924) (xy 168.343437 -279.51288) (xy 168.37893 -279.546972)
			(xy 168.408495 -279.586316) (xy 168.431366 -279.629893) (xy 168.44695 -279.676574) (xy 168.454845 -279.725151)
			(xy 168.455335 -279.749504) (xy 168.794188 -279.749504) (xy 168.798148 -279.70045) (xy 168.809925 -279.652666)
			(xy 168.829216 -279.60739) (xy 168.855519 -279.565794) (xy 168.888154 -279.528957) (xy 168.926275 -279.497832)
			(xy 168.968896 -279.473225) (xy 169.014912 -279.455773) (xy 169.063131 -279.445929) (xy 169.112306 -279.443948)
			(xy 169.161161 -279.44988) (xy 169.208432 -279.463572) (xy 169.252894 -279.48467) (xy 169.293397 -279.512626)
			(xy 169.32889 -279.546718) (xy 169.358455 -279.586062) (xy 169.381326 -279.629639) (xy 169.39691 -279.67632)
			(xy 169.404805 -279.724897) (xy 169.4053 -279.749504) (xy 169.405295 -279.749758) (xy 169.744148 -279.749758)
			(xy 169.748108 -279.700704) (xy 169.759885 -279.65292) (xy 169.779176 -279.607644) (xy 169.805479 -279.566048)
			(xy 169.838114 -279.529211) (xy 169.876235 -279.498086) (xy 169.918856 -279.473479) (xy 169.964872 -279.456027)
			(xy 170.013091 -279.446183) (xy 170.062266 -279.444202) (xy 170.111121 -279.450134) (xy 170.158392 -279.463826)
			(xy 170.202854 -279.484924) (xy 170.243357 -279.51288) (xy 170.27885 -279.546972) (xy 170.308415 -279.586316)
			(xy 170.331286 -279.629893) (xy 170.34687 -279.676574) (xy 170.354765 -279.725151) (xy 170.355255 -279.749504)
			(xy 170.694108 -279.749504) (xy 170.698068 -279.70045) (xy 170.709845 -279.652666) (xy 170.729136 -279.60739)
			(xy 170.755439 -279.565794) (xy 170.788074 -279.528957) (xy 170.826195 -279.497832) (xy 170.868816 -279.473225)
			(xy 170.914832 -279.455773) (xy 170.963051 -279.445929) (xy 171.012226 -279.443948) (xy 171.061081 -279.44988)
			(xy 171.108352 -279.463572) (xy 171.152814 -279.48467) (xy 171.193317 -279.512626) (xy 171.22881 -279.546718)
			(xy 171.258375 -279.586062) (xy 171.281246 -279.629639) (xy 171.29683 -279.67632) (xy 171.304725 -279.724897)
			(xy 171.30522 -279.749504) (xy 171.305215 -279.749758) (xy 171.644068 -279.749758) (xy 171.648028 -279.700704)
			(xy 171.659805 -279.65292) (xy 171.679096 -279.607644) (xy 171.705399 -279.566048) (xy 171.738034 -279.529211)
			(xy 171.776155 -279.498086) (xy 171.818776 -279.473479) (xy 171.864792 -279.456027) (xy 171.913011 -279.446183)
			(xy 171.962186 -279.444202) (xy 172.011041 -279.450134) (xy 172.058312 -279.463826) (xy 172.102774 -279.484924)
			(xy 172.143277 -279.51288) (xy 172.17877 -279.546972) (xy 172.208335 -279.586316) (xy 172.231206 -279.629893)
			(xy 172.24679 -279.676574) (xy 172.254685 -279.725151) (xy 172.255175 -279.749504) (xy 172.594028 -279.749504)
			(xy 172.597988 -279.70045) (xy 172.609765 -279.652666) (xy 172.629056 -279.60739) (xy 172.655359 -279.565794)
			(xy 172.687994 -279.528957) (xy 172.726115 -279.497832) (xy 172.768736 -279.473225) (xy 172.814752 -279.455773)
			(xy 172.862971 -279.445929) (xy 172.912146 -279.443948) (xy 172.961001 -279.44988) (xy 173.008272 -279.463572)
			(xy 173.052734 -279.48467) (xy 173.093237 -279.512626) (xy 173.12873 -279.546718) (xy 173.158295 -279.586062)
			(xy 173.181166 -279.629639) (xy 173.19675 -279.67632) (xy 173.204645 -279.724897) (xy 173.20514 -279.749504)
			(xy 173.205135 -279.749758) (xy 173.544242 -279.749758) (xy 173.548202 -279.700704) (xy 173.559979 -279.65292)
			(xy 173.57927 -279.607644) (xy 173.605573 -279.566048) (xy 173.638208 -279.529211) (xy 173.676329 -279.498086)
			(xy 173.71895 -279.473479) (xy 173.764966 -279.456027) (xy 173.813185 -279.446183) (xy 173.86236 -279.444202)
			(xy 173.911215 -279.450134) (xy 173.958486 -279.463826) (xy 174.002948 -279.484924) (xy 174.043451 -279.51288)
			(xy 174.078944 -279.546972) (xy 174.108509 -279.586316) (xy 174.13138 -279.629893) (xy 174.146964 -279.676574)
			(xy 174.154859 -279.725151) (xy 174.155349 -279.749504) (xy 174.494202 -279.749504) (xy 174.498162 -279.70045)
			(xy 174.509939 -279.652666) (xy 174.52923 -279.60739) (xy 174.555533 -279.565794) (xy 174.588168 -279.528957)
			(xy 174.626289 -279.497832) (xy 174.66891 -279.473225) (xy 174.714926 -279.455773) (xy 174.763145 -279.445929)
			(xy 174.81232 -279.443948) (xy 174.861175 -279.44988) (xy 174.908446 -279.463572) (xy 174.952908 -279.48467)
			(xy 174.993411 -279.512626) (xy 175.028904 -279.546718) (xy 175.058469 -279.586062) (xy 175.08134 -279.629639)
			(xy 175.096924 -279.67632) (xy 175.104819 -279.724897) (xy 175.105314 -279.749504) (xy 175.105309 -279.749758)
			(xy 175.444162 -279.749758) (xy 175.448122 -279.700704) (xy 175.459899 -279.65292) (xy 175.47919 -279.607644)
			(xy 175.505493 -279.566048) (xy 175.538128 -279.529211) (xy 175.576249 -279.498086) (xy 175.61887 -279.473479)
			(xy 175.664886 -279.456027) (xy 175.713105 -279.446183) (xy 175.76228 -279.444202) (xy 175.811135 -279.450134)
			(xy 175.858406 -279.463826) (xy 175.902868 -279.484924) (xy 175.943371 -279.51288) (xy 175.978864 -279.546972)
			(xy 176.008429 -279.586316) (xy 176.0313 -279.629893) (xy 176.046884 -279.676574) (xy 176.054779 -279.725151)
			(xy 176.055269 -279.749504) (xy 176.394122 -279.749504) (xy 176.398082 -279.70045) (xy 176.409859 -279.652666)
			(xy 176.42915 -279.60739) (xy 176.455453 -279.565794) (xy 176.488088 -279.528957) (xy 176.526209 -279.497832)
			(xy 176.56883 -279.473225) (xy 176.614846 -279.455773) (xy 176.663065 -279.445929) (xy 176.71224 -279.443948)
			(xy 176.761095 -279.44988) (xy 176.808366 -279.463572) (xy 176.852828 -279.48467) (xy 176.893331 -279.512626)
			(xy 176.928824 -279.546718) (xy 176.958389 -279.586062) (xy 176.98126 -279.629639) (xy 176.996844 -279.67632)
			(xy 177.004739 -279.724897) (xy 177.005234 -279.749504) (xy 177.005229 -279.749758) (xy 177.344082 -279.749758)
			(xy 177.348042 -279.700704) (xy 177.359819 -279.65292) (xy 177.37911 -279.607644) (xy 177.405413 -279.566048)
			(xy 177.438048 -279.529211) (xy 177.476169 -279.498086) (xy 177.51879 -279.473479) (xy 177.564806 -279.456027)
			(xy 177.613025 -279.446183) (xy 177.6622 -279.444202) (xy 177.711055 -279.450134) (xy 177.758326 -279.463826)
			(xy 177.802788 -279.484924) (xy 177.843291 -279.51288) (xy 177.878784 -279.546972) (xy 177.908349 -279.586316)
			(xy 177.93122 -279.629893) (xy 177.946804 -279.676574) (xy 177.954699 -279.725151) (xy 177.955189 -279.749504)
			(xy 178.294042 -279.749504) (xy 178.298002 -279.70045) (xy 178.309779 -279.652666) (xy 178.32907 -279.60739)
			(xy 178.355373 -279.565794) (xy 178.388008 -279.528957) (xy 178.426129 -279.497832) (xy 178.46875 -279.473225)
			(xy 178.514766 -279.455773) (xy 178.562985 -279.445929) (xy 178.61216 -279.443948) (xy 178.661015 -279.44988)
			(xy 178.708286 -279.463572) (xy 178.752748 -279.48467) (xy 178.793251 -279.512626) (xy 178.828744 -279.546718)
			(xy 178.858309 -279.586062) (xy 178.88118 -279.629639) (xy 178.896764 -279.67632) (xy 178.904659 -279.724897)
			(xy 178.905154 -279.749504) (xy 178.905149 -279.749758) (xy 179.244256 -279.749758) (xy 179.248216 -279.700704)
			(xy 179.259993 -279.65292) (xy 179.279284 -279.607644) (xy 179.305587 -279.566048) (xy 179.338222 -279.529211)
			(xy 179.376343 -279.498086) (xy 179.418964 -279.473479) (xy 179.46498 -279.456027) (xy 179.513199 -279.446183)
			(xy 179.562374 -279.444202) (xy 179.611229 -279.450134) (xy 179.6585 -279.463826) (xy 179.702962 -279.484924)
			(xy 179.743465 -279.51288) (xy 179.778958 -279.546972) (xy 179.808523 -279.586316) (xy 179.831394 -279.629893)
			(xy 179.846978 -279.676574) (xy 179.854873 -279.725151) (xy 179.855363 -279.749504) (xy 180.194216 -279.749504)
			(xy 180.198176 -279.70045) (xy 180.209953 -279.652666) (xy 180.229244 -279.60739) (xy 180.255547 -279.565794)
			(xy 180.288182 -279.528957) (xy 180.326303 -279.497832) (xy 180.368924 -279.473225) (xy 180.41494 -279.455773)
			(xy 180.463159 -279.445929) (xy 180.512334 -279.443948) (xy 180.561189 -279.44988) (xy 180.60846 -279.463572)
			(xy 180.652922 -279.48467) (xy 180.693425 -279.512626) (xy 180.728918 -279.546718) (xy 180.758483 -279.586062)
			(xy 180.781354 -279.629639) (xy 180.796938 -279.67632) (xy 180.804833 -279.724897) (xy 180.805328 -279.749504)
			(xy 180.805323 -279.749758) (xy 181.144176 -279.749758) (xy 181.148136 -279.700704) (xy 181.159913 -279.65292)
			(xy 181.179204 -279.607644) (xy 181.205507 -279.566048) (xy 181.238142 -279.529211) (xy 181.276263 -279.498086)
			(xy 181.318884 -279.473479) (xy 181.3649 -279.456027) (xy 181.413119 -279.446183) (xy 181.462294 -279.444202)
			(xy 181.511149 -279.450134) (xy 181.55842 -279.463826) (xy 181.602882 -279.484924) (xy 181.643385 -279.51288)
			(xy 181.678878 -279.546972) (xy 181.708443 -279.586316) (xy 181.731314 -279.629893) (xy 181.746898 -279.676574)
			(xy 181.754793 -279.725151) (xy 181.755283 -279.749504) (xy 182.094136 -279.749504) (xy 182.098096 -279.70045)
			(xy 182.109873 -279.652666) (xy 182.129164 -279.60739) (xy 182.155467 -279.565794) (xy 182.188102 -279.528957)
			(xy 182.226223 -279.497832) (xy 182.268844 -279.473225) (xy 182.31486 -279.455773) (xy 182.363079 -279.445929)
			(xy 182.412254 -279.443948) (xy 182.461109 -279.44988) (xy 182.50838 -279.463572) (xy 182.552842 -279.48467)
			(xy 182.593345 -279.512626) (xy 182.628838 -279.546718) (xy 182.658403 -279.586062) (xy 182.681274 -279.629639)
			(xy 182.696858 -279.67632) (xy 182.704753 -279.724897) (xy 182.705248 -279.749504) (xy 182.705243 -279.749758)
			(xy 183.044096 -279.749758) (xy 183.048056 -279.700704) (xy 183.059833 -279.65292) (xy 183.079124 -279.607644)
			(xy 183.105427 -279.566048) (xy 183.138062 -279.529211) (xy 183.176183 -279.498086) (xy 183.218804 -279.473479)
			(xy 183.26482 -279.456027) (xy 183.313039 -279.446183) (xy 183.362214 -279.444202) (xy 183.411069 -279.450134)
			(xy 183.45834 -279.463826) (xy 183.502802 -279.484924) (xy 183.543305 -279.51288) (xy 183.578798 -279.546972)
			(xy 183.608363 -279.586316) (xy 183.631234 -279.629893) (xy 183.646818 -279.676574) (xy 183.654713 -279.725151)
			(xy 183.655203 -279.749504) (xy 183.994056 -279.749504) (xy 183.998016 -279.70045) (xy 184.009793 -279.652666)
			(xy 184.029084 -279.60739) (xy 184.055387 -279.565794) (xy 184.088022 -279.528957) (xy 184.126143 -279.497832)
			(xy 184.168764 -279.473225) (xy 184.21478 -279.455773) (xy 184.262999 -279.445929) (xy 184.312174 -279.443948)
			(xy 184.361029 -279.44988) (xy 184.4083 -279.463572) (xy 184.452762 -279.48467) (xy 184.493265 -279.512626)
			(xy 184.528758 -279.546718) (xy 184.558323 -279.586062) (xy 184.581194 -279.629639) (xy 184.596778 -279.67632)
			(xy 184.604673 -279.724897) (xy 184.605168 -279.749504) (xy 184.605163 -279.749758) (xy 184.94427 -279.749758)
			(xy 184.94823 -279.700704) (xy 184.960007 -279.65292) (xy 184.979298 -279.607644) (xy 185.005601 -279.566048)
			(xy 185.038236 -279.529211) (xy 185.076357 -279.498086) (xy 185.118978 -279.473479) (xy 185.164994 -279.456027)
			(xy 185.213213 -279.446183) (xy 185.262388 -279.444202) (xy 185.311243 -279.450134) (xy 185.358514 -279.463826)
			(xy 185.402976 -279.484924) (xy 185.443479 -279.51288) (xy 185.478972 -279.546972) (xy 185.508537 -279.586316)
			(xy 185.531408 -279.629893) (xy 185.546992 -279.676574) (xy 185.554887 -279.725151) (xy 185.555377 -279.749504)
			(xy 185.89423 -279.749504) (xy 185.89819 -279.70045) (xy 185.909967 -279.652666) (xy 185.929258 -279.60739)
			(xy 185.955561 -279.565794) (xy 185.988196 -279.528957) (xy 186.026317 -279.497832) (xy 186.068938 -279.473225)
			(xy 186.114954 -279.455773) (xy 186.163173 -279.445929) (xy 186.212348 -279.443948) (xy 186.261203 -279.44988)
			(xy 186.308474 -279.463572) (xy 186.352936 -279.48467) (xy 186.393439 -279.512626) (xy 186.428932 -279.546718)
			(xy 186.458497 -279.586062) (xy 186.481368 -279.629639) (xy 186.496952 -279.67632) (xy 186.504847 -279.724897)
			(xy 186.505342 -279.749504) (xy 186.505337 -279.749758) (xy 186.84419 -279.749758) (xy 186.84815 -279.700704)
			(xy 186.859927 -279.65292) (xy 186.879218 -279.607644) (xy 186.905521 -279.566048) (xy 186.938156 -279.529211)
			(xy 186.976277 -279.498086) (xy 187.018898 -279.473479) (xy 187.064914 -279.456027) (xy 187.113133 -279.446183)
			(xy 187.162308 -279.444202) (xy 187.211163 -279.450134) (xy 187.258434 -279.463826) (xy 187.302896 -279.484924)
			(xy 187.343399 -279.51288) (xy 187.378892 -279.546972) (xy 187.408457 -279.586316) (xy 187.431328 -279.629893)
			(xy 187.446912 -279.676574) (xy 187.454807 -279.725151) (xy 187.455297 -279.749504) (xy 187.79415 -279.749504)
			(xy 187.79811 -279.70045) (xy 187.809887 -279.652666) (xy 187.829178 -279.60739) (xy 187.855481 -279.565794)
			(xy 187.888116 -279.528957) (xy 187.926237 -279.497832) (xy 187.968858 -279.473225) (xy 188.014874 -279.455773)
			(xy 188.063093 -279.445929) (xy 188.112268 -279.443948) (xy 188.161123 -279.44988) (xy 188.208394 -279.463572)
			(xy 188.252856 -279.48467) (xy 188.293359 -279.512626) (xy 188.328852 -279.546718) (xy 188.358417 -279.586062)
			(xy 188.381288 -279.629639) (xy 188.396872 -279.67632) (xy 188.404767 -279.724897) (xy 188.405262 -279.749504)
			(xy 188.405257 -279.749758) (xy 188.74411 -279.749758) (xy 188.74807 -279.700704) (xy 188.759847 -279.65292)
			(xy 188.779138 -279.607644) (xy 188.805441 -279.566048) (xy 188.838076 -279.529211) (xy 188.876197 -279.498086)
			(xy 188.918818 -279.473479) (xy 188.964834 -279.456027) (xy 189.013053 -279.446183) (xy 189.062228 -279.444202)
			(xy 189.111083 -279.450134) (xy 189.158354 -279.463826) (xy 189.202816 -279.484924) (xy 189.243319 -279.51288)
			(xy 189.278812 -279.546972) (xy 189.308377 -279.586316) (xy 189.331248 -279.629893) (xy 189.346832 -279.676574)
			(xy 189.354727 -279.725151) (xy 189.355217 -279.749504) (xy 189.69407 -279.749504) (xy 189.69803 -279.70045)
			(xy 189.709807 -279.652666) (xy 189.729098 -279.60739) (xy 189.755401 -279.565794) (xy 189.788036 -279.528957)
			(xy 189.826157 -279.497832) (xy 189.868778 -279.473225) (xy 189.914794 -279.455773) (xy 189.963013 -279.445929)
			(xy 190.012188 -279.443948) (xy 190.061043 -279.44988) (xy 190.108314 -279.463572) (xy 190.152776 -279.48467)
			(xy 190.193279 -279.512626) (xy 190.228772 -279.546718) (xy 190.258337 -279.586062) (xy 190.281208 -279.629639)
			(xy 190.296792 -279.67632) (xy 190.304687 -279.724897) (xy 190.305182 -279.749504) (xy 190.305177 -279.749758)
			(xy 190.64403 -279.749758) (xy 190.64799 -279.700704) (xy 190.659767 -279.65292) (xy 190.679058 -279.607644)
			(xy 190.705361 -279.566048) (xy 190.737996 -279.529211) (xy 190.776117 -279.498086) (xy 190.818738 -279.473479)
			(xy 190.864754 -279.456027) (xy 190.912973 -279.446183) (xy 190.962148 -279.444202) (xy 191.011003 -279.450134)
			(xy 191.058274 -279.463826) (xy 191.102736 -279.484924) (xy 191.143239 -279.51288) (xy 191.178732 -279.546972)
			(xy 191.208297 -279.586316) (xy 191.231168 -279.629893) (xy 191.246752 -279.676574) (xy 191.254647 -279.725151)
			(xy 191.255137 -279.749504) (xy 191.594244 -279.749504) (xy 191.598204 -279.70045) (xy 191.609981 -279.652666)
			(xy 191.629272 -279.60739) (xy 191.655575 -279.565794) (xy 191.68821 -279.528957) (xy 191.726331 -279.497832)
			(xy 191.768952 -279.473225) (xy 191.814968 -279.455773) (xy 191.863187 -279.445929) (xy 191.912362 -279.443948)
			(xy 191.961217 -279.44988) (xy 192.008488 -279.463572) (xy 192.05295 -279.48467) (xy 192.093453 -279.512626)
			(xy 192.128946 -279.546718) (xy 192.158511 -279.586062) (xy 192.181382 -279.629639) (xy 192.196966 -279.67632)
			(xy 192.204861 -279.724897) (xy 192.205356 -279.749504) (xy 192.205351 -279.749758) (xy 192.544204 -279.749758)
			(xy 192.548164 -279.700704) (xy 192.559941 -279.65292) (xy 192.579232 -279.607644) (xy 192.605535 -279.566048)
			(xy 192.63817 -279.529211) (xy 192.676291 -279.498086) (xy 192.718912 -279.473479) (xy 192.764928 -279.456027)
			(xy 192.813147 -279.446183) (xy 192.862322 -279.444202) (xy 192.911177 -279.450134) (xy 192.958448 -279.463826)
			(xy 193.00291 -279.484924) (xy 193.043413 -279.51288) (xy 193.078906 -279.546972) (xy 193.108471 -279.586316)
			(xy 193.131342 -279.629893) (xy 193.146926 -279.676574) (xy 193.154821 -279.725151) (xy 193.155311 -279.749504)
			(xy 193.494164 -279.749504) (xy 193.498124 -279.70045) (xy 193.509901 -279.652666) (xy 193.529192 -279.60739)
			(xy 193.555495 -279.565794) (xy 193.58813 -279.528957) (xy 193.626251 -279.497832) (xy 193.668872 -279.473225)
			(xy 193.714888 -279.455773) (xy 193.763107 -279.445929) (xy 193.812282 -279.443948) (xy 193.861137 -279.44988)
			(xy 193.908408 -279.463572) (xy 193.95287 -279.48467) (xy 193.993373 -279.512626) (xy 194.028866 -279.546718)
			(xy 194.058431 -279.586062) (xy 194.081302 -279.629639) (xy 194.096886 -279.67632) (xy 194.104781 -279.724897)
			(xy 194.105276 -279.749504) (xy 194.105271 -279.749758) (xy 194.444124 -279.749758) (xy 194.448084 -279.700704)
			(xy 194.459861 -279.65292) (xy 194.479152 -279.607644) (xy 194.505455 -279.566048) (xy 194.53809 -279.529211)
			(xy 194.576211 -279.498086) (xy 194.618832 -279.473479) (xy 194.664848 -279.456027) (xy 194.713067 -279.446183)
			(xy 194.762242 -279.444202) (xy 194.811097 -279.450134) (xy 194.858368 -279.463826) (xy 194.90283 -279.484924)
			(xy 194.943333 -279.51288) (xy 194.978826 -279.546972) (xy 195.008391 -279.586316) (xy 195.031262 -279.629893)
			(xy 195.046846 -279.676574) (xy 195.054741 -279.725151) (xy 195.055236 -279.749758) (xy 195.394084 -279.749758)
			(xy 195.398044 -279.700704) (xy 195.409821 -279.65292) (xy 195.429112 -279.607644) (xy 195.455415 -279.566048)
			(xy 195.48805 -279.529211) (xy 195.526171 -279.498086) (xy 195.568792 -279.473479) (xy 195.614808 -279.456027)
			(xy 195.663027 -279.446183) (xy 195.712202 -279.444202) (xy 195.761057 -279.450134) (xy 195.808328 -279.463826)
			(xy 195.85279 -279.484924) (xy 195.893293 -279.51288) (xy 195.928786 -279.546972) (xy 195.958351 -279.586316)
			(xy 195.981222 -279.629893) (xy 195.996806 -279.676574) (xy 196.004701 -279.725151) (xy 196.005196 -279.749758)
			(xy 196.344044 -279.749758) (xy 196.348004 -279.700704) (xy 196.359781 -279.65292) (xy 196.379072 -279.607644)
			(xy 196.405375 -279.566048) (xy 196.43801 -279.529211) (xy 196.476131 -279.498086) (xy 196.518752 -279.473479)
			(xy 196.564768 -279.456027) (xy 196.612987 -279.446183) (xy 196.662162 -279.444202) (xy 196.711017 -279.450134)
			(xy 196.758288 -279.463826) (xy 196.80275 -279.484924) (xy 196.843253 -279.51288) (xy 196.878746 -279.546972)
			(xy 196.908311 -279.586316) (xy 196.931182 -279.629893) (xy 196.946766 -279.676574) (xy 196.954661 -279.725151)
			(xy 196.955156 -279.749758) (xy 197.294258 -279.749758) (xy 197.298218 -279.700704) (xy 197.309995 -279.65292)
			(xy 197.329286 -279.607644) (xy 197.355589 -279.566048) (xy 197.388224 -279.529211) (xy 197.426345 -279.498086)
			(xy 197.468966 -279.473479) (xy 197.514982 -279.456027) (xy 197.563201 -279.446183) (xy 197.612376 -279.444202)
			(xy 197.661231 -279.450134) (xy 197.708502 -279.463826) (xy 197.752964 -279.484924) (xy 197.793467 -279.51288)
			(xy 197.82896 -279.546972) (xy 197.858525 -279.586316) (xy 197.881396 -279.629893) (xy 197.89698 -279.676574)
			(xy 197.904875 -279.725151) (xy 197.90537 -279.749758) (xy 198.244218 -279.749758) (xy 198.248178 -279.700704)
			(xy 198.259955 -279.65292) (xy 198.279246 -279.607644) (xy 198.305549 -279.566048) (xy 198.338184 -279.529211)
			(xy 198.376305 -279.498086) (xy 198.418926 -279.473479) (xy 198.464942 -279.456027) (xy 198.513161 -279.446183)
			(xy 198.562336 -279.444202) (xy 198.611191 -279.450134) (xy 198.658462 -279.463826) (xy 198.702924 -279.484924)
			(xy 198.743427 -279.51288) (xy 198.77892 -279.546972) (xy 198.808485 -279.586316) (xy 198.831356 -279.629893)
			(xy 198.84694 -279.676574) (xy 198.854835 -279.725151) (xy 198.85533 -279.749758) (xy 198.855325 -279.750012)
			(xy 199.194432 -279.750012) (xy 199.198392 -279.700958) (xy 199.210169 -279.653174) (xy 199.22946 -279.607898)
			(xy 199.255763 -279.566302) (xy 199.288398 -279.529465) (xy 199.326519 -279.49834) (xy 199.36914 -279.473733)
			(xy 199.415156 -279.456281) (xy 199.463375 -279.446437) (xy 199.51255 -279.444456) (xy 199.561405 -279.450388)
			(xy 199.608676 -279.46408) (xy 199.653138 -279.485178) (xy 199.693641 -279.513134) (xy 199.729134 -279.547226)
			(xy 199.744283 -279.567386) (xy 230.452928 -279.567386) (xy 230.456999 -279.511764) (xy 230.469125 -279.457327)
			(xy 230.489048 -279.405236) (xy 230.516344 -279.356601) (xy 230.55043 -279.312458) (xy 230.590579 -279.273749)
			(xy 230.635937 -279.241298) (xy 230.685537 -279.215797) (xy 230.738321 -279.19779) (xy 230.793164 -279.18766)
			(xy 230.848898 -279.185623) (xy 230.904335 -279.191723) (xy 230.958292 -279.205829) (xy 231.009621 -279.227641)
			(xy 231.057227 -279.256695) (xy 231.100095 -279.29237) (xy 231.137312 -279.333907) (xy 231.168085 -279.38042)
			(xy 231.191757 -279.430917) (xy 231.207825 -279.484324) (xy 231.215945 -279.5395) (xy 231.216454 -279.567386)
			(xy 231.215945 -279.595272) (xy 231.207825 -279.650448) (xy 231.191757 -279.703855) (xy 231.168085 -279.754352)
			(xy 231.137312 -279.800865) (xy 231.100095 -279.842402) (xy 231.057227 -279.878077) (xy 231.009621 -279.907131)
			(xy 230.958292 -279.928943) (xy 230.904335 -279.943049) (xy 230.848898 -279.949149) (xy 230.793164 -279.947112)
			(xy 230.738321 -279.936982) (xy 230.685537 -279.918975) (xy 230.635937 -279.893474) (xy 230.590579 -279.861023)
			(xy 230.55043 -279.822314) (xy 230.516344 -279.778171) (xy 230.489048 -279.729536) (xy 230.469125 -279.677445)
			(xy 230.456999 -279.623008) (xy 230.452928 -279.567386) (xy 199.744283 -279.567386) (xy 199.758699 -279.58657)
			(xy 199.78157 -279.630147) (xy 199.797154 -279.676828) (xy 199.805049 -279.725405) (xy 199.805544 -279.750012)
			(xy 199.805049 -279.774619) (xy 199.797154 -279.823196) (xy 199.78157 -279.869877) (xy 199.758699 -279.913454)
			(xy 199.729134 -279.952798) (xy 199.693641 -279.98689) (xy 199.653138 -280.014846) (xy 199.608676 -280.035944)
			(xy 199.561405 -280.049636) (xy 199.51255 -280.055568) (xy 199.463375 -280.053587) (xy 199.415156 -280.043743)
			(xy 199.36914 -280.026291) (xy 199.326519 -280.001684) (xy 199.288398 -279.970559) (xy 199.255763 -279.933722)
			(xy 199.22946 -279.892126) (xy 199.210169 -279.84685) (xy 199.198392 -279.799066) (xy 199.194432 -279.750012)
			(xy 198.855325 -279.750012) (xy 198.854835 -279.774365) (xy 198.84694 -279.822942) (xy 198.831356 -279.869623)
			(xy 198.808485 -279.9132) (xy 198.77892 -279.952544) (xy 198.743427 -279.986636) (xy 198.702924 -280.014592)
			(xy 198.658462 -280.03569) (xy 198.611191 -280.049382) (xy 198.562336 -280.055314) (xy 198.513161 -280.053333)
			(xy 198.464942 -280.043489) (xy 198.418926 -280.026037) (xy 198.376305 -280.00143) (xy 198.338184 -279.970305)
			(xy 198.305549 -279.933468) (xy 198.279246 -279.891872) (xy 198.259955 -279.846596) (xy 198.248178 -279.798812)
			(xy 198.244218 -279.749758) (xy 197.90537 -279.749758) (xy 197.904875 -279.774365) (xy 197.89698 -279.822942)
			(xy 197.881396 -279.869623) (xy 197.858525 -279.9132) (xy 197.82896 -279.952544) (xy 197.793467 -279.986636)
			(xy 197.752964 -280.014592) (xy 197.708502 -280.03569) (xy 197.661231 -280.049382) (xy 197.612376 -280.055314)
			(xy 197.563201 -280.053333) (xy 197.514982 -280.043489) (xy 197.468966 -280.026037) (xy 197.426345 -280.00143)
			(xy 197.388224 -279.970305) (xy 197.355589 -279.933468) (xy 197.329286 -279.891872) (xy 197.309995 -279.846596)
			(xy 197.298218 -279.798812) (xy 197.294258 -279.749758) (xy 196.955156 -279.749758) (xy 196.954661 -279.774365)
			(xy 196.946766 -279.822942) (xy 196.931182 -279.869623) (xy 196.908311 -279.9132) (xy 196.878746 -279.952544)
			(xy 196.843253 -279.986636) (xy 196.80275 -280.014592) (xy 196.758288 -280.03569) (xy 196.711017 -280.049382)
			(xy 196.662162 -280.055314) (xy 196.612987 -280.053333) (xy 196.564768 -280.043489) (xy 196.518752 -280.026037)
			(xy 196.476131 -280.00143) (xy 196.43801 -279.970305) (xy 196.405375 -279.933468) (xy 196.379072 -279.891872)
			(xy 196.359781 -279.846596) (xy 196.348004 -279.798812) (xy 196.344044 -279.749758) (xy 196.005196 -279.749758)
			(xy 196.004701 -279.774365) (xy 195.996806 -279.822942) (xy 195.981222 -279.869623) (xy 195.958351 -279.9132)
			(xy 195.928786 -279.952544) (xy 195.893293 -279.986636) (xy 195.85279 -280.014592) (xy 195.808328 -280.03569)
			(xy 195.761057 -280.049382) (xy 195.712202 -280.055314) (xy 195.663027 -280.053333) (xy 195.614808 -280.043489)
			(xy 195.568792 -280.026037) (xy 195.526171 -280.00143) (xy 195.48805 -279.970305) (xy 195.455415 -279.933468)
			(xy 195.429112 -279.891872) (xy 195.409821 -279.846596) (xy 195.398044 -279.798812) (xy 195.394084 -279.749758)
			(xy 195.055236 -279.749758) (xy 195.054741 -279.774365) (xy 195.046846 -279.822942) (xy 195.031262 -279.869623)
			(xy 195.008391 -279.9132) (xy 194.978826 -279.952544) (xy 194.943333 -279.986636) (xy 194.90283 -280.014592)
			(xy 194.858368 -280.03569) (xy 194.811097 -280.049382) (xy 194.762242 -280.055314) (xy 194.713067 -280.053333)
			(xy 194.664848 -280.043489) (xy 194.618832 -280.026037) (xy 194.576211 -280.00143) (xy 194.53809 -279.970305)
			(xy 194.505455 -279.933468) (xy 194.479152 -279.891872) (xy 194.459861 -279.846596) (xy 194.448084 -279.798812)
			(xy 194.444124 -279.749758) (xy 194.105271 -279.749758) (xy 194.104781 -279.774111) (xy 194.096886 -279.822688)
			(xy 194.081302 -279.869369) (xy 194.058431 -279.912946) (xy 194.028866 -279.95229) (xy 193.993373 -279.986382)
			(xy 193.95287 -280.014338) (xy 193.908408 -280.035436) (xy 193.861137 -280.049128) (xy 193.812282 -280.05506)
			(xy 193.763107 -280.053079) (xy 193.714888 -280.043235) (xy 193.668872 -280.025783) (xy 193.626251 -280.001176)
			(xy 193.58813 -279.970051) (xy 193.555495 -279.933214) (xy 193.529192 -279.891618) (xy 193.509901 -279.846342)
			(xy 193.498124 -279.798558) (xy 193.494164 -279.749504) (xy 193.155311 -279.749504) (xy 193.155316 -279.749758)
			(xy 193.154821 -279.774365) (xy 193.146926 -279.822942) (xy 193.131342 -279.869623) (xy 193.108471 -279.9132)
			(xy 193.078906 -279.952544) (xy 193.043413 -279.986636) (xy 193.00291 -280.014592) (xy 192.958448 -280.03569)
			(xy 192.911177 -280.049382) (xy 192.862322 -280.055314) (xy 192.813147 -280.053333) (xy 192.764928 -280.043489)
			(xy 192.718912 -280.026037) (xy 192.676291 -280.00143) (xy 192.63817 -279.970305) (xy 192.605535 -279.933468)
			(xy 192.579232 -279.891872) (xy 192.559941 -279.846596) (xy 192.548164 -279.798812) (xy 192.544204 -279.749758)
			(xy 192.205351 -279.749758) (xy 192.204861 -279.774111) (xy 192.196966 -279.822688) (xy 192.181382 -279.869369)
			(xy 192.158511 -279.912946) (xy 192.128946 -279.95229) (xy 192.093453 -279.986382) (xy 192.05295 -280.014338)
			(xy 192.008488 -280.035436) (xy 191.961217 -280.049128) (xy 191.912362 -280.05506) (xy 191.863187 -280.053079)
			(xy 191.814968 -280.043235) (xy 191.768952 -280.025783) (xy 191.726331 -280.001176) (xy 191.68821 -279.970051)
			(xy 191.655575 -279.933214) (xy 191.629272 -279.891618) (xy 191.609981 -279.846342) (xy 191.598204 -279.798558)
			(xy 191.594244 -279.749504) (xy 191.255137 -279.749504) (xy 191.255142 -279.749758) (xy 191.254647 -279.774365)
			(xy 191.246752 -279.822942) (xy 191.231168 -279.869623) (xy 191.208297 -279.9132) (xy 191.178732 -279.952544)
			(xy 191.143239 -279.986636) (xy 191.102736 -280.014592) (xy 191.058274 -280.03569) (xy 191.011003 -280.049382)
			(xy 190.962148 -280.055314) (xy 190.912973 -280.053333) (xy 190.864754 -280.043489) (xy 190.818738 -280.026037)
			(xy 190.776117 -280.00143) (xy 190.737996 -279.970305) (xy 190.705361 -279.933468) (xy 190.679058 -279.891872)
			(xy 190.659767 -279.846596) (xy 190.64799 -279.798812) (xy 190.64403 -279.749758) (xy 190.305177 -279.749758)
			(xy 190.304687 -279.774111) (xy 190.296792 -279.822688) (xy 190.281208 -279.869369) (xy 190.258337 -279.912946)
			(xy 190.228772 -279.95229) (xy 190.193279 -279.986382) (xy 190.152776 -280.014338) (xy 190.108314 -280.035436)
			(xy 190.061043 -280.049128) (xy 190.012188 -280.05506) (xy 189.963013 -280.053079) (xy 189.914794 -280.043235)
			(xy 189.868778 -280.025783) (xy 189.826157 -280.001176) (xy 189.788036 -279.970051) (xy 189.755401 -279.933214)
			(xy 189.729098 -279.891618) (xy 189.709807 -279.846342) (xy 189.69803 -279.798558) (xy 189.69407 -279.749504)
			(xy 189.355217 -279.749504) (xy 189.355222 -279.749758) (xy 189.354727 -279.774365) (xy 189.346832 -279.822942)
			(xy 189.331248 -279.869623) (xy 189.308377 -279.9132) (xy 189.278812 -279.952544) (xy 189.243319 -279.986636)
			(xy 189.202816 -280.014592) (xy 189.158354 -280.03569) (xy 189.111083 -280.049382) (xy 189.062228 -280.055314)
			(xy 189.013053 -280.053333) (xy 188.964834 -280.043489) (xy 188.918818 -280.026037) (xy 188.876197 -280.00143)
			(xy 188.838076 -279.970305) (xy 188.805441 -279.933468) (xy 188.779138 -279.891872) (xy 188.759847 -279.846596)
			(xy 188.74807 -279.798812) (xy 188.74411 -279.749758) (xy 188.405257 -279.749758) (xy 188.404767 -279.774111)
			(xy 188.396872 -279.822688) (xy 188.381288 -279.869369) (xy 188.358417 -279.912946) (xy 188.328852 -279.95229)
			(xy 188.293359 -279.986382) (xy 188.252856 -280.014338) (xy 188.208394 -280.035436) (xy 188.161123 -280.049128)
			(xy 188.112268 -280.05506) (xy 188.063093 -280.053079) (xy 188.014874 -280.043235) (xy 187.968858 -280.025783)
			(xy 187.926237 -280.001176) (xy 187.888116 -279.970051) (xy 187.855481 -279.933214) (xy 187.829178 -279.891618)
			(xy 187.809887 -279.846342) (xy 187.79811 -279.798558) (xy 187.79415 -279.749504) (xy 187.455297 -279.749504)
			(xy 187.455302 -279.749758) (xy 187.454807 -279.774365) (xy 187.446912 -279.822942) (xy 187.431328 -279.869623)
			(xy 187.408457 -279.9132) (xy 187.378892 -279.952544) (xy 187.343399 -279.986636) (xy 187.302896 -280.014592)
			(xy 187.258434 -280.03569) (xy 187.211163 -280.049382) (xy 187.162308 -280.055314) (xy 187.113133 -280.053333)
			(xy 187.064914 -280.043489) (xy 187.018898 -280.026037) (xy 186.976277 -280.00143) (xy 186.938156 -279.970305)
			(xy 186.905521 -279.933468) (xy 186.879218 -279.891872) (xy 186.859927 -279.846596) (xy 186.84815 -279.798812)
			(xy 186.84419 -279.749758) (xy 186.505337 -279.749758) (xy 186.504847 -279.774111) (xy 186.496952 -279.822688)
			(xy 186.481368 -279.869369) (xy 186.458497 -279.912946) (xy 186.428932 -279.95229) (xy 186.393439 -279.986382)
			(xy 186.352936 -280.014338) (xy 186.308474 -280.035436) (xy 186.261203 -280.049128) (xy 186.212348 -280.05506)
			(xy 186.163173 -280.053079) (xy 186.114954 -280.043235) (xy 186.068938 -280.025783) (xy 186.026317 -280.001176)
			(xy 185.988196 -279.970051) (xy 185.955561 -279.933214) (xy 185.929258 -279.891618) (xy 185.909967 -279.846342)
			(xy 185.89819 -279.798558) (xy 185.89423 -279.749504) (xy 185.555377 -279.749504) (xy 185.555382 -279.749758)
			(xy 185.554887 -279.774365) (xy 185.546992 -279.822942) (xy 185.531408 -279.869623) (xy 185.508537 -279.9132)
			(xy 185.478972 -279.952544) (xy 185.443479 -279.986636) (xy 185.402976 -280.014592) (xy 185.358514 -280.03569)
			(xy 185.311243 -280.049382) (xy 185.262388 -280.055314) (xy 185.213213 -280.053333) (xy 185.164994 -280.043489)
			(xy 185.118978 -280.026037) (xy 185.076357 -280.00143) (xy 185.038236 -279.970305) (xy 185.005601 -279.933468)
			(xy 184.979298 -279.891872) (xy 184.960007 -279.846596) (xy 184.94823 -279.798812) (xy 184.94427 -279.749758)
			(xy 184.605163 -279.749758) (xy 184.604673 -279.774111) (xy 184.596778 -279.822688) (xy 184.581194 -279.869369)
			(xy 184.558323 -279.912946) (xy 184.528758 -279.95229) (xy 184.493265 -279.986382) (xy 184.452762 -280.014338)
			(xy 184.4083 -280.035436) (xy 184.361029 -280.049128) (xy 184.312174 -280.05506) (xy 184.262999 -280.053079)
			(xy 184.21478 -280.043235) (xy 184.168764 -280.025783) (xy 184.126143 -280.001176) (xy 184.088022 -279.970051)
			(xy 184.055387 -279.933214) (xy 184.029084 -279.891618) (xy 184.009793 -279.846342) (xy 183.998016 -279.798558)
			(xy 183.994056 -279.749504) (xy 183.655203 -279.749504) (xy 183.655208 -279.749758) (xy 183.654713 -279.774365)
			(xy 183.646818 -279.822942) (xy 183.631234 -279.869623) (xy 183.608363 -279.9132) (xy 183.578798 -279.952544)
			(xy 183.543305 -279.986636) (xy 183.502802 -280.014592) (xy 183.45834 -280.03569) (xy 183.411069 -280.049382)
			(xy 183.362214 -280.055314) (xy 183.313039 -280.053333) (xy 183.26482 -280.043489) (xy 183.218804 -280.026037)
			(xy 183.176183 -280.00143) (xy 183.138062 -279.970305) (xy 183.105427 -279.933468) (xy 183.079124 -279.891872)
			(xy 183.059833 -279.846596) (xy 183.048056 -279.798812) (xy 183.044096 -279.749758) (xy 182.705243 -279.749758)
			(xy 182.704753 -279.774111) (xy 182.696858 -279.822688) (xy 182.681274 -279.869369) (xy 182.658403 -279.912946)
			(xy 182.628838 -279.95229) (xy 182.593345 -279.986382) (xy 182.552842 -280.014338) (xy 182.50838 -280.035436)
			(xy 182.461109 -280.049128) (xy 182.412254 -280.05506) (xy 182.363079 -280.053079) (xy 182.31486 -280.043235)
			(xy 182.268844 -280.025783) (xy 182.226223 -280.001176) (xy 182.188102 -279.970051) (xy 182.155467 -279.933214)
			(xy 182.129164 -279.891618) (xy 182.109873 -279.846342) (xy 182.098096 -279.798558) (xy 182.094136 -279.749504)
			(xy 181.755283 -279.749504) (xy 181.755288 -279.749758) (xy 181.754793 -279.774365) (xy 181.746898 -279.822942)
			(xy 181.731314 -279.869623) (xy 181.708443 -279.9132) (xy 181.678878 -279.952544) (xy 181.643385 -279.986636)
			(xy 181.602882 -280.014592) (xy 181.55842 -280.03569) (xy 181.511149 -280.049382) (xy 181.462294 -280.055314)
			(xy 181.413119 -280.053333) (xy 181.3649 -280.043489) (xy 181.318884 -280.026037) (xy 181.276263 -280.00143)
			(xy 181.238142 -279.970305) (xy 181.205507 -279.933468) (xy 181.179204 -279.891872) (xy 181.159913 -279.846596)
			(xy 181.148136 -279.798812) (xy 181.144176 -279.749758) (xy 180.805323 -279.749758) (xy 180.804833 -279.774111)
			(xy 180.796938 -279.822688) (xy 180.781354 -279.869369) (xy 180.758483 -279.912946) (xy 180.728918 -279.95229)
			(xy 180.693425 -279.986382) (xy 180.652922 -280.014338) (xy 180.60846 -280.035436) (xy 180.561189 -280.049128)
			(xy 180.512334 -280.05506) (xy 180.463159 -280.053079) (xy 180.41494 -280.043235) (xy 180.368924 -280.025783)
			(xy 180.326303 -280.001176) (xy 180.288182 -279.970051) (xy 180.255547 -279.933214) (xy 180.229244 -279.891618)
			(xy 180.209953 -279.846342) (xy 180.198176 -279.798558) (xy 180.194216 -279.749504) (xy 179.855363 -279.749504)
			(xy 179.855368 -279.749758) (xy 179.854873 -279.774365) (xy 179.846978 -279.822942) (xy 179.831394 -279.869623)
			(xy 179.808523 -279.9132) (xy 179.778958 -279.952544) (xy 179.743465 -279.986636) (xy 179.702962 -280.014592)
			(xy 179.6585 -280.03569) (xy 179.611229 -280.049382) (xy 179.562374 -280.055314) (xy 179.513199 -280.053333)
			(xy 179.46498 -280.043489) (xy 179.418964 -280.026037) (xy 179.376343 -280.00143) (xy 179.338222 -279.970305)
			(xy 179.305587 -279.933468) (xy 179.279284 -279.891872) (xy 179.259993 -279.846596) (xy 179.248216 -279.798812)
			(xy 179.244256 -279.749758) (xy 178.905149 -279.749758) (xy 178.904659 -279.774111) (xy 178.896764 -279.822688)
			(xy 178.88118 -279.869369) (xy 178.858309 -279.912946) (xy 178.828744 -279.95229) (xy 178.793251 -279.986382)
			(xy 178.752748 -280.014338) (xy 178.708286 -280.035436) (xy 178.661015 -280.049128) (xy 178.61216 -280.05506)
			(xy 178.562985 -280.053079) (xy 178.514766 -280.043235) (xy 178.46875 -280.025783) (xy 178.426129 -280.001176)
			(xy 178.388008 -279.970051) (xy 178.355373 -279.933214) (xy 178.32907 -279.891618) (xy 178.309779 -279.846342)
			(xy 178.298002 -279.798558) (xy 178.294042 -279.749504) (xy 177.955189 -279.749504) (xy 177.955194 -279.749758)
			(xy 177.954699 -279.774365) (xy 177.946804 -279.822942) (xy 177.93122 -279.869623) (xy 177.908349 -279.9132)
			(xy 177.878784 -279.952544) (xy 177.843291 -279.986636) (xy 177.802788 -280.014592) (xy 177.758326 -280.03569)
			(xy 177.711055 -280.049382) (xy 177.6622 -280.055314) (xy 177.613025 -280.053333) (xy 177.564806 -280.043489)
			(xy 177.51879 -280.026037) (xy 177.476169 -280.00143) (xy 177.438048 -279.970305) (xy 177.405413 -279.933468)
			(xy 177.37911 -279.891872) (xy 177.359819 -279.846596) (xy 177.348042 -279.798812) (xy 177.344082 -279.749758)
			(xy 177.005229 -279.749758) (xy 177.004739 -279.774111) (xy 176.996844 -279.822688) (xy 176.98126 -279.869369)
			(xy 176.958389 -279.912946) (xy 176.928824 -279.95229) (xy 176.893331 -279.986382) (xy 176.852828 -280.014338)
			(xy 176.808366 -280.035436) (xy 176.761095 -280.049128) (xy 176.71224 -280.05506) (xy 176.663065 -280.053079)
			(xy 176.614846 -280.043235) (xy 176.56883 -280.025783) (xy 176.526209 -280.001176) (xy 176.488088 -279.970051)
			(xy 176.455453 -279.933214) (xy 176.42915 -279.891618) (xy 176.409859 -279.846342) (xy 176.398082 -279.798558)
			(xy 176.394122 -279.749504) (xy 176.055269 -279.749504) (xy 176.055274 -279.749758) (xy 176.054779 -279.774365)
			(xy 176.046884 -279.822942) (xy 176.0313 -279.869623) (xy 176.008429 -279.9132) (xy 175.978864 -279.952544)
			(xy 175.943371 -279.986636) (xy 175.902868 -280.014592) (xy 175.858406 -280.03569) (xy 175.811135 -280.049382)
			(xy 175.76228 -280.055314) (xy 175.713105 -280.053333) (xy 175.664886 -280.043489) (xy 175.61887 -280.026037)
			(xy 175.576249 -280.00143) (xy 175.538128 -279.970305) (xy 175.505493 -279.933468) (xy 175.47919 -279.891872)
			(xy 175.459899 -279.846596) (xy 175.448122 -279.798812) (xy 175.444162 -279.749758) (xy 175.105309 -279.749758)
			(xy 175.104819 -279.774111) (xy 175.096924 -279.822688) (xy 175.08134 -279.869369) (xy 175.058469 -279.912946)
			(xy 175.028904 -279.95229) (xy 174.993411 -279.986382) (xy 174.952908 -280.014338) (xy 174.908446 -280.035436)
			(xy 174.861175 -280.049128) (xy 174.81232 -280.05506) (xy 174.763145 -280.053079) (xy 174.714926 -280.043235)
			(xy 174.66891 -280.025783) (xy 174.626289 -280.001176) (xy 174.588168 -279.970051) (xy 174.555533 -279.933214)
			(xy 174.52923 -279.891618) (xy 174.509939 -279.846342) (xy 174.498162 -279.798558) (xy 174.494202 -279.749504)
			(xy 174.155349 -279.749504) (xy 174.155354 -279.749758) (xy 174.154859 -279.774365) (xy 174.146964 -279.822942)
			(xy 174.13138 -279.869623) (xy 174.108509 -279.9132) (xy 174.078944 -279.952544) (xy 174.043451 -279.986636)
			(xy 174.002948 -280.014592) (xy 173.958486 -280.03569) (xy 173.911215 -280.049382) (xy 173.86236 -280.055314)
			(xy 173.813185 -280.053333) (xy 173.764966 -280.043489) (xy 173.71895 -280.026037) (xy 173.676329 -280.00143)
			(xy 173.638208 -279.970305) (xy 173.605573 -279.933468) (xy 173.57927 -279.891872) (xy 173.559979 -279.846596)
			(xy 173.548202 -279.798812) (xy 173.544242 -279.749758) (xy 173.205135 -279.749758) (xy 173.204645 -279.774111)
			(xy 173.19675 -279.822688) (xy 173.181166 -279.869369) (xy 173.158295 -279.912946) (xy 173.12873 -279.95229)
			(xy 173.093237 -279.986382) (xy 173.052734 -280.014338) (xy 173.008272 -280.035436) (xy 172.961001 -280.049128)
			(xy 172.912146 -280.05506) (xy 172.862971 -280.053079) (xy 172.814752 -280.043235) (xy 172.768736 -280.025783)
			(xy 172.726115 -280.001176) (xy 172.687994 -279.970051) (xy 172.655359 -279.933214) (xy 172.629056 -279.891618)
			(xy 172.609765 -279.846342) (xy 172.597988 -279.798558) (xy 172.594028 -279.749504) (xy 172.255175 -279.749504)
			(xy 172.25518 -279.749758) (xy 172.254685 -279.774365) (xy 172.24679 -279.822942) (xy 172.231206 -279.869623)
			(xy 172.208335 -279.9132) (xy 172.17877 -279.952544) (xy 172.143277 -279.986636) (xy 172.102774 -280.014592)
			(xy 172.058312 -280.03569) (xy 172.011041 -280.049382) (xy 171.962186 -280.055314) (xy 171.913011 -280.053333)
			(xy 171.864792 -280.043489) (xy 171.818776 -280.026037) (xy 171.776155 -280.00143) (xy 171.738034 -279.970305)
			(xy 171.705399 -279.933468) (xy 171.679096 -279.891872) (xy 171.659805 -279.846596) (xy 171.648028 -279.798812)
			(xy 171.644068 -279.749758) (xy 171.305215 -279.749758) (xy 171.304725 -279.774111) (xy 171.29683 -279.822688)
			(xy 171.281246 -279.869369) (xy 171.258375 -279.912946) (xy 171.22881 -279.95229) (xy 171.193317 -279.986382)
			(xy 171.152814 -280.014338) (xy 171.108352 -280.035436) (xy 171.061081 -280.049128) (xy 171.012226 -280.05506)
			(xy 170.963051 -280.053079) (xy 170.914832 -280.043235) (xy 170.868816 -280.025783) (xy 170.826195 -280.001176)
			(xy 170.788074 -279.970051) (xy 170.755439 -279.933214) (xy 170.729136 -279.891618) (xy 170.709845 -279.846342)
			(xy 170.698068 -279.798558) (xy 170.694108 -279.749504) (xy 170.355255 -279.749504) (xy 170.35526 -279.749758)
			(xy 170.354765 -279.774365) (xy 170.34687 -279.822942) (xy 170.331286 -279.869623) (xy 170.308415 -279.9132)
			(xy 170.27885 -279.952544) (xy 170.243357 -279.986636) (xy 170.202854 -280.014592) (xy 170.158392 -280.03569)
			(xy 170.111121 -280.049382) (xy 170.062266 -280.055314) (xy 170.013091 -280.053333) (xy 169.964872 -280.043489)
			(xy 169.918856 -280.026037) (xy 169.876235 -280.00143) (xy 169.838114 -279.970305) (xy 169.805479 -279.933468)
			(xy 169.779176 -279.891872) (xy 169.759885 -279.846596) (xy 169.748108 -279.798812) (xy 169.744148 -279.749758)
			(xy 169.405295 -279.749758) (xy 169.404805 -279.774111) (xy 169.39691 -279.822688) (xy 169.381326 -279.869369)
			(xy 169.358455 -279.912946) (xy 169.32889 -279.95229) (xy 169.293397 -279.986382) (xy 169.252894 -280.014338)
			(xy 169.208432 -280.035436) (xy 169.161161 -280.049128) (xy 169.112306 -280.05506) (xy 169.063131 -280.053079)
			(xy 169.014912 -280.043235) (xy 168.968896 -280.025783) (xy 168.926275 -280.001176) (xy 168.888154 -279.970051)
			(xy 168.855519 -279.933214) (xy 168.829216 -279.891618) (xy 168.809925 -279.846342) (xy 168.798148 -279.798558)
			(xy 168.794188 -279.749504) (xy 168.455335 -279.749504) (xy 168.45534 -279.749758) (xy 168.454845 -279.774365)
			(xy 168.44695 -279.822942) (xy 168.431366 -279.869623) (xy 168.408495 -279.9132) (xy 168.37893 -279.952544)
			(xy 168.343437 -279.986636) (xy 168.302934 -280.014592) (xy 168.258472 -280.03569) (xy 168.211201 -280.049382)
			(xy 168.162346 -280.055314) (xy 168.113171 -280.053333) (xy 168.064952 -280.043489) (xy 168.018936 -280.026037)
			(xy 167.976315 -280.00143) (xy 167.938194 -279.970305) (xy 167.905559 -279.933468) (xy 167.879256 -279.891872)
			(xy 167.859965 -279.846596) (xy 167.848188 -279.798812) (xy 167.844228 -279.749758) (xy 167.505375 -279.749758)
			(xy 167.504885 -279.774111) (xy 167.49699 -279.822688) (xy 167.481406 -279.869369) (xy 167.458535 -279.912946)
			(xy 167.42897 -279.95229) (xy 167.393477 -279.986382) (xy 167.352974 -280.014338) (xy 167.308512 -280.035436)
			(xy 167.261241 -280.049128) (xy 167.212386 -280.05506) (xy 167.163211 -280.053079) (xy 167.114992 -280.043235)
			(xy 167.068976 -280.025783) (xy 167.026355 -280.001176) (xy 166.988234 -279.970051) (xy 166.955599 -279.933214)
			(xy 166.929296 -279.891618) (xy 166.910005 -279.846342) (xy 166.898228 -279.798558) (xy 166.894268 -279.749504)
			(xy 166.555161 -279.749504) (xy 166.555166 -279.749758) (xy 166.554671 -279.774365) (xy 166.546776 -279.822942)
			(xy 166.531192 -279.869623) (xy 166.508321 -279.9132) (xy 166.478756 -279.952544) (xy 166.443263 -279.986636)
			(xy 166.40276 -280.014592) (xy 166.358298 -280.03569) (xy 166.311027 -280.049382) (xy 166.262172 -280.055314)
			(xy 166.212997 -280.053333) (xy 166.164778 -280.043489) (xy 166.118762 -280.026037) (xy 166.076141 -280.00143)
			(xy 166.03802 -279.970305) (xy 166.005385 -279.933468) (xy 165.979082 -279.891872) (xy 165.959791 -279.846596)
			(xy 165.948014 -279.798812) (xy 165.944054 -279.749758) (xy 165.605201 -279.749758) (xy 165.604711 -279.774111)
			(xy 165.596816 -279.822688) (xy 165.581232 -279.869369) (xy 165.558361 -279.912946) (xy 165.528796 -279.95229)
			(xy 165.493303 -279.986382) (xy 165.4528 -280.014338) (xy 165.408338 -280.035436) (xy 165.361067 -280.049128)
			(xy 165.312212 -280.05506) (xy 165.263037 -280.053079) (xy 165.214818 -280.043235) (xy 165.168802 -280.025783)
			(xy 165.126181 -280.001176) (xy 165.08806 -279.970051) (xy 165.055425 -279.933214) (xy 165.029122 -279.891618)
			(xy 165.009831 -279.846342) (xy 164.998054 -279.798558) (xy 164.994094 -279.749504) (xy 164.654846 -279.749504)
			(xy 164.654847 -279.77385) (xy 164.647305 -279.821367) (xy 164.632405 -279.867113) (xy 164.610516 -279.909958)
			(xy 164.58218 -279.94884) (xy 164.548098 -279.982799) (xy 164.509114 -280.010994) (xy 164.46619 -280.032727)
			(xy 164.42039 -280.047462) (xy 164.396674 -280.05151) (xy 164.378132 -280.054304) (xy 164.353748 -280.082752)
			(xy 164.353748 -280.10104) (xy 224.384106 -280.10104) (xy 224.388177 -280.045418) (xy 224.400303 -279.990981)
			(xy 224.420226 -279.93889) (xy 224.447522 -279.890255) (xy 224.481608 -279.846112) (xy 224.521757 -279.807403)
			(xy 224.567115 -279.774952) (xy 224.616715 -279.749451) (xy 224.669499 -279.731444) (xy 224.724342 -279.721314)
			(xy 224.780076 -279.719277) (xy 224.835513 -279.725377) (xy 224.88947 -279.739483) (xy 224.940799 -279.761295)
			(xy 224.988405 -279.790349) (xy 225.031273 -279.826024) (xy 225.06849 -279.867561) (xy 225.099263 -279.914074)
			(xy 225.122935 -279.964571) (xy 225.139003 -280.017978) (xy 225.147123 -280.073154) (xy 225.147632 -280.10104)
			(xy 226.403406 -280.10104) (xy 226.407477 -280.045418) (xy 226.419603 -279.990981) (xy 226.439526 -279.93889)
			(xy 226.466822 -279.890255) (xy 226.500908 -279.846112) (xy 226.541057 -279.807403) (xy 226.586415 -279.774952)
			(xy 226.636015 -279.749451) (xy 226.688799 -279.731444) (xy 226.743642 -279.721314) (xy 226.799376 -279.719277)
			(xy 226.854813 -279.725377) (xy 226.90877 -279.739483) (xy 226.960099 -279.761295) (xy 227.007705 -279.790349)
			(xy 227.050573 -279.826024) (xy 227.08779 -279.867561) (xy 227.118563 -279.914074) (xy 227.142235 -279.964571)
			(xy 227.158303 -280.017978) (xy 227.166423 -280.073154) (xy 227.166932 -280.10104) (xy 227.166423 -280.128926)
			(xy 227.158303 -280.184102) (xy 227.142235 -280.237509) (xy 227.118563 -280.288006) (xy 227.08779 -280.334519)
			(xy 227.050573 -280.376056) (xy 227.007705 -280.411731) (xy 226.960099 -280.440785) (xy 226.90877 -280.462597)
			(xy 226.854813 -280.476703) (xy 226.799376 -280.482803) (xy 226.743642 -280.480766) (xy 226.688799 -280.470636)
			(xy 226.636015 -280.452629) (xy 226.586415 -280.427128) (xy 226.541057 -280.394677) (xy 226.500908 -280.355968)
			(xy 226.466822 -280.311825) (xy 226.439526 -280.26319) (xy 226.419603 -280.211099) (xy 226.407477 -280.156662)
			(xy 226.403406 -280.10104) (xy 225.147632 -280.10104) (xy 225.147123 -280.128926) (xy 225.139003 -280.184102)
			(xy 225.122935 -280.237509) (xy 225.099263 -280.288006) (xy 225.06849 -280.334519) (xy 225.031273 -280.376056)
			(xy 224.988405 -280.411731) (xy 224.940799 -280.440785) (xy 224.88947 -280.462597) (xy 224.835513 -280.476703)
			(xy 224.780076 -280.482803) (xy 224.724342 -280.480766) (xy 224.669499 -280.470636) (xy 224.616715 -280.452629)
			(xy 224.567115 -280.427128) (xy 224.521757 -280.394677) (xy 224.481608 -280.355968) (xy 224.447522 -280.311825)
			(xy 224.420226 -280.26319) (xy 224.400303 -280.211099) (xy 224.388177 -280.156662) (xy 224.384106 -280.10104)
			(xy 164.353748 -280.10104) (xy 164.353748 -280.366724) (xy 164.378132 -280.395172) (xy 164.396674 -280.397966)
			(xy 164.420372 -280.402096) (xy 164.466164 -280.416827) (xy 164.509079 -280.438555) (xy 164.548057 -280.466744)
			(xy 164.582132 -280.500696) (xy 164.610463 -280.53957) (xy 164.632348 -280.582406) (xy 164.647246 -280.628144)
			(xy 164.654787 -280.675651) (xy 164.654787 -280.699718) (xy 164.994094 -280.699718) (xy 164.998054 -280.650664)
			(xy 165.009831 -280.60288) (xy 165.029122 -280.557604) (xy 165.055425 -280.516008) (xy 165.08806 -280.479171)
			(xy 165.126181 -280.448046) (xy 165.168802 -280.423439) (xy 165.214818 -280.405987) (xy 165.263037 -280.396143)
			(xy 165.312212 -280.394162) (xy 165.361067 -280.400094) (xy 165.408338 -280.413786) (xy 165.4528 -280.434884)
			(xy 165.493303 -280.46284) (xy 165.528796 -280.496932) (xy 165.558361 -280.536276) (xy 165.581232 -280.579853)
			(xy 165.596816 -280.626534) (xy 165.604711 -280.675111) (xy 165.605206 -280.699718) (xy 165.944054 -280.699718)
			(xy 165.948014 -280.650664) (xy 165.959791 -280.60288) (xy 165.979082 -280.557604) (xy 166.005385 -280.516008)
			(xy 166.03802 -280.479171) (xy 166.076141 -280.448046) (xy 166.118762 -280.423439) (xy 166.164778 -280.405987)
			(xy 166.212997 -280.396143) (xy 166.262172 -280.394162) (xy 166.311027 -280.400094) (xy 166.358298 -280.413786)
			(xy 166.40276 -280.434884) (xy 166.443263 -280.46284) (xy 166.478756 -280.496932) (xy 166.508321 -280.536276)
			(xy 166.531192 -280.579853) (xy 166.546776 -280.626534) (xy 166.554671 -280.675111) (xy 166.555166 -280.699718)
			(xy 166.894268 -280.699718) (xy 166.898228 -280.650664) (xy 166.910005 -280.60288) (xy 166.929296 -280.557604)
			(xy 166.955599 -280.516008) (xy 166.988234 -280.479171) (xy 167.026355 -280.448046) (xy 167.068976 -280.423439)
			(xy 167.114992 -280.405987) (xy 167.163211 -280.396143) (xy 167.212386 -280.394162) (xy 167.261241 -280.400094)
			(xy 167.308512 -280.413786) (xy 167.352974 -280.434884) (xy 167.393477 -280.46284) (xy 167.42897 -280.496932)
			(xy 167.458535 -280.536276) (xy 167.481406 -280.579853) (xy 167.49699 -280.626534) (xy 167.504885 -280.675111)
			(xy 167.50538 -280.699718) (xy 167.844228 -280.699718) (xy 167.848188 -280.650664) (xy 167.859965 -280.60288)
			(xy 167.879256 -280.557604) (xy 167.905559 -280.516008) (xy 167.938194 -280.479171) (xy 167.976315 -280.448046)
			(xy 168.018936 -280.423439) (xy 168.064952 -280.405987) (xy 168.113171 -280.396143) (xy 168.162346 -280.394162)
			(xy 168.211201 -280.400094) (xy 168.258472 -280.413786) (xy 168.302934 -280.434884) (xy 168.343437 -280.46284)
			(xy 168.37893 -280.496932) (xy 168.408495 -280.536276) (xy 168.431366 -280.579853) (xy 168.44695 -280.626534)
			(xy 168.454845 -280.675111) (xy 168.45534 -280.699718) (xy 168.794188 -280.699718) (xy 168.798148 -280.650664)
			(xy 168.809925 -280.60288) (xy 168.829216 -280.557604) (xy 168.855519 -280.516008) (xy 168.888154 -280.479171)
			(xy 168.926275 -280.448046) (xy 168.968896 -280.423439) (xy 169.014912 -280.405987) (xy 169.063131 -280.396143)
			(xy 169.112306 -280.394162) (xy 169.161161 -280.400094) (xy 169.208432 -280.413786) (xy 169.252894 -280.434884)
			(xy 169.293397 -280.46284) (xy 169.32889 -280.496932) (xy 169.358455 -280.536276) (xy 169.381326 -280.579853)
			(xy 169.39691 -280.626534) (xy 169.404805 -280.675111) (xy 169.4053 -280.699718) (xy 169.744148 -280.699718)
			(xy 169.748108 -280.650664) (xy 169.759885 -280.60288) (xy 169.779176 -280.557604) (xy 169.805479 -280.516008)
			(xy 169.838114 -280.479171) (xy 169.876235 -280.448046) (xy 169.918856 -280.423439) (xy 169.964872 -280.405987)
			(xy 170.013091 -280.396143) (xy 170.062266 -280.394162) (xy 170.111121 -280.400094) (xy 170.158392 -280.413786)
			(xy 170.202854 -280.434884) (xy 170.243357 -280.46284) (xy 170.27885 -280.496932) (xy 170.308415 -280.536276)
			(xy 170.331286 -280.579853) (xy 170.34687 -280.626534) (xy 170.354765 -280.675111) (xy 170.35526 -280.699718)
			(xy 170.694108 -280.699718) (xy 170.698068 -280.650664) (xy 170.709845 -280.60288) (xy 170.729136 -280.557604)
			(xy 170.755439 -280.516008) (xy 170.788074 -280.479171) (xy 170.826195 -280.448046) (xy 170.868816 -280.423439)
			(xy 170.914832 -280.405987) (xy 170.963051 -280.396143) (xy 171.012226 -280.394162) (xy 171.061081 -280.400094)
			(xy 171.108352 -280.413786) (xy 171.152814 -280.434884) (xy 171.193317 -280.46284) (xy 171.22881 -280.496932)
			(xy 171.258375 -280.536276) (xy 171.281246 -280.579853) (xy 171.29683 -280.626534) (xy 171.304725 -280.675111)
			(xy 171.30522 -280.699718) (xy 171.644068 -280.699718) (xy 171.648028 -280.650664) (xy 171.659805 -280.60288)
			(xy 171.679096 -280.557604) (xy 171.705399 -280.516008) (xy 171.738034 -280.479171) (xy 171.776155 -280.448046)
			(xy 171.818776 -280.423439) (xy 171.864792 -280.405987) (xy 171.913011 -280.396143) (xy 171.962186 -280.394162)
			(xy 172.011041 -280.400094) (xy 172.058312 -280.413786) (xy 172.102774 -280.434884) (xy 172.143277 -280.46284)
			(xy 172.17877 -280.496932) (xy 172.208335 -280.536276) (xy 172.231206 -280.579853) (xy 172.24679 -280.626534)
			(xy 172.254685 -280.675111) (xy 172.25518 -280.699718) (xy 172.594028 -280.699718) (xy 172.597988 -280.650664)
			(xy 172.609765 -280.60288) (xy 172.629056 -280.557604) (xy 172.655359 -280.516008) (xy 172.687994 -280.479171)
			(xy 172.726115 -280.448046) (xy 172.768736 -280.423439) (xy 172.814752 -280.405987) (xy 172.862971 -280.396143)
			(xy 172.912146 -280.394162) (xy 172.961001 -280.400094) (xy 173.008272 -280.413786) (xy 173.052734 -280.434884)
			(xy 173.093237 -280.46284) (xy 173.12873 -280.496932) (xy 173.158295 -280.536276) (xy 173.181166 -280.579853)
			(xy 173.19675 -280.626534) (xy 173.204645 -280.675111) (xy 173.20514 -280.699718) (xy 173.544242 -280.699718)
			(xy 173.548202 -280.650664) (xy 173.559979 -280.60288) (xy 173.57927 -280.557604) (xy 173.605573 -280.516008)
			(xy 173.638208 -280.479171) (xy 173.676329 -280.448046) (xy 173.71895 -280.423439) (xy 173.764966 -280.405987)
			(xy 173.813185 -280.396143) (xy 173.86236 -280.394162) (xy 173.911215 -280.400094) (xy 173.958486 -280.413786)
			(xy 174.002948 -280.434884) (xy 174.043451 -280.46284) (xy 174.078944 -280.496932) (xy 174.108509 -280.536276)
			(xy 174.13138 -280.579853) (xy 174.146964 -280.626534) (xy 174.154859 -280.675111) (xy 174.155354 -280.699718)
			(xy 174.494202 -280.699718) (xy 174.498162 -280.650664) (xy 174.509939 -280.60288) (xy 174.52923 -280.557604)
			(xy 174.555533 -280.516008) (xy 174.588168 -280.479171) (xy 174.626289 -280.448046) (xy 174.66891 -280.423439)
			(xy 174.714926 -280.405987) (xy 174.763145 -280.396143) (xy 174.81232 -280.394162) (xy 174.861175 -280.400094)
			(xy 174.908446 -280.413786) (xy 174.952908 -280.434884) (xy 174.993411 -280.46284) (xy 175.028904 -280.496932)
			(xy 175.058469 -280.536276) (xy 175.08134 -280.579853) (xy 175.096924 -280.626534) (xy 175.104819 -280.675111)
			(xy 175.105314 -280.699718) (xy 175.444162 -280.699718) (xy 175.448122 -280.650664) (xy 175.459899 -280.60288)
			(xy 175.47919 -280.557604) (xy 175.505493 -280.516008) (xy 175.538128 -280.479171) (xy 175.576249 -280.448046)
			(xy 175.61887 -280.423439) (xy 175.664886 -280.405987) (xy 175.713105 -280.396143) (xy 175.76228 -280.394162)
			(xy 175.811135 -280.400094) (xy 175.858406 -280.413786) (xy 175.902868 -280.434884) (xy 175.943371 -280.46284)
			(xy 175.978864 -280.496932) (xy 176.008429 -280.536276) (xy 176.0313 -280.579853) (xy 176.046884 -280.626534)
			(xy 176.054779 -280.675111) (xy 176.055274 -280.699718) (xy 176.394122 -280.699718) (xy 176.398082 -280.650664)
			(xy 176.409859 -280.60288) (xy 176.42915 -280.557604) (xy 176.455453 -280.516008) (xy 176.488088 -280.479171)
			(xy 176.526209 -280.448046) (xy 176.56883 -280.423439) (xy 176.614846 -280.405987) (xy 176.663065 -280.396143)
			(xy 176.71224 -280.394162) (xy 176.761095 -280.400094) (xy 176.808366 -280.413786) (xy 176.852828 -280.434884)
			(xy 176.893331 -280.46284) (xy 176.928824 -280.496932) (xy 176.958389 -280.536276) (xy 176.98126 -280.579853)
			(xy 176.996844 -280.626534) (xy 177.004739 -280.675111) (xy 177.005234 -280.699718) (xy 177.344082 -280.699718)
			(xy 177.348042 -280.650664) (xy 177.359819 -280.60288) (xy 177.37911 -280.557604) (xy 177.405413 -280.516008)
			(xy 177.438048 -280.479171) (xy 177.476169 -280.448046) (xy 177.51879 -280.423439) (xy 177.564806 -280.405987)
			(xy 177.613025 -280.396143) (xy 177.6622 -280.394162) (xy 177.711055 -280.400094) (xy 177.758326 -280.413786)
			(xy 177.802788 -280.434884) (xy 177.843291 -280.46284) (xy 177.878784 -280.496932) (xy 177.908349 -280.536276)
			(xy 177.93122 -280.579853) (xy 177.946804 -280.626534) (xy 177.954699 -280.675111) (xy 177.955194 -280.699718)
			(xy 178.294042 -280.699718) (xy 178.298002 -280.650664) (xy 178.309779 -280.60288) (xy 178.32907 -280.557604)
			(xy 178.355373 -280.516008) (xy 178.388008 -280.479171) (xy 178.426129 -280.448046) (xy 178.46875 -280.423439)
			(xy 178.514766 -280.405987) (xy 178.562985 -280.396143) (xy 178.61216 -280.394162) (xy 178.661015 -280.400094)
			(xy 178.708286 -280.413786) (xy 178.752748 -280.434884) (xy 178.793251 -280.46284) (xy 178.828744 -280.496932)
			(xy 178.858309 -280.536276) (xy 178.88118 -280.579853) (xy 178.896764 -280.626534) (xy 178.904659 -280.675111)
			(xy 178.905154 -280.699718) (xy 179.244256 -280.699718) (xy 179.248216 -280.650664) (xy 179.259993 -280.60288)
			(xy 179.279284 -280.557604) (xy 179.305587 -280.516008) (xy 179.338222 -280.479171) (xy 179.376343 -280.448046)
			(xy 179.418964 -280.423439) (xy 179.46498 -280.405987) (xy 179.513199 -280.396143) (xy 179.562374 -280.394162)
			(xy 179.611229 -280.400094) (xy 179.6585 -280.413786) (xy 179.702962 -280.434884) (xy 179.743465 -280.46284)
			(xy 179.778958 -280.496932) (xy 179.808523 -280.536276) (xy 179.831394 -280.579853) (xy 179.846978 -280.626534)
			(xy 179.854873 -280.675111) (xy 179.855368 -280.699718) (xy 180.194216 -280.699718) (xy 180.198176 -280.650664)
			(xy 180.209953 -280.60288) (xy 180.229244 -280.557604) (xy 180.255547 -280.516008) (xy 180.288182 -280.479171)
			(xy 180.326303 -280.448046) (xy 180.368924 -280.423439) (xy 180.41494 -280.405987) (xy 180.463159 -280.396143)
			(xy 180.512334 -280.394162) (xy 180.561189 -280.400094) (xy 180.60846 -280.413786) (xy 180.652922 -280.434884)
			(xy 180.693425 -280.46284) (xy 180.728918 -280.496932) (xy 180.758483 -280.536276) (xy 180.781354 -280.579853)
			(xy 180.796938 -280.626534) (xy 180.804833 -280.675111) (xy 180.805328 -280.699718) (xy 181.144176 -280.699718)
			(xy 181.148136 -280.650664) (xy 181.159913 -280.60288) (xy 181.179204 -280.557604) (xy 181.205507 -280.516008)
			(xy 181.238142 -280.479171) (xy 181.276263 -280.448046) (xy 181.318884 -280.423439) (xy 181.3649 -280.405987)
			(xy 181.413119 -280.396143) (xy 181.462294 -280.394162) (xy 181.511149 -280.400094) (xy 181.55842 -280.413786)
			(xy 181.602882 -280.434884) (xy 181.643385 -280.46284) (xy 181.678878 -280.496932) (xy 181.708443 -280.536276)
			(xy 181.731314 -280.579853) (xy 181.746898 -280.626534) (xy 181.754793 -280.675111) (xy 181.755288 -280.699718)
			(xy 182.094136 -280.699718) (xy 182.098096 -280.650664) (xy 182.109873 -280.60288) (xy 182.129164 -280.557604)
			(xy 182.155467 -280.516008) (xy 182.188102 -280.479171) (xy 182.226223 -280.448046) (xy 182.268844 -280.423439)
			(xy 182.31486 -280.405987) (xy 182.363079 -280.396143) (xy 182.412254 -280.394162) (xy 182.461109 -280.400094)
			(xy 182.50838 -280.413786) (xy 182.552842 -280.434884) (xy 182.593345 -280.46284) (xy 182.628838 -280.496932)
			(xy 182.658403 -280.536276) (xy 182.681274 -280.579853) (xy 182.696858 -280.626534) (xy 182.704753 -280.675111)
			(xy 182.705248 -280.699718) (xy 183.044096 -280.699718) (xy 183.048056 -280.650664) (xy 183.059833 -280.60288)
			(xy 183.079124 -280.557604) (xy 183.105427 -280.516008) (xy 183.138062 -280.479171) (xy 183.176183 -280.448046)
			(xy 183.218804 -280.423439) (xy 183.26482 -280.405987) (xy 183.313039 -280.396143) (xy 183.362214 -280.394162)
			(xy 183.411069 -280.400094) (xy 183.45834 -280.413786) (xy 183.502802 -280.434884) (xy 183.543305 -280.46284)
			(xy 183.578798 -280.496932) (xy 183.608363 -280.536276) (xy 183.631234 -280.579853) (xy 183.646818 -280.626534)
			(xy 183.654713 -280.675111) (xy 183.655208 -280.699718) (xy 183.994056 -280.699718) (xy 183.998016 -280.650664)
			(xy 184.009793 -280.60288) (xy 184.029084 -280.557604) (xy 184.055387 -280.516008) (xy 184.088022 -280.479171)
			(xy 184.126143 -280.448046) (xy 184.168764 -280.423439) (xy 184.21478 -280.405987) (xy 184.262999 -280.396143)
			(xy 184.312174 -280.394162) (xy 184.361029 -280.400094) (xy 184.4083 -280.413786) (xy 184.452762 -280.434884)
			(xy 184.493265 -280.46284) (xy 184.528758 -280.496932) (xy 184.558323 -280.536276) (xy 184.581194 -280.579853)
			(xy 184.596778 -280.626534) (xy 184.604673 -280.675111) (xy 184.605168 -280.699718) (xy 184.94427 -280.699718)
			(xy 184.94823 -280.650664) (xy 184.960007 -280.60288) (xy 184.979298 -280.557604) (xy 185.005601 -280.516008)
			(xy 185.038236 -280.479171) (xy 185.076357 -280.448046) (xy 185.118978 -280.423439) (xy 185.164994 -280.405987)
			(xy 185.213213 -280.396143) (xy 185.262388 -280.394162) (xy 185.311243 -280.400094) (xy 185.358514 -280.413786)
			(xy 185.402976 -280.434884) (xy 185.443479 -280.46284) (xy 185.478972 -280.496932) (xy 185.508537 -280.536276)
			(xy 185.531408 -280.579853) (xy 185.546992 -280.626534) (xy 185.554887 -280.675111) (xy 185.555382 -280.699718)
			(xy 185.89423 -280.699718) (xy 185.89819 -280.650664) (xy 185.909967 -280.60288) (xy 185.929258 -280.557604)
			(xy 185.955561 -280.516008) (xy 185.988196 -280.479171) (xy 186.026317 -280.448046) (xy 186.068938 -280.423439)
			(xy 186.114954 -280.405987) (xy 186.163173 -280.396143) (xy 186.212348 -280.394162) (xy 186.261203 -280.400094)
			(xy 186.308474 -280.413786) (xy 186.352936 -280.434884) (xy 186.393439 -280.46284) (xy 186.428932 -280.496932)
			(xy 186.458497 -280.536276) (xy 186.481368 -280.579853) (xy 186.496952 -280.626534) (xy 186.504847 -280.675111)
			(xy 186.505342 -280.699718) (xy 186.84419 -280.699718) (xy 186.84815 -280.650664) (xy 186.859927 -280.60288)
			(xy 186.879218 -280.557604) (xy 186.905521 -280.516008) (xy 186.938156 -280.479171) (xy 186.976277 -280.448046)
			(xy 187.018898 -280.423439) (xy 187.064914 -280.405987) (xy 187.113133 -280.396143) (xy 187.162308 -280.394162)
			(xy 187.211163 -280.400094) (xy 187.258434 -280.413786) (xy 187.302896 -280.434884) (xy 187.343399 -280.46284)
			(xy 187.378892 -280.496932) (xy 187.408457 -280.536276) (xy 187.431328 -280.579853) (xy 187.446912 -280.626534)
			(xy 187.454807 -280.675111) (xy 187.455302 -280.699718) (xy 187.79415 -280.699718) (xy 187.79811 -280.650664)
			(xy 187.809887 -280.60288) (xy 187.829178 -280.557604) (xy 187.855481 -280.516008) (xy 187.888116 -280.479171)
			(xy 187.926237 -280.448046) (xy 187.968858 -280.423439) (xy 188.014874 -280.405987) (xy 188.063093 -280.396143)
			(xy 188.112268 -280.394162) (xy 188.161123 -280.400094) (xy 188.208394 -280.413786) (xy 188.252856 -280.434884)
			(xy 188.293359 -280.46284) (xy 188.328852 -280.496932) (xy 188.358417 -280.536276) (xy 188.381288 -280.579853)
			(xy 188.396872 -280.626534) (xy 188.404767 -280.675111) (xy 188.405262 -280.699718) (xy 188.74411 -280.699718)
			(xy 188.74807 -280.650664) (xy 188.759847 -280.60288) (xy 188.779138 -280.557604) (xy 188.805441 -280.516008)
			(xy 188.838076 -280.479171) (xy 188.876197 -280.448046) (xy 188.918818 -280.423439) (xy 188.964834 -280.405987)
			(xy 189.013053 -280.396143) (xy 189.062228 -280.394162) (xy 189.111083 -280.400094) (xy 189.158354 -280.413786)
			(xy 189.202816 -280.434884) (xy 189.243319 -280.46284) (xy 189.278812 -280.496932) (xy 189.308377 -280.536276)
			(xy 189.331248 -280.579853) (xy 189.346832 -280.626534) (xy 189.354727 -280.675111) (xy 189.355222 -280.699718)
			(xy 189.69407 -280.699718) (xy 189.69803 -280.650664) (xy 189.709807 -280.60288) (xy 189.729098 -280.557604)
			(xy 189.755401 -280.516008) (xy 189.788036 -280.479171) (xy 189.826157 -280.448046) (xy 189.868778 -280.423439)
			(xy 189.914794 -280.405987) (xy 189.963013 -280.396143) (xy 190.012188 -280.394162) (xy 190.061043 -280.400094)
			(xy 190.108314 -280.413786) (xy 190.152776 -280.434884) (xy 190.193279 -280.46284) (xy 190.228772 -280.496932)
			(xy 190.258337 -280.536276) (xy 190.281208 -280.579853) (xy 190.296792 -280.626534) (xy 190.304687 -280.675111)
			(xy 190.305182 -280.699718) (xy 190.644284 -280.699718) (xy 190.648244 -280.650664) (xy 190.660021 -280.60288)
			(xy 190.679312 -280.557604) (xy 190.705615 -280.516008) (xy 190.73825 -280.479171) (xy 190.776371 -280.448046)
			(xy 190.818992 -280.423439) (xy 190.865008 -280.405987) (xy 190.913227 -280.396143) (xy 190.962402 -280.394162)
			(xy 191.011257 -280.400094) (xy 191.058528 -280.413786) (xy 191.10299 -280.434884) (xy 191.143493 -280.46284)
			(xy 191.178986 -280.496932) (xy 191.208551 -280.536276) (xy 191.231422 -280.579853) (xy 191.247006 -280.626534)
			(xy 191.254901 -280.675111) (xy 191.255396 -280.699718) (xy 191.594244 -280.699718) (xy 191.598204 -280.650664)
			(xy 191.609981 -280.60288) (xy 191.629272 -280.557604) (xy 191.655575 -280.516008) (xy 191.68821 -280.479171)
			(xy 191.726331 -280.448046) (xy 191.768952 -280.423439) (xy 191.814968 -280.405987) (xy 191.863187 -280.396143)
			(xy 191.912362 -280.394162) (xy 191.961217 -280.400094) (xy 192.008488 -280.413786) (xy 192.05295 -280.434884)
			(xy 192.093453 -280.46284) (xy 192.128946 -280.496932) (xy 192.158511 -280.536276) (xy 192.181382 -280.579853)
			(xy 192.196966 -280.626534) (xy 192.204861 -280.675111) (xy 192.205356 -280.699718) (xy 192.544204 -280.699718)
			(xy 192.548164 -280.650664) (xy 192.559941 -280.60288) (xy 192.579232 -280.557604) (xy 192.605535 -280.516008)
			(xy 192.63817 -280.479171) (xy 192.676291 -280.448046) (xy 192.718912 -280.423439) (xy 192.764928 -280.405987)
			(xy 192.813147 -280.396143) (xy 192.862322 -280.394162) (xy 192.911177 -280.400094) (xy 192.958448 -280.413786)
			(xy 193.00291 -280.434884) (xy 193.043413 -280.46284) (xy 193.078906 -280.496932) (xy 193.108471 -280.536276)
			(xy 193.131342 -280.579853) (xy 193.146926 -280.626534) (xy 193.154821 -280.675111) (xy 193.155316 -280.699718)
			(xy 193.494164 -280.699718) (xy 193.498124 -280.650664) (xy 193.509901 -280.60288) (xy 193.529192 -280.557604)
			(xy 193.555495 -280.516008) (xy 193.58813 -280.479171) (xy 193.626251 -280.448046) (xy 193.668872 -280.423439)
			(xy 193.714888 -280.405987) (xy 193.763107 -280.396143) (xy 193.812282 -280.394162) (xy 193.861137 -280.400094)
			(xy 193.908408 -280.413786) (xy 193.95287 -280.434884) (xy 193.993373 -280.46284) (xy 194.028866 -280.496932)
			(xy 194.058431 -280.536276) (xy 194.081302 -280.579853) (xy 194.096886 -280.626534) (xy 194.104781 -280.675111)
			(xy 194.105276 -280.699718) (xy 194.444124 -280.699718) (xy 194.448084 -280.650664) (xy 194.459861 -280.60288)
			(xy 194.479152 -280.557604) (xy 194.505455 -280.516008) (xy 194.53809 -280.479171) (xy 194.576211 -280.448046)
			(xy 194.618832 -280.423439) (xy 194.664848 -280.405987) (xy 194.713067 -280.396143) (xy 194.762242 -280.394162)
			(xy 194.811097 -280.400094) (xy 194.858368 -280.413786) (xy 194.90283 -280.434884) (xy 194.943333 -280.46284)
			(xy 194.978826 -280.496932) (xy 195.008391 -280.536276) (xy 195.031262 -280.579853) (xy 195.046846 -280.626534)
			(xy 195.054741 -280.675111) (xy 195.055236 -280.699718) (xy 195.394084 -280.699718) (xy 195.398044 -280.650664)
			(xy 195.409821 -280.60288) (xy 195.429112 -280.557604) (xy 195.455415 -280.516008) (xy 195.48805 -280.479171)
			(xy 195.526171 -280.448046) (xy 195.568792 -280.423439) (xy 195.614808 -280.405987) (xy 195.663027 -280.396143)
			(xy 195.712202 -280.394162) (xy 195.761057 -280.400094) (xy 195.808328 -280.413786) (xy 195.85279 -280.434884)
			(xy 195.893293 -280.46284) (xy 195.928786 -280.496932) (xy 195.958351 -280.536276) (xy 195.981222 -280.579853)
			(xy 195.996806 -280.626534) (xy 196.004701 -280.675111) (xy 196.005196 -280.699718) (xy 196.344298 -280.699718)
			(xy 196.348258 -280.650664) (xy 196.360035 -280.60288) (xy 196.379326 -280.557604) (xy 196.405629 -280.516008)
			(xy 196.438264 -280.479171) (xy 196.476385 -280.448046) (xy 196.519006 -280.423439) (xy 196.565022 -280.405987)
			(xy 196.613241 -280.396143) (xy 196.662416 -280.394162) (xy 196.711271 -280.400094) (xy 196.758542 -280.413786)
			(xy 196.803004 -280.434884) (xy 196.843507 -280.46284) (xy 196.879 -280.496932) (xy 196.908565 -280.536276)
			(xy 196.931436 -280.579853) (xy 196.94702 -280.626534) (xy 196.954915 -280.675111) (xy 196.95541 -280.699718)
			(xy 197.294258 -280.699718) (xy 197.298218 -280.650664) (xy 197.309995 -280.60288) (xy 197.329286 -280.557604)
			(xy 197.355589 -280.516008) (xy 197.388224 -280.479171) (xy 197.426345 -280.448046) (xy 197.468966 -280.423439)
			(xy 197.514982 -280.405987) (xy 197.563201 -280.396143) (xy 197.612376 -280.394162) (xy 197.661231 -280.400094)
			(xy 197.708502 -280.413786) (xy 197.752964 -280.434884) (xy 197.793467 -280.46284) (xy 197.82896 -280.496932)
			(xy 197.858525 -280.536276) (xy 197.881396 -280.579853) (xy 197.89698 -280.626534) (xy 197.904875 -280.675111)
			(xy 197.90537 -280.699718) (xy 198.244218 -280.699718) (xy 198.248178 -280.650664) (xy 198.259955 -280.60288)
			(xy 198.279246 -280.557604) (xy 198.305549 -280.516008) (xy 198.338184 -280.479171) (xy 198.376305 -280.448046)
			(xy 198.418926 -280.423439) (xy 198.464942 -280.405987) (xy 198.513161 -280.396143) (xy 198.562336 -280.394162)
			(xy 198.611191 -280.400094) (xy 198.658462 -280.413786) (xy 198.702924 -280.434884) (xy 198.743427 -280.46284)
			(xy 198.77892 -280.496932) (xy 198.781663 -280.500582) (xy 228.815644 -280.500582) (xy 228.819715 -280.44496)
			(xy 228.831841 -280.390523) (xy 228.851764 -280.338432) (xy 228.87906 -280.289797) (xy 228.913146 -280.245654)
			(xy 228.953295 -280.206945) (xy 228.998653 -280.174494) (xy 229.048253 -280.148993) (xy 229.101037 -280.130986)
			(xy 229.15588 -280.120856) (xy 229.211614 -280.118819) (xy 229.267051 -280.124919) (xy 229.321008 -280.139025)
			(xy 229.372337 -280.160837) (xy 229.419943 -280.189891) (xy 229.462811 -280.225566) (xy 229.500028 -280.267103)
			(xy 229.530801 -280.313616) (xy 229.554473 -280.364113) (xy 229.570541 -280.41752) (xy 229.578661 -280.472696)
			(xy 229.57917 -280.500582) (xy 229.578661 -280.528468) (xy 229.570541 -280.583644) (xy 229.554473 -280.637051)
			(xy 229.530801 -280.687548) (xy 229.500028 -280.734061) (xy 229.462811 -280.775598) (xy 229.419943 -280.811273)
			(xy 229.372337 -280.840327) (xy 229.321008 -280.862139) (xy 229.267051 -280.876245) (xy 229.211614 -280.882345)
			(xy 229.15588 -280.880308) (xy 229.101037 -280.870178) (xy 229.048253 -280.852171) (xy 228.998653 -280.82667)
			(xy 228.953295 -280.794219) (xy 228.913146 -280.75551) (xy 228.87906 -280.711367) (xy 228.851764 -280.662732)
			(xy 228.831841 -280.610641) (xy 228.819715 -280.556204) (xy 228.815644 -280.500582) (xy 198.781663 -280.500582)
			(xy 198.808485 -280.536276) (xy 198.831356 -280.579853) (xy 198.84694 -280.626534) (xy 198.854835 -280.675111)
			(xy 198.85533 -280.699718) (xy 198.854835 -280.724325) (xy 198.84694 -280.772902) (xy 198.831356 -280.819583)
			(xy 198.808485 -280.86316) (xy 198.77892 -280.902504) (xy 198.743427 -280.936596) (xy 198.702924 -280.964552)
			(xy 198.658462 -280.98565) (xy 198.611191 -280.999342) (xy 198.562336 -281.005274) (xy 198.513161 -281.003293)
			(xy 198.464942 -280.993449) (xy 198.418926 -280.975997) (xy 198.376305 -280.95139) (xy 198.338184 -280.920265)
			(xy 198.305549 -280.883428) (xy 198.279246 -280.841832) (xy 198.259955 -280.796556) (xy 198.248178 -280.748772)
			(xy 198.244218 -280.699718) (xy 197.90537 -280.699718) (xy 197.904875 -280.724325) (xy 197.89698 -280.772902)
			(xy 197.881396 -280.819583) (xy 197.858525 -280.86316) (xy 197.82896 -280.902504) (xy 197.793467 -280.936596)
			(xy 197.752964 -280.964552) (xy 197.708502 -280.98565) (xy 197.661231 -280.999342) (xy 197.612376 -281.005274)
			(xy 197.563201 -281.003293) (xy 197.514982 -280.993449) (xy 197.468966 -280.975997) (xy 197.426345 -280.95139)
			(xy 197.388224 -280.920265) (xy 197.355589 -280.883428) (xy 197.329286 -280.841832) (xy 197.309995 -280.796556)
			(xy 197.298218 -280.748772) (xy 197.294258 -280.699718) (xy 196.95541 -280.699718) (xy 196.954915 -280.724325)
			(xy 196.94702 -280.772902) (xy 196.931436 -280.819583) (xy 196.908565 -280.86316) (xy 196.879 -280.902504)
			(xy 196.843507 -280.936596) (xy 196.803004 -280.964552) (xy 196.758542 -280.98565) (xy 196.711271 -280.999342)
			(xy 196.662416 -281.005274) (xy 196.613241 -281.003293) (xy 196.565022 -280.993449) (xy 196.519006 -280.975997)
			(xy 196.476385 -280.95139) (xy 196.438264 -280.920265) (xy 196.405629 -280.883428) (xy 196.379326 -280.841832)
			(xy 196.360035 -280.796556) (xy 196.348258 -280.748772) (xy 196.344298 -280.699718) (xy 196.005196 -280.699718)
			(xy 196.004701 -280.724325) (xy 195.996806 -280.772902) (xy 195.981222 -280.819583) (xy 195.958351 -280.86316)
			(xy 195.928786 -280.902504) (xy 195.893293 -280.936596) (xy 195.85279 -280.964552) (xy 195.808328 -280.98565)
			(xy 195.761057 -280.999342) (xy 195.712202 -281.005274) (xy 195.663027 -281.003293) (xy 195.614808 -280.993449)
			(xy 195.568792 -280.975997) (xy 195.526171 -280.95139) (xy 195.48805 -280.920265) (xy 195.455415 -280.883428)
			(xy 195.429112 -280.841832) (xy 195.409821 -280.796556) (xy 195.398044 -280.748772) (xy 195.394084 -280.699718)
			(xy 195.055236 -280.699718) (xy 195.054741 -280.724325) (xy 195.046846 -280.772902) (xy 195.031262 -280.819583)
			(xy 195.008391 -280.86316) (xy 194.978826 -280.902504) (xy 194.943333 -280.936596) (xy 194.90283 -280.964552)
			(xy 194.858368 -280.98565) (xy 194.811097 -280.999342) (xy 194.762242 -281.005274) (xy 194.713067 -281.003293)
			(xy 194.664848 -280.993449) (xy 194.618832 -280.975997) (xy 194.576211 -280.95139) (xy 194.53809 -280.920265)
			(xy 194.505455 -280.883428) (xy 194.479152 -280.841832) (xy 194.459861 -280.796556) (xy 194.448084 -280.748772)
			(xy 194.444124 -280.699718) (xy 194.105276 -280.699718) (xy 194.104781 -280.724325) (xy 194.096886 -280.772902)
			(xy 194.081302 -280.819583) (xy 194.058431 -280.86316) (xy 194.028866 -280.902504) (xy 193.993373 -280.936596)
			(xy 193.95287 -280.964552) (xy 193.908408 -280.98565) (xy 193.861137 -280.999342) (xy 193.812282 -281.005274)
			(xy 193.763107 -281.003293) (xy 193.714888 -280.993449) (xy 193.668872 -280.975997) (xy 193.626251 -280.95139)
			(xy 193.58813 -280.920265) (xy 193.555495 -280.883428) (xy 193.529192 -280.841832) (xy 193.509901 -280.796556)
			(xy 193.498124 -280.748772) (xy 193.494164 -280.699718) (xy 193.155316 -280.699718) (xy 193.154821 -280.724325)
			(xy 193.146926 -280.772902) (xy 193.131342 -280.819583) (xy 193.108471 -280.86316) (xy 193.078906 -280.902504)
			(xy 193.043413 -280.936596) (xy 193.00291 -280.964552) (xy 192.958448 -280.98565) (xy 192.911177 -280.999342)
			(xy 192.862322 -281.005274) (xy 192.813147 -281.003293) (xy 192.764928 -280.993449) (xy 192.718912 -280.975997)
			(xy 192.676291 -280.95139) (xy 192.63817 -280.920265) (xy 192.605535 -280.883428) (xy 192.579232 -280.841832)
			(xy 192.559941 -280.796556) (xy 192.548164 -280.748772) (xy 192.544204 -280.699718) (xy 192.205356 -280.699718)
			(xy 192.204861 -280.724325) (xy 192.196966 -280.772902) (xy 192.181382 -280.819583) (xy 192.158511 -280.86316)
			(xy 192.128946 -280.902504) (xy 192.093453 -280.936596) (xy 192.05295 -280.964552) (xy 192.008488 -280.98565)
			(xy 191.961217 -280.999342) (xy 191.912362 -281.005274) (xy 191.863187 -281.003293) (xy 191.814968 -280.993449)
			(xy 191.768952 -280.975997) (xy 191.726331 -280.95139) (xy 191.68821 -280.920265) (xy 191.655575 -280.883428)
			(xy 191.629272 -280.841832) (xy 191.609981 -280.796556) (xy 191.598204 -280.748772) (xy 191.594244 -280.699718)
			(xy 191.255396 -280.699718) (xy 191.254901 -280.724325) (xy 191.247006 -280.772902) (xy 191.231422 -280.819583)
			(xy 191.208551 -280.86316) (xy 191.178986 -280.902504) (xy 191.143493 -280.936596) (xy 191.10299 -280.964552)
			(xy 191.058528 -280.98565) (xy 191.011257 -280.999342) (xy 190.962402 -281.005274) (xy 190.913227 -281.003293)
			(xy 190.865008 -280.993449) (xy 190.818992 -280.975997) (xy 190.776371 -280.95139) (xy 190.73825 -280.920265)
			(xy 190.705615 -280.883428) (xy 190.679312 -280.841832) (xy 190.660021 -280.796556) (xy 190.648244 -280.748772)
			(xy 190.644284 -280.699718) (xy 190.305182 -280.699718) (xy 190.304687 -280.724325) (xy 190.296792 -280.772902)
			(xy 190.281208 -280.819583) (xy 190.258337 -280.86316) (xy 190.228772 -280.902504) (xy 190.193279 -280.936596)
			(xy 190.152776 -280.964552) (xy 190.108314 -280.98565) (xy 190.061043 -280.999342) (xy 190.012188 -281.005274)
			(xy 189.963013 -281.003293) (xy 189.914794 -280.993449) (xy 189.868778 -280.975997) (xy 189.826157 -280.95139)
			(xy 189.788036 -280.920265) (xy 189.755401 -280.883428) (xy 189.729098 -280.841832) (xy 189.709807 -280.796556)
			(xy 189.69803 -280.748772) (xy 189.69407 -280.699718) (xy 189.355222 -280.699718) (xy 189.354727 -280.724325)
			(xy 189.346832 -280.772902) (xy 189.331248 -280.819583) (xy 189.308377 -280.86316) (xy 189.278812 -280.902504)
			(xy 189.243319 -280.936596) (xy 189.202816 -280.964552) (xy 189.158354 -280.98565) (xy 189.111083 -280.999342)
			(xy 189.062228 -281.005274) (xy 189.013053 -281.003293) (xy 188.964834 -280.993449) (xy 188.918818 -280.975997)
			(xy 188.876197 -280.95139) (xy 188.838076 -280.920265) (xy 188.805441 -280.883428) (xy 188.779138 -280.841832)
			(xy 188.759847 -280.796556) (xy 188.74807 -280.748772) (xy 188.74411 -280.699718) (xy 188.405262 -280.699718)
			(xy 188.404767 -280.724325) (xy 188.396872 -280.772902) (xy 188.381288 -280.819583) (xy 188.358417 -280.86316)
			(xy 188.328852 -280.902504) (xy 188.293359 -280.936596) (xy 188.252856 -280.964552) (xy 188.208394 -280.98565)
			(xy 188.161123 -280.999342) (xy 188.112268 -281.005274) (xy 188.063093 -281.003293) (xy 188.014874 -280.993449)
			(xy 187.968858 -280.975997) (xy 187.926237 -280.95139) (xy 187.888116 -280.920265) (xy 187.855481 -280.883428)
			(xy 187.829178 -280.841832) (xy 187.809887 -280.796556) (xy 187.79811 -280.748772) (xy 187.79415 -280.699718)
			(xy 187.455302 -280.699718) (xy 187.454807 -280.724325) (xy 187.446912 -280.772902) (xy 187.431328 -280.819583)
			(xy 187.408457 -280.86316) (xy 187.378892 -280.902504) (xy 187.343399 -280.936596) (xy 187.302896 -280.964552)
			(xy 187.258434 -280.98565) (xy 187.211163 -280.999342) (xy 187.162308 -281.005274) (xy 187.113133 -281.003293)
			(xy 187.064914 -280.993449) (xy 187.018898 -280.975997) (xy 186.976277 -280.95139) (xy 186.938156 -280.920265)
			(xy 186.905521 -280.883428) (xy 186.879218 -280.841832) (xy 186.859927 -280.796556) (xy 186.84815 -280.748772)
			(xy 186.84419 -280.699718) (xy 186.505342 -280.699718) (xy 186.504847 -280.724325) (xy 186.496952 -280.772902)
			(xy 186.481368 -280.819583) (xy 186.458497 -280.86316) (xy 186.428932 -280.902504) (xy 186.393439 -280.936596)
			(xy 186.352936 -280.964552) (xy 186.308474 -280.98565) (xy 186.261203 -280.999342) (xy 186.212348 -281.005274)
			(xy 186.163173 -281.003293) (xy 186.114954 -280.993449) (xy 186.068938 -280.975997) (xy 186.026317 -280.95139)
			(xy 185.988196 -280.920265) (xy 185.955561 -280.883428) (xy 185.929258 -280.841832) (xy 185.909967 -280.796556)
			(xy 185.89819 -280.748772) (xy 185.89423 -280.699718) (xy 185.555382 -280.699718) (xy 185.554887 -280.724325)
			(xy 185.546992 -280.772902) (xy 185.531408 -280.819583) (xy 185.508537 -280.86316) (xy 185.478972 -280.902504)
			(xy 185.443479 -280.936596) (xy 185.402976 -280.964552) (xy 185.358514 -280.98565) (xy 185.311243 -280.999342)
			(xy 185.262388 -281.005274) (xy 185.213213 -281.003293) (xy 185.164994 -280.993449) (xy 185.118978 -280.975997)
			(xy 185.076357 -280.95139) (xy 185.038236 -280.920265) (xy 185.005601 -280.883428) (xy 184.979298 -280.841832)
			(xy 184.960007 -280.796556) (xy 184.94823 -280.748772) (xy 184.94427 -280.699718) (xy 184.605168 -280.699718)
			(xy 184.604673 -280.724325) (xy 184.596778 -280.772902) (xy 184.581194 -280.819583) (xy 184.558323 -280.86316)
			(xy 184.528758 -280.902504) (xy 184.493265 -280.936596) (xy 184.452762 -280.964552) (xy 184.4083 -280.98565)
			(xy 184.361029 -280.999342) (xy 184.312174 -281.005274) (xy 184.262999 -281.003293) (xy 184.21478 -280.993449)
			(xy 184.168764 -280.975997) (xy 184.126143 -280.95139) (xy 184.088022 -280.920265) (xy 184.055387 -280.883428)
			(xy 184.029084 -280.841832) (xy 184.009793 -280.796556) (xy 183.998016 -280.748772) (xy 183.994056 -280.699718)
			(xy 183.655208 -280.699718) (xy 183.654713 -280.724325) (xy 183.646818 -280.772902) (xy 183.631234 -280.819583)
			(xy 183.608363 -280.86316) (xy 183.578798 -280.902504) (xy 183.543305 -280.936596) (xy 183.502802 -280.964552)
			(xy 183.45834 -280.98565) (xy 183.411069 -280.999342) (xy 183.362214 -281.005274) (xy 183.313039 -281.003293)
			(xy 183.26482 -280.993449) (xy 183.218804 -280.975997) (xy 183.176183 -280.95139) (xy 183.138062 -280.920265)
			(xy 183.105427 -280.883428) (xy 183.079124 -280.841832) (xy 183.059833 -280.796556) (xy 183.048056 -280.748772)
			(xy 183.044096 -280.699718) (xy 182.705248 -280.699718) (xy 182.704753 -280.724325) (xy 182.696858 -280.772902)
			(xy 182.681274 -280.819583) (xy 182.658403 -280.86316) (xy 182.628838 -280.902504) (xy 182.593345 -280.936596)
			(xy 182.552842 -280.964552) (xy 182.50838 -280.98565) (xy 182.461109 -280.999342) (xy 182.412254 -281.005274)
			(xy 182.363079 -281.003293) (xy 182.31486 -280.993449) (xy 182.268844 -280.975997) (xy 182.226223 -280.95139)
			(xy 182.188102 -280.920265) (xy 182.155467 -280.883428) (xy 182.129164 -280.841832) (xy 182.109873 -280.796556)
			(xy 182.098096 -280.748772) (xy 182.094136 -280.699718) (xy 181.755288 -280.699718) (xy 181.754793 -280.724325)
			(xy 181.746898 -280.772902) (xy 181.731314 -280.819583) (xy 181.708443 -280.86316) (xy 181.678878 -280.902504)
			(xy 181.643385 -280.936596) (xy 181.602882 -280.964552) (xy 181.55842 -280.98565) (xy 181.511149 -280.999342)
			(xy 181.462294 -281.005274) (xy 181.413119 -281.003293) (xy 181.3649 -280.993449) (xy 181.318884 -280.975997)
			(xy 181.276263 -280.95139) (xy 181.238142 -280.920265) (xy 181.205507 -280.883428) (xy 181.179204 -280.841832)
			(xy 181.159913 -280.796556) (xy 181.148136 -280.748772) (xy 181.144176 -280.699718) (xy 180.805328 -280.699718)
			(xy 180.804833 -280.724325) (xy 180.796938 -280.772902) (xy 180.781354 -280.819583) (xy 180.758483 -280.86316)
			(xy 180.728918 -280.902504) (xy 180.693425 -280.936596) (xy 180.652922 -280.964552) (xy 180.60846 -280.98565)
			(xy 180.561189 -280.999342) (xy 180.512334 -281.005274) (xy 180.463159 -281.003293) (xy 180.41494 -280.993449)
			(xy 180.368924 -280.975997) (xy 180.326303 -280.95139) (xy 180.288182 -280.920265) (xy 180.255547 -280.883428)
			(xy 180.229244 -280.841832) (xy 180.209953 -280.796556) (xy 180.198176 -280.748772) (xy 180.194216 -280.699718)
			(xy 179.855368 -280.699718) (xy 179.854873 -280.724325) (xy 179.846978 -280.772902) (xy 179.831394 -280.819583)
			(xy 179.808523 -280.86316) (xy 179.778958 -280.902504) (xy 179.743465 -280.936596) (xy 179.702962 -280.964552)
			(xy 179.6585 -280.98565) (xy 179.611229 -280.999342) (xy 179.562374 -281.005274) (xy 179.513199 -281.003293)
			(xy 179.46498 -280.993449) (xy 179.418964 -280.975997) (xy 179.376343 -280.95139) (xy 179.338222 -280.920265)
			(xy 179.305587 -280.883428) (xy 179.279284 -280.841832) (xy 179.259993 -280.796556) (xy 179.248216 -280.748772)
			(xy 179.244256 -280.699718) (xy 178.905154 -280.699718) (xy 178.904659 -280.724325) (xy 178.896764 -280.772902)
			(xy 178.88118 -280.819583) (xy 178.858309 -280.86316) (xy 178.828744 -280.902504) (xy 178.793251 -280.936596)
			(xy 178.752748 -280.964552) (xy 178.708286 -280.98565) (xy 178.661015 -280.999342) (xy 178.61216 -281.005274)
			(xy 178.562985 -281.003293) (xy 178.514766 -280.993449) (xy 178.46875 -280.975997) (xy 178.426129 -280.95139)
			(xy 178.388008 -280.920265) (xy 178.355373 -280.883428) (xy 178.32907 -280.841832) (xy 178.309779 -280.796556)
			(xy 178.298002 -280.748772) (xy 178.294042 -280.699718) (xy 177.955194 -280.699718) (xy 177.954699 -280.724325)
			(xy 177.946804 -280.772902) (xy 177.93122 -280.819583) (xy 177.908349 -280.86316) (xy 177.878784 -280.902504)
			(xy 177.843291 -280.936596) (xy 177.802788 -280.964552) (xy 177.758326 -280.98565) (xy 177.711055 -280.999342)
			(xy 177.6622 -281.005274) (xy 177.613025 -281.003293) (xy 177.564806 -280.993449) (xy 177.51879 -280.975997)
			(xy 177.476169 -280.95139) (xy 177.438048 -280.920265) (xy 177.405413 -280.883428) (xy 177.37911 -280.841832)
			(xy 177.359819 -280.796556) (xy 177.348042 -280.748772) (xy 177.344082 -280.699718) (xy 177.005234 -280.699718)
			(xy 177.004739 -280.724325) (xy 176.996844 -280.772902) (xy 176.98126 -280.819583) (xy 176.958389 -280.86316)
			(xy 176.928824 -280.902504) (xy 176.893331 -280.936596) (xy 176.852828 -280.964552) (xy 176.808366 -280.98565)
			(xy 176.761095 -280.999342) (xy 176.71224 -281.005274) (xy 176.663065 -281.003293) (xy 176.614846 -280.993449)
			(xy 176.56883 -280.975997) (xy 176.526209 -280.95139) (xy 176.488088 -280.920265) (xy 176.455453 -280.883428)
			(xy 176.42915 -280.841832) (xy 176.409859 -280.796556) (xy 176.398082 -280.748772) (xy 176.394122 -280.699718)
			(xy 176.055274 -280.699718) (xy 176.054779 -280.724325) (xy 176.046884 -280.772902) (xy 176.0313 -280.819583)
			(xy 176.008429 -280.86316) (xy 175.978864 -280.902504) (xy 175.943371 -280.936596) (xy 175.902868 -280.964552)
			(xy 175.858406 -280.98565) (xy 175.811135 -280.999342) (xy 175.76228 -281.005274) (xy 175.713105 -281.003293)
			(xy 175.664886 -280.993449) (xy 175.61887 -280.975997) (xy 175.576249 -280.95139) (xy 175.538128 -280.920265)
			(xy 175.505493 -280.883428) (xy 175.47919 -280.841832) (xy 175.459899 -280.796556) (xy 175.448122 -280.748772)
			(xy 175.444162 -280.699718) (xy 175.105314 -280.699718) (xy 175.104819 -280.724325) (xy 175.096924 -280.772902)
			(xy 175.08134 -280.819583) (xy 175.058469 -280.86316) (xy 175.028904 -280.902504) (xy 174.993411 -280.936596)
			(xy 174.952908 -280.964552) (xy 174.908446 -280.98565) (xy 174.861175 -280.999342) (xy 174.81232 -281.005274)
			(xy 174.763145 -281.003293) (xy 174.714926 -280.993449) (xy 174.66891 -280.975997) (xy 174.626289 -280.95139)
			(xy 174.588168 -280.920265) (xy 174.555533 -280.883428) (xy 174.52923 -280.841832) (xy 174.509939 -280.796556)
			(xy 174.498162 -280.748772) (xy 174.494202 -280.699718) (xy 174.155354 -280.699718) (xy 174.154859 -280.724325)
			(xy 174.146964 -280.772902) (xy 174.13138 -280.819583) (xy 174.108509 -280.86316) (xy 174.078944 -280.902504)
			(xy 174.043451 -280.936596) (xy 174.002948 -280.964552) (xy 173.958486 -280.98565) (xy 173.911215 -280.999342)
			(xy 173.86236 -281.005274) (xy 173.813185 -281.003293) (xy 173.764966 -280.993449) (xy 173.71895 -280.975997)
			(xy 173.676329 -280.95139) (xy 173.638208 -280.920265) (xy 173.605573 -280.883428) (xy 173.57927 -280.841832)
			(xy 173.559979 -280.796556) (xy 173.548202 -280.748772) (xy 173.544242 -280.699718) (xy 173.20514 -280.699718)
			(xy 173.204645 -280.724325) (xy 173.19675 -280.772902) (xy 173.181166 -280.819583) (xy 173.158295 -280.86316)
			(xy 173.12873 -280.902504) (xy 173.093237 -280.936596) (xy 173.052734 -280.964552) (xy 173.008272 -280.98565)
			(xy 172.961001 -280.999342) (xy 172.912146 -281.005274) (xy 172.862971 -281.003293) (xy 172.814752 -280.993449)
			(xy 172.768736 -280.975997) (xy 172.726115 -280.95139) (xy 172.687994 -280.920265) (xy 172.655359 -280.883428)
			(xy 172.629056 -280.841832) (xy 172.609765 -280.796556) (xy 172.597988 -280.748772) (xy 172.594028 -280.699718)
			(xy 172.25518 -280.699718) (xy 172.254685 -280.724325) (xy 172.24679 -280.772902) (xy 172.231206 -280.819583)
			(xy 172.208335 -280.86316) (xy 172.17877 -280.902504) (xy 172.143277 -280.936596) (xy 172.102774 -280.964552)
			(xy 172.058312 -280.98565) (xy 172.011041 -280.999342) (xy 171.962186 -281.005274) (xy 171.913011 -281.003293)
			(xy 171.864792 -280.993449) (xy 171.818776 -280.975997) (xy 171.776155 -280.95139) (xy 171.738034 -280.920265)
			(xy 171.705399 -280.883428) (xy 171.679096 -280.841832) (xy 171.659805 -280.796556) (xy 171.648028 -280.748772)
			(xy 171.644068 -280.699718) (xy 171.30522 -280.699718) (xy 171.304725 -280.724325) (xy 171.29683 -280.772902)
			(xy 171.281246 -280.819583) (xy 171.258375 -280.86316) (xy 171.22881 -280.902504) (xy 171.193317 -280.936596)
			(xy 171.152814 -280.964552) (xy 171.108352 -280.98565) (xy 171.061081 -280.999342) (xy 171.012226 -281.005274)
			(xy 170.963051 -281.003293) (xy 170.914832 -280.993449) (xy 170.868816 -280.975997) (xy 170.826195 -280.95139)
			(xy 170.788074 -280.920265) (xy 170.755439 -280.883428) (xy 170.729136 -280.841832) (xy 170.709845 -280.796556)
			(xy 170.698068 -280.748772) (xy 170.694108 -280.699718) (xy 170.35526 -280.699718) (xy 170.354765 -280.724325)
			(xy 170.34687 -280.772902) (xy 170.331286 -280.819583) (xy 170.308415 -280.86316) (xy 170.27885 -280.902504)
			(xy 170.243357 -280.936596) (xy 170.202854 -280.964552) (xy 170.158392 -280.98565) (xy 170.111121 -280.999342)
			(xy 170.062266 -281.005274) (xy 170.013091 -281.003293) (xy 169.964872 -280.993449) (xy 169.918856 -280.975997)
			(xy 169.876235 -280.95139) (xy 169.838114 -280.920265) (xy 169.805479 -280.883428) (xy 169.779176 -280.841832)
			(xy 169.759885 -280.796556) (xy 169.748108 -280.748772) (xy 169.744148 -280.699718) (xy 169.4053 -280.699718)
			(xy 169.404805 -280.724325) (xy 169.39691 -280.772902) (xy 169.381326 -280.819583) (xy 169.358455 -280.86316)
			(xy 169.32889 -280.902504) (xy 169.293397 -280.936596) (xy 169.252894 -280.964552) (xy 169.208432 -280.98565)
			(xy 169.161161 -280.999342) (xy 169.112306 -281.005274) (xy 169.063131 -281.003293) (xy 169.014912 -280.993449)
			(xy 168.968896 -280.975997) (xy 168.926275 -280.95139) (xy 168.888154 -280.920265) (xy 168.855519 -280.883428)
			(xy 168.829216 -280.841832) (xy 168.809925 -280.796556) (xy 168.798148 -280.748772) (xy 168.794188 -280.699718)
			(xy 168.45534 -280.699718) (xy 168.454845 -280.724325) (xy 168.44695 -280.772902) (xy 168.431366 -280.819583)
			(xy 168.408495 -280.86316) (xy 168.37893 -280.902504) (xy 168.343437 -280.936596) (xy 168.302934 -280.964552)
			(xy 168.258472 -280.98565) (xy 168.211201 -280.999342) (xy 168.162346 -281.005274) (xy 168.113171 -281.003293)
			(xy 168.064952 -280.993449) (xy 168.018936 -280.975997) (xy 167.976315 -280.95139) (xy 167.938194 -280.920265)
			(xy 167.905559 -280.883428) (xy 167.879256 -280.841832) (xy 167.859965 -280.796556) (xy 167.848188 -280.748772)
			(xy 167.844228 -280.699718) (xy 167.50538 -280.699718) (xy 167.504885 -280.724325) (xy 167.49699 -280.772902)
			(xy 167.481406 -280.819583) (xy 167.458535 -280.86316) (xy 167.42897 -280.902504) (xy 167.393477 -280.936596)
			(xy 167.352974 -280.964552) (xy 167.308512 -280.98565) (xy 167.261241 -280.999342) (xy 167.212386 -281.005274)
			(xy 167.163211 -281.003293) (xy 167.114992 -280.993449) (xy 167.068976 -280.975997) (xy 167.026355 -280.95139)
			(xy 166.988234 -280.920265) (xy 166.955599 -280.883428) (xy 166.929296 -280.841832) (xy 166.910005 -280.796556)
			(xy 166.898228 -280.748772) (xy 166.894268 -280.699718) (xy 166.555166 -280.699718) (xy 166.554671 -280.724325)
			(xy 166.546776 -280.772902) (xy 166.531192 -280.819583) (xy 166.508321 -280.86316) (xy 166.478756 -280.902504)
			(xy 166.443263 -280.936596) (xy 166.40276 -280.964552) (xy 166.358298 -280.98565) (xy 166.311027 -280.999342)
			(xy 166.262172 -281.005274) (xy 166.212997 -281.003293) (xy 166.164778 -280.993449) (xy 166.118762 -280.975997)
			(xy 166.076141 -280.95139) (xy 166.03802 -280.920265) (xy 166.005385 -280.883428) (xy 165.979082 -280.841832)
			(xy 165.959791 -280.796556) (xy 165.948014 -280.748772) (xy 165.944054 -280.699718) (xy 165.605206 -280.699718)
			(xy 165.604711 -280.724325) (xy 165.596816 -280.772902) (xy 165.581232 -280.819583) (xy 165.558361 -280.86316)
			(xy 165.528796 -280.902504) (xy 165.493303 -280.936596) (xy 165.4528 -280.964552) (xy 165.408338 -280.98565)
			(xy 165.361067 -280.999342) (xy 165.312212 -281.005274) (xy 165.263037 -281.003293) (xy 165.214818 -280.993449)
			(xy 165.168802 -280.975997) (xy 165.126181 -280.95139) (xy 165.08806 -280.920265) (xy 165.055425 -280.883428)
			(xy 165.029122 -280.841832) (xy 165.009831 -280.796556) (xy 164.998054 -280.748772) (xy 164.994094 -280.699718)
			(xy 164.654787 -280.699718) (xy 164.654787 -280.723754) (xy 164.647244 -280.771262) (xy 164.632346 -280.816999)
			(xy 164.61046 -280.859834) (xy 164.582129 -280.898709) (xy 164.548053 -280.93266) (xy 164.509075 -280.960848)
			(xy 164.466159 -280.982576) (xy 164.420367 -280.997306) (xy 164.396674 -281.00147) (xy 164.378132 -281.004264)
			(xy 164.353748 -281.032712) (xy 164.353748 -281.316938) (xy 164.378132 -281.345386) (xy 164.396674 -281.34818)
			(xy 164.420371 -281.35231) (xy 164.466161 -281.36704) (xy 164.509074 -281.388768) (xy 164.54805 -281.416956)
			(xy 164.582123 -281.450906) (xy 164.610452 -281.489779) (xy 164.632336 -281.532613) (xy 164.647233 -281.578349)
			(xy 164.654774 -281.625855) (xy 164.654773 -281.649932) (xy 164.994094 -281.649932) (xy 164.998054 -281.600878)
			(xy 165.009831 -281.553094) (xy 165.029122 -281.507818) (xy 165.055425 -281.466222) (xy 165.08806 -281.429385)
			(xy 165.126181 -281.39826) (xy 165.168802 -281.373653) (xy 165.214818 -281.356201) (xy 165.263037 -281.346357)
			(xy 165.312212 -281.344376) (xy 165.361067 -281.350308) (xy 165.408338 -281.364) (xy 165.4528 -281.385098)
			(xy 165.493303 -281.413054) (xy 165.528796 -281.447146) (xy 165.558361 -281.48649) (xy 165.581232 -281.530067)
			(xy 165.596816 -281.576748) (xy 165.604711 -281.625325) (xy 165.605206 -281.649932) (xy 165.944054 -281.649932)
			(xy 165.948014 -281.600878) (xy 165.959791 -281.553094) (xy 165.979082 -281.507818) (xy 166.005385 -281.466222)
			(xy 166.03802 -281.429385) (xy 166.076141 -281.39826) (xy 166.118762 -281.373653) (xy 166.164778 -281.356201)
			(xy 166.212997 -281.346357) (xy 166.262172 -281.344376) (xy 166.311027 -281.350308) (xy 166.358298 -281.364)
			(xy 166.40276 -281.385098) (xy 166.443263 -281.413054) (xy 166.478756 -281.447146) (xy 166.508321 -281.48649)
			(xy 166.531192 -281.530067) (xy 166.546776 -281.576748) (xy 166.554671 -281.625325) (xy 166.555166 -281.649932)
			(xy 166.894268 -281.649932) (xy 166.898228 -281.600878) (xy 166.910005 -281.553094) (xy 166.929296 -281.507818)
			(xy 166.955599 -281.466222) (xy 166.988234 -281.429385) (xy 167.026355 -281.39826) (xy 167.068976 -281.373653)
			(xy 167.114992 -281.356201) (xy 167.163211 -281.346357) (xy 167.212386 -281.344376) (xy 167.261241 -281.350308)
			(xy 167.308512 -281.364) (xy 167.352974 -281.385098) (xy 167.393477 -281.413054) (xy 167.42897 -281.447146)
			(xy 167.458535 -281.48649) (xy 167.481406 -281.530067) (xy 167.49699 -281.576748) (xy 167.504885 -281.625325)
			(xy 167.50538 -281.649932) (xy 167.844228 -281.649932) (xy 167.848188 -281.600878) (xy 167.859965 -281.553094)
			(xy 167.879256 -281.507818) (xy 167.905559 -281.466222) (xy 167.938194 -281.429385) (xy 167.976315 -281.39826)
			(xy 168.018936 -281.373653) (xy 168.064952 -281.356201) (xy 168.113171 -281.346357) (xy 168.162346 -281.344376)
			(xy 168.211201 -281.350308) (xy 168.258472 -281.364) (xy 168.302934 -281.385098) (xy 168.343437 -281.413054)
			(xy 168.37893 -281.447146) (xy 168.408495 -281.48649) (xy 168.431366 -281.530067) (xy 168.44695 -281.576748)
			(xy 168.454845 -281.625325) (xy 168.45534 -281.649932) (xy 168.794188 -281.649932) (xy 168.798148 -281.600878)
			(xy 168.809925 -281.553094) (xy 168.829216 -281.507818) (xy 168.855519 -281.466222) (xy 168.888154 -281.429385)
			(xy 168.926275 -281.39826) (xy 168.968896 -281.373653) (xy 169.014912 -281.356201) (xy 169.063131 -281.346357)
			(xy 169.112306 -281.344376) (xy 169.161161 -281.350308) (xy 169.208432 -281.364) (xy 169.252894 -281.385098)
			(xy 169.293397 -281.413054) (xy 169.32889 -281.447146) (xy 169.358455 -281.48649) (xy 169.381326 -281.530067)
			(xy 169.39691 -281.576748) (xy 169.404805 -281.625325) (xy 169.4053 -281.649932) (xy 169.744148 -281.649932)
			(xy 169.748108 -281.600878) (xy 169.759885 -281.553094) (xy 169.779176 -281.507818) (xy 169.805479 -281.466222)
			(xy 169.838114 -281.429385) (xy 169.876235 -281.39826) (xy 169.918856 -281.373653) (xy 169.964872 -281.356201)
			(xy 170.013091 -281.346357) (xy 170.062266 -281.344376) (xy 170.111121 -281.350308) (xy 170.158392 -281.364)
			(xy 170.202854 -281.385098) (xy 170.243357 -281.413054) (xy 170.27885 -281.447146) (xy 170.308415 -281.48649)
			(xy 170.331286 -281.530067) (xy 170.34687 -281.576748) (xy 170.354765 -281.625325) (xy 170.35526 -281.649932)
			(xy 170.694108 -281.649932) (xy 170.698068 -281.600878) (xy 170.709845 -281.553094) (xy 170.729136 -281.507818)
			(xy 170.755439 -281.466222) (xy 170.788074 -281.429385) (xy 170.826195 -281.39826) (xy 170.868816 -281.373653)
			(xy 170.914832 -281.356201) (xy 170.963051 -281.346357) (xy 171.012226 -281.344376) (xy 171.061081 -281.350308)
			(xy 171.108352 -281.364) (xy 171.152814 -281.385098) (xy 171.193317 -281.413054) (xy 171.22881 -281.447146)
			(xy 171.258375 -281.48649) (xy 171.281246 -281.530067) (xy 171.29683 -281.576748) (xy 171.304725 -281.625325)
			(xy 171.30522 -281.649932) (xy 171.644068 -281.649932) (xy 171.648028 -281.600878) (xy 171.659805 -281.553094)
			(xy 171.679096 -281.507818) (xy 171.705399 -281.466222) (xy 171.738034 -281.429385) (xy 171.776155 -281.39826)
			(xy 171.818776 -281.373653) (xy 171.864792 -281.356201) (xy 171.913011 -281.346357) (xy 171.962186 -281.344376)
			(xy 172.011041 -281.350308) (xy 172.058312 -281.364) (xy 172.102774 -281.385098) (xy 172.143277 -281.413054)
			(xy 172.17877 -281.447146) (xy 172.208335 -281.48649) (xy 172.231206 -281.530067) (xy 172.24679 -281.576748)
			(xy 172.254685 -281.625325) (xy 172.25518 -281.649932) (xy 172.594282 -281.649932) (xy 172.598242 -281.600878)
			(xy 172.610019 -281.553094) (xy 172.62931 -281.507818) (xy 172.655613 -281.466222) (xy 172.688248 -281.429385)
			(xy 172.726369 -281.39826) (xy 172.76899 -281.373653) (xy 172.815006 -281.356201) (xy 172.863225 -281.346357)
			(xy 172.9124 -281.344376) (xy 172.961255 -281.350308) (xy 173.008526 -281.364) (xy 173.052988 -281.385098)
			(xy 173.093491 -281.413054) (xy 173.128984 -281.447146) (xy 173.158549 -281.48649) (xy 173.18142 -281.530067)
			(xy 173.197004 -281.576748) (xy 173.204899 -281.625325) (xy 173.205394 -281.649932) (xy 173.544242 -281.649932)
			(xy 173.548202 -281.600878) (xy 173.559979 -281.553094) (xy 173.57927 -281.507818) (xy 173.605573 -281.466222)
			(xy 173.638208 -281.429385) (xy 173.676329 -281.39826) (xy 173.71895 -281.373653) (xy 173.764966 -281.356201)
			(xy 173.813185 -281.346357) (xy 173.86236 -281.344376) (xy 173.911215 -281.350308) (xy 173.958486 -281.364)
			(xy 174.002948 -281.385098) (xy 174.043451 -281.413054) (xy 174.078944 -281.447146) (xy 174.108509 -281.48649)
			(xy 174.13138 -281.530067) (xy 174.146964 -281.576748) (xy 174.154859 -281.625325) (xy 174.155354 -281.649932)
			(xy 174.494202 -281.649932) (xy 174.498162 -281.600878) (xy 174.509939 -281.553094) (xy 174.52923 -281.507818)
			(xy 174.555533 -281.466222) (xy 174.588168 -281.429385) (xy 174.626289 -281.39826) (xy 174.66891 -281.373653)
			(xy 174.714926 -281.356201) (xy 174.763145 -281.346357) (xy 174.81232 -281.344376) (xy 174.861175 -281.350308)
			(xy 174.908446 -281.364) (xy 174.952908 -281.385098) (xy 174.993411 -281.413054) (xy 175.028904 -281.447146)
			(xy 175.058469 -281.48649) (xy 175.08134 -281.530067) (xy 175.096924 -281.576748) (xy 175.104819 -281.625325)
			(xy 175.105314 -281.649932) (xy 175.444162 -281.649932) (xy 175.448122 -281.600878) (xy 175.459899 -281.553094)
			(xy 175.47919 -281.507818) (xy 175.505493 -281.466222) (xy 175.538128 -281.429385) (xy 175.576249 -281.39826)
			(xy 175.61887 -281.373653) (xy 175.664886 -281.356201) (xy 175.713105 -281.346357) (xy 175.76228 -281.344376)
			(xy 175.811135 -281.350308) (xy 175.858406 -281.364) (xy 175.902868 -281.385098) (xy 175.943371 -281.413054)
			(xy 175.978864 -281.447146) (xy 176.008429 -281.48649) (xy 176.0313 -281.530067) (xy 176.046884 -281.576748)
			(xy 176.054779 -281.625325) (xy 176.055274 -281.649932) (xy 176.394122 -281.649932) (xy 176.398082 -281.600878)
			(xy 176.409859 -281.553094) (xy 176.42915 -281.507818) (xy 176.455453 -281.466222) (xy 176.488088 -281.429385)
			(xy 176.526209 -281.39826) (xy 176.56883 -281.373653) (xy 176.614846 -281.356201) (xy 176.663065 -281.346357)
			(xy 176.71224 -281.344376) (xy 176.761095 -281.350308) (xy 176.808366 -281.364) (xy 176.852828 -281.385098)
			(xy 176.893331 -281.413054) (xy 176.928824 -281.447146) (xy 176.958389 -281.48649) (xy 176.98126 -281.530067)
			(xy 176.996844 -281.576748) (xy 177.004739 -281.625325) (xy 177.005234 -281.649932) (xy 177.344082 -281.649932)
			(xy 177.348042 -281.600878) (xy 177.359819 -281.553094) (xy 177.37911 -281.507818) (xy 177.405413 -281.466222)
			(xy 177.438048 -281.429385) (xy 177.476169 -281.39826) (xy 177.51879 -281.373653) (xy 177.564806 -281.356201)
			(xy 177.613025 -281.346357) (xy 177.6622 -281.344376) (xy 177.711055 -281.350308) (xy 177.758326 -281.364)
			(xy 177.802788 -281.385098) (xy 177.843291 -281.413054) (xy 177.878784 -281.447146) (xy 177.908349 -281.48649)
			(xy 177.93122 -281.530067) (xy 177.946804 -281.576748) (xy 177.954699 -281.625325) (xy 177.955194 -281.649932)
			(xy 178.294042 -281.649932) (xy 178.298002 -281.600878) (xy 178.309779 -281.553094) (xy 178.32907 -281.507818)
			(xy 178.355373 -281.466222) (xy 178.388008 -281.429385) (xy 178.426129 -281.39826) (xy 178.46875 -281.373653)
			(xy 178.514766 -281.356201) (xy 178.562985 -281.346357) (xy 178.61216 -281.344376) (xy 178.661015 -281.350308)
			(xy 178.708286 -281.364) (xy 178.752748 -281.385098) (xy 178.793251 -281.413054) (xy 178.828744 -281.447146)
			(xy 178.858309 -281.48649) (xy 178.88118 -281.530067) (xy 178.896764 -281.576748) (xy 178.904659 -281.625325)
			(xy 178.905154 -281.649932) (xy 179.244256 -281.649932) (xy 179.248216 -281.600878) (xy 179.259993 -281.553094)
			(xy 179.279284 -281.507818) (xy 179.305587 -281.466222) (xy 179.338222 -281.429385) (xy 179.376343 -281.39826)
			(xy 179.418964 -281.373653) (xy 179.46498 -281.356201) (xy 179.513199 -281.346357) (xy 179.562374 -281.344376)
			(xy 179.611229 -281.350308) (xy 179.6585 -281.364) (xy 179.702962 -281.385098) (xy 179.743465 -281.413054)
			(xy 179.778958 -281.447146) (xy 179.808523 -281.48649) (xy 179.831394 -281.530067) (xy 179.846978 -281.576748)
			(xy 179.854873 -281.625325) (xy 179.855368 -281.649932) (xy 180.194216 -281.649932) (xy 180.198176 -281.600878)
			(xy 180.209953 -281.553094) (xy 180.229244 -281.507818) (xy 180.255547 -281.466222) (xy 180.288182 -281.429385)
			(xy 180.326303 -281.39826) (xy 180.368924 -281.373653) (xy 180.41494 -281.356201) (xy 180.463159 -281.346357)
			(xy 180.512334 -281.344376) (xy 180.561189 -281.350308) (xy 180.60846 -281.364) (xy 180.652922 -281.385098)
			(xy 180.693425 -281.413054) (xy 180.728918 -281.447146) (xy 180.758483 -281.48649) (xy 180.781354 -281.530067)
			(xy 180.796938 -281.576748) (xy 180.804833 -281.625325) (xy 180.805328 -281.649932) (xy 181.144176 -281.649932)
			(xy 181.148136 -281.600878) (xy 181.159913 -281.553094) (xy 181.179204 -281.507818) (xy 181.205507 -281.466222)
			(xy 181.238142 -281.429385) (xy 181.276263 -281.39826) (xy 181.318884 -281.373653) (xy 181.3649 -281.356201)
			(xy 181.413119 -281.346357) (xy 181.462294 -281.344376) (xy 181.511149 -281.350308) (xy 181.55842 -281.364)
			(xy 181.602882 -281.385098) (xy 181.643385 -281.413054) (xy 181.678878 -281.447146) (xy 181.708443 -281.48649)
			(xy 181.731314 -281.530067) (xy 181.746898 -281.576748) (xy 181.754793 -281.625325) (xy 181.755288 -281.649932)
			(xy 182.094136 -281.649932) (xy 182.098096 -281.600878) (xy 182.109873 -281.553094) (xy 182.129164 -281.507818)
			(xy 182.155467 -281.466222) (xy 182.188102 -281.429385) (xy 182.226223 -281.39826) (xy 182.268844 -281.373653)
			(xy 182.31486 -281.356201) (xy 182.363079 -281.346357) (xy 182.412254 -281.344376) (xy 182.461109 -281.350308)
			(xy 182.50838 -281.364) (xy 182.552842 -281.385098) (xy 182.593345 -281.413054) (xy 182.628838 -281.447146)
			(xy 182.658403 -281.48649) (xy 182.681274 -281.530067) (xy 182.696858 -281.576748) (xy 182.704753 -281.625325)
			(xy 182.705248 -281.649932) (xy 183.044096 -281.649932) (xy 183.048056 -281.600878) (xy 183.059833 -281.553094)
			(xy 183.079124 -281.507818) (xy 183.105427 -281.466222) (xy 183.138062 -281.429385) (xy 183.176183 -281.39826)
			(xy 183.218804 -281.373653) (xy 183.26482 -281.356201) (xy 183.313039 -281.346357) (xy 183.362214 -281.344376)
			(xy 183.411069 -281.350308) (xy 183.45834 -281.364) (xy 183.502802 -281.385098) (xy 183.543305 -281.413054)
			(xy 183.578798 -281.447146) (xy 183.608363 -281.48649) (xy 183.631234 -281.530067) (xy 183.646818 -281.576748)
			(xy 183.654713 -281.625325) (xy 183.655208 -281.649932) (xy 183.994056 -281.649932) (xy 183.998016 -281.600878)
			(xy 184.009793 -281.553094) (xy 184.029084 -281.507818) (xy 184.055387 -281.466222) (xy 184.088022 -281.429385)
			(xy 184.126143 -281.39826) (xy 184.168764 -281.373653) (xy 184.21478 -281.356201) (xy 184.262999 -281.346357)
			(xy 184.312174 -281.344376) (xy 184.361029 -281.350308) (xy 184.4083 -281.364) (xy 184.452762 -281.385098)
			(xy 184.493265 -281.413054) (xy 184.528758 -281.447146) (xy 184.558323 -281.48649) (xy 184.581194 -281.530067)
			(xy 184.596778 -281.576748) (xy 184.604673 -281.625325) (xy 184.605168 -281.649932) (xy 184.94427 -281.649932)
			(xy 184.94823 -281.600878) (xy 184.960007 -281.553094) (xy 184.979298 -281.507818) (xy 185.005601 -281.466222)
			(xy 185.038236 -281.429385) (xy 185.076357 -281.39826) (xy 185.118978 -281.373653) (xy 185.164994 -281.356201)
			(xy 185.213213 -281.346357) (xy 185.262388 -281.344376) (xy 185.311243 -281.350308) (xy 185.358514 -281.364)
			(xy 185.402976 -281.385098) (xy 185.443479 -281.413054) (xy 185.478972 -281.447146) (xy 185.508537 -281.48649)
			(xy 185.531408 -281.530067) (xy 185.546992 -281.576748) (xy 185.554887 -281.625325) (xy 185.555382 -281.649932)
			(xy 185.89423 -281.649932) (xy 185.89819 -281.600878) (xy 185.909967 -281.553094) (xy 185.929258 -281.507818)
			(xy 185.955561 -281.466222) (xy 185.988196 -281.429385) (xy 186.026317 -281.39826) (xy 186.068938 -281.373653)
			(xy 186.114954 -281.356201) (xy 186.163173 -281.346357) (xy 186.212348 -281.344376) (xy 186.261203 -281.350308)
			(xy 186.308474 -281.364) (xy 186.352936 -281.385098) (xy 186.393439 -281.413054) (xy 186.428932 -281.447146)
			(xy 186.458497 -281.48649) (xy 186.481368 -281.530067) (xy 186.496952 -281.576748) (xy 186.504847 -281.625325)
			(xy 186.505342 -281.649932) (xy 186.84419 -281.649932) (xy 186.84815 -281.600878) (xy 186.859927 -281.553094)
			(xy 186.879218 -281.507818) (xy 186.905521 -281.466222) (xy 186.938156 -281.429385) (xy 186.976277 -281.39826)
			(xy 187.018898 -281.373653) (xy 187.064914 -281.356201) (xy 187.113133 -281.346357) (xy 187.162308 -281.344376)
			(xy 187.211163 -281.350308) (xy 187.258434 -281.364) (xy 187.302896 -281.385098) (xy 187.343399 -281.413054)
			(xy 187.378892 -281.447146) (xy 187.408457 -281.48649) (xy 187.431328 -281.530067) (xy 187.446912 -281.576748)
			(xy 187.454807 -281.625325) (xy 187.455302 -281.649932) (xy 187.79415 -281.649932) (xy 187.79811 -281.600878)
			(xy 187.809887 -281.553094) (xy 187.829178 -281.507818) (xy 187.855481 -281.466222) (xy 187.888116 -281.429385)
			(xy 187.926237 -281.39826) (xy 187.968858 -281.373653) (xy 188.014874 -281.356201) (xy 188.063093 -281.346357)
			(xy 188.112268 -281.344376) (xy 188.161123 -281.350308) (xy 188.208394 -281.364) (xy 188.252856 -281.385098)
			(xy 188.293359 -281.413054) (xy 188.328852 -281.447146) (xy 188.358417 -281.48649) (xy 188.381288 -281.530067)
			(xy 188.396872 -281.576748) (xy 188.404767 -281.625325) (xy 188.405262 -281.649932) (xy 188.74411 -281.649932)
			(xy 188.74807 -281.600878) (xy 188.759847 -281.553094) (xy 188.779138 -281.507818) (xy 188.805441 -281.466222)
			(xy 188.838076 -281.429385) (xy 188.876197 -281.39826) (xy 188.918818 -281.373653) (xy 188.964834 -281.356201)
			(xy 189.013053 -281.346357) (xy 189.062228 -281.344376) (xy 189.111083 -281.350308) (xy 189.158354 -281.364)
			(xy 189.202816 -281.385098) (xy 189.243319 -281.413054) (xy 189.278812 -281.447146) (xy 189.308377 -281.48649)
			(xy 189.331248 -281.530067) (xy 189.346832 -281.576748) (xy 189.354727 -281.625325) (xy 189.355222 -281.649932)
			(xy 189.69407 -281.649932) (xy 189.69803 -281.600878) (xy 189.709807 -281.553094) (xy 189.729098 -281.507818)
			(xy 189.755401 -281.466222) (xy 189.788036 -281.429385) (xy 189.826157 -281.39826) (xy 189.868778 -281.373653)
			(xy 189.914794 -281.356201) (xy 189.963013 -281.346357) (xy 190.012188 -281.344376) (xy 190.061043 -281.350308)
			(xy 190.108314 -281.364) (xy 190.152776 -281.385098) (xy 190.193279 -281.413054) (xy 190.228772 -281.447146)
			(xy 190.258337 -281.48649) (xy 190.281208 -281.530067) (xy 190.296792 -281.576748) (xy 190.304687 -281.625325)
			(xy 190.305182 -281.649932) (xy 190.644284 -281.649932) (xy 190.648244 -281.600878) (xy 190.660021 -281.553094)
			(xy 190.679312 -281.507818) (xy 190.705615 -281.466222) (xy 190.73825 -281.429385) (xy 190.776371 -281.39826)
			(xy 190.818992 -281.373653) (xy 190.865008 -281.356201) (xy 190.913227 -281.346357) (xy 190.962402 -281.344376)
			(xy 191.011257 -281.350308) (xy 191.058528 -281.364) (xy 191.10299 -281.385098) (xy 191.143493 -281.413054)
			(xy 191.178986 -281.447146) (xy 191.208551 -281.48649) (xy 191.231422 -281.530067) (xy 191.247006 -281.576748)
			(xy 191.254901 -281.625325) (xy 191.255396 -281.649932) (xy 191.594244 -281.649932) (xy 191.598204 -281.600878)
			(xy 191.609981 -281.553094) (xy 191.629272 -281.507818) (xy 191.655575 -281.466222) (xy 191.68821 -281.429385)
			(xy 191.726331 -281.39826) (xy 191.768952 -281.373653) (xy 191.814968 -281.356201) (xy 191.863187 -281.346357)
			(xy 191.912362 -281.344376) (xy 191.961217 -281.350308) (xy 192.008488 -281.364) (xy 192.05295 -281.385098)
			(xy 192.093453 -281.413054) (xy 192.128946 -281.447146) (xy 192.158511 -281.48649) (xy 192.181382 -281.530067)
			(xy 192.196966 -281.576748) (xy 192.204861 -281.625325) (xy 192.205356 -281.649932) (xy 192.544204 -281.649932)
			(xy 192.548164 -281.600878) (xy 192.559941 -281.553094) (xy 192.579232 -281.507818) (xy 192.605535 -281.466222)
			(xy 192.63817 -281.429385) (xy 192.676291 -281.39826) (xy 192.718912 -281.373653) (xy 192.764928 -281.356201)
			(xy 192.813147 -281.346357) (xy 192.862322 -281.344376) (xy 192.911177 -281.350308) (xy 192.958448 -281.364)
			(xy 193.00291 -281.385098) (xy 193.043413 -281.413054) (xy 193.078906 -281.447146) (xy 193.108471 -281.48649)
			(xy 193.131342 -281.530067) (xy 193.146926 -281.576748) (xy 193.154821 -281.625325) (xy 193.155311 -281.649678)
			(xy 193.49391 -281.649678) (xy 193.49787 -281.600624) (xy 193.509647 -281.55284) (xy 193.528938 -281.507564)
			(xy 193.555241 -281.465968) (xy 193.587876 -281.429131) (xy 193.625997 -281.398006) (xy 193.668618 -281.373399)
			(xy 193.714634 -281.355947) (xy 193.762853 -281.346103) (xy 193.812028 -281.344122) (xy 193.860883 -281.350054)
			(xy 193.908154 -281.363746) (xy 193.952616 -281.384844) (xy 193.993119 -281.4128) (xy 194.028612 -281.446892)
			(xy 194.058177 -281.486236) (xy 194.081048 -281.529813) (xy 194.096632 -281.576494) (xy 194.104527 -281.625071)
			(xy 194.105022 -281.649678) (xy 194.105017 -281.649932) (xy 194.44387 -281.649932) (xy 194.44783 -281.600878)
			(xy 194.459607 -281.553094) (xy 194.478898 -281.507818) (xy 194.505201 -281.466222) (xy 194.537836 -281.429385)
			(xy 194.575957 -281.39826) (xy 194.618578 -281.373653) (xy 194.664594 -281.356201) (xy 194.712813 -281.346357)
			(xy 194.761988 -281.344376) (xy 194.810843 -281.350308) (xy 194.858114 -281.364) (xy 194.902576 -281.385098)
			(xy 194.943079 -281.413054) (xy 194.978572 -281.447146) (xy 195.008137 -281.48649) (xy 195.031008 -281.530067)
			(xy 195.046592 -281.576748) (xy 195.054487 -281.625325) (xy 195.054982 -281.649932) (xy 195.394084 -281.649932)
			(xy 195.398044 -281.600878) (xy 195.409821 -281.553094) (xy 195.429112 -281.507818) (xy 195.455415 -281.466222)
			(xy 195.48805 -281.429385) (xy 195.526171 -281.39826) (xy 195.568792 -281.373653) (xy 195.614808 -281.356201)
			(xy 195.663027 -281.346357) (xy 195.712202 -281.344376) (xy 195.761057 -281.350308) (xy 195.808328 -281.364)
			(xy 195.85279 -281.385098) (xy 195.893293 -281.413054) (xy 195.928786 -281.447146) (xy 195.958351 -281.48649)
			(xy 195.981222 -281.530067) (xy 195.996806 -281.576748) (xy 196.004701 -281.625325) (xy 196.005196 -281.649932)
			(xy 196.344044 -281.649932) (xy 196.348004 -281.600878) (xy 196.359781 -281.553094) (xy 196.379072 -281.507818)
			(xy 196.405375 -281.466222) (xy 196.43801 -281.429385) (xy 196.476131 -281.39826) (xy 196.518752 -281.373653)
			(xy 196.564768 -281.356201) (xy 196.612987 -281.346357) (xy 196.662162 -281.344376) (xy 196.711017 -281.350308)
			(xy 196.758288 -281.364) (xy 196.80275 -281.385098) (xy 196.843253 -281.413054) (xy 196.878746 -281.447146)
			(xy 196.908311 -281.48649) (xy 196.931182 -281.530067) (xy 196.946766 -281.576748) (xy 196.954661 -281.625325)
			(xy 196.955156 -281.649932) (xy 196.954661 -281.674539) (xy 196.954482 -281.67564) (xy 197.273414 -281.67564)
			(xy 197.273414 -281.624224) (xy 197.281457 -281.573442) (xy 197.297345 -281.524543) (xy 197.320688 -281.478731)
			(xy 197.350909 -281.437135) (xy 197.387265 -281.400779) (xy 197.428861 -281.370558) (xy 197.474673 -281.347215)
			(xy 197.523572 -281.331327) (xy 197.574354 -281.323284) (xy 197.62577 -281.323284) (xy 197.676552 -281.331327)
			(xy 197.725451 -281.347215) (xy 197.771263 -281.370558) (xy 197.812859 -281.400779) (xy 197.849215 -281.437135)
			(xy 197.879436 -281.478731) (xy 197.902779 -281.524543) (xy 197.918667 -281.573442) (xy 197.92671 -281.624224)
			(xy 197.927214 -281.649932) (xy 197.92671 -281.67564) (xy 198.223374 -281.67564) (xy 198.223374 -281.624224)
			(xy 198.231417 -281.573442) (xy 198.247305 -281.524543) (xy 198.270648 -281.478731) (xy 198.300869 -281.437135)
			(xy 198.337225 -281.400779) (xy 198.378821 -281.370558) (xy 198.424633 -281.347215) (xy 198.473532 -281.331327)
			(xy 198.524314 -281.323284) (xy 198.57573 -281.323284) (xy 198.626512 -281.331327) (xy 198.660401 -281.342338)
			(xy 219.957142 -281.342338) (xy 219.957591 -281.315084) (xy 219.965344 -281.26113) (xy 219.980698 -281.208829)
			(xy 220.003339 -281.159245) (xy 220.032808 -281.11339) (xy 220.068504 -281.072195) (xy 220.109699 -281.036501)
			(xy 220.155556 -281.007034) (xy 220.20514 -280.984393) (xy 220.257441 -280.969041) (xy 220.311396 -280.96129)
			(xy 220.33865 -280.96083) (xy 220.367389 -280.961342) (xy 220.424216 -280.96997) (xy 220.479106 -280.987024)
			(xy 220.530818 -281.012118) (xy 220.578181 -281.044683) (xy 220.599508 -281.063954) (xy 220.60662 -281.070558)
			(xy 220.624146 -281.07767) (xy 220.713554 -281.07767) (xy 220.73108 -281.070558) (xy 220.738192 -281.063954)
			(xy 220.759519 -281.044684) (xy 220.806882 -281.012119) (xy 220.858593 -280.987028) (xy 220.913484 -280.969978)
			(xy 220.970311 -280.961356) (xy 221.027789 -280.961356) (xy 221.084616 -280.969978) (xy 221.139507 -280.987028)
			(xy 221.191218 -281.012119) (xy 221.238581 -281.044684) (xy 221.259908 -281.063954) (xy 221.26702 -281.070558)
			(xy 221.284546 -281.07767) (xy 221.373954 -281.07767) (xy 221.39148 -281.070558) (xy 221.398592 -281.063954)
			(xy 221.419901 -281.044662) (xy 221.467268 -281.012098) (xy 221.518984 -280.987009) (xy 221.573879 -280.969964)
			(xy 221.63071 -280.961347) (xy 221.65945 -280.96083) (xy 221.689572 -280.961438) (xy 221.749066 -280.970911)
			(xy 221.806334 -280.989613) (xy 221.859951 -281.017081) (xy 221.908588 -281.052631) (xy 221.930214 -281.073606)
			(xy 221.937326 -281.080972) (xy 221.956122 -281.088592) (xy 222.048578 -281.088592) (xy 222.067374 -281.080972)
			(xy 222.074486 -281.073606) (xy 222.096095 -281.052608) (xy 222.144728 -281.017042) (xy 222.198348 -280.989565)
			(xy 222.255622 -280.970861) (xy 222.315125 -280.961395) (xy 222.34525 -280.96083) (xy 222.372503 -280.961302)
			(xy 222.426456 -280.969053) (xy 222.478756 -280.984405) (xy 222.528338 -281.007044) (xy 222.574194 -281.03651)
			(xy 222.615388 -281.072204) (xy 222.651082 -281.113397) (xy 222.68055 -281.159251) (xy 222.703191 -281.208833)
			(xy 222.718544 -281.261132) (xy 222.726297 -281.315085) (xy 222.726758 -281.342338) (xy 222.726303 -281.370075)
			(xy 222.718308 -281.42497) (xy 222.702434 -281.478124) (xy 222.679017 -281.528413) (xy 222.648552 -281.574772)
			(xy 222.630492 -281.59583) (xy 222.624142 -281.602688) (xy 222.617538 -281.620214) (xy 222.617538 -281.706574)
			(xy 222.624142 -281.723846) (xy 222.630492 -281.730704) (xy 222.648552 -281.751802) (xy 222.679062 -281.798204)
			(xy 222.702529 -281.848536) (xy 222.718457 -281.901736) (xy 222.726509 -281.956683) (xy 222.727012 -281.98445)
			(xy 222.726498 -282.011701) (xy 222.718748 -282.06565) (xy 222.703399 -282.117947) (xy 222.680762 -282.167527)
			(xy 222.6513 -282.21338) (xy 222.615611 -282.254573) (xy 222.574423 -282.290267) (xy 222.528574 -282.319736)
			(xy 222.478998 -282.34238) (xy 222.426703 -282.357737) (xy 222.372755 -282.365494) (xy 222.345504 -282.365958)
			(xy 222.315381 -282.365383) (xy 222.255885 -282.355902) (xy 222.198617 -282.337192) (xy 222.145 -282.309718)
			(xy 222.096365 -282.27416) (xy 222.07474 -282.253182) (xy 222.067628 -282.245816) (xy 222.048832 -282.238196)
			(xy 221.956376 -282.238196) (xy 221.93758 -282.245816) (xy 221.930468 -282.253182) (xy 221.908833 -282.274152)
			(xy 221.860207 -282.309722) (xy 221.806594 -282.337204) (xy 221.749325 -282.355915) (xy 221.689828 -282.365389)
			(xy 221.659704 -282.365958) (xy 221.630966 -282.365416) (xy 221.57414 -282.356796) (xy 221.51925 -282.339749)
			(xy 221.467538 -282.314662) (xy 221.420174 -282.282102) (xy 221.398846 -282.262834) (xy 221.391734 -282.25623)
			(xy 221.374208 -282.249118) (xy 221.2848 -282.249118) (xy 221.267274 -282.25623) (xy 221.260162 -282.262834)
			(xy 221.238835 -282.282104) (xy 221.191472 -282.314669) (xy 221.139761 -282.33976) (xy 221.08487 -282.35681)
			(xy 221.028043 -282.365432) (xy 220.970565 -282.365432) (xy 220.913738 -282.35681) (xy 220.858847 -282.33976)
			(xy 220.807136 -282.314669) (xy 220.759773 -282.282104) (xy 220.738446 -282.262834) (xy 220.731334 -282.25623)
			(xy 220.713808 -282.249118) (xy 220.6244 -282.249118) (xy 220.606874 -282.25623) (xy 220.599762 -282.262834)
			(xy 220.578429 -282.282098) (xy 220.531069 -282.314666) (xy 220.479359 -282.339761) (xy 220.424469 -282.356813)
			(xy 220.367643 -282.365437) (xy 220.338904 -282.365958) (xy 220.311649 -282.365541) (xy 220.257694 -282.357783)
			(xy 220.205392 -282.342425) (xy 220.155809 -282.319779) (xy 220.109953 -282.290307) (xy 220.068759 -282.254608)
			(xy 220.033065 -282.21341) (xy 220.003599 -282.167551) (xy 219.980959 -282.117965) (xy 219.965607 -282.065661)
			(xy 219.957856 -282.011705) (xy 219.957396 -281.98445) (xy 219.957855 -281.956713) (xy 219.965851 -281.901819)
			(xy 219.981725 -281.848666) (xy 220.005141 -281.798377) (xy 220.035603 -281.752016) (xy 220.053662 -281.730958)
			(xy 220.060012 -281.7241) (xy 220.066616 -281.706574) (xy 220.066616 -281.620214) (xy 220.060012 -281.602942)
			(xy 220.053662 -281.596084) (xy 220.035589 -281.574997) (xy 220.005082 -281.528592) (xy 219.981619 -281.478257)
			(xy 219.965694 -281.425054) (xy 219.957644 -281.370105) (xy 219.957142 -281.342338) (xy 198.660401 -281.342338)
			(xy 198.675411 -281.347215) (xy 198.721223 -281.370558) (xy 198.762819 -281.400779) (xy 198.799175 -281.437135)
			(xy 198.829396 -281.478731) (xy 198.852739 -281.524543) (xy 198.868627 -281.573442) (xy 198.87667 -281.624224)
			(xy 198.877174 -281.649932) (xy 198.877169 -281.650186) (xy 199.194432 -281.650186) (xy 199.198392 -281.601132)
			(xy 199.210169 -281.553348) (xy 199.22946 -281.508072) (xy 199.255763 -281.466476) (xy 199.288398 -281.429639)
			(xy 199.326519 -281.398514) (xy 199.36914 -281.373907) (xy 199.415156 -281.356455) (xy 199.463375 -281.346611)
			(xy 199.51255 -281.34463) (xy 199.561405 -281.350562) (xy 199.608676 -281.364254) (xy 199.653138 -281.385352)
			(xy 199.693641 -281.413308) (xy 199.729134 -281.4474) (xy 199.758699 -281.486744) (xy 199.78157 -281.530321)
			(xy 199.797154 -281.577002) (xy 199.805049 -281.625579) (xy 199.805544 -281.650186) (xy 199.805049 -281.674793)
			(xy 199.797154 -281.72337) (xy 199.78157 -281.770051) (xy 199.758699 -281.813628) (xy 199.729134 -281.852972)
			(xy 199.693641 -281.887064) (xy 199.653138 -281.91502) (xy 199.608676 -281.936118) (xy 199.561405 -281.94981)
			(xy 199.51255 -281.955742) (xy 199.463375 -281.953761) (xy 199.415156 -281.943917) (xy 199.36914 -281.926465)
			(xy 199.326519 -281.901858) (xy 199.288398 -281.870733) (xy 199.255763 -281.833896) (xy 199.22946 -281.7923)
			(xy 199.210169 -281.747024) (xy 199.198392 -281.69924) (xy 199.194432 -281.650186) (xy 198.877169 -281.650186)
			(xy 198.87667 -281.67564) (xy 198.868627 -281.726422) (xy 198.852739 -281.775321) (xy 198.829396 -281.821133)
			(xy 198.799175 -281.862729) (xy 198.762819 -281.899085) (xy 198.721223 -281.929306) (xy 198.675411 -281.952649)
			(xy 198.626512 -281.968537) (xy 198.57573 -281.97658) (xy 198.524314 -281.97658) (xy 198.473532 -281.968537)
			(xy 198.424633 -281.952649) (xy 198.378821 -281.929306) (xy 198.337225 -281.899085) (xy 198.300869 -281.862729)
			(xy 198.270648 -281.821133) (xy 198.247305 -281.775321) (xy 198.231417 -281.726422) (xy 198.223374 -281.67564)
			(xy 197.92671 -281.67564) (xy 197.918667 -281.726422) (xy 197.902779 -281.775321) (xy 197.879436 -281.821133)
			(xy 197.849215 -281.862729) (xy 197.812859 -281.899085) (xy 197.771263 -281.929306) (xy 197.725451 -281.952649)
			(xy 197.676552 -281.968537) (xy 197.62577 -281.97658) (xy 197.574354 -281.97658) (xy 197.523572 -281.968537)
			(xy 197.474673 -281.952649) (xy 197.428861 -281.929306) (xy 197.387265 -281.899085) (xy 197.350909 -281.862729)
			(xy 197.320688 -281.821133) (xy 197.297345 -281.775321) (xy 197.281457 -281.726422) (xy 197.273414 -281.67564)
			(xy 196.954482 -281.67564) (xy 196.946766 -281.723116) (xy 196.931182 -281.769797) (xy 196.908311 -281.813374)
			(xy 196.878746 -281.852718) (xy 196.843253 -281.88681) (xy 196.80275 -281.914766) (xy 196.758288 -281.935864)
			(xy 196.711017 -281.949556) (xy 196.662162 -281.955488) (xy 196.612987 -281.953507) (xy 196.564768 -281.943663)
			(xy 196.518752 -281.926211) (xy 196.476131 -281.901604) (xy 196.43801 -281.870479) (xy 196.405375 -281.833642)
			(xy 196.379072 -281.792046) (xy 196.359781 -281.74677) (xy 196.348004 -281.698986) (xy 196.344044 -281.649932)
			(xy 196.005196 -281.649932) (xy 196.004701 -281.674539) (xy 195.996806 -281.723116) (xy 195.981222 -281.769797)
			(xy 195.958351 -281.813374) (xy 195.928786 -281.852718) (xy 195.893293 -281.88681) (xy 195.85279 -281.914766)
			(xy 195.808328 -281.935864) (xy 195.761057 -281.949556) (xy 195.712202 -281.955488) (xy 195.663027 -281.953507)
			(xy 195.614808 -281.943663) (xy 195.568792 -281.926211) (xy 195.526171 -281.901604) (xy 195.48805 -281.870479)
			(xy 195.455415 -281.833642) (xy 195.429112 -281.792046) (xy 195.409821 -281.74677) (xy 195.398044 -281.698986)
			(xy 195.394084 -281.649932) (xy 195.054982 -281.649932) (xy 195.054487 -281.674539) (xy 195.046592 -281.723116)
			(xy 195.031008 -281.769797) (xy 195.008137 -281.813374) (xy 194.978572 -281.852718) (xy 194.943079 -281.88681)
			(xy 194.902576 -281.914766) (xy 194.858114 -281.935864) (xy 194.810843 -281.949556) (xy 194.761988 -281.955488)
			(xy 194.712813 -281.953507) (xy 194.664594 -281.943663) (xy 194.618578 -281.926211) (xy 194.575957 -281.901604)
			(xy 194.537836 -281.870479) (xy 194.505201 -281.833642) (xy 194.478898 -281.792046) (xy 194.459607 -281.74677)
			(xy 194.44783 -281.698986) (xy 194.44387 -281.649932) (xy 194.105017 -281.649932) (xy 194.104527 -281.674285)
			(xy 194.096632 -281.722862) (xy 194.081048 -281.769543) (xy 194.058177 -281.81312) (xy 194.028612 -281.852464)
			(xy 193.993119 -281.886556) (xy 193.952616 -281.914512) (xy 193.908154 -281.93561) (xy 193.860883 -281.949302)
			(xy 193.812028 -281.955234) (xy 193.762853 -281.953253) (xy 193.714634 -281.943409) (xy 193.668618 -281.925957)
			(xy 193.625997 -281.90135) (xy 193.587876 -281.870225) (xy 193.555241 -281.833388) (xy 193.528938 -281.791792)
			(xy 193.509647 -281.746516) (xy 193.49787 -281.698732) (xy 193.49391 -281.649678) (xy 193.155311 -281.649678)
			(xy 193.155316 -281.649932) (xy 193.154821 -281.674539) (xy 193.146926 -281.723116) (xy 193.131342 -281.769797)
			(xy 193.108471 -281.813374) (xy 193.078906 -281.852718) (xy 193.043413 -281.88681) (xy 193.00291 -281.914766)
			(xy 192.958448 -281.935864) (xy 192.911177 -281.949556) (xy 192.862322 -281.955488) (xy 192.813147 -281.953507)
			(xy 192.764928 -281.943663) (xy 192.718912 -281.926211) (xy 192.676291 -281.901604) (xy 192.63817 -281.870479)
			(xy 192.605535 -281.833642) (xy 192.579232 -281.792046) (xy 192.559941 -281.74677) (xy 192.548164 -281.698986)
			(xy 192.544204 -281.649932) (xy 192.205356 -281.649932) (xy 192.204861 -281.674539) (xy 192.196966 -281.723116)
			(xy 192.181382 -281.769797) (xy 192.158511 -281.813374) (xy 192.128946 -281.852718) (xy 192.093453 -281.88681)
			(xy 192.05295 -281.914766) (xy 192.008488 -281.935864) (xy 191.961217 -281.949556) (xy 191.912362 -281.955488)
			(xy 191.863187 -281.953507) (xy 191.814968 -281.943663) (xy 191.768952 -281.926211) (xy 191.726331 -281.901604)
			(xy 191.68821 -281.870479) (xy 191.655575 -281.833642) (xy 191.629272 -281.792046) (xy 191.609981 -281.74677)
			(xy 191.598204 -281.698986) (xy 191.594244 -281.649932) (xy 191.255396 -281.649932) (xy 191.254901 -281.674539)
			(xy 191.247006 -281.723116) (xy 191.231422 -281.769797) (xy 191.208551 -281.813374) (xy 191.178986 -281.852718)
			(xy 191.143493 -281.88681) (xy 191.10299 -281.914766) (xy 191.058528 -281.935864) (xy 191.011257 -281.949556)
			(xy 190.962402 -281.955488) (xy 190.913227 -281.953507) (xy 190.865008 -281.943663) (xy 190.818992 -281.926211)
			(xy 190.776371 -281.901604) (xy 190.73825 -281.870479) (xy 190.705615 -281.833642) (xy 190.679312 -281.792046)
			(xy 190.660021 -281.74677) (xy 190.648244 -281.698986) (xy 190.644284 -281.649932) (xy 190.305182 -281.649932)
			(xy 190.304687 -281.674539) (xy 190.296792 -281.723116) (xy 190.281208 -281.769797) (xy 190.258337 -281.813374)
			(xy 190.228772 -281.852718) (xy 190.193279 -281.88681) (xy 190.152776 -281.914766) (xy 190.108314 -281.935864)
			(xy 190.061043 -281.949556) (xy 190.012188 -281.955488) (xy 189.963013 -281.953507) (xy 189.914794 -281.943663)
			(xy 189.868778 -281.926211) (xy 189.826157 -281.901604) (xy 189.788036 -281.870479) (xy 189.755401 -281.833642)
			(xy 189.729098 -281.792046) (xy 189.709807 -281.74677) (xy 189.69803 -281.698986) (xy 189.69407 -281.649932)
			(xy 189.355222 -281.649932) (xy 189.354727 -281.674539) (xy 189.346832 -281.723116) (xy 189.331248 -281.769797)
			(xy 189.308377 -281.813374) (xy 189.278812 -281.852718) (xy 189.243319 -281.88681) (xy 189.202816 -281.914766)
			(xy 189.158354 -281.935864) (xy 189.111083 -281.949556) (xy 189.062228 -281.955488) (xy 189.013053 -281.953507)
			(xy 188.964834 -281.943663) (xy 188.918818 -281.926211) (xy 188.876197 -281.901604) (xy 188.838076 -281.870479)
			(xy 188.805441 -281.833642) (xy 188.779138 -281.792046) (xy 188.759847 -281.74677) (xy 188.74807 -281.698986)
			(xy 188.74411 -281.649932) (xy 188.405262 -281.649932) (xy 188.404767 -281.674539) (xy 188.396872 -281.723116)
			(xy 188.381288 -281.769797) (xy 188.358417 -281.813374) (xy 188.328852 -281.852718) (xy 188.293359 -281.88681)
			(xy 188.252856 -281.914766) (xy 188.208394 -281.935864) (xy 188.161123 -281.949556) (xy 188.112268 -281.955488)
			(xy 188.063093 -281.953507) (xy 188.014874 -281.943663) (xy 187.968858 -281.926211) (xy 187.926237 -281.901604)
			(xy 187.888116 -281.870479) (xy 187.855481 -281.833642) (xy 187.829178 -281.792046) (xy 187.809887 -281.74677)
			(xy 187.79811 -281.698986) (xy 187.79415 -281.649932) (xy 187.455302 -281.649932) (xy 187.454807 -281.674539)
			(xy 187.446912 -281.723116) (xy 187.431328 -281.769797) (xy 187.408457 -281.813374) (xy 187.378892 -281.852718)
			(xy 187.343399 -281.88681) (xy 187.302896 -281.914766) (xy 187.258434 -281.935864) (xy 187.211163 -281.949556)
			(xy 187.162308 -281.955488) (xy 187.113133 -281.953507) (xy 187.064914 -281.943663) (xy 187.018898 -281.926211)
			(xy 186.976277 -281.901604) (xy 186.938156 -281.870479) (xy 186.905521 -281.833642) (xy 186.879218 -281.792046)
			(xy 186.859927 -281.74677) (xy 186.84815 -281.698986) (xy 186.84419 -281.649932) (xy 186.505342 -281.649932)
			(xy 186.504847 -281.674539) (xy 186.496952 -281.723116) (xy 186.481368 -281.769797) (xy 186.458497 -281.813374)
			(xy 186.428932 -281.852718) (xy 186.393439 -281.88681) (xy 186.352936 -281.914766) (xy 186.308474 -281.935864)
			(xy 186.261203 -281.949556) (xy 186.212348 -281.955488) (xy 186.163173 -281.953507) (xy 186.114954 -281.943663)
			(xy 186.068938 -281.926211) (xy 186.026317 -281.901604) (xy 185.988196 -281.870479) (xy 185.955561 -281.833642)
			(xy 185.929258 -281.792046) (xy 185.909967 -281.74677) (xy 185.89819 -281.698986) (xy 185.89423 -281.649932)
			(xy 185.555382 -281.649932) (xy 185.554887 -281.674539) (xy 185.546992 -281.723116) (xy 185.531408 -281.769797)
			(xy 185.508537 -281.813374) (xy 185.478972 -281.852718) (xy 185.443479 -281.88681) (xy 185.402976 -281.914766)
			(xy 185.358514 -281.935864) (xy 185.311243 -281.949556) (xy 185.262388 -281.955488) (xy 185.213213 -281.953507)
			(xy 185.164994 -281.943663) (xy 185.118978 -281.926211) (xy 185.076357 -281.901604) (xy 185.038236 -281.870479)
			(xy 185.005601 -281.833642) (xy 184.979298 -281.792046) (xy 184.960007 -281.74677) (xy 184.94823 -281.698986)
			(xy 184.94427 -281.649932) (xy 184.605168 -281.649932) (xy 184.604673 -281.674539) (xy 184.596778 -281.723116)
			(xy 184.581194 -281.769797) (xy 184.558323 -281.813374) (xy 184.528758 -281.852718) (xy 184.493265 -281.88681)
			(xy 184.452762 -281.914766) (xy 184.4083 -281.935864) (xy 184.361029 -281.949556) (xy 184.312174 -281.955488)
			(xy 184.262999 -281.953507) (xy 184.21478 -281.943663) (xy 184.168764 -281.926211) (xy 184.126143 -281.901604)
			(xy 184.088022 -281.870479) (xy 184.055387 -281.833642) (xy 184.029084 -281.792046) (xy 184.009793 -281.74677)
			(xy 183.998016 -281.698986) (xy 183.994056 -281.649932) (xy 183.655208 -281.649932) (xy 183.654713 -281.674539)
			(xy 183.646818 -281.723116) (xy 183.631234 -281.769797) (xy 183.608363 -281.813374) (xy 183.578798 -281.852718)
			(xy 183.543305 -281.88681) (xy 183.502802 -281.914766) (xy 183.45834 -281.935864) (xy 183.411069 -281.949556)
			(xy 183.362214 -281.955488) (xy 183.313039 -281.953507) (xy 183.26482 -281.943663) (xy 183.218804 -281.926211)
			(xy 183.176183 -281.901604) (xy 183.138062 -281.870479) (xy 183.105427 -281.833642) (xy 183.079124 -281.792046)
			(xy 183.059833 -281.74677) (xy 183.048056 -281.698986) (xy 183.044096 -281.649932) (xy 182.705248 -281.649932)
			(xy 182.704753 -281.674539) (xy 182.696858 -281.723116) (xy 182.681274 -281.769797) (xy 182.658403 -281.813374)
			(xy 182.628838 -281.852718) (xy 182.593345 -281.88681) (xy 182.552842 -281.914766) (xy 182.50838 -281.935864)
			(xy 182.461109 -281.949556) (xy 182.412254 -281.955488) (xy 182.363079 -281.953507) (xy 182.31486 -281.943663)
			(xy 182.268844 -281.926211) (xy 182.226223 -281.901604) (xy 182.188102 -281.870479) (xy 182.155467 -281.833642)
			(xy 182.129164 -281.792046) (xy 182.109873 -281.74677) (xy 182.098096 -281.698986) (xy 182.094136 -281.649932)
			(xy 181.755288 -281.649932) (xy 181.754793 -281.674539) (xy 181.746898 -281.723116) (xy 181.731314 -281.769797)
			(xy 181.708443 -281.813374) (xy 181.678878 -281.852718) (xy 181.643385 -281.88681) (xy 181.602882 -281.914766)
			(xy 181.55842 -281.935864) (xy 181.511149 -281.949556) (xy 181.462294 -281.955488) (xy 181.413119 -281.953507)
			(xy 181.3649 -281.943663) (xy 181.318884 -281.926211) (xy 181.276263 -281.901604) (xy 181.238142 -281.870479)
			(xy 181.205507 -281.833642) (xy 181.179204 -281.792046) (xy 181.159913 -281.74677) (xy 181.148136 -281.698986)
			(xy 181.144176 -281.649932) (xy 180.805328 -281.649932) (xy 180.804833 -281.674539) (xy 180.796938 -281.723116)
			(xy 180.781354 -281.769797) (xy 180.758483 -281.813374) (xy 180.728918 -281.852718) (xy 180.693425 -281.88681)
			(xy 180.652922 -281.914766) (xy 180.60846 -281.935864) (xy 180.561189 -281.949556) (xy 180.512334 -281.955488)
			(xy 180.463159 -281.953507) (xy 180.41494 -281.943663) (xy 180.368924 -281.926211) (xy 180.326303 -281.901604)
			(xy 180.288182 -281.870479) (xy 180.255547 -281.833642) (xy 180.229244 -281.792046) (xy 180.209953 -281.74677)
			(xy 180.198176 -281.698986) (xy 180.194216 -281.649932) (xy 179.855368 -281.649932) (xy 179.854873 -281.674539)
			(xy 179.846978 -281.723116) (xy 179.831394 -281.769797) (xy 179.808523 -281.813374) (xy 179.778958 -281.852718)
			(xy 179.743465 -281.88681) (xy 179.702962 -281.914766) (xy 179.6585 -281.935864) (xy 179.611229 -281.949556)
			(xy 179.562374 -281.955488) (xy 179.513199 -281.953507) (xy 179.46498 -281.943663) (xy 179.418964 -281.926211)
			(xy 179.376343 -281.901604) (xy 179.338222 -281.870479) (xy 179.305587 -281.833642) (xy 179.279284 -281.792046)
			(xy 179.259993 -281.74677) (xy 179.248216 -281.698986) (xy 179.244256 -281.649932) (xy 178.905154 -281.649932)
			(xy 178.904659 -281.674539) (xy 178.896764 -281.723116) (xy 178.88118 -281.769797) (xy 178.858309 -281.813374)
			(xy 178.828744 -281.852718) (xy 178.793251 -281.88681) (xy 178.752748 -281.914766) (xy 178.708286 -281.935864)
			(xy 178.661015 -281.949556) (xy 178.61216 -281.955488) (xy 178.562985 -281.953507) (xy 178.514766 -281.943663)
			(xy 178.46875 -281.926211) (xy 178.426129 -281.901604) (xy 178.388008 -281.870479) (xy 178.355373 -281.833642)
			(xy 178.32907 -281.792046) (xy 178.309779 -281.74677) (xy 178.298002 -281.698986) (xy 178.294042 -281.649932)
			(xy 177.955194 -281.649932) (xy 177.954699 -281.674539) (xy 177.946804 -281.723116) (xy 177.93122 -281.769797)
			(xy 177.908349 -281.813374) (xy 177.878784 -281.852718) (xy 177.843291 -281.88681) (xy 177.802788 -281.914766)
			(xy 177.758326 -281.935864) (xy 177.711055 -281.949556) (xy 177.6622 -281.955488) (xy 177.613025 -281.953507)
			(xy 177.564806 -281.943663) (xy 177.51879 -281.926211) (xy 177.476169 -281.901604) (xy 177.438048 -281.870479)
			(xy 177.405413 -281.833642) (xy 177.37911 -281.792046) (xy 177.359819 -281.74677) (xy 177.348042 -281.698986)
			(xy 177.344082 -281.649932) (xy 177.005234 -281.649932) (xy 177.004739 -281.674539) (xy 176.996844 -281.723116)
			(xy 176.98126 -281.769797) (xy 176.958389 -281.813374) (xy 176.928824 -281.852718) (xy 176.893331 -281.88681)
			(xy 176.852828 -281.914766) (xy 176.808366 -281.935864) (xy 176.761095 -281.949556) (xy 176.71224 -281.955488)
			(xy 176.663065 -281.953507) (xy 176.614846 -281.943663) (xy 176.56883 -281.926211) (xy 176.526209 -281.901604)
			(xy 176.488088 -281.870479) (xy 176.455453 -281.833642) (xy 176.42915 -281.792046) (xy 176.409859 -281.74677)
			(xy 176.398082 -281.698986) (xy 176.394122 -281.649932) (xy 176.055274 -281.649932) (xy 176.054779 -281.674539)
			(xy 176.046884 -281.723116) (xy 176.0313 -281.769797) (xy 176.008429 -281.813374) (xy 175.978864 -281.852718)
			(xy 175.943371 -281.88681) (xy 175.902868 -281.914766) (xy 175.858406 -281.935864) (xy 175.811135 -281.949556)
			(xy 175.76228 -281.955488) (xy 175.713105 -281.953507) (xy 175.664886 -281.943663) (xy 175.61887 -281.926211)
			(xy 175.576249 -281.901604) (xy 175.538128 -281.870479) (xy 175.505493 -281.833642) (xy 175.47919 -281.792046)
			(xy 175.459899 -281.74677) (xy 175.448122 -281.698986) (xy 175.444162 -281.649932) (xy 175.105314 -281.649932)
			(xy 175.104819 -281.674539) (xy 175.096924 -281.723116) (xy 175.08134 -281.769797) (xy 175.058469 -281.813374)
			(xy 175.028904 -281.852718) (xy 174.993411 -281.88681) (xy 174.952908 -281.914766) (xy 174.908446 -281.935864)
			(xy 174.861175 -281.949556) (xy 174.81232 -281.955488) (xy 174.763145 -281.953507) (xy 174.714926 -281.943663)
			(xy 174.66891 -281.926211) (xy 174.626289 -281.901604) (xy 174.588168 -281.870479) (xy 174.555533 -281.833642)
			(xy 174.52923 -281.792046) (xy 174.509939 -281.74677) (xy 174.498162 -281.698986) (xy 174.494202 -281.649932)
			(xy 174.155354 -281.649932) (xy 174.154859 -281.674539) (xy 174.146964 -281.723116) (xy 174.13138 -281.769797)
			(xy 174.108509 -281.813374) (xy 174.078944 -281.852718) (xy 174.043451 -281.88681) (xy 174.002948 -281.914766)
			(xy 173.958486 -281.935864) (xy 173.911215 -281.949556) (xy 173.86236 -281.955488) (xy 173.813185 -281.953507)
			(xy 173.764966 -281.943663) (xy 173.71895 -281.926211) (xy 173.676329 -281.901604) (xy 173.638208 -281.870479)
			(xy 173.605573 -281.833642) (xy 173.57927 -281.792046) (xy 173.559979 -281.74677) (xy 173.548202 -281.698986)
			(xy 173.544242 -281.649932) (xy 173.205394 -281.649932) (xy 173.204899 -281.674539) (xy 173.197004 -281.723116)
			(xy 173.18142 -281.769797) (xy 173.158549 -281.813374) (xy 173.128984 -281.852718) (xy 173.093491 -281.88681)
			(xy 173.052988 -281.914766) (xy 173.008526 -281.935864) (xy 172.961255 -281.949556) (xy 172.9124 -281.955488)
			(xy 172.863225 -281.953507) (xy 172.815006 -281.943663) (xy 172.76899 -281.926211) (xy 172.726369 -281.901604)
			(xy 172.688248 -281.870479) (xy 172.655613 -281.833642) (xy 172.62931 -281.792046) (xy 172.610019 -281.74677)
			(xy 172.598242 -281.698986) (xy 172.594282 -281.649932) (xy 172.25518 -281.649932) (xy 172.254685 -281.674539)
			(xy 172.24679 -281.723116) (xy 172.231206 -281.769797) (xy 172.208335 -281.813374) (xy 172.17877 -281.852718)
			(xy 172.143277 -281.88681) (xy 172.102774 -281.914766) (xy 172.058312 -281.935864) (xy 172.011041 -281.949556)
			(xy 171.962186 -281.955488) (xy 171.913011 -281.953507) (xy 171.864792 -281.943663) (xy 171.818776 -281.926211)
			(xy 171.776155 -281.901604) (xy 171.738034 -281.870479) (xy 171.705399 -281.833642) (xy 171.679096 -281.792046)
			(xy 171.659805 -281.74677) (xy 171.648028 -281.698986) (xy 171.644068 -281.649932) (xy 171.30522 -281.649932)
			(xy 171.304725 -281.674539) (xy 171.29683 -281.723116) (xy 171.281246 -281.769797) (xy 171.258375 -281.813374)
			(xy 171.22881 -281.852718) (xy 171.193317 -281.88681) (xy 171.152814 -281.914766) (xy 171.108352 -281.935864)
			(xy 171.061081 -281.949556) (xy 171.012226 -281.955488) (xy 170.963051 -281.953507) (xy 170.914832 -281.943663)
			(xy 170.868816 -281.926211) (xy 170.826195 -281.901604) (xy 170.788074 -281.870479) (xy 170.755439 -281.833642)
			(xy 170.729136 -281.792046) (xy 170.709845 -281.74677) (xy 170.698068 -281.698986) (xy 170.694108 -281.649932)
			(xy 170.35526 -281.649932) (xy 170.354765 -281.674539) (xy 170.34687 -281.723116) (xy 170.331286 -281.769797)
			(xy 170.308415 -281.813374) (xy 170.27885 -281.852718) (xy 170.243357 -281.88681) (xy 170.202854 -281.914766)
			(xy 170.158392 -281.935864) (xy 170.111121 -281.949556) (xy 170.062266 -281.955488) (xy 170.013091 -281.953507)
			(xy 169.964872 -281.943663) (xy 169.918856 -281.926211) (xy 169.876235 -281.901604) (xy 169.838114 -281.870479)
			(xy 169.805479 -281.833642) (xy 169.779176 -281.792046) (xy 169.759885 -281.74677) (xy 169.748108 -281.698986)
			(xy 169.744148 -281.649932) (xy 169.4053 -281.649932) (xy 169.404805 -281.674539) (xy 169.39691 -281.723116)
			(xy 169.381326 -281.769797) (xy 169.358455 -281.813374) (xy 169.32889 -281.852718) (xy 169.293397 -281.88681)
			(xy 169.252894 -281.914766) (xy 169.208432 -281.935864) (xy 169.161161 -281.949556) (xy 169.112306 -281.955488)
			(xy 169.063131 -281.953507) (xy 169.014912 -281.943663) (xy 168.968896 -281.926211) (xy 168.926275 -281.901604)
			(xy 168.888154 -281.870479) (xy 168.855519 -281.833642) (xy 168.829216 -281.792046) (xy 168.809925 -281.74677)
			(xy 168.798148 -281.698986) (xy 168.794188 -281.649932) (xy 168.45534 -281.649932) (xy 168.454845 -281.674539)
			(xy 168.44695 -281.723116) (xy 168.431366 -281.769797) (xy 168.408495 -281.813374) (xy 168.37893 -281.852718)
			(xy 168.343437 -281.88681) (xy 168.302934 -281.914766) (xy 168.258472 -281.935864) (xy 168.211201 -281.949556)
			(xy 168.162346 -281.955488) (xy 168.113171 -281.953507) (xy 168.064952 -281.943663) (xy 168.018936 -281.926211)
			(xy 167.976315 -281.901604) (xy 167.938194 -281.870479) (xy 167.905559 -281.833642) (xy 167.879256 -281.792046)
			(xy 167.859965 -281.74677) (xy 167.848188 -281.698986) (xy 167.844228 -281.649932) (xy 167.50538 -281.649932)
			(xy 167.504885 -281.674539) (xy 167.49699 -281.723116) (xy 167.481406 -281.769797) (xy 167.458535 -281.813374)
			(xy 167.42897 -281.852718) (xy 167.393477 -281.88681) (xy 167.352974 -281.914766) (xy 167.308512 -281.935864)
			(xy 167.261241 -281.949556) (xy 167.212386 -281.955488) (xy 167.163211 -281.953507) (xy 167.114992 -281.943663)
			(xy 167.068976 -281.926211) (xy 167.026355 -281.901604) (xy 166.988234 -281.870479) (xy 166.955599 -281.833642)
			(xy 166.929296 -281.792046) (xy 166.910005 -281.74677) (xy 166.898228 -281.698986) (xy 166.894268 -281.649932)
			(xy 166.555166 -281.649932) (xy 166.554671 -281.674539) (xy 166.546776 -281.723116) (xy 166.531192 -281.769797)
			(xy 166.508321 -281.813374) (xy 166.478756 -281.852718) (xy 166.443263 -281.88681) (xy 166.40276 -281.914766)
			(xy 166.358298 -281.935864) (xy 166.311027 -281.949556) (xy 166.262172 -281.955488) (xy 166.212997 -281.953507)
			(xy 166.164778 -281.943663) (xy 166.118762 -281.926211) (xy 166.076141 -281.901604) (xy 166.03802 -281.870479)
			(xy 166.005385 -281.833642) (xy 165.979082 -281.792046) (xy 165.959791 -281.74677) (xy 165.948014 -281.698986)
			(xy 165.944054 -281.649932) (xy 165.605206 -281.649932) (xy 165.604711 -281.674539) (xy 165.596816 -281.723116)
			(xy 165.581232 -281.769797) (xy 165.558361 -281.813374) (xy 165.528796 -281.852718) (xy 165.493303 -281.88681)
			(xy 165.4528 -281.914766) (xy 165.408338 -281.935864) (xy 165.361067 -281.949556) (xy 165.312212 -281.955488)
			(xy 165.263037 -281.953507) (xy 165.214818 -281.943663) (xy 165.168802 -281.926211) (xy 165.126181 -281.901604)
			(xy 165.08806 -281.870479) (xy 165.055425 -281.833642) (xy 165.029122 -281.792046) (xy 165.009831 -281.74677)
			(xy 164.998054 -281.698986) (xy 164.994094 -281.649932) (xy 164.654773 -281.649932) (xy 164.654773 -281.673955)
			(xy 164.64723 -281.72146) (xy 164.632332 -281.767196) (xy 164.610447 -281.810029) (xy 164.582117 -281.848901)
			(xy 164.548042 -281.88285) (xy 164.509066 -281.911037) (xy 164.466152 -281.932764) (xy 164.420362 -281.947493)
			(xy 164.396674 -281.951684) (xy 164.378132 -281.954478) (xy 164.353748 -281.982926) (xy 164.353748 -282.599892)
			(xy 189.69407 -282.599892) (xy 189.69803 -282.550838) (xy 189.709807 -282.503054) (xy 189.729098 -282.457778)
			(xy 189.755401 -282.416182) (xy 189.788036 -282.379345) (xy 189.826157 -282.34822) (xy 189.868778 -282.323613)
			(xy 189.914794 -282.306161) (xy 189.963013 -282.296317) (xy 190.012188 -282.294336) (xy 190.061043 -282.300268)
			(xy 190.108314 -282.31396) (xy 190.152776 -282.335058) (xy 190.193279 -282.363014) (xy 190.228772 -282.397106)
			(xy 190.258337 -282.43645) (xy 190.281208 -282.480027) (xy 190.296792 -282.526708) (xy 190.304687 -282.575285)
			(xy 190.305182 -282.599892) (xy 190.64403 -282.599892) (xy 190.64799 -282.550838) (xy 190.659767 -282.503054)
			(xy 190.679058 -282.457778) (xy 190.705361 -282.416182) (xy 190.737996 -282.379345) (xy 190.776117 -282.34822)
			(xy 190.818738 -282.323613) (xy 190.864754 -282.306161) (xy 190.912973 -282.296317) (xy 190.962148 -282.294336)
			(xy 191.011003 -282.300268) (xy 191.058274 -282.31396) (xy 191.102736 -282.335058) (xy 191.143239 -282.363014)
			(xy 191.178732 -282.397106) (xy 191.208297 -282.43645) (xy 191.231168 -282.480027) (xy 191.246752 -282.526708)
			(xy 191.254647 -282.575285) (xy 191.255142 -282.599892) (xy 192.544204 -282.599892) (xy 192.548164 -282.550838)
			(xy 192.559941 -282.503054) (xy 192.579232 -282.457778) (xy 192.605535 -282.416182) (xy 192.63817 -282.379345)
			(xy 192.676291 -282.34822) (xy 192.718912 -282.323613) (xy 192.764928 -282.306161) (xy 192.813147 -282.296317)
			(xy 192.862322 -282.294336) (xy 192.911177 -282.300268) (xy 192.958448 -282.31396) (xy 193.00291 -282.335058)
			(xy 193.043413 -282.363014) (xy 193.078906 -282.397106) (xy 193.108471 -282.43645) (xy 193.131342 -282.480027)
			(xy 193.146926 -282.526708) (xy 193.154821 -282.575285) (xy 193.155316 -282.599892) (xy 193.494164 -282.599892)
			(xy 193.498124 -282.550838) (xy 193.509901 -282.503054) (xy 193.529192 -282.457778) (xy 193.555495 -282.416182)
			(xy 193.58813 -282.379345) (xy 193.626251 -282.34822) (xy 193.668872 -282.323613) (xy 193.714888 -282.306161)
			(xy 193.763107 -282.296317) (xy 193.812282 -282.294336) (xy 193.861137 -282.300268) (xy 193.908408 -282.31396)
			(xy 193.95287 -282.335058) (xy 193.993373 -282.363014) (xy 194.028866 -282.397106) (xy 194.058431 -282.43645)
			(xy 194.081302 -282.480027) (xy 194.096886 -282.526708) (xy 194.104781 -282.575285) (xy 194.105276 -282.599892)
			(xy 194.444124 -282.599892) (xy 194.448084 -282.550838) (xy 194.459861 -282.503054) (xy 194.479152 -282.457778)
			(xy 194.505455 -282.416182) (xy 194.53809 -282.379345) (xy 194.576211 -282.34822) (xy 194.618832 -282.323613)
			(xy 194.664848 -282.306161) (xy 194.713067 -282.296317) (xy 194.762242 -282.294336) (xy 194.811097 -282.300268)
			(xy 194.858368 -282.31396) (xy 194.90283 -282.335058) (xy 194.943333 -282.363014) (xy 194.978826 -282.397106)
			(xy 195.008391 -282.43645) (xy 195.031262 -282.480027) (xy 195.046846 -282.526708) (xy 195.054741 -282.575285)
			(xy 195.055236 -282.599892) (xy 195.054741 -282.624499) (xy 195.054562 -282.6256) (xy 195.37324 -282.6256)
			(xy 195.37324 -282.574184) (xy 195.381283 -282.523402) (xy 195.397171 -282.474503) (xy 195.420514 -282.428691)
			(xy 195.450735 -282.387095) (xy 195.487091 -282.350739) (xy 195.528687 -282.320518) (xy 195.574499 -282.297175)
			(xy 195.623398 -282.281287) (xy 195.67418 -282.273244) (xy 195.725596 -282.273244) (xy 195.776378 -282.281287)
			(xy 195.825277 -282.297175) (xy 195.871089 -282.320518) (xy 195.912685 -282.350739) (xy 195.949041 -282.387095)
			(xy 195.979262 -282.428691) (xy 196.002605 -282.474503) (xy 196.018493 -282.523402) (xy 196.026536 -282.574184)
			(xy 196.02704 -282.599892) (xy 196.026536 -282.6256) (xy 196.3232 -282.6256) (xy 196.3232 -282.574184)
			(xy 196.331243 -282.523402) (xy 196.347131 -282.474503) (xy 196.370474 -282.428691) (xy 196.400695 -282.387095)
			(xy 196.437051 -282.350739) (xy 196.478647 -282.320518) (xy 196.524459 -282.297175) (xy 196.573358 -282.281287)
			(xy 196.62414 -282.273244) (xy 196.675556 -282.273244) (xy 196.726338 -282.281287) (xy 196.775237 -282.297175)
			(xy 196.821049 -282.320518) (xy 196.862645 -282.350739) (xy 196.899001 -282.387095) (xy 196.929222 -282.428691)
			(xy 196.952565 -282.474503) (xy 196.968453 -282.523402) (xy 196.976496 -282.574184) (xy 196.977 -282.599892)
			(xy 197.294258 -282.599892) (xy 197.298218 -282.550838) (xy 197.309995 -282.503054) (xy 197.329286 -282.457778)
			(xy 197.355589 -282.416182) (xy 197.388224 -282.379345) (xy 197.426345 -282.34822) (xy 197.468966 -282.323613)
			(xy 197.514982 -282.306161) (xy 197.563201 -282.296317) (xy 197.612376 -282.294336) (xy 197.661231 -282.300268)
			(xy 197.708502 -282.31396) (xy 197.752964 -282.335058) (xy 197.793467 -282.363014) (xy 197.82896 -282.397106)
			(xy 197.858525 -282.43645) (xy 197.881396 -282.480027) (xy 197.89698 -282.526708) (xy 197.904875 -282.575285)
			(xy 197.90537 -282.599892) (xy 198.244218 -282.599892) (xy 198.248178 -282.550838) (xy 198.259955 -282.503054)
			(xy 198.279246 -282.457778) (xy 198.305549 -282.416182) (xy 198.338184 -282.379345) (xy 198.376305 -282.34822)
			(xy 198.418926 -282.323613) (xy 198.464942 -282.306161) (xy 198.513161 -282.296317) (xy 198.562336 -282.294336)
			(xy 198.611191 -282.300268) (xy 198.658462 -282.31396) (xy 198.702924 -282.335058) (xy 198.743427 -282.363014)
			(xy 198.77892 -282.397106) (xy 198.808485 -282.43645) (xy 198.831356 -282.480027) (xy 198.84694 -282.526708)
			(xy 198.854835 -282.575285) (xy 198.85533 -282.599892) (xy 198.854835 -282.624499) (xy 198.84694 -282.673076)
			(xy 198.831356 -282.719757) (xy 198.808485 -282.763334) (xy 198.77892 -282.802678) (xy 198.743427 -282.83677)
			(xy 198.702924 -282.864726) (xy 198.658462 -282.885824) (xy 198.611191 -282.899516) (xy 198.562336 -282.905448)
			(xy 198.513161 -282.903467) (xy 198.464942 -282.893623) (xy 198.418926 -282.876171) (xy 198.376305 -282.851564)
			(xy 198.338184 -282.820439) (xy 198.305549 -282.783602) (xy 198.279246 -282.742006) (xy 198.259955 -282.69673)
			(xy 198.248178 -282.648946) (xy 198.244218 -282.599892) (xy 197.90537 -282.599892) (xy 197.904875 -282.624499)
			(xy 197.89698 -282.673076) (xy 197.881396 -282.719757) (xy 197.858525 -282.763334) (xy 197.82896 -282.802678)
			(xy 197.793467 -282.83677) (xy 197.752964 -282.864726) (xy 197.708502 -282.885824) (xy 197.661231 -282.899516)
			(xy 197.612376 -282.905448) (xy 197.563201 -282.903467) (xy 197.514982 -282.893623) (xy 197.468966 -282.876171)
			(xy 197.426345 -282.851564) (xy 197.388224 -282.820439) (xy 197.355589 -282.783602) (xy 197.329286 -282.742006)
			(xy 197.309995 -282.69673) (xy 197.298218 -282.648946) (xy 197.294258 -282.599892) (xy 196.977 -282.599892)
			(xy 196.976496 -282.6256) (xy 196.968453 -282.676382) (xy 196.952565 -282.725281) (xy 196.929222 -282.771093)
			(xy 196.899001 -282.812689) (xy 196.862645 -282.849045) (xy 196.821049 -282.879266) (xy 196.775237 -282.902609)
			(xy 196.726338 -282.918497) (xy 196.675556 -282.92654) (xy 196.62414 -282.92654) (xy 196.573358 -282.918497)
			(xy 196.524459 -282.902609) (xy 196.478647 -282.879266) (xy 196.437051 -282.849045) (xy 196.400695 -282.812689)
			(xy 196.370474 -282.771093) (xy 196.347131 -282.725281) (xy 196.331243 -282.676382) (xy 196.3232 -282.6256)
			(xy 196.026536 -282.6256) (xy 196.018493 -282.676382) (xy 196.002605 -282.725281) (xy 195.979262 -282.771093)
			(xy 195.949041 -282.812689) (xy 195.912685 -282.849045) (xy 195.871089 -282.879266) (xy 195.825277 -282.902609)
			(xy 195.776378 -282.918497) (xy 195.725596 -282.92654) (xy 195.67418 -282.92654) (xy 195.623398 -282.918497)
			(xy 195.574499 -282.902609) (xy 195.528687 -282.879266) (xy 195.487091 -282.849045) (xy 195.450735 -282.812689)
			(xy 195.420514 -282.771093) (xy 195.397171 -282.725281) (xy 195.381283 -282.676382) (xy 195.37324 -282.6256)
			(xy 195.054562 -282.6256) (xy 195.046846 -282.673076) (xy 195.031262 -282.719757) (xy 195.008391 -282.763334)
			(xy 194.978826 -282.802678) (xy 194.943333 -282.83677) (xy 194.90283 -282.864726) (xy 194.858368 -282.885824)
			(xy 194.811097 -282.899516) (xy 194.762242 -282.905448) (xy 194.713067 -282.903467) (xy 194.664848 -282.893623)
			(xy 194.618832 -282.876171) (xy 194.576211 -282.851564) (xy 194.53809 -282.820439) (xy 194.505455 -282.783602)
			(xy 194.479152 -282.742006) (xy 194.459861 -282.69673) (xy 194.448084 -282.648946) (xy 194.444124 -282.599892)
			(xy 194.105276 -282.599892) (xy 194.104781 -282.624499) (xy 194.096886 -282.673076) (xy 194.081302 -282.719757)
			(xy 194.058431 -282.763334) (xy 194.028866 -282.802678) (xy 193.993373 -282.83677) (xy 193.95287 -282.864726)
			(xy 193.908408 -282.885824) (xy 193.861137 -282.899516) (xy 193.812282 -282.905448) (xy 193.763107 -282.903467)
			(xy 193.714888 -282.893623) (xy 193.668872 -282.876171) (xy 193.626251 -282.851564) (xy 193.58813 -282.820439)
			(xy 193.555495 -282.783602) (xy 193.529192 -282.742006) (xy 193.509901 -282.69673) (xy 193.498124 -282.648946)
			(xy 193.494164 -282.599892) (xy 193.155316 -282.599892) (xy 193.154821 -282.624499) (xy 193.146926 -282.673076)
			(xy 193.131342 -282.719757) (xy 193.108471 -282.763334) (xy 193.078906 -282.802678) (xy 193.043413 -282.83677)
			(xy 193.00291 -282.864726) (xy 192.958448 -282.885824) (xy 192.911177 -282.899516) (xy 192.862322 -282.905448)
			(xy 192.813147 -282.903467) (xy 192.764928 -282.893623) (xy 192.718912 -282.876171) (xy 192.676291 -282.851564)
			(xy 192.63817 -282.820439) (xy 192.605535 -282.783602) (xy 192.579232 -282.742006) (xy 192.559941 -282.69673)
			(xy 192.548164 -282.648946) (xy 192.544204 -282.599892) (xy 191.255142 -282.599892) (xy 191.254647 -282.624499)
			(xy 191.246752 -282.673076) (xy 191.231168 -282.719757) (xy 191.208297 -282.763334) (xy 191.178732 -282.802678)
			(xy 191.143239 -282.83677) (xy 191.102736 -282.864726) (xy 191.058274 -282.885824) (xy 191.011003 -282.899516)
			(xy 190.962148 -282.905448) (xy 190.912973 -282.903467) (xy 190.864754 -282.893623) (xy 190.818738 -282.876171)
			(xy 190.776117 -282.851564) (xy 190.737996 -282.820439) (xy 190.705361 -282.783602) (xy 190.679058 -282.742006)
			(xy 190.659767 -282.69673) (xy 190.64799 -282.648946) (xy 190.64403 -282.599892) (xy 190.305182 -282.599892)
			(xy 190.304687 -282.624499) (xy 190.296792 -282.673076) (xy 190.281208 -282.719757) (xy 190.258337 -282.763334)
			(xy 190.228772 -282.802678) (xy 190.193279 -282.83677) (xy 190.152776 -282.864726) (xy 190.108314 -282.885824)
			(xy 190.061043 -282.899516) (xy 190.012188 -282.905448) (xy 189.963013 -282.903467) (xy 189.914794 -282.893623)
			(xy 189.868778 -282.876171) (xy 189.826157 -282.851564) (xy 189.788036 -282.820439) (xy 189.755401 -282.783602)
			(xy 189.729098 -282.742006) (xy 189.709807 -282.69673) (xy 189.69803 -282.648946) (xy 189.69407 -282.599892)
			(xy 164.353748 -282.599892) (xy 164.353748 -283.074872) (xy 164.519114 -283.074872) (xy 164.523074 -283.025818)
			(xy 164.534851 -282.978034) (xy 164.554142 -282.932758) (xy 164.580445 -282.891162) (xy 164.61308 -282.854325)
			(xy 164.651201 -282.8232) (xy 164.693822 -282.798593) (xy 164.739838 -282.781141) (xy 164.788057 -282.771297)
			(xy 164.837232 -282.769316) (xy 164.886087 -282.775248) (xy 164.933358 -282.78894) (xy 164.97782 -282.810038)
			(xy 165.018323 -282.837994) (xy 165.053816 -282.872086) (xy 165.083381 -282.91143) (xy 165.106252 -282.955007)
			(xy 165.121836 -283.001688) (xy 165.129731 -283.050265) (xy 165.130226 -283.074872) (xy 165.469074 -283.074872)
			(xy 165.473034 -283.025818) (xy 165.484811 -282.978034) (xy 165.504102 -282.932758) (xy 165.530405 -282.891162)
			(xy 165.56304 -282.854325) (xy 165.601161 -282.8232) (xy 165.643782 -282.798593) (xy 165.689798 -282.781141)
			(xy 165.738017 -282.771297) (xy 165.787192 -282.769316) (xy 165.836047 -282.775248) (xy 165.883318 -282.78894)
			(xy 165.92778 -282.810038) (xy 165.968283 -282.837994) (xy 166.003776 -282.872086) (xy 166.033341 -282.91143)
			(xy 166.056212 -282.955007) (xy 166.071796 -283.001688) (xy 166.079691 -283.050265) (xy 166.080186 -283.074872)
			(xy 166.419288 -283.074872) (xy 166.423248 -283.025818) (xy 166.435025 -282.978034) (xy 166.454316 -282.932758)
			(xy 166.480619 -282.891162) (xy 166.513254 -282.854325) (xy 166.551375 -282.8232) (xy 166.593996 -282.798593)
			(xy 166.640012 -282.781141) (xy 166.688231 -282.771297) (xy 166.737406 -282.769316) (xy 166.786261 -282.775248)
			(xy 166.833532 -282.78894) (xy 166.877994 -282.810038) (xy 166.918497 -282.837994) (xy 166.95399 -282.872086)
			(xy 166.983555 -282.91143) (xy 167.006426 -282.955007) (xy 167.02201 -283.001688) (xy 167.029905 -283.050265)
			(xy 167.0304 -283.074872) (xy 167.369248 -283.074872) (xy 167.373208 -283.025818) (xy 167.384985 -282.978034)
			(xy 167.404276 -282.932758) (xy 167.430579 -282.891162) (xy 167.463214 -282.854325) (xy 167.501335 -282.8232)
			(xy 167.543956 -282.798593) (xy 167.589972 -282.781141) (xy 167.638191 -282.771297) (xy 167.687366 -282.769316)
			(xy 167.736221 -282.775248) (xy 167.783492 -282.78894) (xy 167.827954 -282.810038) (xy 167.868457 -282.837994)
			(xy 167.90395 -282.872086) (xy 167.933515 -282.91143) (xy 167.956386 -282.955007) (xy 167.97197 -283.001688)
			(xy 167.979865 -283.050265) (xy 167.98036 -283.074872) (xy 168.319208 -283.074872) (xy 168.323168 -283.025818)
			(xy 168.334945 -282.978034) (xy 168.354236 -282.932758) (xy 168.380539 -282.891162) (xy 168.413174 -282.854325)
			(xy 168.451295 -282.8232) (xy 168.493916 -282.798593) (xy 168.539932 -282.781141) (xy 168.588151 -282.771297)
			(xy 168.637326 -282.769316) (xy 168.686181 -282.775248) (xy 168.733452 -282.78894) (xy 168.777914 -282.810038)
			(xy 168.818417 -282.837994) (xy 168.85391 -282.872086) (xy 168.883475 -282.91143) (xy 168.906346 -282.955007)
			(xy 168.92193 -283.001688) (xy 168.929825 -283.050265) (xy 168.93032 -283.074872) (xy 169.269168 -283.074872)
			(xy 169.273128 -283.025818) (xy 169.284905 -282.978034) (xy 169.304196 -282.932758) (xy 169.330499 -282.891162)
			(xy 169.363134 -282.854325) (xy 169.401255 -282.8232) (xy 169.443876 -282.798593) (xy 169.489892 -282.781141)
			(xy 169.538111 -282.771297) (xy 169.587286 -282.769316) (xy 169.636141 -282.775248) (xy 169.683412 -282.78894)
			(xy 169.727874 -282.810038) (xy 169.768377 -282.837994) (xy 169.80387 -282.872086) (xy 169.833435 -282.91143)
			(xy 169.856306 -282.955007) (xy 169.87189 -283.001688) (xy 169.879785 -283.050265) (xy 169.88028 -283.074872)
			(xy 170.219128 -283.074872) (xy 170.223088 -283.025818) (xy 170.234865 -282.978034) (xy 170.254156 -282.932758)
			(xy 170.280459 -282.891162) (xy 170.313094 -282.854325) (xy 170.351215 -282.8232) (xy 170.393836 -282.798593)
			(xy 170.439852 -282.781141) (xy 170.488071 -282.771297) (xy 170.537246 -282.769316) (xy 170.586101 -282.775248)
			(xy 170.633372 -282.78894) (xy 170.677834 -282.810038) (xy 170.718337 -282.837994) (xy 170.75383 -282.872086)
			(xy 170.783395 -282.91143) (xy 170.806266 -282.955007) (xy 170.82185 -283.001688) (xy 170.829745 -283.050265)
			(xy 170.83024 -283.074872) (xy 171.169088 -283.074872) (xy 171.173048 -283.025818) (xy 171.184825 -282.978034)
			(xy 171.204116 -282.932758) (xy 171.230419 -282.891162) (xy 171.263054 -282.854325) (xy 171.301175 -282.8232)
			(xy 171.343796 -282.798593) (xy 171.389812 -282.781141) (xy 171.438031 -282.771297) (xy 171.487206 -282.769316)
			(xy 171.536061 -282.775248) (xy 171.583332 -282.78894) (xy 171.627794 -282.810038) (xy 171.668297 -282.837994)
			(xy 171.70379 -282.872086) (xy 171.733355 -282.91143) (xy 171.756226 -282.955007) (xy 171.77181 -283.001688)
			(xy 171.779705 -283.050265) (xy 171.7802 -283.074872) (xy 172.119302 -283.074872) (xy 172.123262 -283.025818)
			(xy 172.135039 -282.978034) (xy 172.15433 -282.932758) (xy 172.180633 -282.891162) (xy 172.213268 -282.854325)
			(xy 172.251389 -282.8232) (xy 172.29401 -282.798593) (xy 172.340026 -282.781141) (xy 172.388245 -282.771297)
			(xy 172.43742 -282.769316) (xy 172.486275 -282.775248) (xy 172.533546 -282.78894) (xy 172.578008 -282.810038)
			(xy 172.618511 -282.837994) (xy 172.654004 -282.872086) (xy 172.683569 -282.91143) (xy 172.70644 -282.955007)
			(xy 172.722024 -283.001688) (xy 172.729919 -283.050265) (xy 172.730414 -283.074872) (xy 173.069262 -283.074872)
			(xy 173.073222 -283.025818) (xy 173.084999 -282.978034) (xy 173.10429 -282.932758) (xy 173.130593 -282.891162)
			(xy 173.163228 -282.854325) (xy 173.201349 -282.8232) (xy 173.24397 -282.798593) (xy 173.289986 -282.781141)
			(xy 173.338205 -282.771297) (xy 173.38738 -282.769316) (xy 173.436235 -282.775248) (xy 173.483506 -282.78894)
			(xy 173.527968 -282.810038) (xy 173.568471 -282.837994) (xy 173.603964 -282.872086) (xy 173.633529 -282.91143)
			(xy 173.6564 -282.955007) (xy 173.671984 -283.001688) (xy 173.679879 -283.050265) (xy 173.680374 -283.074872)
			(xy 174.019222 -283.074872) (xy 174.023182 -283.025818) (xy 174.034959 -282.978034) (xy 174.05425 -282.932758)
			(xy 174.080553 -282.891162) (xy 174.113188 -282.854325) (xy 174.151309 -282.8232) (xy 174.19393 -282.798593)
			(xy 174.239946 -282.781141) (xy 174.288165 -282.771297) (xy 174.33734 -282.769316) (xy 174.386195 -282.775248)
			(xy 174.433466 -282.78894) (xy 174.477928 -282.810038) (xy 174.518431 -282.837994) (xy 174.553924 -282.872086)
			(xy 174.583489 -282.91143) (xy 174.60636 -282.955007) (xy 174.621944 -283.001688) (xy 174.629839 -283.050265)
			(xy 174.630334 -283.074872) (xy 175.919142 -283.074872) (xy 175.923102 -283.025818) (xy 175.934879 -282.978034)
			(xy 175.95417 -282.932758) (xy 175.980473 -282.891162) (xy 176.013108 -282.854325) (xy 176.051229 -282.8232)
			(xy 176.09385 -282.798593) (xy 176.139866 -282.781141) (xy 176.188085 -282.771297) (xy 176.23726 -282.769316)
			(xy 176.286115 -282.775248) (xy 176.333386 -282.78894) (xy 176.377848 -282.810038) (xy 176.418351 -282.837994)
			(xy 176.453844 -282.872086) (xy 176.483409 -282.91143) (xy 176.50628 -282.955007) (xy 176.521864 -283.001688)
			(xy 176.529759 -283.050265) (xy 176.530254 -283.074872) (xy 176.869102 -283.074872) (xy 176.873062 -283.025818)
			(xy 176.884839 -282.978034) (xy 176.90413 -282.932758) (xy 176.930433 -282.891162) (xy 176.963068 -282.854325)
			(xy 177.001189 -282.8232) (xy 177.04381 -282.798593) (xy 177.089826 -282.781141) (xy 177.138045 -282.771297)
			(xy 177.18722 -282.769316) (xy 177.236075 -282.775248) (xy 177.283346 -282.78894) (xy 177.327808 -282.810038)
			(xy 177.368311 -282.837994) (xy 177.403804 -282.872086) (xy 177.433369 -282.91143) (xy 177.45624 -282.955007)
			(xy 177.471824 -283.001688) (xy 177.479719 -283.050265) (xy 177.480214 -283.074872) (xy 177.819062 -283.074872)
			(xy 177.823022 -283.025818) (xy 177.834799 -282.978034) (xy 177.85409 -282.932758) (xy 177.880393 -282.891162)
			(xy 177.913028 -282.854325) (xy 177.951149 -282.8232) (xy 177.99377 -282.798593) (xy 178.039786 -282.781141)
			(xy 178.088005 -282.771297) (xy 178.13718 -282.769316) (xy 178.186035 -282.775248) (xy 178.233306 -282.78894)
			(xy 178.277768 -282.810038) (xy 178.318271 -282.837994) (xy 178.353764 -282.872086) (xy 178.383329 -282.91143)
			(xy 178.4062 -282.955007) (xy 178.421784 -283.001688) (xy 178.429679 -283.050265) (xy 178.430174 -283.074872)
			(xy 178.769276 -283.074872) (xy 178.773236 -283.025818) (xy 178.785013 -282.978034) (xy 178.804304 -282.932758)
			(xy 178.830607 -282.891162) (xy 178.863242 -282.854325) (xy 178.901363 -282.8232) (xy 178.943984 -282.798593)
			(xy 178.99 -282.781141) (xy 179.038219 -282.771297) (xy 179.087394 -282.769316) (xy 179.136249 -282.775248)
			(xy 179.18352 -282.78894) (xy 179.227982 -282.810038) (xy 179.268485 -282.837994) (xy 179.303978 -282.872086)
			(xy 179.333543 -282.91143) (xy 179.356414 -282.955007) (xy 179.371998 -283.001688) (xy 179.379893 -283.050265)
			(xy 179.380388 -283.074872) (xy 179.719236 -283.074872) (xy 179.723196 -283.025818) (xy 179.734973 -282.978034)
			(xy 179.754264 -282.932758) (xy 179.780567 -282.891162) (xy 179.813202 -282.854325) (xy 179.851323 -282.8232)
			(xy 179.893944 -282.798593) (xy 179.93996 -282.781141) (xy 179.988179 -282.771297) (xy 180.037354 -282.769316)
			(xy 180.086209 -282.775248) (xy 180.13348 -282.78894) (xy 180.177942 -282.810038) (xy 180.218445 -282.837994)
			(xy 180.253938 -282.872086) (xy 180.283503 -282.91143) (xy 180.306374 -282.955007) (xy 180.321958 -283.001688)
			(xy 180.329853 -283.050265) (xy 180.330348 -283.074872) (xy 180.669196 -283.074872) (xy 180.673156 -283.025818)
			(xy 180.684933 -282.978034) (xy 180.704224 -282.932758) (xy 180.730527 -282.891162) (xy 180.763162 -282.854325)
			(xy 180.801283 -282.8232) (xy 180.843904 -282.798593) (xy 180.88992 -282.781141) (xy 180.938139 -282.771297)
			(xy 180.987314 -282.769316) (xy 181.036169 -282.775248) (xy 181.08344 -282.78894) (xy 181.127902 -282.810038)
			(xy 181.168405 -282.837994) (xy 181.203898 -282.872086) (xy 181.233463 -282.91143) (xy 181.256334 -282.955007)
			(xy 181.271918 -283.001688) (xy 181.279813 -283.050265) (xy 181.280308 -283.074872) (xy 181.619156 -283.074872)
			(xy 181.623116 -283.025818) (xy 181.634893 -282.978034) (xy 181.654184 -282.932758) (xy 181.680487 -282.891162)
			(xy 181.713122 -282.854325) (xy 181.751243 -282.8232) (xy 181.793864 -282.798593) (xy 181.83988 -282.781141)
			(xy 181.888099 -282.771297) (xy 181.937274 -282.769316) (xy 181.986129 -282.775248) (xy 182.0334 -282.78894)
			(xy 182.077862 -282.810038) (xy 182.118365 -282.837994) (xy 182.153858 -282.872086) (xy 182.183423 -282.91143)
			(xy 182.206294 -282.955007) (xy 182.221878 -283.001688) (xy 182.229773 -283.050265) (xy 182.230268 -283.074872)
			(xy 182.569116 -283.074872) (xy 182.573076 -283.025818) (xy 182.584853 -282.978034) (xy 182.604144 -282.932758)
			(xy 182.630447 -282.891162) (xy 182.663082 -282.854325) (xy 182.701203 -282.8232) (xy 182.743824 -282.798593)
			(xy 182.78984 -282.781141) (xy 182.838059 -282.771297) (xy 182.887234 -282.769316) (xy 182.936089 -282.775248)
			(xy 182.98336 -282.78894) (xy 183.027822 -282.810038) (xy 183.068325 -282.837994) (xy 183.103818 -282.872086)
			(xy 183.133383 -282.91143) (xy 183.156254 -282.955007) (xy 183.171838 -283.001688) (xy 183.179733 -283.050265)
			(xy 183.180228 -283.074872) (xy 184.469036 -283.074872) (xy 184.472996 -283.025818) (xy 184.484773 -282.978034)
			(xy 184.504064 -282.932758) (xy 184.530367 -282.891162) (xy 184.563002 -282.854325) (xy 184.601123 -282.8232)
			(xy 184.643744 -282.798593) (xy 184.68976 -282.781141) (xy 184.737979 -282.771297) (xy 184.787154 -282.769316)
			(xy 184.836009 -282.775248) (xy 184.88328 -282.78894) (xy 184.927742 -282.810038) (xy 184.968245 -282.837994)
			(xy 185.003738 -282.872086) (xy 185.033303 -282.91143) (xy 185.056174 -282.955007) (xy 185.071758 -283.001688)
			(xy 185.079653 -283.050265) (xy 185.080148 -283.074872) (xy 185.41925 -283.074872) (xy 185.42321 -283.025818)
			(xy 185.434987 -282.978034) (xy 185.454278 -282.932758) (xy 185.480581 -282.891162) (xy 185.513216 -282.854325)
			(xy 185.551337 -282.8232) (xy 185.593958 -282.798593) (xy 185.639974 -282.781141) (xy 185.688193 -282.771297)
			(xy 185.737368 -282.769316) (xy 185.786223 -282.775248) (xy 185.833494 -282.78894) (xy 185.877956 -282.810038)
			(xy 185.918459 -282.837994) (xy 185.953952 -282.872086) (xy 185.983517 -282.91143) (xy 186.006388 -282.955007)
			(xy 186.021972 -283.001688) (xy 186.029867 -283.050265) (xy 186.030362 -283.074872) (xy 186.36921 -283.074872)
			(xy 186.37317 -283.025818) (xy 186.384947 -282.978034) (xy 186.404238 -282.932758) (xy 186.430541 -282.891162)
			(xy 186.463176 -282.854325) (xy 186.501297 -282.8232) (xy 186.543918 -282.798593) (xy 186.589934 -282.781141)
			(xy 186.638153 -282.771297) (xy 186.687328 -282.769316) (xy 186.736183 -282.775248) (xy 186.783454 -282.78894)
			(xy 186.827916 -282.810038) (xy 186.868419 -282.837994) (xy 186.903912 -282.872086) (xy 186.933477 -282.91143)
			(xy 186.956348 -282.955007) (xy 186.971932 -283.001688) (xy 186.979827 -283.050265) (xy 186.980322 -283.074872)
			(xy 187.31917 -283.074872) (xy 187.32313 -283.025818) (xy 187.334907 -282.978034) (xy 187.354198 -282.932758)
			(xy 187.380501 -282.891162) (xy 187.413136 -282.854325) (xy 187.451257 -282.8232) (xy 187.493878 -282.798593)
			(xy 187.539894 -282.781141) (xy 187.588113 -282.771297) (xy 187.637288 -282.769316) (xy 187.686143 -282.775248)
			(xy 187.733414 -282.78894) (xy 187.777876 -282.810038) (xy 187.818379 -282.837994) (xy 187.853872 -282.872086)
			(xy 187.883437 -282.91143) (xy 187.906308 -282.955007) (xy 187.921892 -283.001688) (xy 187.929787 -283.050265)
			(xy 187.930282 -283.074872) (xy 188.26913 -283.074872) (xy 188.27309 -283.025818) (xy 188.284867 -282.978034)
			(xy 188.304158 -282.932758) (xy 188.330461 -282.891162) (xy 188.363096 -282.854325) (xy 188.401217 -282.8232)
			(xy 188.443838 -282.798593) (xy 188.489854 -282.781141) (xy 188.538073 -282.771297) (xy 188.587248 -282.769316)
			(xy 188.636103 -282.775248) (xy 188.683374 -282.78894) (xy 188.727836 -282.810038) (xy 188.768339 -282.837994)
			(xy 188.803832 -282.872086) (xy 188.833397 -282.91143) (xy 188.856268 -282.955007) (xy 188.871852 -283.001688)
			(xy 188.873115 -283.009458) (xy 224.751517 -283.009458) (xy 224.751517 -282.954942) (xy 224.759276 -282.900982)
			(xy 224.774636 -282.848675) (xy 224.797284 -282.799087) (xy 224.826759 -282.753227) (xy 224.862462 -282.712029)
			(xy 224.903664 -282.676332) (xy 224.949527 -282.646862) (xy 224.999118 -282.62422) (xy 225.051427 -282.608866)
			(xy 225.105388 -282.601114) (xy 225.132646 -282.600654) (xy 225.161385 -282.601162) (xy 225.218213 -282.60979)
			(xy 225.273103 -282.626845) (xy 225.324815 -282.651939) (xy 225.372177 -282.684507) (xy 225.393504 -282.703778)
			(xy 225.400616 -282.710382) (xy 225.418142 -282.717494) (xy 225.50755 -282.717494) (xy 225.525076 -282.710382)
			(xy 225.532188 -282.703778) (xy 225.553515 -282.684508) (xy 225.600878 -282.651943) (xy 225.652589 -282.626852)
			(xy 225.70748 -282.609802) (xy 225.764307 -282.60118) (xy 225.821785 -282.60118) (xy 225.878612 -282.609802)
			(xy 225.933503 -282.626852) (xy 225.985214 -282.651943) (xy 226.032577 -282.684508) (xy 226.053904 -282.703778)
			(xy 226.061016 -282.710382) (xy 226.078542 -282.717494) (xy 226.16795 -282.717494) (xy 226.185476 -282.710382)
			(xy 226.192588 -282.703778) (xy 226.213902 -282.684492) (xy 226.261267 -282.651926) (xy 226.312982 -282.626836)
			(xy 226.367876 -282.609789) (xy 226.424706 -282.601172) (xy 226.453446 -282.600654) (xy 226.483568 -282.601258)
			(xy 226.543063 -282.610731) (xy 226.60033 -282.629434) (xy 226.653948 -282.656902) (xy 226.702584 -282.692454)
			(xy 226.72421 -282.71343) (xy 226.731322 -282.720796) (xy 226.750118 -282.728416) (xy 226.842574 -282.728416)
			(xy 226.86137 -282.720796) (xy 226.868482 -282.71343) (xy 226.890097 -282.692439) (xy 226.938728 -282.65687)
			(xy 226.992347 -282.629392) (xy 227.049619 -282.610687) (xy 227.109121 -282.60122) (xy 227.139246 -282.600654)
			(xy 227.166492 -282.601219) (xy 227.22043 -282.60898) (xy 227.272714 -282.624338) (xy 227.32228 -282.646979)
			(xy 227.36812 -282.676444) (xy 227.409301 -282.712132) (xy 227.444984 -282.753317) (xy 227.474443 -282.79916)
			(xy 227.497078 -282.84873) (xy 227.512429 -282.901015) (xy 227.520184 -282.954954) (xy 227.520184 -283.009446)
			(xy 227.520182 -283.009457) (xy 228.998917 -283.009457) (xy 228.998917 -282.954943) (xy 229.006676 -282.900984)
			(xy 229.022035 -282.848678) (xy 229.044682 -282.79909) (xy 229.074156 -282.753231) (xy 229.109857 -282.712033)
			(xy 229.151058 -282.676336) (xy 229.19692 -282.646866) (xy 229.24651 -282.624223) (xy 229.298817 -282.608868)
			(xy 229.352777 -282.601115) (xy 229.380034 -282.600654) (xy 229.408773 -282.601169) (xy 229.4656 -282.609796)
			(xy 229.520491 -282.626849) (xy 229.572202 -282.651942) (xy 229.619565 -282.684507) (xy 229.640892 -282.703778)
			(xy 229.648004 -282.710382) (xy 229.66553 -282.717494) (xy 229.754938 -282.717494) (xy 229.772464 -282.710382)
			(xy 229.779576 -282.703778) (xy 229.800903 -282.684508) (xy 229.848266 -282.651943) (xy 229.899977 -282.626852)
			(xy 229.954868 -282.609802) (xy 230.011695 -282.60118) (xy 230.069173 -282.60118) (xy 230.126 -282.609802)
			(xy 230.180891 -282.626852) (xy 230.232602 -282.651943) (xy 230.279965 -282.684508) (xy 230.301292 -282.703778)
			(xy 230.308404 -282.710382) (xy 230.32593 -282.717494) (xy 230.415338 -282.717494) (xy 230.432864 -282.710382)
			(xy 230.439976 -282.703778) (xy 230.461295 -282.684498) (xy 230.508658 -282.651931) (xy 230.560372 -282.62684)
			(xy 230.615265 -282.609792) (xy 230.672094 -282.601173) (xy 230.700834 -282.600654) (xy 230.730958 -282.601202)
			(xy 230.790456 -282.610688) (xy 230.847724 -282.629405) (xy 230.901341 -282.656886) (xy 230.949974 -282.692449)
			(xy 230.971598 -282.71343) (xy 230.97871 -282.720796) (xy 230.997506 -282.728416) (xy 231.089962 -282.728416)
			(xy 231.108758 -282.720796) (xy 231.11587 -282.71343) (xy 231.13749 -282.692444) (xy 231.186119 -282.656875)
			(xy 231.239737 -282.629396) (xy 231.297009 -282.610689) (xy 231.356509 -282.601221) (xy 231.386634 -282.600654)
			(xy 231.413881 -282.601219) (xy 231.46782 -282.608978) (xy 231.520105 -282.624335) (xy 231.569673 -282.646975)
			(xy 231.615514 -282.67644) (xy 231.656696 -282.712128) (xy 231.692381 -282.753313) (xy 231.721841 -282.799157)
			(xy 231.744477 -282.848727) (xy 231.759829 -282.901014) (xy 231.767584 -282.954953) (xy 231.767584 -283.009447)
			(xy 231.759829 -283.063386) (xy 231.744477 -283.115673) (xy 231.721841 -283.165243) (xy 231.692381 -283.211087)
			(xy 231.656696 -283.252272) (xy 231.615514 -283.28796) (xy 231.569673 -283.317425) (xy 231.520105 -283.340065)
			(xy 231.46782 -283.355422) (xy 231.413881 -283.363181) (xy 231.386634 -283.36367) (xy 231.356512 -283.363072)
			(xy 231.297017 -283.353597) (xy 231.239749 -283.334892) (xy 231.186132 -283.307422) (xy 231.137496 -283.27187)
			(xy 231.11587 -283.250894) (xy 231.108758 -283.243528) (xy 231.089962 -283.235908) (xy 230.997506 -283.235908)
			(xy 230.97871 -283.243528) (xy 230.971598 -283.250894) (xy 230.949996 -283.271899) (xy 230.901361 -283.307465)
			(xy 230.847739 -283.33494) (xy 230.790464 -283.353642) (xy 230.73096 -283.363106) (xy 230.700834 -283.36367)
			(xy 230.672095 -283.363168) (xy 230.615267 -283.354537) (xy 230.560377 -283.337481) (xy 230.508666 -283.312385)
			(xy 230.461303 -283.279817) (xy 230.439976 -283.260546) (xy 230.432864 -283.253942) (xy 230.415338 -283.24683)
			(xy 230.32593 -283.24683) (xy 230.308404 -283.253942) (xy 230.301292 -283.260546) (xy 230.279965 -283.279816)
			(xy 230.232602 -283.312381) (xy 230.180891 -283.337472) (xy 230.126 -283.354522) (xy 230.069173 -283.363144)
			(xy 230.011695 -283.363144) (xy 229.954868 -283.354522) (xy 229.899977 -283.337472) (xy 229.848266 -283.312381)
			(xy 229.800903 -283.279816) (xy 229.779576 -283.260546) (xy 229.772464 -283.253942) (xy 229.754938 -283.24683)
			(xy 229.66553 -283.24683) (xy 229.648004 -283.253942) (xy 229.640892 -283.260546) (xy 229.619549 -283.279798)
			(xy 229.572191 -283.312367) (xy 229.520484 -283.337464) (xy 229.465597 -283.354519) (xy 229.408772 -283.363147)
			(xy 229.380034 -283.36367) (xy 229.352777 -283.363285) (xy 229.298817 -283.355532) (xy 229.24651 -283.340177)
			(xy 229.19692 -283.317534) (xy 229.151058 -283.288064) (xy 229.109857 -283.252367) (xy 229.074156 -283.211169)
			(xy 229.044682 -283.16531) (xy 229.022035 -283.115722) (xy 229.006676 -283.063416) (xy 228.998917 -283.009457)
			(xy 227.520182 -283.009457) (xy 227.512429 -283.063385) (xy 227.497078 -283.11567) (xy 227.474443 -283.16524)
			(xy 227.444984 -283.211083) (xy 227.409301 -283.252268) (xy 227.36812 -283.287956) (xy 227.32228 -283.317421)
			(xy 227.272714 -283.340062) (xy 227.22043 -283.35542) (xy 227.166492 -283.363181) (xy 227.139246 -283.36367)
			(xy 227.109124 -283.363065) (xy 227.04963 -283.353591) (xy 226.992362 -283.334888) (xy 226.938745 -283.30742)
			(xy 226.890108 -283.271869) (xy 226.868482 -283.250894) (xy 226.86137 -283.243528) (xy 226.842574 -283.235908)
			(xy 226.750118 -283.235908) (xy 226.731322 -283.243528) (xy 226.72421 -283.250894) (xy 226.702603 -283.271894)
			(xy 226.653969 -283.30746) (xy 226.600349 -283.334936) (xy 226.543074 -283.35364) (xy 226.483572 -283.363105)
			(xy 226.453446 -283.36367) (xy 226.424707 -283.36316) (xy 226.36788 -283.354532) (xy 226.312989 -283.337477)
			(xy 226.261278 -283.312383) (xy 226.213915 -283.279817) (xy 226.192588 -283.260546) (xy 226.185476 -283.253942)
			(xy 226.16795 -283.24683) (xy 226.078542 -283.24683) (xy 226.061016 -283.253942) (xy 226.053904 -283.260546)
			(xy 226.032577 -283.279816) (xy 225.985214 -283.312381) (xy 225.933503 -283.337472) (xy 225.878612 -283.354522)
			(xy 225.821785 -283.363144) (xy 225.764307 -283.363144) (xy 225.70748 -283.354522) (xy 225.652589 -283.337472)
			(xy 225.600878 -283.312381) (xy 225.553515 -283.279816) (xy 225.532188 -283.260546) (xy 225.525076 -283.253942)
			(xy 225.50755 -283.24683) (xy 225.418142 -283.24683) (xy 225.400616 -283.253942) (xy 225.393504 -283.260546)
			(xy 225.372197 -283.27984) (xy 225.32483 -283.312403) (xy 225.273113 -283.337492) (xy 225.218218 -283.354537)
			(xy 225.161386 -283.363153) (xy 225.132646 -283.36367) (xy 225.105388 -283.363286) (xy 225.051427 -283.355534)
			(xy 224.999118 -283.34018) (xy 224.949527 -283.317538) (xy 224.903664 -283.288068) (xy 224.862462 -283.252371)
			(xy 224.826759 -283.211173) (xy 224.797284 -283.165313) (xy 224.774636 -283.115725) (xy 224.759276 -283.063418)
			(xy 224.751517 -283.009458) (xy 188.873115 -283.009458) (xy 188.879747 -283.050265) (xy 188.880242 -283.074872)
			(xy 188.879747 -283.099479) (xy 188.871852 -283.148056) (xy 188.856268 -283.194737) (xy 188.833397 -283.238314)
			(xy 188.803832 -283.277658) (xy 188.768339 -283.31175) (xy 188.727836 -283.339706) (xy 188.683374 -283.360804)
			(xy 188.636103 -283.374496) (xy 188.587248 -283.380428) (xy 188.538073 -283.378447) (xy 188.489854 -283.368603)
			(xy 188.443838 -283.351151) (xy 188.401217 -283.326544) (xy 188.363096 -283.295419) (xy 188.330461 -283.258582)
			(xy 188.304158 -283.216986) (xy 188.284867 -283.17171) (xy 188.27309 -283.123926) (xy 188.26913 -283.074872)
			(xy 187.930282 -283.074872) (xy 187.929787 -283.099479) (xy 187.921892 -283.148056) (xy 187.906308 -283.194737)
			(xy 187.883437 -283.238314) (xy 187.853872 -283.277658) (xy 187.818379 -283.31175) (xy 187.777876 -283.339706)
			(xy 187.733414 -283.360804) (xy 187.686143 -283.374496) (xy 187.637288 -283.380428) (xy 187.588113 -283.378447)
			(xy 187.539894 -283.368603) (xy 187.493878 -283.351151) (xy 187.451257 -283.326544) (xy 187.413136 -283.295419)
			(xy 187.380501 -283.258582) (xy 187.354198 -283.216986) (xy 187.334907 -283.17171) (xy 187.32313 -283.123926)
			(xy 187.31917 -283.074872) (xy 186.980322 -283.074872) (xy 186.979827 -283.099479) (xy 186.971932 -283.148056)
			(xy 186.956348 -283.194737) (xy 186.933477 -283.238314) (xy 186.903912 -283.277658) (xy 186.868419 -283.31175)
			(xy 186.827916 -283.339706) (xy 186.783454 -283.360804) (xy 186.736183 -283.374496) (xy 186.687328 -283.380428)
			(xy 186.638153 -283.378447) (xy 186.589934 -283.368603) (xy 186.543918 -283.351151) (xy 186.501297 -283.326544)
			(xy 186.463176 -283.295419) (xy 186.430541 -283.258582) (xy 186.404238 -283.216986) (xy 186.384947 -283.17171)
			(xy 186.37317 -283.123926) (xy 186.36921 -283.074872) (xy 186.030362 -283.074872) (xy 186.029867 -283.099479)
			(xy 186.021972 -283.148056) (xy 186.006388 -283.194737) (xy 185.983517 -283.238314) (xy 185.953952 -283.277658)
			(xy 185.918459 -283.31175) (xy 185.877956 -283.339706) (xy 185.833494 -283.360804) (xy 185.786223 -283.374496)
			(xy 185.737368 -283.380428) (xy 185.688193 -283.378447) (xy 185.639974 -283.368603) (xy 185.593958 -283.351151)
			(xy 185.551337 -283.326544) (xy 185.513216 -283.295419) (xy 185.480581 -283.258582) (xy 185.454278 -283.216986)
			(xy 185.434987 -283.17171) (xy 185.42321 -283.123926) (xy 185.41925 -283.074872) (xy 185.080148 -283.074872)
			(xy 185.079653 -283.099479) (xy 185.071758 -283.148056) (xy 185.056174 -283.194737) (xy 185.033303 -283.238314)
			(xy 185.003738 -283.277658) (xy 184.968245 -283.31175) (xy 184.927742 -283.339706) (xy 184.88328 -283.360804)
			(xy 184.836009 -283.374496) (xy 184.787154 -283.380428) (xy 184.737979 -283.378447) (xy 184.68976 -283.368603)
			(xy 184.643744 -283.351151) (xy 184.601123 -283.326544) (xy 184.563002 -283.295419) (xy 184.530367 -283.258582)
			(xy 184.504064 -283.216986) (xy 184.484773 -283.17171) (xy 184.472996 -283.123926) (xy 184.469036 -283.074872)
			(xy 183.180228 -283.074872) (xy 183.179733 -283.099479) (xy 183.171838 -283.148056) (xy 183.156254 -283.194737)
			(xy 183.133383 -283.238314) (xy 183.103818 -283.277658) (xy 183.068325 -283.31175) (xy 183.027822 -283.339706)
			(xy 182.98336 -283.360804) (xy 182.936089 -283.374496) (xy 182.887234 -283.380428) (xy 182.838059 -283.378447)
			(xy 182.78984 -283.368603) (xy 182.743824 -283.351151) (xy 182.701203 -283.326544) (xy 182.663082 -283.295419)
			(xy 182.630447 -283.258582) (xy 182.604144 -283.216986) (xy 182.584853 -283.17171) (xy 182.573076 -283.123926)
			(xy 182.569116 -283.074872) (xy 182.230268 -283.074872) (xy 182.229773 -283.099479) (xy 182.221878 -283.148056)
			(xy 182.206294 -283.194737) (xy 182.183423 -283.238314) (xy 182.153858 -283.277658) (xy 182.118365 -283.31175)
			(xy 182.077862 -283.339706) (xy 182.0334 -283.360804) (xy 181.986129 -283.374496) (xy 181.937274 -283.380428)
			(xy 181.888099 -283.378447) (xy 181.83988 -283.368603) (xy 181.793864 -283.351151) (xy 181.751243 -283.326544)
			(xy 181.713122 -283.295419) (xy 181.680487 -283.258582) (xy 181.654184 -283.216986) (xy 181.634893 -283.17171)
			(xy 181.623116 -283.123926) (xy 181.619156 -283.074872) (xy 181.280308 -283.074872) (xy 181.279813 -283.099479)
			(xy 181.271918 -283.148056) (xy 181.256334 -283.194737) (xy 181.233463 -283.238314) (xy 181.203898 -283.277658)
			(xy 181.168405 -283.31175) (xy 181.127902 -283.339706) (xy 181.08344 -283.360804) (xy 181.036169 -283.374496)
			(xy 180.987314 -283.380428) (xy 180.938139 -283.378447) (xy 180.88992 -283.368603) (xy 180.843904 -283.351151)
			(xy 180.801283 -283.326544) (xy 180.763162 -283.295419) (xy 180.730527 -283.258582) (xy 180.704224 -283.216986)
			(xy 180.684933 -283.17171) (xy 180.673156 -283.123926) (xy 180.669196 -283.074872) (xy 180.330348 -283.074872)
			(xy 180.329853 -283.099479) (xy 180.321958 -283.148056) (xy 180.306374 -283.194737) (xy 180.283503 -283.238314)
			(xy 180.253938 -283.277658) (xy 180.218445 -283.31175) (xy 180.177942 -283.339706) (xy 180.13348 -283.360804)
			(xy 180.086209 -283.374496) (xy 180.037354 -283.380428) (xy 179.988179 -283.378447) (xy 179.93996 -283.368603)
			(xy 179.893944 -283.351151) (xy 179.851323 -283.326544) (xy 179.813202 -283.295419) (xy 179.780567 -283.258582)
			(xy 179.754264 -283.216986) (xy 179.734973 -283.17171) (xy 179.723196 -283.123926) (xy 179.719236 -283.074872)
			(xy 179.380388 -283.074872) (xy 179.379893 -283.099479) (xy 179.371998 -283.148056) (xy 179.356414 -283.194737)
			(xy 179.333543 -283.238314) (xy 179.303978 -283.277658) (xy 179.268485 -283.31175) (xy 179.227982 -283.339706)
			(xy 179.18352 -283.360804) (xy 179.136249 -283.374496) (xy 179.087394 -283.380428) (xy 179.038219 -283.378447)
			(xy 178.99 -283.368603) (xy 178.943984 -283.351151) (xy 178.901363 -283.326544) (xy 178.863242 -283.295419)
			(xy 178.830607 -283.258582) (xy 178.804304 -283.216986) (xy 178.785013 -283.17171) (xy 178.773236 -283.123926)
			(xy 178.769276 -283.074872) (xy 178.430174 -283.074872) (xy 178.429679 -283.099479) (xy 178.421784 -283.148056)
			(xy 178.4062 -283.194737) (xy 178.383329 -283.238314) (xy 178.353764 -283.277658) (xy 178.318271 -283.31175)
			(xy 178.277768 -283.339706) (xy 178.233306 -283.360804) (xy 178.186035 -283.374496) (xy 178.13718 -283.380428)
			(xy 178.088005 -283.378447) (xy 178.039786 -283.368603) (xy 177.99377 -283.351151) (xy 177.951149 -283.326544)
			(xy 177.913028 -283.295419) (xy 177.880393 -283.258582) (xy 177.85409 -283.216986) (xy 177.834799 -283.17171)
			(xy 177.823022 -283.123926) (xy 177.819062 -283.074872) (xy 177.480214 -283.074872) (xy 177.479719 -283.099479)
			(xy 177.471824 -283.148056) (xy 177.45624 -283.194737) (xy 177.433369 -283.238314) (xy 177.403804 -283.277658)
			(xy 177.368311 -283.31175) (xy 177.327808 -283.339706) (xy 177.283346 -283.360804) (xy 177.236075 -283.374496)
			(xy 177.18722 -283.380428) (xy 177.138045 -283.378447) (xy 177.089826 -283.368603) (xy 177.04381 -283.351151)
			(xy 177.001189 -283.326544) (xy 176.963068 -283.295419) (xy 176.930433 -283.258582) (xy 176.90413 -283.216986)
			(xy 176.884839 -283.17171) (xy 176.873062 -283.123926) (xy 176.869102 -283.074872) (xy 176.530254 -283.074872)
			(xy 176.529759 -283.099479) (xy 176.521864 -283.148056) (xy 176.50628 -283.194737) (xy 176.483409 -283.238314)
			(xy 176.453844 -283.277658) (xy 176.418351 -283.31175) (xy 176.377848 -283.339706) (xy 176.333386 -283.360804)
			(xy 176.286115 -283.374496) (xy 176.23726 -283.380428) (xy 176.188085 -283.378447) (xy 176.139866 -283.368603)
			(xy 176.09385 -283.351151) (xy 176.051229 -283.326544) (xy 176.013108 -283.295419) (xy 175.980473 -283.258582)
			(xy 175.95417 -283.216986) (xy 175.934879 -283.17171) (xy 175.923102 -283.123926) (xy 175.919142 -283.074872)
			(xy 174.630334 -283.074872) (xy 174.629839 -283.099479) (xy 174.621944 -283.148056) (xy 174.60636 -283.194737)
			(xy 174.583489 -283.238314) (xy 174.553924 -283.277658) (xy 174.518431 -283.31175) (xy 174.477928 -283.339706)
			(xy 174.433466 -283.360804) (xy 174.386195 -283.374496) (xy 174.33734 -283.380428) (xy 174.288165 -283.378447)
			(xy 174.239946 -283.368603) (xy 174.19393 -283.351151) (xy 174.151309 -283.326544) (xy 174.113188 -283.295419)
			(xy 174.080553 -283.258582) (xy 174.05425 -283.216986) (xy 174.034959 -283.17171) (xy 174.023182 -283.123926)
			(xy 174.019222 -283.074872) (xy 173.680374 -283.074872) (xy 173.679879 -283.099479) (xy 173.671984 -283.148056)
			(xy 173.6564 -283.194737) (xy 173.633529 -283.238314) (xy 173.603964 -283.277658) (xy 173.568471 -283.31175)
			(xy 173.527968 -283.339706) (xy 173.483506 -283.360804) (xy 173.436235 -283.374496) (xy 173.38738 -283.380428)
			(xy 173.338205 -283.378447) (xy 173.289986 -283.368603) (xy 173.24397 -283.351151) (xy 173.201349 -283.326544)
			(xy 173.163228 -283.295419) (xy 173.130593 -283.258582) (xy 173.10429 -283.216986) (xy 173.084999 -283.17171)
			(xy 173.073222 -283.123926) (xy 173.069262 -283.074872) (xy 172.730414 -283.074872) (xy 172.729919 -283.099479)
			(xy 172.722024 -283.148056) (xy 172.70644 -283.194737) (xy 172.683569 -283.238314) (xy 172.654004 -283.277658)
			(xy 172.618511 -283.31175) (xy 172.578008 -283.339706) (xy 172.533546 -283.360804) (xy 172.486275 -283.374496)
			(xy 172.43742 -283.380428) (xy 172.388245 -283.378447) (xy 172.340026 -283.368603) (xy 172.29401 -283.351151)
			(xy 172.251389 -283.326544) (xy 172.213268 -283.295419) (xy 172.180633 -283.258582) (xy 172.15433 -283.216986)
			(xy 172.135039 -283.17171) (xy 172.123262 -283.123926) (xy 172.119302 -283.074872) (xy 171.7802 -283.074872)
			(xy 171.779705 -283.099479) (xy 171.77181 -283.148056) (xy 171.756226 -283.194737) (xy 171.733355 -283.238314)
			(xy 171.70379 -283.277658) (xy 171.668297 -283.31175) (xy 171.627794 -283.339706) (xy 171.583332 -283.360804)
			(xy 171.536061 -283.374496) (xy 171.487206 -283.380428) (xy 171.438031 -283.378447) (xy 171.389812 -283.368603)
			(xy 171.343796 -283.351151) (xy 171.301175 -283.326544) (xy 171.263054 -283.295419) (xy 171.230419 -283.258582)
			(xy 171.204116 -283.216986) (xy 171.184825 -283.17171) (xy 171.173048 -283.123926) (xy 171.169088 -283.074872)
			(xy 170.83024 -283.074872) (xy 170.829745 -283.099479) (xy 170.82185 -283.148056) (xy 170.806266 -283.194737)
			(xy 170.783395 -283.238314) (xy 170.75383 -283.277658) (xy 170.718337 -283.31175) (xy 170.677834 -283.339706)
			(xy 170.633372 -283.360804) (xy 170.586101 -283.374496) (xy 170.537246 -283.380428) (xy 170.488071 -283.378447)
			(xy 170.439852 -283.368603) (xy 170.393836 -283.351151) (xy 170.351215 -283.326544) (xy 170.313094 -283.295419)
			(xy 170.280459 -283.258582) (xy 170.254156 -283.216986) (xy 170.234865 -283.17171) (xy 170.223088 -283.123926)
			(xy 170.219128 -283.074872) (xy 169.88028 -283.074872) (xy 169.879785 -283.099479) (xy 169.87189 -283.148056)
			(xy 169.856306 -283.194737) (xy 169.833435 -283.238314) (xy 169.80387 -283.277658) (xy 169.768377 -283.31175)
			(xy 169.727874 -283.339706) (xy 169.683412 -283.360804) (xy 169.636141 -283.374496) (xy 169.587286 -283.380428)
			(xy 169.538111 -283.378447) (xy 169.489892 -283.368603) (xy 169.443876 -283.351151) (xy 169.401255 -283.326544)
			(xy 169.363134 -283.295419) (xy 169.330499 -283.258582) (xy 169.304196 -283.216986) (xy 169.284905 -283.17171)
			(xy 169.273128 -283.123926) (xy 169.269168 -283.074872) (xy 168.93032 -283.074872) (xy 168.929825 -283.099479)
			(xy 168.92193 -283.148056) (xy 168.906346 -283.194737) (xy 168.883475 -283.238314) (xy 168.85391 -283.277658)
			(xy 168.818417 -283.31175) (xy 168.777914 -283.339706) (xy 168.733452 -283.360804) (xy 168.686181 -283.374496)
			(xy 168.637326 -283.380428) (xy 168.588151 -283.378447) (xy 168.539932 -283.368603) (xy 168.493916 -283.351151)
			(xy 168.451295 -283.326544) (xy 168.413174 -283.295419) (xy 168.380539 -283.258582) (xy 168.354236 -283.216986)
			(xy 168.334945 -283.17171) (xy 168.323168 -283.123926) (xy 168.319208 -283.074872) (xy 167.98036 -283.074872)
			(xy 167.979865 -283.099479) (xy 167.97197 -283.148056) (xy 167.956386 -283.194737) (xy 167.933515 -283.238314)
			(xy 167.90395 -283.277658) (xy 167.868457 -283.31175) (xy 167.827954 -283.339706) (xy 167.783492 -283.360804)
			(xy 167.736221 -283.374496) (xy 167.687366 -283.380428) (xy 167.638191 -283.378447) (xy 167.589972 -283.368603)
			(xy 167.543956 -283.351151) (xy 167.501335 -283.326544) (xy 167.463214 -283.295419) (xy 167.430579 -283.258582)
			(xy 167.404276 -283.216986) (xy 167.384985 -283.17171) (xy 167.373208 -283.123926) (xy 167.369248 -283.074872)
			(xy 167.0304 -283.074872) (xy 167.029905 -283.099479) (xy 167.02201 -283.148056) (xy 167.006426 -283.194737)
			(xy 166.983555 -283.238314) (xy 166.95399 -283.277658) (xy 166.918497 -283.31175) (xy 166.877994 -283.339706)
			(xy 166.833532 -283.360804) (xy 166.786261 -283.374496) (xy 166.737406 -283.380428) (xy 166.688231 -283.378447)
			(xy 166.640012 -283.368603) (xy 166.593996 -283.351151) (xy 166.551375 -283.326544) (xy 166.513254 -283.295419)
			(xy 166.480619 -283.258582) (xy 166.454316 -283.216986) (xy 166.435025 -283.17171) (xy 166.423248 -283.123926)
			(xy 166.419288 -283.074872) (xy 166.080186 -283.074872) (xy 166.079691 -283.099479) (xy 166.071796 -283.148056)
			(xy 166.056212 -283.194737) (xy 166.033341 -283.238314) (xy 166.003776 -283.277658) (xy 165.968283 -283.31175)
			(xy 165.92778 -283.339706) (xy 165.883318 -283.360804) (xy 165.836047 -283.374496) (xy 165.787192 -283.380428)
			(xy 165.738017 -283.378447) (xy 165.689798 -283.368603) (xy 165.643782 -283.351151) (xy 165.601161 -283.326544)
			(xy 165.56304 -283.295419) (xy 165.530405 -283.258582) (xy 165.504102 -283.216986) (xy 165.484811 -283.17171)
			(xy 165.473034 -283.123926) (xy 165.469074 -283.074872) (xy 165.130226 -283.074872) (xy 165.129731 -283.099479)
			(xy 165.121836 -283.148056) (xy 165.106252 -283.194737) (xy 165.083381 -283.238314) (xy 165.053816 -283.277658)
			(xy 165.018323 -283.31175) (xy 164.97782 -283.339706) (xy 164.933358 -283.360804) (xy 164.886087 -283.374496)
			(xy 164.837232 -283.380428) (xy 164.788057 -283.378447) (xy 164.739838 -283.368603) (xy 164.693822 -283.351151)
			(xy 164.651201 -283.326544) (xy 164.61308 -283.295419) (xy 164.580445 -283.258582) (xy 164.554142 -283.216986)
			(xy 164.534851 -283.17171) (xy 164.523074 -283.123926) (xy 164.519114 -283.074872) (xy 164.353748 -283.074872)
			(xy 164.353748 -283.549852) (xy 189.69407 -283.549852) (xy 189.69803 -283.500798) (xy 189.709807 -283.453014)
			(xy 189.729098 -283.407738) (xy 189.755401 -283.366142) (xy 189.788036 -283.329305) (xy 189.826157 -283.29818)
			(xy 189.868778 -283.273573) (xy 189.914794 -283.256121) (xy 189.963013 -283.246277) (xy 190.012188 -283.244296)
			(xy 190.061043 -283.250228) (xy 190.108314 -283.26392) (xy 190.152776 -283.285018) (xy 190.193279 -283.312974)
			(xy 190.228772 -283.347066) (xy 190.258337 -283.38641) (xy 190.281208 -283.429987) (xy 190.296792 -283.476668)
			(xy 190.304687 -283.525245) (xy 190.305182 -283.549852) (xy 190.64403 -283.549852) (xy 190.64799 -283.500798)
			(xy 190.659767 -283.453014) (xy 190.679058 -283.407738) (xy 190.705361 -283.366142) (xy 190.737996 -283.329305)
			(xy 190.776117 -283.29818) (xy 190.818738 -283.273573) (xy 190.864754 -283.256121) (xy 190.912973 -283.246277)
			(xy 190.962148 -283.244296) (xy 191.011003 -283.250228) (xy 191.058274 -283.26392) (xy 191.102736 -283.285018)
			(xy 191.143239 -283.312974) (xy 191.178732 -283.347066) (xy 191.208297 -283.38641) (xy 191.231168 -283.429987)
			(xy 191.246752 -283.476668) (xy 191.254647 -283.525245) (xy 191.255142 -283.549852) (xy 191.594244 -283.549852)
			(xy 191.598204 -283.500798) (xy 191.609981 -283.453014) (xy 191.629272 -283.407738) (xy 191.655575 -283.366142)
			(xy 191.68821 -283.329305) (xy 191.726331 -283.29818) (xy 191.768952 -283.273573) (xy 191.814968 -283.256121)
			(xy 191.863187 -283.246277) (xy 191.912362 -283.244296) (xy 191.961217 -283.250228) (xy 192.008488 -283.26392)
			(xy 192.05295 -283.285018) (xy 192.093453 -283.312974) (xy 192.128946 -283.347066) (xy 192.158511 -283.38641)
			(xy 192.181382 -283.429987) (xy 192.196966 -283.476668) (xy 192.204861 -283.525245) (xy 192.205356 -283.549852)
			(xy 192.544204 -283.549852) (xy 192.548164 -283.500798) (xy 192.559941 -283.453014) (xy 192.579232 -283.407738)
			(xy 192.605535 -283.366142) (xy 192.63817 -283.329305) (xy 192.676291 -283.29818) (xy 192.718912 -283.273573)
			(xy 192.764928 -283.256121) (xy 192.813147 -283.246277) (xy 192.862322 -283.244296) (xy 192.911177 -283.250228)
			(xy 192.958448 -283.26392) (xy 193.00291 -283.285018) (xy 193.043413 -283.312974) (xy 193.078906 -283.347066)
			(xy 193.108471 -283.38641) (xy 193.131342 -283.429987) (xy 193.146926 -283.476668) (xy 193.154821 -283.525245)
			(xy 193.155316 -283.549852) (xy 193.494164 -283.549852) (xy 193.498124 -283.500798) (xy 193.509901 -283.453014)
			(xy 193.529192 -283.407738) (xy 193.555495 -283.366142) (xy 193.58813 -283.329305) (xy 193.626251 -283.29818)
			(xy 193.668872 -283.273573) (xy 193.714888 -283.256121) (xy 193.763107 -283.246277) (xy 193.812282 -283.244296)
			(xy 193.861137 -283.250228) (xy 193.908408 -283.26392) (xy 193.95287 -283.285018) (xy 193.993373 -283.312974)
			(xy 194.028866 -283.347066) (xy 194.058431 -283.38641) (xy 194.081302 -283.429987) (xy 194.096886 -283.476668)
			(xy 194.104781 -283.525245) (xy 194.105276 -283.549852) (xy 194.444124 -283.549852) (xy 194.448084 -283.500798)
			(xy 194.459861 -283.453014) (xy 194.479152 -283.407738) (xy 194.505455 -283.366142) (xy 194.53809 -283.329305)
			(xy 194.576211 -283.29818) (xy 194.618832 -283.273573) (xy 194.664848 -283.256121) (xy 194.713067 -283.246277)
			(xy 194.762242 -283.244296) (xy 194.811097 -283.250228) (xy 194.858368 -283.26392) (xy 194.90283 -283.285018)
			(xy 194.943333 -283.312974) (xy 194.978826 -283.347066) (xy 195.008391 -283.38641) (xy 195.031262 -283.429987)
			(xy 195.046846 -283.476668) (xy 195.054741 -283.525245) (xy 195.055236 -283.549852) (xy 195.394084 -283.549852)
			(xy 195.398044 -283.500798) (xy 195.409821 -283.453014) (xy 195.429112 -283.407738) (xy 195.455415 -283.366142)
			(xy 195.48805 -283.329305) (xy 195.526171 -283.29818) (xy 195.568792 -283.273573) (xy 195.614808 -283.256121)
			(xy 195.663027 -283.246277) (xy 195.712202 -283.244296) (xy 195.761057 -283.250228) (xy 195.808328 -283.26392)
			(xy 195.85279 -283.285018) (xy 195.893293 -283.312974) (xy 195.928786 -283.347066) (xy 195.958351 -283.38641)
			(xy 195.981222 -283.429987) (xy 195.996806 -283.476668) (xy 196.004701 -283.525245) (xy 196.005196 -283.549852)
			(xy 196.344044 -283.549852) (xy 196.348004 -283.500798) (xy 196.359781 -283.453014) (xy 196.379072 -283.407738)
			(xy 196.405375 -283.366142) (xy 196.43801 -283.329305) (xy 196.476131 -283.29818) (xy 196.518752 -283.273573)
			(xy 196.564768 -283.256121) (xy 196.612987 -283.246277) (xy 196.662162 -283.244296) (xy 196.711017 -283.250228)
			(xy 196.758288 -283.26392) (xy 196.80275 -283.285018) (xy 196.843253 -283.312974) (xy 196.878746 -283.347066)
			(xy 196.908311 -283.38641) (xy 196.931182 -283.429987) (xy 196.946766 -283.476668) (xy 196.954661 -283.525245)
			(xy 196.955156 -283.549852) (xy 196.954661 -283.574459) (xy 196.954482 -283.57556) (xy 197.273414 -283.57556)
			(xy 197.273414 -283.524144) (xy 197.281457 -283.473362) (xy 197.297345 -283.424463) (xy 197.320688 -283.378651)
			(xy 197.350909 -283.337055) (xy 197.387265 -283.300699) (xy 197.428861 -283.270478) (xy 197.474673 -283.247135)
			(xy 197.523572 -283.231247) (xy 197.574354 -283.223204) (xy 197.62577 -283.223204) (xy 197.676552 -283.231247)
			(xy 197.725451 -283.247135) (xy 197.771263 -283.270478) (xy 197.812859 -283.300699) (xy 197.849215 -283.337055)
			(xy 197.879436 -283.378651) (xy 197.902779 -283.424463) (xy 197.918667 -283.473362) (xy 197.92671 -283.524144)
			(xy 197.927214 -283.549852) (xy 197.92671 -283.57556) (xy 198.223374 -283.57556) (xy 198.223374 -283.524144)
			(xy 198.231417 -283.473362) (xy 198.247305 -283.424463) (xy 198.270648 -283.378651) (xy 198.300869 -283.337055)
			(xy 198.337225 -283.300699) (xy 198.378821 -283.270478) (xy 198.424633 -283.247135) (xy 198.473532 -283.231247)
			(xy 198.524314 -283.223204) (xy 198.57573 -283.223204) (xy 198.626512 -283.231247) (xy 198.675411 -283.247135)
			(xy 198.721223 -283.270478) (xy 198.762819 -283.300699) (xy 198.799175 -283.337055) (xy 198.829396 -283.378651)
			(xy 198.852739 -283.424463) (xy 198.868627 -283.473362) (xy 198.87667 -283.524144) (xy 198.877174 -283.549852)
			(xy 198.877169 -283.550106) (xy 199.194432 -283.550106) (xy 199.198392 -283.501052) (xy 199.210169 -283.453268)
			(xy 199.22946 -283.407992) (xy 199.255763 -283.366396) (xy 199.288398 -283.329559) (xy 199.326519 -283.298434)
			(xy 199.36914 -283.273827) (xy 199.415156 -283.256375) (xy 199.463375 -283.246531) (xy 199.51255 -283.24455)
			(xy 199.561405 -283.250482) (xy 199.608676 -283.264174) (xy 199.653138 -283.285272) (xy 199.693641 -283.313228)
			(xy 199.729134 -283.34732) (xy 199.758699 -283.386664) (xy 199.78157 -283.430241) (xy 199.797154 -283.476922)
			(xy 199.805049 -283.525499) (xy 199.805544 -283.550106) (xy 199.805444 -283.555057) (xy 209.894309 -283.555057)
			(xy 209.894309 -283.500543) (xy 209.902068 -283.446583) (xy 209.917427 -283.394277) (xy 209.940074 -283.344689)
			(xy 209.969548 -283.298829) (xy 210.005248 -283.257631) (xy 210.046449 -283.221933) (xy 210.09231 -283.192462)
			(xy 210.1419 -283.169818) (xy 210.194207 -283.154462) (xy 210.248167 -283.146707) (xy 210.275424 -283.146246)
			(xy 210.302795 -283.146687) (xy 210.356976 -283.154509) (xy 210.40948 -283.170003) (xy 210.459226 -283.192851)
			(xy 210.505192 -283.222582) (xy 210.526122 -283.240226) (xy 210.533234 -283.246322) (xy 210.550252 -283.252672)
			(xy 210.635596 -283.252672) (xy 210.652614 -283.246322) (xy 210.659726 -283.240226) (xy 210.680679 -283.222612)
			(xy 210.726645 -283.192896) (xy 210.776388 -283.170054) (xy 210.828884 -283.154558) (xy 210.883056 -283.146723)
			(xy 210.910424 -283.146246) (xy 210.937671 -283.146826) (xy 210.991609 -283.154584) (xy 211.043895 -283.169939)
			(xy 211.093463 -283.192579) (xy 211.139305 -283.222043) (xy 211.180487 -283.25773) (xy 211.216172 -283.298914)
			(xy 211.245632 -283.344758) (xy 211.268269 -283.394328) (xy 211.283621 -283.446614) (xy 211.291376 -283.500553)
			(xy 211.291376 -283.555047) (xy 211.283621 -283.608986) (xy 211.268269 -283.661272) (xy 211.245632 -283.710842)
			(xy 211.216172 -283.756686) (xy 211.180487 -283.79787) (xy 211.139305 -283.833557) (xy 211.093463 -283.863021)
			(xy 211.043895 -283.885661) (xy 210.991609 -283.901016) (xy 210.937671 -283.908774) (xy 210.910424 -283.909262)
			(xy 210.883054 -283.908791) (xy 210.828875 -283.900976) (xy 210.776371 -283.885488) (xy 210.726624 -283.862648)
			(xy 210.680657 -283.832923) (xy 210.659726 -283.815282) (xy 210.652614 -283.809186) (xy 210.635596 -283.802836)
			(xy 210.550252 -283.802836) (xy 210.533234 -283.809186) (xy 210.526122 -283.815282) (xy 210.50519 -283.832921)
			(xy 210.459218 -283.862634) (xy 210.40947 -283.88547) (xy 210.356969 -283.900961) (xy 210.302793 -283.908788)
			(xy 210.275424 -283.909262) (xy 210.248167 -283.908893) (xy 210.194207 -283.901138) (xy 210.1419 -283.885782)
			(xy 210.09231 -283.863138) (xy 210.046449 -283.833667) (xy 210.005248 -283.797969) (xy 209.969548 -283.756771)
			(xy 209.940074 -283.710911) (xy 209.917427 -283.661323) (xy 209.902068 -283.609017) (xy 209.894309 -283.555057)
			(xy 199.805444 -283.555057) (xy 199.805049 -283.574713) (xy 199.797154 -283.62329) (xy 199.78157 -283.669971)
			(xy 199.758699 -283.713548) (xy 199.729134 -283.752892) (xy 199.693641 -283.786984) (xy 199.653138 -283.81494)
			(xy 199.608676 -283.836038) (xy 199.561405 -283.84973) (xy 199.51255 -283.855662) (xy 199.463375 -283.853681)
			(xy 199.415156 -283.843837) (xy 199.36914 -283.826385) (xy 199.326519 -283.801778) (xy 199.288398 -283.770653)
			(xy 199.255763 -283.733816) (xy 199.22946 -283.69222) (xy 199.210169 -283.646944) (xy 199.198392 -283.59916)
			(xy 199.194432 -283.550106) (xy 198.877169 -283.550106) (xy 198.87667 -283.57556) (xy 198.868627 -283.626342)
			(xy 198.852739 -283.675241) (xy 198.829396 -283.721053) (xy 198.799175 -283.762649) (xy 198.762819 -283.799005)
			(xy 198.721223 -283.829226) (xy 198.675411 -283.852569) (xy 198.626512 -283.868457) (xy 198.57573 -283.8765)
			(xy 198.524314 -283.8765) (xy 198.473532 -283.868457) (xy 198.424633 -283.852569) (xy 198.378821 -283.829226)
			(xy 198.337225 -283.799005) (xy 198.300869 -283.762649) (xy 198.270648 -283.721053) (xy 198.247305 -283.675241)
			(xy 198.231417 -283.626342) (xy 198.223374 -283.57556) (xy 197.92671 -283.57556) (xy 197.918667 -283.626342)
			(xy 197.902779 -283.675241) (xy 197.879436 -283.721053) (xy 197.849215 -283.762649) (xy 197.812859 -283.799005)
			(xy 197.771263 -283.829226) (xy 197.725451 -283.852569) (xy 197.676552 -283.868457) (xy 197.62577 -283.8765)
			(xy 197.574354 -283.8765) (xy 197.523572 -283.868457) (xy 197.474673 -283.852569) (xy 197.428861 -283.829226)
			(xy 197.387265 -283.799005) (xy 197.350909 -283.762649) (xy 197.320688 -283.721053) (xy 197.297345 -283.675241)
			(xy 197.281457 -283.626342) (xy 197.273414 -283.57556) (xy 196.954482 -283.57556) (xy 196.946766 -283.623036)
			(xy 196.931182 -283.669717) (xy 196.908311 -283.713294) (xy 196.878746 -283.752638) (xy 196.843253 -283.78673)
			(xy 196.80275 -283.814686) (xy 196.758288 -283.835784) (xy 196.711017 -283.849476) (xy 196.662162 -283.855408)
			(xy 196.612987 -283.853427) (xy 196.564768 -283.843583) (xy 196.518752 -283.826131) (xy 196.476131 -283.801524)
			(xy 196.43801 -283.770399) (xy 196.405375 -283.733562) (xy 196.379072 -283.691966) (xy 196.359781 -283.64669)
			(xy 196.348004 -283.598906) (xy 196.344044 -283.549852) (xy 196.005196 -283.549852) (xy 196.004701 -283.574459)
			(xy 195.996806 -283.623036) (xy 195.981222 -283.669717) (xy 195.958351 -283.713294) (xy 195.928786 -283.752638)
			(xy 195.893293 -283.78673) (xy 195.85279 -283.814686) (xy 195.808328 -283.835784) (xy 195.761057 -283.849476)
			(xy 195.712202 -283.855408) (xy 195.663027 -283.853427) (xy 195.614808 -283.843583) (xy 195.568792 -283.826131)
			(xy 195.526171 -283.801524) (xy 195.48805 -283.770399) (xy 195.455415 -283.733562) (xy 195.429112 -283.691966)
			(xy 195.409821 -283.64669) (xy 195.398044 -283.598906) (xy 195.394084 -283.549852) (xy 195.055236 -283.549852)
			(xy 195.054741 -283.574459) (xy 195.046846 -283.623036) (xy 195.031262 -283.669717) (xy 195.008391 -283.713294)
			(xy 194.978826 -283.752638) (xy 194.943333 -283.78673) (xy 194.90283 -283.814686) (xy 194.858368 -283.835784)
			(xy 194.811097 -283.849476) (xy 194.762242 -283.855408) (xy 194.713067 -283.853427) (xy 194.664848 -283.843583)
			(xy 194.618832 -283.826131) (xy 194.576211 -283.801524) (xy 194.53809 -283.770399) (xy 194.505455 -283.733562)
			(xy 194.479152 -283.691966) (xy 194.459861 -283.64669) (xy 194.448084 -283.598906) (xy 194.444124 -283.549852)
			(xy 194.105276 -283.549852) (xy 194.104781 -283.574459) (xy 194.096886 -283.623036) (xy 194.081302 -283.669717)
			(xy 194.058431 -283.713294) (xy 194.028866 -283.752638) (xy 193.993373 -283.78673) (xy 193.95287 -283.814686)
			(xy 193.908408 -283.835784) (xy 193.861137 -283.849476) (xy 193.812282 -283.855408) (xy 193.763107 -283.853427)
			(xy 193.714888 -283.843583) (xy 193.668872 -283.826131) (xy 193.626251 -283.801524) (xy 193.58813 -283.770399)
			(xy 193.555495 -283.733562) (xy 193.529192 -283.691966) (xy 193.509901 -283.64669) (xy 193.498124 -283.598906)
			(xy 193.494164 -283.549852) (xy 193.155316 -283.549852) (xy 193.154821 -283.574459) (xy 193.146926 -283.623036)
			(xy 193.131342 -283.669717) (xy 193.108471 -283.713294) (xy 193.078906 -283.752638) (xy 193.043413 -283.78673)
			(xy 193.00291 -283.814686) (xy 192.958448 -283.835784) (xy 192.911177 -283.849476) (xy 192.862322 -283.855408)
			(xy 192.813147 -283.853427) (xy 192.764928 -283.843583) (xy 192.718912 -283.826131) (xy 192.676291 -283.801524)
			(xy 192.63817 -283.770399) (xy 192.605535 -283.733562) (xy 192.579232 -283.691966) (xy 192.559941 -283.64669)
			(xy 192.548164 -283.598906) (xy 192.544204 -283.549852) (xy 192.205356 -283.549852) (xy 192.204861 -283.574459)
			(xy 192.196966 -283.623036) (xy 192.181382 -283.669717) (xy 192.158511 -283.713294) (xy 192.128946 -283.752638)
			(xy 192.093453 -283.78673) (xy 192.05295 -283.814686) (xy 192.008488 -283.835784) (xy 191.961217 -283.849476)
			(xy 191.912362 -283.855408) (xy 191.863187 -283.853427) (xy 191.814968 -283.843583) (xy 191.768952 -283.826131)
			(xy 191.726331 -283.801524) (xy 191.68821 -283.770399) (xy 191.655575 -283.733562) (xy 191.629272 -283.691966)
			(xy 191.609981 -283.64669) (xy 191.598204 -283.598906) (xy 191.594244 -283.549852) (xy 191.255142 -283.549852)
			(xy 191.254647 -283.574459) (xy 191.246752 -283.623036) (xy 191.231168 -283.669717) (xy 191.208297 -283.713294)
			(xy 191.178732 -283.752638) (xy 191.143239 -283.78673) (xy 191.102736 -283.814686) (xy 191.058274 -283.835784)
			(xy 191.011003 -283.849476) (xy 190.962148 -283.855408) (xy 190.912973 -283.853427) (xy 190.864754 -283.843583)
			(xy 190.818738 -283.826131) (xy 190.776117 -283.801524) (xy 190.737996 -283.770399) (xy 190.705361 -283.733562)
			(xy 190.679058 -283.691966) (xy 190.659767 -283.64669) (xy 190.64799 -283.598906) (xy 190.64403 -283.549852)
			(xy 190.305182 -283.549852) (xy 190.304687 -283.574459) (xy 190.296792 -283.623036) (xy 190.281208 -283.669717)
			(xy 190.258337 -283.713294) (xy 190.228772 -283.752638) (xy 190.193279 -283.78673) (xy 190.152776 -283.814686)
			(xy 190.108314 -283.835784) (xy 190.061043 -283.849476) (xy 190.012188 -283.855408) (xy 189.963013 -283.853427)
			(xy 189.914794 -283.843583) (xy 189.868778 -283.826131) (xy 189.826157 -283.801524) (xy 189.788036 -283.770399)
			(xy 189.755401 -283.733562) (xy 189.729098 -283.691966) (xy 189.709807 -283.64669) (xy 189.69803 -283.598906)
			(xy 189.69407 -283.549852) (xy 164.353748 -283.549852) (xy 164.353748 -284.024832) (xy 164.519114 -284.024832)
			(xy 164.523074 -283.975778) (xy 164.534851 -283.927994) (xy 164.554142 -283.882718) (xy 164.580445 -283.841122)
			(xy 164.61308 -283.804285) (xy 164.651201 -283.77316) (xy 164.693822 -283.748553) (xy 164.739838 -283.731101)
			(xy 164.788057 -283.721257) (xy 164.837232 -283.719276) (xy 164.886087 -283.725208) (xy 164.933358 -283.7389)
			(xy 164.97782 -283.759998) (xy 165.018323 -283.787954) (xy 165.053816 -283.822046) (xy 165.083381 -283.86139)
			(xy 165.106252 -283.904967) (xy 165.121836 -283.951648) (xy 165.129731 -284.000225) (xy 165.130226 -284.024832)
			(xy 165.469074 -284.024832) (xy 165.473034 -283.975778) (xy 165.484811 -283.927994) (xy 165.504102 -283.882718)
			(xy 165.530405 -283.841122) (xy 165.56304 -283.804285) (xy 165.601161 -283.77316) (xy 165.643782 -283.748553)
			(xy 165.689798 -283.731101) (xy 165.738017 -283.721257) (xy 165.787192 -283.719276) (xy 165.836047 -283.725208)
			(xy 165.883318 -283.7389) (xy 165.92778 -283.759998) (xy 165.968283 -283.787954) (xy 166.003776 -283.822046)
			(xy 166.033341 -283.86139) (xy 166.056212 -283.904967) (xy 166.071796 -283.951648) (xy 166.079691 -284.000225)
			(xy 166.080186 -284.024832) (xy 166.419288 -284.024832) (xy 166.423248 -283.975778) (xy 166.435025 -283.927994)
			(xy 166.454316 -283.882718) (xy 166.480619 -283.841122) (xy 166.513254 -283.804285) (xy 166.551375 -283.77316)
			(xy 166.593996 -283.748553) (xy 166.640012 -283.731101) (xy 166.688231 -283.721257) (xy 166.737406 -283.719276)
			(xy 166.786261 -283.725208) (xy 166.833532 -283.7389) (xy 166.877994 -283.759998) (xy 166.918497 -283.787954)
			(xy 166.95399 -283.822046) (xy 166.983555 -283.86139) (xy 167.006426 -283.904967) (xy 167.02201 -283.951648)
			(xy 167.029905 -284.000225) (xy 167.0304 -284.024832) (xy 167.369248 -284.024832) (xy 167.373208 -283.975778)
			(xy 167.384985 -283.927994) (xy 167.404276 -283.882718) (xy 167.430579 -283.841122) (xy 167.463214 -283.804285)
			(xy 167.501335 -283.77316) (xy 167.543956 -283.748553) (xy 167.589972 -283.731101) (xy 167.638191 -283.721257)
			(xy 167.687366 -283.719276) (xy 167.736221 -283.725208) (xy 167.783492 -283.7389) (xy 167.827954 -283.759998)
			(xy 167.868457 -283.787954) (xy 167.90395 -283.822046) (xy 167.933515 -283.86139) (xy 167.956386 -283.904967)
			(xy 167.97197 -283.951648) (xy 167.979865 -284.000225) (xy 167.98036 -284.024832) (xy 168.319208 -284.024832)
			(xy 168.323168 -283.975778) (xy 168.334945 -283.927994) (xy 168.354236 -283.882718) (xy 168.380539 -283.841122)
			(xy 168.413174 -283.804285) (xy 168.451295 -283.77316) (xy 168.493916 -283.748553) (xy 168.539932 -283.731101)
			(xy 168.588151 -283.721257) (xy 168.637326 -283.719276) (xy 168.686181 -283.725208) (xy 168.733452 -283.7389)
			(xy 168.777914 -283.759998) (xy 168.818417 -283.787954) (xy 168.85391 -283.822046) (xy 168.883475 -283.86139)
			(xy 168.906346 -283.904967) (xy 168.92193 -283.951648) (xy 168.929825 -284.000225) (xy 168.93032 -284.024832)
			(xy 169.269168 -284.024832) (xy 169.273128 -283.975778) (xy 169.284905 -283.927994) (xy 169.304196 -283.882718)
			(xy 169.330499 -283.841122) (xy 169.363134 -283.804285) (xy 169.401255 -283.77316) (xy 169.443876 -283.748553)
			(xy 169.489892 -283.731101) (xy 169.538111 -283.721257) (xy 169.587286 -283.719276) (xy 169.636141 -283.725208)
			(xy 169.683412 -283.7389) (xy 169.727874 -283.759998) (xy 169.768377 -283.787954) (xy 169.80387 -283.822046)
			(xy 169.833435 -283.86139) (xy 169.856306 -283.904967) (xy 169.87189 -283.951648) (xy 169.879785 -284.000225)
			(xy 169.88028 -284.024832) (xy 170.219128 -284.024832) (xy 170.223088 -283.975778) (xy 170.234865 -283.927994)
			(xy 170.254156 -283.882718) (xy 170.280459 -283.841122) (xy 170.313094 -283.804285) (xy 170.351215 -283.77316)
			(xy 170.393836 -283.748553) (xy 170.439852 -283.731101) (xy 170.488071 -283.721257) (xy 170.537246 -283.719276)
			(xy 170.586101 -283.725208) (xy 170.633372 -283.7389) (xy 170.677834 -283.759998) (xy 170.718337 -283.787954)
			(xy 170.75383 -283.822046) (xy 170.783395 -283.86139) (xy 170.806266 -283.904967) (xy 170.82185 -283.951648)
			(xy 170.829745 -284.000225) (xy 170.83024 -284.024832) (xy 171.169088 -284.024832) (xy 171.173048 -283.975778)
			(xy 171.184825 -283.927994) (xy 171.204116 -283.882718) (xy 171.230419 -283.841122) (xy 171.263054 -283.804285)
			(xy 171.301175 -283.77316) (xy 171.343796 -283.748553) (xy 171.389812 -283.731101) (xy 171.438031 -283.721257)
			(xy 171.487206 -283.719276) (xy 171.536061 -283.725208) (xy 171.583332 -283.7389) (xy 171.627794 -283.759998)
			(xy 171.668297 -283.787954) (xy 171.70379 -283.822046) (xy 171.733355 -283.86139) (xy 171.756226 -283.904967)
			(xy 171.77181 -283.951648) (xy 171.779705 -284.000225) (xy 171.7802 -284.024832) (xy 172.119048 -284.024832)
			(xy 172.123008 -283.975778) (xy 172.134785 -283.927994) (xy 172.154076 -283.882718) (xy 172.180379 -283.841122)
			(xy 172.213014 -283.804285) (xy 172.251135 -283.77316) (xy 172.293756 -283.748553) (xy 172.339772 -283.731101)
			(xy 172.387991 -283.721257) (xy 172.437166 -283.719276) (xy 172.486021 -283.725208) (xy 172.533292 -283.7389)
			(xy 172.577754 -283.759998) (xy 172.618257 -283.787954) (xy 172.65375 -283.822046) (xy 172.683315 -283.86139)
			(xy 172.706186 -283.904967) (xy 172.72177 -283.951648) (xy 172.729665 -284.000225) (xy 172.73016 -284.024832)
			(xy 173.069262 -284.024832) (xy 173.073222 -283.975778) (xy 173.084999 -283.927994) (xy 173.10429 -283.882718)
			(xy 173.130593 -283.841122) (xy 173.163228 -283.804285) (xy 173.201349 -283.77316) (xy 173.24397 -283.748553)
			(xy 173.289986 -283.731101) (xy 173.338205 -283.721257) (xy 173.38738 -283.719276) (xy 173.436235 -283.725208)
			(xy 173.483506 -283.7389) (xy 173.527968 -283.759998) (xy 173.568471 -283.787954) (xy 173.603964 -283.822046)
			(xy 173.633529 -283.86139) (xy 173.6564 -283.904967) (xy 173.671984 -283.951648) (xy 173.679879 -284.000225)
			(xy 173.680374 -284.024832) (xy 174.019222 -284.024832) (xy 174.023182 -283.975778) (xy 174.034959 -283.927994)
			(xy 174.05425 -283.882718) (xy 174.080553 -283.841122) (xy 174.113188 -283.804285) (xy 174.151309 -283.77316)
			(xy 174.19393 -283.748553) (xy 174.239946 -283.731101) (xy 174.288165 -283.721257) (xy 174.33734 -283.719276)
			(xy 174.386195 -283.725208) (xy 174.433466 -283.7389) (xy 174.477928 -283.759998) (xy 174.518431 -283.787954)
			(xy 174.553924 -283.822046) (xy 174.583489 -283.86139) (xy 174.60636 -283.904967) (xy 174.621944 -283.951648)
			(xy 174.629839 -284.000225) (xy 174.630334 -284.024832) (xy 175.919142 -284.024832) (xy 175.923102 -283.975778)
			(xy 175.934879 -283.927994) (xy 175.95417 -283.882718) (xy 175.980473 -283.841122) (xy 176.013108 -283.804285)
			(xy 176.051229 -283.77316) (xy 176.09385 -283.748553) (xy 176.139866 -283.731101) (xy 176.188085 -283.721257)
			(xy 176.23726 -283.719276) (xy 176.286115 -283.725208) (xy 176.333386 -283.7389) (xy 176.377848 -283.759998)
			(xy 176.418351 -283.787954) (xy 176.453844 -283.822046) (xy 176.483409 -283.86139) (xy 176.50628 -283.904967)
			(xy 176.521864 -283.951648) (xy 176.529759 -284.000225) (xy 176.530254 -284.024832) (xy 176.869102 -284.024832)
			(xy 176.873062 -283.975778) (xy 176.884839 -283.927994) (xy 176.90413 -283.882718) (xy 176.930433 -283.841122)
			(xy 176.963068 -283.804285) (xy 177.001189 -283.77316) (xy 177.04381 -283.748553) (xy 177.089826 -283.731101)
			(xy 177.138045 -283.721257) (xy 177.18722 -283.719276) (xy 177.236075 -283.725208) (xy 177.283346 -283.7389)
			(xy 177.327808 -283.759998) (xy 177.368311 -283.787954) (xy 177.403804 -283.822046) (xy 177.433369 -283.86139)
			(xy 177.45624 -283.904967) (xy 177.471824 -283.951648) (xy 177.479719 -284.000225) (xy 177.480214 -284.024832)
			(xy 177.819062 -284.024832) (xy 177.823022 -283.975778) (xy 177.834799 -283.927994) (xy 177.85409 -283.882718)
			(xy 177.880393 -283.841122) (xy 177.913028 -283.804285) (xy 177.951149 -283.77316) (xy 177.99377 -283.748553)
			(xy 178.039786 -283.731101) (xy 178.088005 -283.721257) (xy 178.13718 -283.719276) (xy 178.186035 -283.725208)
			(xy 178.233306 -283.7389) (xy 178.277768 -283.759998) (xy 178.318271 -283.787954) (xy 178.353764 -283.822046)
			(xy 178.383329 -283.86139) (xy 178.4062 -283.904967) (xy 178.421784 -283.951648) (xy 178.429679 -284.000225)
			(xy 178.430174 -284.024832) (xy 178.769276 -284.024832) (xy 178.773236 -283.975778) (xy 178.785013 -283.927994)
			(xy 178.804304 -283.882718) (xy 178.830607 -283.841122) (xy 178.863242 -283.804285) (xy 178.901363 -283.77316)
			(xy 178.943984 -283.748553) (xy 178.99 -283.731101) (xy 179.038219 -283.721257) (xy 179.087394 -283.719276)
			(xy 179.136249 -283.725208) (xy 179.18352 -283.7389) (xy 179.227982 -283.759998) (xy 179.268485 -283.787954)
			(xy 179.303978 -283.822046) (xy 179.333543 -283.86139) (xy 179.356414 -283.904967) (xy 179.371998 -283.951648)
			(xy 179.379893 -284.000225) (xy 179.380388 -284.024832) (xy 179.719236 -284.024832) (xy 179.723196 -283.975778)
			(xy 179.734973 -283.927994) (xy 179.754264 -283.882718) (xy 179.780567 -283.841122) (xy 179.813202 -283.804285)
			(xy 179.851323 -283.77316) (xy 179.893944 -283.748553) (xy 179.93996 -283.731101) (xy 179.988179 -283.721257)
			(xy 180.037354 -283.719276) (xy 180.086209 -283.725208) (xy 180.13348 -283.7389) (xy 180.177942 -283.759998)
			(xy 180.218445 -283.787954) (xy 180.253938 -283.822046) (xy 180.283503 -283.86139) (xy 180.306374 -283.904967)
			(xy 180.321958 -283.951648) (xy 180.329853 -284.000225) (xy 180.330348 -284.024832) (xy 180.669196 -284.024832)
			(xy 180.673156 -283.975778) (xy 180.684933 -283.927994) (xy 180.704224 -283.882718) (xy 180.730527 -283.841122)
			(xy 180.763162 -283.804285) (xy 180.801283 -283.77316) (xy 180.843904 -283.748553) (xy 180.88992 -283.731101)
			(xy 180.938139 -283.721257) (xy 180.987314 -283.719276) (xy 181.036169 -283.725208) (xy 181.08344 -283.7389)
			(xy 181.127902 -283.759998) (xy 181.168405 -283.787954) (xy 181.203898 -283.822046) (xy 181.233463 -283.86139)
			(xy 181.256334 -283.904967) (xy 181.271918 -283.951648) (xy 181.279813 -284.000225) (xy 181.280308 -284.024832)
			(xy 181.619156 -284.024832) (xy 181.623116 -283.975778) (xy 181.634893 -283.927994) (xy 181.654184 -283.882718)
			(xy 181.680487 -283.841122) (xy 181.713122 -283.804285) (xy 181.751243 -283.77316) (xy 181.793864 -283.748553)
			(xy 181.83988 -283.731101) (xy 181.888099 -283.721257) (xy 181.937274 -283.719276) (xy 181.986129 -283.725208)
			(xy 182.0334 -283.7389) (xy 182.077862 -283.759998) (xy 182.118365 -283.787954) (xy 182.153858 -283.822046)
			(xy 182.183423 -283.86139) (xy 182.206294 -283.904967) (xy 182.221878 -283.951648) (xy 182.229773 -284.000225)
			(xy 182.230268 -284.024832) (xy 182.569116 -284.024832) (xy 182.573076 -283.975778) (xy 182.584853 -283.927994)
			(xy 182.604144 -283.882718) (xy 182.630447 -283.841122) (xy 182.663082 -283.804285) (xy 182.701203 -283.77316)
			(xy 182.743824 -283.748553) (xy 182.78984 -283.731101) (xy 182.838059 -283.721257) (xy 182.887234 -283.719276)
			(xy 182.936089 -283.725208) (xy 182.98336 -283.7389) (xy 183.027822 -283.759998) (xy 183.068325 -283.787954)
			(xy 183.103818 -283.822046) (xy 183.133383 -283.86139) (xy 183.156254 -283.904967) (xy 183.171838 -283.951648)
			(xy 183.179733 -284.000225) (xy 183.180228 -284.024832) (xy 184.469036 -284.024832) (xy 184.472996 -283.975778)
			(xy 184.484773 -283.927994) (xy 184.504064 -283.882718) (xy 184.530367 -283.841122) (xy 184.563002 -283.804285)
			(xy 184.601123 -283.77316) (xy 184.643744 -283.748553) (xy 184.68976 -283.731101) (xy 184.737979 -283.721257)
			(xy 184.787154 -283.719276) (xy 184.836009 -283.725208) (xy 184.88328 -283.7389) (xy 184.927742 -283.759998)
			(xy 184.968245 -283.787954) (xy 185.003738 -283.822046) (xy 185.033303 -283.86139) (xy 185.056174 -283.904967)
			(xy 185.071758 -283.951648) (xy 185.079653 -284.000225) (xy 185.080148 -284.024832) (xy 185.41925 -284.024832)
			(xy 185.42321 -283.975778) (xy 185.434987 -283.927994) (xy 185.454278 -283.882718) (xy 185.480581 -283.841122)
			(xy 185.513216 -283.804285) (xy 185.551337 -283.77316) (xy 185.593958 -283.748553) (xy 185.639974 -283.731101)
			(xy 185.688193 -283.721257) (xy 185.737368 -283.719276) (xy 185.786223 -283.725208) (xy 185.833494 -283.7389)
			(xy 185.877956 -283.759998) (xy 185.918459 -283.787954) (xy 185.953952 -283.822046) (xy 185.983517 -283.86139)
			(xy 186.006388 -283.904967) (xy 186.021972 -283.951648) (xy 186.029867 -284.000225) (xy 186.030362 -284.024832)
			(xy 186.36921 -284.024832) (xy 186.37317 -283.975778) (xy 186.384947 -283.927994) (xy 186.404238 -283.882718)
			(xy 186.430541 -283.841122) (xy 186.463176 -283.804285) (xy 186.501297 -283.77316) (xy 186.543918 -283.748553)
			(xy 186.589934 -283.731101) (xy 186.638153 -283.721257) (xy 186.687328 -283.719276) (xy 186.736183 -283.725208)
			(xy 186.783454 -283.7389) (xy 186.827916 -283.759998) (xy 186.868419 -283.787954) (xy 186.903912 -283.822046)
			(xy 186.933477 -283.86139) (xy 186.956348 -283.904967) (xy 186.971932 -283.951648) (xy 186.979827 -284.000225)
			(xy 186.980322 -284.024832) (xy 187.31917 -284.024832) (xy 187.32313 -283.975778) (xy 187.334907 -283.927994)
			(xy 187.354198 -283.882718) (xy 187.380501 -283.841122) (xy 187.413136 -283.804285) (xy 187.451257 -283.77316)
			(xy 187.493878 -283.748553) (xy 187.539894 -283.731101) (xy 187.588113 -283.721257) (xy 187.637288 -283.719276)
			(xy 187.686143 -283.725208) (xy 187.733414 -283.7389) (xy 187.777876 -283.759998) (xy 187.818379 -283.787954)
			(xy 187.853872 -283.822046) (xy 187.883437 -283.86139) (xy 187.906308 -283.904967) (xy 187.921892 -283.951648)
			(xy 187.929787 -284.000225) (xy 187.930282 -284.024832) (xy 188.26913 -284.024832) (xy 188.27309 -283.975778)
			(xy 188.284867 -283.927994) (xy 188.304158 -283.882718) (xy 188.330461 -283.841122) (xy 188.363096 -283.804285)
			(xy 188.401217 -283.77316) (xy 188.443838 -283.748553) (xy 188.489854 -283.731101) (xy 188.538073 -283.721257)
			(xy 188.587248 -283.719276) (xy 188.636103 -283.725208) (xy 188.683374 -283.7389) (xy 188.727836 -283.759998)
			(xy 188.768339 -283.787954) (xy 188.803832 -283.822046) (xy 188.833397 -283.86139) (xy 188.856268 -283.904967)
			(xy 188.871852 -283.951648) (xy 188.879747 -284.000225) (xy 188.880242 -284.024832) (xy 188.879747 -284.049439)
			(xy 188.871852 -284.098016) (xy 188.856268 -284.144697) (xy 188.833397 -284.188274) (xy 188.803832 -284.227618)
			(xy 188.768339 -284.26171) (xy 188.727836 -284.289666) (xy 188.683374 -284.310764) (xy 188.636103 -284.324456)
			(xy 188.587248 -284.330388) (xy 188.538073 -284.328407) (xy 188.489854 -284.318563) (xy 188.443838 -284.301111)
			(xy 188.401217 -284.276504) (xy 188.363096 -284.245379) (xy 188.330461 -284.208542) (xy 188.304158 -284.166946)
			(xy 188.284867 -284.12167) (xy 188.27309 -284.073886) (xy 188.26913 -284.024832) (xy 187.930282 -284.024832)
			(xy 187.929787 -284.049439) (xy 187.921892 -284.098016) (xy 187.906308 -284.144697) (xy 187.883437 -284.188274)
			(xy 187.853872 -284.227618) (xy 187.818379 -284.26171) (xy 187.777876 -284.289666) (xy 187.733414 -284.310764)
			(xy 187.686143 -284.324456) (xy 187.637288 -284.330388) (xy 187.588113 -284.328407) (xy 187.539894 -284.318563)
			(xy 187.493878 -284.301111) (xy 187.451257 -284.276504) (xy 187.413136 -284.245379) (xy 187.380501 -284.208542)
			(xy 187.354198 -284.166946) (xy 187.334907 -284.12167) (xy 187.32313 -284.073886) (xy 187.31917 -284.024832)
			(xy 186.980322 -284.024832) (xy 186.979827 -284.049439) (xy 186.971932 -284.098016) (xy 186.956348 -284.144697)
			(xy 186.933477 -284.188274) (xy 186.903912 -284.227618) (xy 186.868419 -284.26171) (xy 186.827916 -284.289666)
			(xy 186.783454 -284.310764) (xy 186.736183 -284.324456) (xy 186.687328 -284.330388) (xy 186.638153 -284.328407)
			(xy 186.589934 -284.318563) (xy 186.543918 -284.301111) (xy 186.501297 -284.276504) (xy 186.463176 -284.245379)
			(xy 186.430541 -284.208542) (xy 186.404238 -284.166946) (xy 186.384947 -284.12167) (xy 186.37317 -284.073886)
			(xy 186.36921 -284.024832) (xy 186.030362 -284.024832) (xy 186.029867 -284.049439) (xy 186.021972 -284.098016)
			(xy 186.006388 -284.144697) (xy 185.983517 -284.188274) (xy 185.953952 -284.227618) (xy 185.918459 -284.26171)
			(xy 185.877956 -284.289666) (xy 185.833494 -284.310764) (xy 185.786223 -284.324456) (xy 185.737368 -284.330388)
			(xy 185.688193 -284.328407) (xy 185.639974 -284.318563) (xy 185.593958 -284.301111) (xy 185.551337 -284.276504)
			(xy 185.513216 -284.245379) (xy 185.480581 -284.208542) (xy 185.454278 -284.166946) (xy 185.434987 -284.12167)
			(xy 185.42321 -284.073886) (xy 185.41925 -284.024832) (xy 185.080148 -284.024832) (xy 185.079653 -284.049439)
			(xy 185.071758 -284.098016) (xy 185.056174 -284.144697) (xy 185.033303 -284.188274) (xy 185.003738 -284.227618)
			(xy 184.968245 -284.26171) (xy 184.927742 -284.289666) (xy 184.88328 -284.310764) (xy 184.836009 -284.324456)
			(xy 184.787154 -284.330388) (xy 184.737979 -284.328407) (xy 184.68976 -284.318563) (xy 184.643744 -284.301111)
			(xy 184.601123 -284.276504) (xy 184.563002 -284.245379) (xy 184.530367 -284.208542) (xy 184.504064 -284.166946)
			(xy 184.484773 -284.12167) (xy 184.472996 -284.073886) (xy 184.469036 -284.024832) (xy 183.180228 -284.024832)
			(xy 183.179733 -284.049439) (xy 183.171838 -284.098016) (xy 183.156254 -284.144697) (xy 183.133383 -284.188274)
			(xy 183.103818 -284.227618) (xy 183.068325 -284.26171) (xy 183.027822 -284.289666) (xy 182.98336 -284.310764)
			(xy 182.936089 -284.324456) (xy 182.887234 -284.330388) (xy 182.838059 -284.328407) (xy 182.78984 -284.318563)
			(xy 182.743824 -284.301111) (xy 182.701203 -284.276504) (xy 182.663082 -284.245379) (xy 182.630447 -284.208542)
			(xy 182.604144 -284.166946) (xy 182.584853 -284.12167) (xy 182.573076 -284.073886) (xy 182.569116 -284.024832)
			(xy 182.230268 -284.024832) (xy 182.229773 -284.049439) (xy 182.221878 -284.098016) (xy 182.206294 -284.144697)
			(xy 182.183423 -284.188274) (xy 182.153858 -284.227618) (xy 182.118365 -284.26171) (xy 182.077862 -284.289666)
			(xy 182.0334 -284.310764) (xy 181.986129 -284.324456) (xy 181.937274 -284.330388) (xy 181.888099 -284.328407)
			(xy 181.83988 -284.318563) (xy 181.793864 -284.301111) (xy 181.751243 -284.276504) (xy 181.713122 -284.245379)
			(xy 181.680487 -284.208542) (xy 181.654184 -284.166946) (xy 181.634893 -284.12167) (xy 181.623116 -284.073886)
			(xy 181.619156 -284.024832) (xy 181.280308 -284.024832) (xy 181.279813 -284.049439) (xy 181.271918 -284.098016)
			(xy 181.256334 -284.144697) (xy 181.233463 -284.188274) (xy 181.203898 -284.227618) (xy 181.168405 -284.26171)
			(xy 181.127902 -284.289666) (xy 181.08344 -284.310764) (xy 181.036169 -284.324456) (xy 180.987314 -284.330388)
			(xy 180.938139 -284.328407) (xy 180.88992 -284.318563) (xy 180.843904 -284.301111) (xy 180.801283 -284.276504)
			(xy 180.763162 -284.245379) (xy 180.730527 -284.208542) (xy 180.704224 -284.166946) (xy 180.684933 -284.12167)
			(xy 180.673156 -284.073886) (xy 180.669196 -284.024832) (xy 180.330348 -284.024832) (xy 180.329853 -284.049439)
			(xy 180.321958 -284.098016) (xy 180.306374 -284.144697) (xy 180.283503 -284.188274) (xy 180.253938 -284.227618)
			(xy 180.218445 -284.26171) (xy 180.177942 -284.289666) (xy 180.13348 -284.310764) (xy 180.086209 -284.324456)
			(xy 180.037354 -284.330388) (xy 179.988179 -284.328407) (xy 179.93996 -284.318563) (xy 179.893944 -284.301111)
			(xy 179.851323 -284.276504) (xy 179.813202 -284.245379) (xy 179.780567 -284.208542) (xy 179.754264 -284.166946)
			(xy 179.734973 -284.12167) (xy 179.723196 -284.073886) (xy 179.719236 -284.024832) (xy 179.380388 -284.024832)
			(xy 179.379893 -284.049439) (xy 179.371998 -284.098016) (xy 179.356414 -284.144697) (xy 179.333543 -284.188274)
			(xy 179.303978 -284.227618) (xy 179.268485 -284.26171) (xy 179.227982 -284.289666) (xy 179.18352 -284.310764)
			(xy 179.136249 -284.324456) (xy 179.087394 -284.330388) (xy 179.038219 -284.328407) (xy 178.99 -284.318563)
			(xy 178.943984 -284.301111) (xy 178.901363 -284.276504) (xy 178.863242 -284.245379) (xy 178.830607 -284.208542)
			(xy 178.804304 -284.166946) (xy 178.785013 -284.12167) (xy 178.773236 -284.073886) (xy 178.769276 -284.024832)
			(xy 178.430174 -284.024832) (xy 178.429679 -284.049439) (xy 178.421784 -284.098016) (xy 178.4062 -284.144697)
			(xy 178.383329 -284.188274) (xy 178.353764 -284.227618) (xy 178.318271 -284.26171) (xy 178.277768 -284.289666)
			(xy 178.233306 -284.310764) (xy 178.186035 -284.324456) (xy 178.13718 -284.330388) (xy 178.088005 -284.328407)
			(xy 178.039786 -284.318563) (xy 177.99377 -284.301111) (xy 177.951149 -284.276504) (xy 177.913028 -284.245379)
			(xy 177.880393 -284.208542) (xy 177.85409 -284.166946) (xy 177.834799 -284.12167) (xy 177.823022 -284.073886)
			(xy 177.819062 -284.024832) (xy 177.480214 -284.024832) (xy 177.479719 -284.049439) (xy 177.471824 -284.098016)
			(xy 177.45624 -284.144697) (xy 177.433369 -284.188274) (xy 177.403804 -284.227618) (xy 177.368311 -284.26171)
			(xy 177.327808 -284.289666) (xy 177.283346 -284.310764) (xy 177.236075 -284.324456) (xy 177.18722 -284.330388)
			(xy 177.138045 -284.328407) (xy 177.089826 -284.318563) (xy 177.04381 -284.301111) (xy 177.001189 -284.276504)
			(xy 176.963068 -284.245379) (xy 176.930433 -284.208542) (xy 176.90413 -284.166946) (xy 176.884839 -284.12167)
			(xy 176.873062 -284.073886) (xy 176.869102 -284.024832) (xy 176.530254 -284.024832) (xy 176.529759 -284.049439)
			(xy 176.521864 -284.098016) (xy 176.50628 -284.144697) (xy 176.483409 -284.188274) (xy 176.453844 -284.227618)
			(xy 176.418351 -284.26171) (xy 176.377848 -284.289666) (xy 176.333386 -284.310764) (xy 176.286115 -284.324456)
			(xy 176.23726 -284.330388) (xy 176.188085 -284.328407) (xy 176.139866 -284.318563) (xy 176.09385 -284.301111)
			(xy 176.051229 -284.276504) (xy 176.013108 -284.245379) (xy 175.980473 -284.208542) (xy 175.95417 -284.166946)
			(xy 175.934879 -284.12167) (xy 175.923102 -284.073886) (xy 175.919142 -284.024832) (xy 174.630334 -284.024832)
			(xy 174.629839 -284.049439) (xy 174.621944 -284.098016) (xy 174.60636 -284.144697) (xy 174.583489 -284.188274)
			(xy 174.553924 -284.227618) (xy 174.518431 -284.26171) (xy 174.477928 -284.289666) (xy 174.433466 -284.310764)
			(xy 174.386195 -284.324456) (xy 174.33734 -284.330388) (xy 174.288165 -284.328407) (xy 174.239946 -284.318563)
			(xy 174.19393 -284.301111) (xy 174.151309 -284.276504) (xy 174.113188 -284.245379) (xy 174.080553 -284.208542)
			(xy 174.05425 -284.166946) (xy 174.034959 -284.12167) (xy 174.023182 -284.073886) (xy 174.019222 -284.024832)
			(xy 173.680374 -284.024832) (xy 173.679879 -284.049439) (xy 173.671984 -284.098016) (xy 173.6564 -284.144697)
			(xy 173.633529 -284.188274) (xy 173.603964 -284.227618) (xy 173.568471 -284.26171) (xy 173.527968 -284.289666)
			(xy 173.483506 -284.310764) (xy 173.436235 -284.324456) (xy 173.38738 -284.330388) (xy 173.338205 -284.328407)
			(xy 173.289986 -284.318563) (xy 173.24397 -284.301111) (xy 173.201349 -284.276504) (xy 173.163228 -284.245379)
			(xy 173.130593 -284.208542) (xy 173.10429 -284.166946) (xy 173.084999 -284.12167) (xy 173.073222 -284.073886)
			(xy 173.069262 -284.024832) (xy 172.73016 -284.024832) (xy 172.729665 -284.049439) (xy 172.72177 -284.098016)
			(xy 172.706186 -284.144697) (xy 172.683315 -284.188274) (xy 172.65375 -284.227618) (xy 172.618257 -284.26171)
			(xy 172.577754 -284.289666) (xy 172.533292 -284.310764) (xy 172.486021 -284.324456) (xy 172.437166 -284.330388)
			(xy 172.387991 -284.328407) (xy 172.339772 -284.318563) (xy 172.293756 -284.301111) (xy 172.251135 -284.276504)
			(xy 172.213014 -284.245379) (xy 172.180379 -284.208542) (xy 172.154076 -284.166946) (xy 172.134785 -284.12167)
			(xy 172.123008 -284.073886) (xy 172.119048 -284.024832) (xy 171.7802 -284.024832) (xy 171.779705 -284.049439)
			(xy 171.77181 -284.098016) (xy 171.756226 -284.144697) (xy 171.733355 -284.188274) (xy 171.70379 -284.227618)
			(xy 171.668297 -284.26171) (xy 171.627794 -284.289666) (xy 171.583332 -284.310764) (xy 171.536061 -284.324456)
			(xy 171.487206 -284.330388) (xy 171.438031 -284.328407) (xy 171.389812 -284.318563) (xy 171.343796 -284.301111)
			(xy 171.301175 -284.276504) (xy 171.263054 -284.245379) (xy 171.230419 -284.208542) (xy 171.204116 -284.166946)
			(xy 171.184825 -284.12167) (xy 171.173048 -284.073886) (xy 171.169088 -284.024832) (xy 170.83024 -284.024832)
			(xy 170.829745 -284.049439) (xy 170.82185 -284.098016) (xy 170.806266 -284.144697) (xy 170.783395 -284.188274)
			(xy 170.75383 -284.227618) (xy 170.718337 -284.26171) (xy 170.677834 -284.289666) (xy 170.633372 -284.310764)
			(xy 170.586101 -284.324456) (xy 170.537246 -284.330388) (xy 170.488071 -284.328407) (xy 170.439852 -284.318563)
			(xy 170.393836 -284.301111) (xy 170.351215 -284.276504) (xy 170.313094 -284.245379) (xy 170.280459 -284.208542)
			(xy 170.254156 -284.166946) (xy 170.234865 -284.12167) (xy 170.223088 -284.073886) (xy 170.219128 -284.024832)
			(xy 169.88028 -284.024832) (xy 169.879785 -284.049439) (xy 169.87189 -284.098016) (xy 169.856306 -284.144697)
			(xy 169.833435 -284.188274) (xy 169.80387 -284.227618) (xy 169.768377 -284.26171) (xy 169.727874 -284.289666)
			(xy 169.683412 -284.310764) (xy 169.636141 -284.324456) (xy 169.587286 -284.330388) (xy 169.538111 -284.328407)
			(xy 169.489892 -284.318563) (xy 169.443876 -284.301111) (xy 169.401255 -284.276504) (xy 169.363134 -284.245379)
			(xy 169.330499 -284.208542) (xy 169.304196 -284.166946) (xy 169.284905 -284.12167) (xy 169.273128 -284.073886)
			(xy 169.269168 -284.024832) (xy 168.93032 -284.024832) (xy 168.929825 -284.049439) (xy 168.92193 -284.098016)
			(xy 168.906346 -284.144697) (xy 168.883475 -284.188274) (xy 168.85391 -284.227618) (xy 168.818417 -284.26171)
			(xy 168.777914 -284.289666) (xy 168.733452 -284.310764) (xy 168.686181 -284.324456) (xy 168.637326 -284.330388)
			(xy 168.588151 -284.328407) (xy 168.539932 -284.318563) (xy 168.493916 -284.301111) (xy 168.451295 -284.276504)
			(xy 168.413174 -284.245379) (xy 168.380539 -284.208542) (xy 168.354236 -284.166946) (xy 168.334945 -284.12167)
			(xy 168.323168 -284.073886) (xy 168.319208 -284.024832) (xy 167.98036 -284.024832) (xy 167.979865 -284.049439)
			(xy 167.97197 -284.098016) (xy 167.956386 -284.144697) (xy 167.933515 -284.188274) (xy 167.90395 -284.227618)
			(xy 167.868457 -284.26171) (xy 167.827954 -284.289666) (xy 167.783492 -284.310764) (xy 167.736221 -284.324456)
			(xy 167.687366 -284.330388) (xy 167.638191 -284.328407) (xy 167.589972 -284.318563) (xy 167.543956 -284.301111)
			(xy 167.501335 -284.276504) (xy 167.463214 -284.245379) (xy 167.430579 -284.208542) (xy 167.404276 -284.166946)
			(xy 167.384985 -284.12167) (xy 167.373208 -284.073886) (xy 167.369248 -284.024832) (xy 167.0304 -284.024832)
			(xy 167.029905 -284.049439) (xy 167.02201 -284.098016) (xy 167.006426 -284.144697) (xy 166.983555 -284.188274)
			(xy 166.95399 -284.227618) (xy 166.918497 -284.26171) (xy 166.877994 -284.289666) (xy 166.833532 -284.310764)
			(xy 166.786261 -284.324456) (xy 166.737406 -284.330388) (xy 166.688231 -284.328407) (xy 166.640012 -284.318563)
			(xy 166.593996 -284.301111) (xy 166.551375 -284.276504) (xy 166.513254 -284.245379) (xy 166.480619 -284.208542)
			(xy 166.454316 -284.166946) (xy 166.435025 -284.12167) (xy 166.423248 -284.073886) (xy 166.419288 -284.024832)
			(xy 166.080186 -284.024832) (xy 166.079691 -284.049439) (xy 166.071796 -284.098016) (xy 166.056212 -284.144697)
			(xy 166.033341 -284.188274) (xy 166.003776 -284.227618) (xy 165.968283 -284.26171) (xy 165.92778 -284.289666)
			(xy 165.883318 -284.310764) (xy 165.836047 -284.324456) (xy 165.787192 -284.330388) (xy 165.738017 -284.328407)
			(xy 165.689798 -284.318563) (xy 165.643782 -284.301111) (xy 165.601161 -284.276504) (xy 165.56304 -284.245379)
			(xy 165.530405 -284.208542) (xy 165.504102 -284.166946) (xy 165.484811 -284.12167) (xy 165.473034 -284.073886)
			(xy 165.469074 -284.024832) (xy 165.130226 -284.024832) (xy 165.129731 -284.049439) (xy 165.121836 -284.098016)
			(xy 165.106252 -284.144697) (xy 165.083381 -284.188274) (xy 165.053816 -284.227618) (xy 165.018323 -284.26171)
			(xy 164.97782 -284.289666) (xy 164.933358 -284.310764) (xy 164.886087 -284.324456) (xy 164.837232 -284.330388)
			(xy 164.788057 -284.328407) (xy 164.739838 -284.318563) (xy 164.693822 -284.301111) (xy 164.651201 -284.276504)
			(xy 164.61308 -284.245379) (xy 164.580445 -284.208542) (xy 164.554142 -284.166946) (xy 164.534851 -284.12167)
			(xy 164.523074 -284.073886) (xy 164.519114 -284.024832) (xy 164.353748 -284.024832) (xy 164.353748 -284.499812)
			(xy 189.69407 -284.499812) (xy 189.69803 -284.450758) (xy 189.709807 -284.402974) (xy 189.729098 -284.357698)
			(xy 189.755401 -284.316102) (xy 189.788036 -284.279265) (xy 189.826157 -284.24814) (xy 189.868778 -284.223533)
			(xy 189.914794 -284.206081) (xy 189.963013 -284.196237) (xy 190.012188 -284.194256) (xy 190.061043 -284.200188)
			(xy 190.108314 -284.21388) (xy 190.152776 -284.234978) (xy 190.193279 -284.262934) (xy 190.228772 -284.297026)
			(xy 190.258337 -284.33637) (xy 190.281208 -284.379947) (xy 190.296792 -284.426628) (xy 190.304687 -284.475205)
			(xy 190.305182 -284.499812) (xy 190.64403 -284.499812) (xy 190.64799 -284.450758) (xy 190.659767 -284.402974)
			(xy 190.679058 -284.357698) (xy 190.705361 -284.316102) (xy 190.737996 -284.279265) (xy 190.776117 -284.24814)
			(xy 190.818738 -284.223533) (xy 190.864754 -284.206081) (xy 190.912973 -284.196237) (xy 190.962148 -284.194256)
			(xy 191.011003 -284.200188) (xy 191.058274 -284.21388) (xy 191.102736 -284.234978) (xy 191.143239 -284.262934)
			(xy 191.178732 -284.297026) (xy 191.208297 -284.33637) (xy 191.231168 -284.379947) (xy 191.246752 -284.426628)
			(xy 191.254647 -284.475205) (xy 191.255142 -284.499812) (xy 191.594244 -284.499812) (xy 191.598204 -284.450758)
			(xy 191.609981 -284.402974) (xy 191.629272 -284.357698) (xy 191.655575 -284.316102) (xy 191.68821 -284.279265)
			(xy 191.726331 -284.24814) (xy 191.768952 -284.223533) (xy 191.814968 -284.206081) (xy 191.863187 -284.196237)
			(xy 191.912362 -284.194256) (xy 191.961217 -284.200188) (xy 192.008488 -284.21388) (xy 192.05295 -284.234978)
			(xy 192.093453 -284.262934) (xy 192.128946 -284.297026) (xy 192.158511 -284.33637) (xy 192.181382 -284.379947)
			(xy 192.196966 -284.426628) (xy 192.204861 -284.475205) (xy 192.205356 -284.499812) (xy 192.544204 -284.499812)
			(xy 192.548164 -284.450758) (xy 192.559941 -284.402974) (xy 192.579232 -284.357698) (xy 192.605535 -284.316102)
			(xy 192.63817 -284.279265) (xy 192.676291 -284.24814) (xy 192.718912 -284.223533) (xy 192.764928 -284.206081)
			(xy 192.813147 -284.196237) (xy 192.862322 -284.194256) (xy 192.911177 -284.200188) (xy 192.958448 -284.21388)
			(xy 193.00291 -284.234978) (xy 193.043413 -284.262934) (xy 193.078906 -284.297026) (xy 193.108471 -284.33637)
			(xy 193.131342 -284.379947) (xy 193.146926 -284.426628) (xy 193.154821 -284.475205) (xy 193.155316 -284.499812)
			(xy 193.494164 -284.499812) (xy 193.498124 -284.450758) (xy 193.509901 -284.402974) (xy 193.529192 -284.357698)
			(xy 193.555495 -284.316102) (xy 193.58813 -284.279265) (xy 193.626251 -284.24814) (xy 193.668872 -284.223533)
			(xy 193.714888 -284.206081) (xy 193.763107 -284.196237) (xy 193.812282 -284.194256) (xy 193.861137 -284.200188)
			(xy 193.908408 -284.21388) (xy 193.95287 -284.234978) (xy 193.993373 -284.262934) (xy 194.028866 -284.297026)
			(xy 194.058431 -284.33637) (xy 194.081302 -284.379947) (xy 194.096886 -284.426628) (xy 194.104781 -284.475205)
			(xy 194.105276 -284.499812) (xy 194.444124 -284.499812) (xy 194.448084 -284.450758) (xy 194.459861 -284.402974)
			(xy 194.479152 -284.357698) (xy 194.505455 -284.316102) (xy 194.53809 -284.279265) (xy 194.576211 -284.24814)
			(xy 194.618832 -284.223533) (xy 194.664848 -284.206081) (xy 194.713067 -284.196237) (xy 194.762242 -284.194256)
			(xy 194.811097 -284.200188) (xy 194.858368 -284.21388) (xy 194.90283 -284.234978) (xy 194.943333 -284.262934)
			(xy 194.978826 -284.297026) (xy 195.008391 -284.33637) (xy 195.031262 -284.379947) (xy 195.046846 -284.426628)
			(xy 195.054741 -284.475205) (xy 195.055236 -284.499812) (xy 195.054741 -284.524419) (xy 195.054562 -284.52552)
			(xy 195.37324 -284.52552) (xy 195.37324 -284.474104) (xy 195.381283 -284.423322) (xy 195.397171 -284.374423)
			(xy 195.420514 -284.328611) (xy 195.450735 -284.287015) (xy 195.487091 -284.250659) (xy 195.528687 -284.220438)
			(xy 195.574499 -284.197095) (xy 195.623398 -284.181207) (xy 195.67418 -284.173164) (xy 195.725596 -284.173164)
			(xy 195.776378 -284.181207) (xy 195.825277 -284.197095) (xy 195.871089 -284.220438) (xy 195.912685 -284.250659)
			(xy 195.949041 -284.287015) (xy 195.979262 -284.328611) (xy 196.002605 -284.374423) (xy 196.018493 -284.423322)
			(xy 196.026536 -284.474104) (xy 196.02704 -284.499812) (xy 196.026536 -284.52552) (xy 196.3232 -284.52552)
			(xy 196.3232 -284.474104) (xy 196.331243 -284.423322) (xy 196.347131 -284.374423) (xy 196.370474 -284.328611)
			(xy 196.400695 -284.287015) (xy 196.437051 -284.250659) (xy 196.478647 -284.220438) (xy 196.524459 -284.197095)
			(xy 196.573358 -284.181207) (xy 196.62414 -284.173164) (xy 196.675556 -284.173164) (xy 196.726338 -284.181207)
			(xy 196.775237 -284.197095) (xy 196.821049 -284.220438) (xy 196.862645 -284.250659) (xy 196.899001 -284.287015)
			(xy 196.929222 -284.328611) (xy 196.952565 -284.374423) (xy 196.968453 -284.423322) (xy 196.976496 -284.474104)
			(xy 196.977 -284.499812) (xy 197.294258 -284.499812) (xy 197.298218 -284.450758) (xy 197.309995 -284.402974)
			(xy 197.329286 -284.357698) (xy 197.355589 -284.316102) (xy 197.388224 -284.279265) (xy 197.426345 -284.24814)
			(xy 197.468966 -284.223533) (xy 197.514982 -284.206081) (xy 197.563201 -284.196237) (xy 197.612376 -284.194256)
			(xy 197.661231 -284.200188) (xy 197.708502 -284.21388) (xy 197.752964 -284.234978) (xy 197.793467 -284.262934)
			(xy 197.82896 -284.297026) (xy 197.858525 -284.33637) (xy 197.881396 -284.379947) (xy 197.89698 -284.426628)
			(xy 197.904875 -284.475205) (xy 197.90537 -284.499812) (xy 198.244218 -284.499812) (xy 198.248178 -284.450758)
			(xy 198.259955 -284.402974) (xy 198.279246 -284.357698) (xy 198.305549 -284.316102) (xy 198.338184 -284.279265)
			(xy 198.376305 -284.24814) (xy 198.418926 -284.223533) (xy 198.464942 -284.206081) (xy 198.513161 -284.196237)
			(xy 198.562336 -284.194256) (xy 198.611191 -284.200188) (xy 198.658462 -284.21388) (xy 198.702924 -284.234978)
			(xy 198.743427 -284.262934) (xy 198.77892 -284.297026) (xy 198.808485 -284.33637) (xy 198.831356 -284.379947)
			(xy 198.84694 -284.426628) (xy 198.854835 -284.475205) (xy 198.85533 -284.499812) (xy 198.854835 -284.524419)
			(xy 198.84694 -284.572996) (xy 198.831356 -284.619677) (xy 198.824812 -284.632146) (xy 210.027772 -284.632146)
			(xy 210.031843 -284.576524) (xy 210.043969 -284.522087) (xy 210.063892 -284.469996) (xy 210.091188 -284.421361)
			(xy 210.125274 -284.377218) (xy 210.165423 -284.338509) (xy 210.210781 -284.306058) (xy 210.260381 -284.280557)
			(xy 210.313165 -284.26255) (xy 210.368008 -284.25242) (xy 210.423742 -284.250383) (xy 210.479179 -284.256483)
			(xy 210.533136 -284.270589) (xy 210.584465 -284.292401) (xy 210.632071 -284.321455) (xy 210.674939 -284.35713)
			(xy 210.712156 -284.398667) (xy 210.742929 -284.44518) (xy 210.766601 -284.495677) (xy 210.782669 -284.549084)
			(xy 210.790789 -284.60426) (xy 210.791298 -284.632146) (xy 210.790789 -284.660032) (xy 210.789506 -284.668747)
			(xy 216.926722 -284.668747) (xy 216.926722 -284.614253) (xy 216.934477 -284.560315) (xy 216.949829 -284.508029)
			(xy 216.972465 -284.458459) (xy 217.001925 -284.412616) (xy 217.037609 -284.371431) (xy 217.07879 -284.335744)
			(xy 217.124631 -284.30628) (xy 217.174199 -284.28364) (xy 217.226483 -284.268284) (xy 217.280421 -284.260524)
			(xy 217.307668 -284.260036) (xy 217.336408 -284.260535) (xy 217.393235 -284.269167) (xy 217.448126 -284.286223)
			(xy 217.499837 -284.31132) (xy 217.547199 -284.343888) (xy 217.568526 -284.36316) (xy 217.575638 -284.369764)
			(xy 217.593164 -284.376876) (xy 217.682572 -284.376876) (xy 217.700098 -284.369764) (xy 217.70721 -284.36316)
			(xy 217.728553 -284.343908) (xy 217.775911 -284.311338) (xy 217.827618 -284.286242) (xy 217.882505 -284.269187)
			(xy 217.93933 -284.260559) (xy 217.968068 -284.260036) (xy 217.99819 -284.260631) (xy 218.057685 -284.270107)
			(xy 218.114953 -284.288812) (xy 218.16857 -284.316282) (xy 218.217206 -284.351836) (xy 218.238832 -284.372812)
			(xy 218.245944 -284.380178) (xy 218.26474 -284.387798) (xy 218.357196 -284.387798) (xy 218.375992 -284.380178)
			(xy 218.383104 -284.372812) (xy 218.404706 -284.351807) (xy 218.453341 -284.316241) (xy 218.506963 -284.288766)
			(xy 218.564238 -284.270063) (xy 218.623742 -284.2606) (xy 218.653868 -284.260036) (xy 218.681238 -284.260512)
			(xy 218.735417 -284.268326) (xy 218.78792 -284.283812) (xy 218.837667 -284.306652) (xy 218.883634 -284.336375)
			(xy 218.904566 -284.354016) (xy 218.911678 -284.360112) (xy 218.928696 -284.366462) (xy 219.01404 -284.366462)
			(xy 219.031058 -284.360112) (xy 219.03817 -284.354016) (xy 219.059105 -284.33638) (xy 219.105076 -284.306667)
			(xy 219.154823 -284.28383) (xy 219.207324 -284.268339) (xy 219.261499 -284.26051) (xy 219.288868 -284.260036)
			(xy 219.316126 -284.260409) (xy 219.370086 -284.268163) (xy 219.422394 -284.283518) (xy 219.471984 -284.306161)
			(xy 219.517846 -284.335632) (xy 219.559048 -284.37133) (xy 219.594749 -284.412528) (xy 219.624223 -284.458388)
			(xy 219.646871 -284.507976) (xy 219.66223 -284.560283) (xy 219.669989 -284.614243) (xy 219.669989 -284.668746)
			(xy 220.945522 -284.668746) (xy 220.945522 -284.614254) (xy 220.953276 -284.560316) (xy 220.968628 -284.508031)
			(xy 220.991263 -284.458463) (xy 221.020722 -284.41262) (xy 221.056404 -284.371435) (xy 221.097584 -284.335748)
			(xy 221.143424 -284.306284) (xy 221.19299 -284.283643) (xy 221.245273 -284.268286) (xy 221.29921 -284.260525)
			(xy 221.326456 -284.260036) (xy 221.355195 -284.260543) (xy 221.412023 -284.269172) (xy 221.466913 -284.286227)
			(xy 221.518624 -284.311322) (xy 221.565987 -284.343889) (xy 221.587314 -284.36316) (xy 221.594426 -284.369764)
			(xy 221.611952 -284.376876) (xy 221.70136 -284.376876) (xy 221.718886 -284.369764) (xy 221.725998 -284.36316)
			(xy 221.747325 -284.34389) (xy 221.794688 -284.311325) (xy 221.846399 -284.286234) (xy 221.90129 -284.269184)
			(xy 221.958117 -284.260562) (xy 222.015595 -284.260562) (xy 222.072422 -284.269184) (xy 222.127313 -284.286234)
			(xy 222.179024 -284.311325) (xy 222.226387 -284.34389) (xy 222.247714 -284.36316) (xy 222.254826 -284.369764)
			(xy 222.272352 -284.376876) (xy 222.36176 -284.376876) (xy 222.379286 -284.369764) (xy 222.386398 -284.36316)
			(xy 222.407705 -284.343866) (xy 222.455072 -284.311302) (xy 222.506789 -284.286214) (xy 222.561684 -284.269169)
			(xy 222.618516 -284.260553) (xy 222.647256 -284.260036) (xy 222.677378 -284.260638) (xy 222.736873 -284.270112)
			(xy 222.79414 -284.288816) (xy 222.847758 -284.316285) (xy 222.896394 -284.351836) (xy 222.91802 -284.372812)
			(xy 222.925132 -284.380178) (xy 222.943928 -284.387798) (xy 223.036384 -284.387798) (xy 223.05518 -284.380178)
			(xy 223.062292 -284.372812) (xy 223.083899 -284.351813) (xy 223.132533 -284.316246) (xy 223.186153 -284.28877)
			(xy 223.243428 -284.270066) (xy 223.30293 -284.260601) (xy 223.333056 -284.260036) (xy 223.360314 -284.260408)
			(xy 223.414276 -284.268161) (xy 223.466585 -284.283515) (xy 223.516177 -284.306157) (xy 223.562041 -284.335628)
			(xy 223.603243 -284.371325) (xy 223.638946 -284.412524) (xy 223.668422 -284.458385) (xy 223.69107 -284.507973)
			(xy 223.70643 -284.560281) (xy 223.714189 -284.614242) (xy 223.714189 -284.668758) (xy 223.70643 -284.722719)
			(xy 223.69107 -284.775027) (xy 223.668422 -284.824615) (xy 223.638946 -284.870476) (xy 223.603243 -284.911675)
			(xy 223.562041 -284.947372) (xy 223.516177 -284.976843) (xy 223.466585 -284.999485) (xy 223.414276 -285.014839)
			(xy 223.360314 -285.022592) (xy 223.333056 -285.023052) (xy 223.302934 -285.022445) (xy 223.243439 -285.012973)
			(xy 223.186172 -284.99427) (xy 223.132554 -284.966802) (xy 223.083918 -284.931251) (xy 223.062292 -284.910276)
			(xy 223.05518 -284.90291) (xy 223.036384 -284.89529) (xy 222.943928 -284.89529) (xy 222.925132 -284.90291)
			(xy 222.91802 -284.910276) (xy 222.896406 -284.931268) (xy 222.847774 -284.966835) (xy 222.794155 -284.994314)
			(xy 222.736883 -285.013019) (xy 222.677381 -285.022486) (xy 222.647256 -285.023052) (xy 222.618517 -285.022541)
			(xy 222.561689 -285.013913) (xy 222.506799 -284.996859) (xy 222.455088 -284.971765) (xy 222.407725 -284.939199)
			(xy 222.386398 -284.919928) (xy 222.379286 -284.913324) (xy 222.36176 -284.906212) (xy 222.272352 -284.906212)
			(xy 222.254826 -284.913324) (xy 222.247714 -284.919928) (xy 222.226387 -284.939198) (xy 222.179024 -284.971763)
			(xy 222.127313 -284.996854) (xy 222.072422 -285.013904) (xy 222.015595 -285.022526) (xy 221.958117 -285.022526)
			(xy 221.90129 -285.013904) (xy 221.846399 -284.996854) (xy 221.794688 -284.971763) (xy 221.747325 -284.939198)
			(xy 221.725998 -284.919928) (xy 221.718886 -284.913324) (xy 221.70136 -284.906212) (xy 221.611952 -284.906212)
			(xy 221.594426 -284.913324) (xy 221.587314 -284.919928) (xy 221.566 -284.939214) (xy 221.518635 -284.971779)
			(xy 221.46692 -284.99687) (xy 221.412026 -285.013916) (xy 221.355196 -285.022534) (xy 221.326456 -285.023052)
			(xy 221.29921 -285.022475) (xy 221.245273 -285.014714) (xy 221.19299 -284.999357) (xy 221.143424 -284.976716)
			(xy 221.097584 -284.947252) (xy 221.056404 -284.911565) (xy 221.020722 -284.87038) (xy 220.991263 -284.824537)
			(xy 220.968628 -284.774969) (xy 220.953276 -284.722684) (xy 220.945522 -284.668746) (xy 219.669989 -284.668746)
			(xy 219.669989 -284.668757) (xy 219.66223 -284.722717) (xy 219.646871 -284.775024) (xy 219.624223 -284.824612)
			(xy 219.594749 -284.870472) (xy 219.559048 -284.91167) (xy 219.517846 -284.947368) (xy 219.471984 -284.976839)
			(xy 219.422394 -284.999482) (xy 219.370086 -285.014837) (xy 219.316126 -285.022591) (xy 219.288868 -285.023052)
			(xy 219.261497 -285.022616) (xy 219.207316 -285.014793) (xy 219.154812 -284.999297) (xy 219.105065 -284.976449)
			(xy 219.0591 -284.946717) (xy 219.03817 -284.929072) (xy 219.031058 -284.922976) (xy 219.01404 -284.916626)
			(xy 218.928696 -284.916626) (xy 218.911678 -284.922976) (xy 218.904566 -284.929072) (xy 218.883616 -284.946689)
			(xy 218.837649 -284.976405) (xy 218.787906 -284.999246) (xy 218.735409 -285.014742) (xy 218.681236 -285.022575)
			(xy 218.653868 -285.023052) (xy 218.623744 -285.022501) (xy 218.564247 -285.013015) (xy 218.506978 -284.994299)
			(xy 218.453362 -284.966819) (xy 218.404728 -284.931257) (xy 218.383104 -284.910276) (xy 218.375992 -284.90291)
			(xy 218.357196 -284.89529) (xy 218.26474 -284.89529) (xy 218.245944 -284.90291) (xy 218.238832 -284.910276)
			(xy 218.217212 -284.931262) (xy 218.168583 -284.96683) (xy 218.114965 -284.99431) (xy 218.057693 -285.013017)
			(xy 217.998193 -285.022485) (xy 217.968068 -285.023052) (xy 217.939329 -285.022534) (xy 217.882502 -285.013908)
			(xy 217.827612 -284.996856) (xy 217.7759 -284.971763) (xy 217.728537 -284.939198) (xy 217.70721 -284.919928)
			(xy 217.700098 -284.913324) (xy 217.682572 -284.906212) (xy 217.593164 -284.906212) (xy 217.575638 -284.913324)
			(xy 217.568526 -284.919928) (xy 217.547207 -284.939208) (xy 217.499843 -284.971774) (xy 217.44813 -284.996866)
			(xy 217.393237 -285.013914) (xy 217.336408 -285.022533) (xy 217.307668 -285.023052) (xy 217.280421 -285.022476)
			(xy 217.226483 -285.014716) (xy 217.174199 -284.99936) (xy 217.124631 -284.97672) (xy 217.07879 -284.947256)
			(xy 217.037609 -284.911569) (xy 217.001925 -284.870384) (xy 216.972465 -284.824541) (xy 216.949829 -284.774971)
			(xy 216.934477 -284.722685) (xy 216.926722 -284.668747) (xy 210.789506 -284.668747) (xy 210.782669 -284.715208)
			(xy 210.766601 -284.768615) (xy 210.742929 -284.819112) (xy 210.712156 -284.865625) (xy 210.674939 -284.907162)
			(xy 210.632071 -284.942837) (xy 210.584465 -284.971891) (xy 210.533136 -284.993703) (xy 210.479179 -285.007809)
			(xy 210.423742 -285.013909) (xy 210.368008 -285.011872) (xy 210.313165 -285.001742) (xy 210.260381 -284.983735)
			(xy 210.210781 -284.958234) (xy 210.165423 -284.925783) (xy 210.125274 -284.887074) (xy 210.091188 -284.842931)
			(xy 210.063892 -284.794296) (xy 210.043969 -284.742205) (xy 210.031843 -284.687768) (xy 210.027772 -284.632146)
			(xy 198.824812 -284.632146) (xy 198.808485 -284.663254) (xy 198.77892 -284.702598) (xy 198.743427 -284.73669)
			(xy 198.702924 -284.764646) (xy 198.658462 -284.785744) (xy 198.611191 -284.799436) (xy 198.562336 -284.805368)
			(xy 198.513161 -284.803387) (xy 198.464942 -284.793543) (xy 198.418926 -284.776091) (xy 198.376305 -284.751484)
			(xy 198.338184 -284.720359) (xy 198.305549 -284.683522) (xy 198.279246 -284.641926) (xy 198.259955 -284.59665)
			(xy 198.248178 -284.548866) (xy 198.244218 -284.499812) (xy 197.90537 -284.499812) (xy 197.904875 -284.524419)
			(xy 197.89698 -284.572996) (xy 197.881396 -284.619677) (xy 197.858525 -284.663254) (xy 197.82896 -284.702598)
			(xy 197.793467 -284.73669) (xy 197.752964 -284.764646) (xy 197.708502 -284.785744) (xy 197.661231 -284.799436)
			(xy 197.612376 -284.805368) (xy 197.563201 -284.803387) (xy 197.514982 -284.793543) (xy 197.468966 -284.776091)
			(xy 197.426345 -284.751484) (xy 197.388224 -284.720359) (xy 197.355589 -284.683522) (xy 197.329286 -284.641926)
			(xy 197.309995 -284.59665) (xy 197.298218 -284.548866) (xy 197.294258 -284.499812) (xy 196.977 -284.499812)
			(xy 196.976496 -284.52552) (xy 196.968453 -284.576302) (xy 196.952565 -284.625201) (xy 196.929222 -284.671013)
			(xy 196.899001 -284.712609) (xy 196.862645 -284.748965) (xy 196.821049 -284.779186) (xy 196.775237 -284.802529)
			(xy 196.726338 -284.818417) (xy 196.675556 -284.82646) (xy 196.62414 -284.82646) (xy 196.573358 -284.818417)
			(xy 196.524459 -284.802529) (xy 196.478647 -284.779186) (xy 196.437051 -284.748965) (xy 196.400695 -284.712609)
			(xy 196.370474 -284.671013) (xy 196.347131 -284.625201) (xy 196.331243 -284.576302) (xy 196.3232 -284.52552)
			(xy 196.026536 -284.52552) (xy 196.018493 -284.576302) (xy 196.002605 -284.625201) (xy 195.979262 -284.671013)
			(xy 195.949041 -284.712609) (xy 195.912685 -284.748965) (xy 195.871089 -284.779186) (xy 195.825277 -284.802529)
			(xy 195.776378 -284.818417) (xy 195.725596 -284.82646) (xy 195.67418 -284.82646) (xy 195.623398 -284.818417)
			(xy 195.574499 -284.802529) (xy 195.528687 -284.779186) (xy 195.487091 -284.748965) (xy 195.450735 -284.712609)
			(xy 195.420514 -284.671013) (xy 195.397171 -284.625201) (xy 195.381283 -284.576302) (xy 195.37324 -284.52552)
			(xy 195.054562 -284.52552) (xy 195.046846 -284.572996) (xy 195.031262 -284.619677) (xy 195.008391 -284.663254)
			(xy 194.978826 -284.702598) (xy 194.943333 -284.73669) (xy 194.90283 -284.764646) (xy 194.858368 -284.785744)
			(xy 194.811097 -284.799436) (xy 194.762242 -284.805368) (xy 194.713067 -284.803387) (xy 194.664848 -284.793543)
			(xy 194.618832 -284.776091) (xy 194.576211 -284.751484) (xy 194.53809 -284.720359) (xy 194.505455 -284.683522)
			(xy 194.479152 -284.641926) (xy 194.459861 -284.59665) (xy 194.448084 -284.548866) (xy 194.444124 -284.499812)
			(xy 194.105276 -284.499812) (xy 194.104781 -284.524419) (xy 194.096886 -284.572996) (xy 194.081302 -284.619677)
			(xy 194.058431 -284.663254) (xy 194.028866 -284.702598) (xy 193.993373 -284.73669) (xy 193.95287 -284.764646)
			(xy 193.908408 -284.785744) (xy 193.861137 -284.799436) (xy 193.812282 -284.805368) (xy 193.763107 -284.803387)
			(xy 193.714888 -284.793543) (xy 193.668872 -284.776091) (xy 193.626251 -284.751484) (xy 193.58813 -284.720359)
			(xy 193.555495 -284.683522) (xy 193.529192 -284.641926) (xy 193.509901 -284.59665) (xy 193.498124 -284.548866)
			(xy 193.494164 -284.499812) (xy 193.155316 -284.499812) (xy 193.154821 -284.524419) (xy 193.146926 -284.572996)
			(xy 193.131342 -284.619677) (xy 193.108471 -284.663254) (xy 193.078906 -284.702598) (xy 193.043413 -284.73669)
			(xy 193.00291 -284.764646) (xy 192.958448 -284.785744) (xy 192.911177 -284.799436) (xy 192.862322 -284.805368)
			(xy 192.813147 -284.803387) (xy 192.764928 -284.793543) (xy 192.718912 -284.776091) (xy 192.676291 -284.751484)
			(xy 192.63817 -284.720359) (xy 192.605535 -284.683522) (xy 192.579232 -284.641926) (xy 192.559941 -284.59665)
			(xy 192.548164 -284.548866) (xy 192.544204 -284.499812) (xy 192.205356 -284.499812) (xy 192.204861 -284.524419)
			(xy 192.196966 -284.572996) (xy 192.181382 -284.619677) (xy 192.158511 -284.663254) (xy 192.128946 -284.702598)
			(xy 192.093453 -284.73669) (xy 192.05295 -284.764646) (xy 192.008488 -284.785744) (xy 191.961217 -284.799436)
			(xy 191.912362 -284.805368) (xy 191.863187 -284.803387) (xy 191.814968 -284.793543) (xy 191.768952 -284.776091)
			(xy 191.726331 -284.751484) (xy 191.68821 -284.720359) (xy 191.655575 -284.683522) (xy 191.629272 -284.641926)
			(xy 191.609981 -284.59665) (xy 191.598204 -284.548866) (xy 191.594244 -284.499812) (xy 191.255142 -284.499812)
			(xy 191.254647 -284.524419) (xy 191.246752 -284.572996) (xy 191.231168 -284.619677) (xy 191.208297 -284.663254)
			(xy 191.178732 -284.702598) (xy 191.143239 -284.73669) (xy 191.102736 -284.764646) (xy 191.058274 -284.785744)
			(xy 191.011003 -284.799436) (xy 190.962148 -284.805368) (xy 190.912973 -284.803387) (xy 190.864754 -284.793543)
			(xy 190.818738 -284.776091) (xy 190.776117 -284.751484) (xy 190.737996 -284.720359) (xy 190.705361 -284.683522)
			(xy 190.679058 -284.641926) (xy 190.659767 -284.59665) (xy 190.64799 -284.548866) (xy 190.64403 -284.499812)
			(xy 190.305182 -284.499812) (xy 190.304687 -284.524419) (xy 190.296792 -284.572996) (xy 190.281208 -284.619677)
			(xy 190.258337 -284.663254) (xy 190.228772 -284.702598) (xy 190.193279 -284.73669) (xy 190.152776 -284.764646)
			(xy 190.108314 -284.785744) (xy 190.061043 -284.799436) (xy 190.012188 -284.805368) (xy 189.963013 -284.803387)
			(xy 189.914794 -284.793543) (xy 189.868778 -284.776091) (xy 189.826157 -284.751484) (xy 189.788036 -284.720359)
			(xy 189.755401 -284.683522) (xy 189.729098 -284.641926) (xy 189.709807 -284.59665) (xy 189.69803 -284.548866)
			(xy 189.69407 -284.499812) (xy 164.353748 -284.499812) (xy 164.353748 -284.974792) (xy 164.519114 -284.974792)
			(xy 164.523074 -284.925738) (xy 164.534851 -284.877954) (xy 164.554142 -284.832678) (xy 164.580445 -284.791082)
			(xy 164.61308 -284.754245) (xy 164.651201 -284.72312) (xy 164.693822 -284.698513) (xy 164.739838 -284.681061)
			(xy 164.788057 -284.671217) (xy 164.837232 -284.669236) (xy 164.886087 -284.675168) (xy 164.933358 -284.68886)
			(xy 164.97782 -284.709958) (xy 165.018323 -284.737914) (xy 165.053816 -284.772006) (xy 165.083381 -284.81135)
			(xy 165.106252 -284.854927) (xy 165.121836 -284.901608) (xy 165.129731 -284.950185) (xy 165.130226 -284.974792)
			(xy 165.469074 -284.974792) (xy 165.473034 -284.925738) (xy 165.484811 -284.877954) (xy 165.504102 -284.832678)
			(xy 165.530405 -284.791082) (xy 165.56304 -284.754245) (xy 165.601161 -284.72312) (xy 165.643782 -284.698513)
			(xy 165.689798 -284.681061) (xy 165.738017 -284.671217) (xy 165.787192 -284.669236) (xy 165.836047 -284.675168)
			(xy 165.883318 -284.68886) (xy 165.92778 -284.709958) (xy 165.968283 -284.737914) (xy 166.003776 -284.772006)
			(xy 166.033341 -284.81135) (xy 166.056212 -284.854927) (xy 166.071796 -284.901608) (xy 166.079691 -284.950185)
			(xy 166.080186 -284.974792) (xy 166.419288 -284.974792) (xy 166.423248 -284.925738) (xy 166.435025 -284.877954)
			(xy 166.454316 -284.832678) (xy 166.480619 -284.791082) (xy 166.513254 -284.754245) (xy 166.551375 -284.72312)
			(xy 166.593996 -284.698513) (xy 166.640012 -284.681061) (xy 166.688231 -284.671217) (xy 166.737406 -284.669236)
			(xy 166.786261 -284.675168) (xy 166.833532 -284.68886) (xy 166.877994 -284.709958) (xy 166.918497 -284.737914)
			(xy 166.95399 -284.772006) (xy 166.983555 -284.81135) (xy 167.006426 -284.854927) (xy 167.02201 -284.901608)
			(xy 167.029905 -284.950185) (xy 167.0304 -284.974792) (xy 167.369248 -284.974792) (xy 167.373208 -284.925738)
			(xy 167.384985 -284.877954) (xy 167.404276 -284.832678) (xy 167.430579 -284.791082) (xy 167.463214 -284.754245)
			(xy 167.501335 -284.72312) (xy 167.543956 -284.698513) (xy 167.589972 -284.681061) (xy 167.638191 -284.671217)
			(xy 167.687366 -284.669236) (xy 167.736221 -284.675168) (xy 167.783492 -284.68886) (xy 167.827954 -284.709958)
			(xy 167.868457 -284.737914) (xy 167.90395 -284.772006) (xy 167.933515 -284.81135) (xy 167.956386 -284.854927)
			(xy 167.97197 -284.901608) (xy 167.979865 -284.950185) (xy 167.98036 -284.974792) (xy 168.319208 -284.974792)
			(xy 168.323168 -284.925738) (xy 168.334945 -284.877954) (xy 168.354236 -284.832678) (xy 168.380539 -284.791082)
			(xy 168.413174 -284.754245) (xy 168.451295 -284.72312) (xy 168.493916 -284.698513) (xy 168.539932 -284.681061)
			(xy 168.588151 -284.671217) (xy 168.637326 -284.669236) (xy 168.686181 -284.675168) (xy 168.733452 -284.68886)
			(xy 168.777914 -284.709958) (xy 168.818417 -284.737914) (xy 168.85391 -284.772006) (xy 168.883475 -284.81135)
			(xy 168.906346 -284.854927) (xy 168.92193 -284.901608) (xy 168.929825 -284.950185) (xy 168.93032 -284.974792)
			(xy 169.269168 -284.974792) (xy 169.273128 -284.925738) (xy 169.284905 -284.877954) (xy 169.304196 -284.832678)
			(xy 169.330499 -284.791082) (xy 169.363134 -284.754245) (xy 169.401255 -284.72312) (xy 169.443876 -284.698513)
			(xy 169.489892 -284.681061) (xy 169.538111 -284.671217) (xy 169.587286 -284.669236) (xy 169.636141 -284.675168)
			(xy 169.683412 -284.68886) (xy 169.727874 -284.709958) (xy 169.768377 -284.737914) (xy 169.80387 -284.772006)
			(xy 169.833435 -284.81135) (xy 169.856306 -284.854927) (xy 169.87189 -284.901608) (xy 169.879785 -284.950185)
			(xy 169.88028 -284.974792) (xy 170.219128 -284.974792) (xy 170.223088 -284.925738) (xy 170.234865 -284.877954)
			(xy 170.254156 -284.832678) (xy 170.280459 -284.791082) (xy 170.313094 -284.754245) (xy 170.351215 -284.72312)
			(xy 170.393836 -284.698513) (xy 170.439852 -284.681061) (xy 170.488071 -284.671217) (xy 170.537246 -284.669236)
			(xy 170.586101 -284.675168) (xy 170.633372 -284.68886) (xy 170.677834 -284.709958) (xy 170.718337 -284.737914)
			(xy 170.75383 -284.772006) (xy 170.783395 -284.81135) (xy 170.806266 -284.854927) (xy 170.82185 -284.901608)
			(xy 170.829745 -284.950185) (xy 170.83024 -284.974792) (xy 171.169088 -284.974792) (xy 171.173048 -284.925738)
			(xy 171.184825 -284.877954) (xy 171.204116 -284.832678) (xy 171.230419 -284.791082) (xy 171.263054 -284.754245)
			(xy 171.301175 -284.72312) (xy 171.343796 -284.698513) (xy 171.389812 -284.681061) (xy 171.438031 -284.671217)
			(xy 171.487206 -284.669236) (xy 171.536061 -284.675168) (xy 171.583332 -284.68886) (xy 171.627794 -284.709958)
			(xy 171.668297 -284.737914) (xy 171.70379 -284.772006) (xy 171.733355 -284.81135) (xy 171.756226 -284.854927)
			(xy 171.77181 -284.901608) (xy 171.779705 -284.950185) (xy 171.7802 -284.974792) (xy 172.119048 -284.974792)
			(xy 172.123008 -284.925738) (xy 172.134785 -284.877954) (xy 172.154076 -284.832678) (xy 172.180379 -284.791082)
			(xy 172.213014 -284.754245) (xy 172.251135 -284.72312) (xy 172.293756 -284.698513) (xy 172.339772 -284.681061)
			(xy 172.387991 -284.671217) (xy 172.437166 -284.669236) (xy 172.486021 -284.675168) (xy 172.533292 -284.68886)
			(xy 172.577754 -284.709958) (xy 172.618257 -284.737914) (xy 172.65375 -284.772006) (xy 172.683315 -284.81135)
			(xy 172.706186 -284.854927) (xy 172.72177 -284.901608) (xy 172.729665 -284.950185) (xy 172.73016 -284.974792)
			(xy 173.069262 -284.974792) (xy 173.073222 -284.925738) (xy 173.084999 -284.877954) (xy 173.10429 -284.832678)
			(xy 173.130593 -284.791082) (xy 173.163228 -284.754245) (xy 173.201349 -284.72312) (xy 173.24397 -284.698513)
			(xy 173.289986 -284.681061) (xy 173.338205 -284.671217) (xy 173.38738 -284.669236) (xy 173.436235 -284.675168)
			(xy 173.483506 -284.68886) (xy 173.527968 -284.709958) (xy 173.568471 -284.737914) (xy 173.603964 -284.772006)
			(xy 173.633529 -284.81135) (xy 173.6564 -284.854927) (xy 173.671984 -284.901608) (xy 173.679879 -284.950185)
			(xy 173.680374 -284.974792) (xy 174.019222 -284.974792) (xy 174.023182 -284.925738) (xy 174.034959 -284.877954)
			(xy 174.05425 -284.832678) (xy 174.080553 -284.791082) (xy 174.113188 -284.754245) (xy 174.151309 -284.72312)
			(xy 174.19393 -284.698513) (xy 174.239946 -284.681061) (xy 174.288165 -284.671217) (xy 174.33734 -284.669236)
			(xy 174.386195 -284.675168) (xy 174.433466 -284.68886) (xy 174.477928 -284.709958) (xy 174.518431 -284.737914)
			(xy 174.553924 -284.772006) (xy 174.583489 -284.81135) (xy 174.60636 -284.854927) (xy 174.621944 -284.901608)
			(xy 174.629839 -284.950185) (xy 174.630334 -284.974792) (xy 175.919142 -284.974792) (xy 175.923102 -284.925738)
			(xy 175.934879 -284.877954) (xy 175.95417 -284.832678) (xy 175.980473 -284.791082) (xy 176.013108 -284.754245)
			(xy 176.051229 -284.72312) (xy 176.09385 -284.698513) (xy 176.139866 -284.681061) (xy 176.188085 -284.671217)
			(xy 176.23726 -284.669236) (xy 176.286115 -284.675168) (xy 176.333386 -284.68886) (xy 176.377848 -284.709958)
			(xy 176.418351 -284.737914) (xy 176.453844 -284.772006) (xy 176.483409 -284.81135) (xy 176.50628 -284.854927)
			(xy 176.521864 -284.901608) (xy 176.529759 -284.950185) (xy 176.530254 -284.974792) (xy 176.869102 -284.974792)
			(xy 176.873062 -284.925738) (xy 176.884839 -284.877954) (xy 176.90413 -284.832678) (xy 176.930433 -284.791082)
			(xy 176.963068 -284.754245) (xy 177.001189 -284.72312) (xy 177.04381 -284.698513) (xy 177.089826 -284.681061)
			(xy 177.138045 -284.671217) (xy 177.18722 -284.669236) (xy 177.236075 -284.675168) (xy 177.283346 -284.68886)
			(xy 177.327808 -284.709958) (xy 177.368311 -284.737914) (xy 177.403804 -284.772006) (xy 177.433369 -284.81135)
			(xy 177.45624 -284.854927) (xy 177.471824 -284.901608) (xy 177.479719 -284.950185) (xy 177.480214 -284.974792)
			(xy 177.819062 -284.974792) (xy 177.823022 -284.925738) (xy 177.834799 -284.877954) (xy 177.85409 -284.832678)
			(xy 177.880393 -284.791082) (xy 177.913028 -284.754245) (xy 177.951149 -284.72312) (xy 177.99377 -284.698513)
			(xy 178.039786 -284.681061) (xy 178.088005 -284.671217) (xy 178.13718 -284.669236) (xy 178.186035 -284.675168)
			(xy 178.233306 -284.68886) (xy 178.277768 -284.709958) (xy 178.318271 -284.737914) (xy 178.353764 -284.772006)
			(xy 178.383329 -284.81135) (xy 178.4062 -284.854927) (xy 178.421784 -284.901608) (xy 178.429679 -284.950185)
			(xy 178.430174 -284.974792) (xy 178.769276 -284.974792) (xy 178.773236 -284.925738) (xy 178.785013 -284.877954)
			(xy 178.804304 -284.832678) (xy 178.830607 -284.791082) (xy 178.863242 -284.754245) (xy 178.901363 -284.72312)
			(xy 178.943984 -284.698513) (xy 178.99 -284.681061) (xy 179.038219 -284.671217) (xy 179.087394 -284.669236)
			(xy 179.136249 -284.675168) (xy 179.18352 -284.68886) (xy 179.227982 -284.709958) (xy 179.268485 -284.737914)
			(xy 179.303978 -284.772006) (xy 179.333543 -284.81135) (xy 179.356414 -284.854927) (xy 179.371998 -284.901608)
			(xy 179.379893 -284.950185) (xy 179.380388 -284.974792) (xy 179.719236 -284.974792) (xy 179.723196 -284.925738)
			(xy 179.734973 -284.877954) (xy 179.754264 -284.832678) (xy 179.780567 -284.791082) (xy 179.813202 -284.754245)
			(xy 179.851323 -284.72312) (xy 179.893944 -284.698513) (xy 179.93996 -284.681061) (xy 179.988179 -284.671217)
			(xy 180.037354 -284.669236) (xy 180.086209 -284.675168) (xy 180.13348 -284.68886) (xy 180.177942 -284.709958)
			(xy 180.218445 -284.737914) (xy 180.253938 -284.772006) (xy 180.283503 -284.81135) (xy 180.306374 -284.854927)
			(xy 180.321958 -284.901608) (xy 180.329853 -284.950185) (xy 180.330348 -284.974792) (xy 180.669196 -284.974792)
			(xy 180.673156 -284.925738) (xy 180.684933 -284.877954) (xy 180.704224 -284.832678) (xy 180.730527 -284.791082)
			(xy 180.763162 -284.754245) (xy 180.801283 -284.72312) (xy 180.843904 -284.698513) (xy 180.88992 -284.681061)
			(xy 180.938139 -284.671217) (xy 180.987314 -284.669236) (xy 181.036169 -284.675168) (xy 181.08344 -284.68886)
			(xy 181.127902 -284.709958) (xy 181.168405 -284.737914) (xy 181.203898 -284.772006) (xy 181.233463 -284.81135)
			(xy 181.256334 -284.854927) (xy 181.271918 -284.901608) (xy 181.279813 -284.950185) (xy 181.280308 -284.974792)
			(xy 181.619156 -284.974792) (xy 181.623116 -284.925738) (xy 181.634893 -284.877954) (xy 181.654184 -284.832678)
			(xy 181.680487 -284.791082) (xy 181.713122 -284.754245) (xy 181.751243 -284.72312) (xy 181.793864 -284.698513)
			(xy 181.83988 -284.681061) (xy 181.888099 -284.671217) (xy 181.937274 -284.669236) (xy 181.986129 -284.675168)
			(xy 182.0334 -284.68886) (xy 182.077862 -284.709958) (xy 182.118365 -284.737914) (xy 182.153858 -284.772006)
			(xy 182.183423 -284.81135) (xy 182.206294 -284.854927) (xy 182.221878 -284.901608) (xy 182.229773 -284.950185)
			(xy 182.230268 -284.974792) (xy 182.569116 -284.974792) (xy 182.573076 -284.925738) (xy 182.584853 -284.877954)
			(xy 182.604144 -284.832678) (xy 182.630447 -284.791082) (xy 182.663082 -284.754245) (xy 182.701203 -284.72312)
			(xy 182.743824 -284.698513) (xy 182.78984 -284.681061) (xy 182.838059 -284.671217) (xy 182.887234 -284.669236)
			(xy 182.936089 -284.675168) (xy 182.98336 -284.68886) (xy 183.027822 -284.709958) (xy 183.068325 -284.737914)
			(xy 183.103818 -284.772006) (xy 183.133383 -284.81135) (xy 183.156254 -284.854927) (xy 183.171838 -284.901608)
			(xy 183.179733 -284.950185) (xy 183.180228 -284.974792) (xy 183.519076 -284.974792) (xy 183.523036 -284.925738)
			(xy 183.534813 -284.877954) (xy 183.554104 -284.832678) (xy 183.580407 -284.791082) (xy 183.613042 -284.754245)
			(xy 183.651163 -284.72312) (xy 183.693784 -284.698513) (xy 183.7398 -284.681061) (xy 183.788019 -284.671217)
			(xy 183.837194 -284.669236) (xy 183.886049 -284.675168) (xy 183.93332 -284.68886) (xy 183.977782 -284.709958)
			(xy 184.018285 -284.737914) (xy 184.053778 -284.772006) (xy 184.083343 -284.81135) (xy 184.106214 -284.854927)
			(xy 184.121798 -284.901608) (xy 184.129693 -284.950185) (xy 184.130188 -284.974792) (xy 184.469036 -284.974792)
			(xy 184.472996 -284.925738) (xy 184.484773 -284.877954) (xy 184.504064 -284.832678) (xy 184.530367 -284.791082)
			(xy 184.563002 -284.754245) (xy 184.601123 -284.72312) (xy 184.643744 -284.698513) (xy 184.68976 -284.681061)
			(xy 184.737979 -284.671217) (xy 184.787154 -284.669236) (xy 184.836009 -284.675168) (xy 184.88328 -284.68886)
			(xy 184.927742 -284.709958) (xy 184.968245 -284.737914) (xy 185.003738 -284.772006) (xy 185.033303 -284.81135)
			(xy 185.056174 -284.854927) (xy 185.071758 -284.901608) (xy 185.079653 -284.950185) (xy 185.080148 -284.974792)
			(xy 185.41925 -284.974792) (xy 185.42321 -284.925738) (xy 185.434987 -284.877954) (xy 185.454278 -284.832678)
			(xy 185.480581 -284.791082) (xy 185.513216 -284.754245) (xy 185.551337 -284.72312) (xy 185.593958 -284.698513)
			(xy 185.639974 -284.681061) (xy 185.688193 -284.671217) (xy 185.737368 -284.669236) (xy 185.786223 -284.675168)
			(xy 185.833494 -284.68886) (xy 185.877956 -284.709958) (xy 185.918459 -284.737914) (xy 185.953952 -284.772006)
			(xy 185.983517 -284.81135) (xy 186.006388 -284.854927) (xy 186.021972 -284.901608) (xy 186.029867 -284.950185)
			(xy 186.030362 -284.974792) (xy 186.36921 -284.974792) (xy 186.37317 -284.925738) (xy 186.384947 -284.877954)
			(xy 186.404238 -284.832678) (xy 186.430541 -284.791082) (xy 186.463176 -284.754245) (xy 186.501297 -284.72312)
			(xy 186.543918 -284.698513) (xy 186.589934 -284.681061) (xy 186.638153 -284.671217) (xy 186.687328 -284.669236)
			(xy 186.736183 -284.675168) (xy 186.783454 -284.68886) (xy 186.827916 -284.709958) (xy 186.868419 -284.737914)
			(xy 186.903912 -284.772006) (xy 186.933477 -284.81135) (xy 186.956348 -284.854927) (xy 186.971932 -284.901608)
			(xy 186.979827 -284.950185) (xy 186.980322 -284.974792) (xy 186.979827 -284.999399) (xy 186.971932 -285.047976)
			(xy 186.956348 -285.094657) (xy 186.933477 -285.138234) (xy 186.903912 -285.177578) (xy 186.868419 -285.21167)
			(xy 186.827916 -285.239626) (xy 186.783454 -285.260724) (xy 186.736183 -285.274416) (xy 186.687328 -285.280348)
			(xy 186.638153 -285.278367) (xy 186.589934 -285.268523) (xy 186.543918 -285.251071) (xy 186.501297 -285.226464)
			(xy 186.463176 -285.195339) (xy 186.430541 -285.158502) (xy 186.404238 -285.116906) (xy 186.384947 -285.07163)
			(xy 186.37317 -285.023846) (xy 186.36921 -284.974792) (xy 186.030362 -284.974792) (xy 186.029867 -284.999399)
			(xy 186.021972 -285.047976) (xy 186.006388 -285.094657) (xy 185.983517 -285.138234) (xy 185.953952 -285.177578)
			(xy 185.918459 -285.21167) (xy 185.877956 -285.239626) (xy 185.833494 -285.260724) (xy 185.786223 -285.274416)
			(xy 185.737368 -285.280348) (xy 185.688193 -285.278367) (xy 185.639974 -285.268523) (xy 185.593958 -285.251071)
			(xy 185.551337 -285.226464) (xy 185.513216 -285.195339) (xy 185.480581 -285.158502) (xy 185.454278 -285.116906)
			(xy 185.434987 -285.07163) (xy 185.42321 -285.023846) (xy 185.41925 -284.974792) (xy 185.080148 -284.974792)
			(xy 185.079653 -284.999399) (xy 185.071758 -285.047976) (xy 185.056174 -285.094657) (xy 185.033303 -285.138234)
			(xy 185.003738 -285.177578) (xy 184.968245 -285.21167) (xy 184.927742 -285.239626) (xy 184.88328 -285.260724)
			(xy 184.836009 -285.274416) (xy 184.787154 -285.280348) (xy 184.737979 -285.278367) (xy 184.68976 -285.268523)
			(xy 184.643744 -285.251071) (xy 184.601123 -285.226464) (xy 184.563002 -285.195339) (xy 184.530367 -285.158502)
			(xy 184.504064 -285.116906) (xy 184.484773 -285.07163) (xy 184.472996 -285.023846) (xy 184.469036 -284.974792)
			(xy 184.130188 -284.974792) (xy 184.129693 -284.999399) (xy 184.121798 -285.047976) (xy 184.106214 -285.094657)
			(xy 184.083343 -285.138234) (xy 184.053778 -285.177578) (xy 184.018285 -285.21167) (xy 183.977782 -285.239626)
			(xy 183.93332 -285.260724) (xy 183.886049 -285.274416) (xy 183.837194 -285.280348) (xy 183.788019 -285.278367)
			(xy 183.7398 -285.268523) (xy 183.693784 -285.251071) (xy 183.651163 -285.226464) (xy 183.613042 -285.195339)
			(xy 183.580407 -285.158502) (xy 183.554104 -285.116906) (xy 183.534813 -285.07163) (xy 183.523036 -285.023846)
			(xy 183.519076 -284.974792) (xy 183.180228 -284.974792) (xy 183.179733 -284.999399) (xy 183.171838 -285.047976)
			(xy 183.156254 -285.094657) (xy 183.133383 -285.138234) (xy 183.103818 -285.177578) (xy 183.068325 -285.21167)
			(xy 183.027822 -285.239626) (xy 182.98336 -285.260724) (xy 182.936089 -285.274416) (xy 182.887234 -285.280348)
			(xy 182.838059 -285.278367) (xy 182.78984 -285.268523) (xy 182.743824 -285.251071) (xy 182.701203 -285.226464)
			(xy 182.663082 -285.195339) (xy 182.630447 -285.158502) (xy 182.604144 -285.116906) (xy 182.584853 -285.07163)
			(xy 182.573076 -285.023846) (xy 182.569116 -284.974792) (xy 182.230268 -284.974792) (xy 182.229773 -284.999399)
			(xy 182.221878 -285.047976) (xy 182.206294 -285.094657) (xy 182.183423 -285.138234) (xy 182.153858 -285.177578)
			(xy 182.118365 -285.21167) (xy 182.077862 -285.239626) (xy 182.0334 -285.260724) (xy 181.986129 -285.274416)
			(xy 181.937274 -285.280348) (xy 181.888099 -285.278367) (xy 181.83988 -285.268523) (xy 181.793864 -285.251071)
			(xy 181.751243 -285.226464) (xy 181.713122 -285.195339) (xy 181.680487 -285.158502) (xy 181.654184 -285.116906)
			(xy 181.634893 -285.07163) (xy 181.623116 -285.023846) (xy 181.619156 -284.974792) (xy 181.280308 -284.974792)
			(xy 181.279813 -284.999399) (xy 181.271918 -285.047976) (xy 181.256334 -285.094657) (xy 181.233463 -285.138234)
			(xy 181.203898 -285.177578) (xy 181.168405 -285.21167) (xy 181.127902 -285.239626) (xy 181.08344 -285.260724)
			(xy 181.036169 -285.274416) (xy 180.987314 -285.280348) (xy 180.938139 -285.278367) (xy 180.88992 -285.268523)
			(xy 180.843904 -285.251071) (xy 180.801283 -285.226464) (xy 180.763162 -285.195339) (xy 180.730527 -285.158502)
			(xy 180.704224 -285.116906) (xy 180.684933 -285.07163) (xy 180.673156 -285.023846) (xy 180.669196 -284.974792)
			(xy 180.330348 -284.974792) (xy 180.329853 -284.999399) (xy 180.321958 -285.047976) (xy 180.306374 -285.094657)
			(xy 180.283503 -285.138234) (xy 180.253938 -285.177578) (xy 180.218445 -285.21167) (xy 180.177942 -285.239626)
			(xy 180.13348 -285.260724) (xy 180.086209 -285.274416) (xy 180.037354 -285.280348) (xy 179.988179 -285.278367)
			(xy 179.93996 -285.268523) (xy 179.893944 -285.251071) (xy 179.851323 -285.226464) (xy 179.813202 -285.195339)
			(xy 179.780567 -285.158502) (xy 179.754264 -285.116906) (xy 179.734973 -285.07163) (xy 179.723196 -285.023846)
			(xy 179.719236 -284.974792) (xy 179.380388 -284.974792) (xy 179.379893 -284.999399) (xy 179.371998 -285.047976)
			(xy 179.356414 -285.094657) (xy 179.333543 -285.138234) (xy 179.303978 -285.177578) (xy 179.268485 -285.21167)
			(xy 179.227982 -285.239626) (xy 179.18352 -285.260724) (xy 179.136249 -285.274416) (xy 179.087394 -285.280348)
			(xy 179.038219 -285.278367) (xy 178.99 -285.268523) (xy 178.943984 -285.251071) (xy 178.901363 -285.226464)
			(xy 178.863242 -285.195339) (xy 178.830607 -285.158502) (xy 178.804304 -285.116906) (xy 178.785013 -285.07163)
			(xy 178.773236 -285.023846) (xy 178.769276 -284.974792) (xy 178.430174 -284.974792) (xy 178.429679 -284.999399)
			(xy 178.421784 -285.047976) (xy 178.4062 -285.094657) (xy 178.383329 -285.138234) (xy 178.353764 -285.177578)
			(xy 178.318271 -285.21167) (xy 178.277768 -285.239626) (xy 178.233306 -285.260724) (xy 178.186035 -285.274416)
			(xy 178.13718 -285.280348) (xy 178.088005 -285.278367) (xy 178.039786 -285.268523) (xy 177.99377 -285.251071)
			(xy 177.951149 -285.226464) (xy 177.913028 -285.195339) (xy 177.880393 -285.158502) (xy 177.85409 -285.116906)
			(xy 177.834799 -285.07163) (xy 177.823022 -285.023846) (xy 177.819062 -284.974792) (xy 177.480214 -284.974792)
			(xy 177.479719 -284.999399) (xy 177.471824 -285.047976) (xy 177.45624 -285.094657) (xy 177.433369 -285.138234)
			(xy 177.403804 -285.177578) (xy 177.368311 -285.21167) (xy 177.327808 -285.239626) (xy 177.283346 -285.260724)
			(xy 177.236075 -285.274416) (xy 177.18722 -285.280348) (xy 177.138045 -285.278367) (xy 177.089826 -285.268523)
			(xy 177.04381 -285.251071) (xy 177.001189 -285.226464) (xy 176.963068 -285.195339) (xy 176.930433 -285.158502)
			(xy 176.90413 -285.116906) (xy 176.884839 -285.07163) (xy 176.873062 -285.023846) (xy 176.869102 -284.974792)
			(xy 176.530254 -284.974792) (xy 176.529759 -284.999399) (xy 176.521864 -285.047976) (xy 176.50628 -285.094657)
			(xy 176.483409 -285.138234) (xy 176.453844 -285.177578) (xy 176.418351 -285.21167) (xy 176.377848 -285.239626)
			(xy 176.333386 -285.260724) (xy 176.286115 -285.274416) (xy 176.23726 -285.280348) (xy 176.188085 -285.278367)
			(xy 176.139866 -285.268523) (xy 176.09385 -285.251071) (xy 176.051229 -285.226464) (xy 176.013108 -285.195339)
			(xy 175.980473 -285.158502) (xy 175.95417 -285.116906) (xy 175.934879 -285.07163) (xy 175.923102 -285.023846)
			(xy 175.919142 -284.974792) (xy 174.630334 -284.974792) (xy 174.629839 -284.999399) (xy 174.621944 -285.047976)
			(xy 174.60636 -285.094657) (xy 174.583489 -285.138234) (xy 174.553924 -285.177578) (xy 174.518431 -285.21167)
			(xy 174.477928 -285.239626) (xy 174.433466 -285.260724) (xy 174.386195 -285.274416) (xy 174.33734 -285.280348)
			(xy 174.288165 -285.278367) (xy 174.239946 -285.268523) (xy 174.19393 -285.251071) (xy 174.151309 -285.226464)
			(xy 174.113188 -285.195339) (xy 174.080553 -285.158502) (xy 174.05425 -285.116906) (xy 174.034959 -285.07163)
			(xy 174.023182 -285.023846) (xy 174.019222 -284.974792) (xy 173.680374 -284.974792) (xy 173.679879 -284.999399)
			(xy 173.671984 -285.047976) (xy 173.6564 -285.094657) (xy 173.633529 -285.138234) (xy 173.603964 -285.177578)
			(xy 173.568471 -285.21167) (xy 173.527968 -285.239626) (xy 173.483506 -285.260724) (xy 173.436235 -285.274416)
			(xy 173.38738 -285.280348) (xy 173.338205 -285.278367) (xy 173.289986 -285.268523) (xy 173.24397 -285.251071)
			(xy 173.201349 -285.226464) (xy 173.163228 -285.195339) (xy 173.130593 -285.158502) (xy 173.10429 -285.116906)
			(xy 173.084999 -285.07163) (xy 173.073222 -285.023846) (xy 173.069262 -284.974792) (xy 172.73016 -284.974792)
			(xy 172.729665 -284.999399) (xy 172.72177 -285.047976) (xy 172.706186 -285.094657) (xy 172.683315 -285.138234)
			(xy 172.65375 -285.177578) (xy 172.618257 -285.21167) (xy 172.577754 -285.239626) (xy 172.533292 -285.260724)
			(xy 172.486021 -285.274416) (xy 172.437166 -285.280348) (xy 172.387991 -285.278367) (xy 172.339772 -285.268523)
			(xy 172.293756 -285.251071) (xy 172.251135 -285.226464) (xy 172.213014 -285.195339) (xy 172.180379 -285.158502)
			(xy 172.154076 -285.116906) (xy 172.134785 -285.07163) (xy 172.123008 -285.023846) (xy 172.119048 -284.974792)
			(xy 171.7802 -284.974792) (xy 171.779705 -284.999399) (xy 171.77181 -285.047976) (xy 171.756226 -285.094657)
			(xy 171.733355 -285.138234) (xy 171.70379 -285.177578) (xy 171.668297 -285.21167) (xy 171.627794 -285.239626)
			(xy 171.583332 -285.260724) (xy 171.536061 -285.274416) (xy 171.487206 -285.280348) (xy 171.438031 -285.278367)
			(xy 171.389812 -285.268523) (xy 171.343796 -285.251071) (xy 171.301175 -285.226464) (xy 171.263054 -285.195339)
			(xy 171.230419 -285.158502) (xy 171.204116 -285.116906) (xy 171.184825 -285.07163) (xy 171.173048 -285.023846)
			(xy 171.169088 -284.974792) (xy 170.83024 -284.974792) (xy 170.829745 -284.999399) (xy 170.82185 -285.047976)
			(xy 170.806266 -285.094657) (xy 170.783395 -285.138234) (xy 170.75383 -285.177578) (xy 170.718337 -285.21167)
			(xy 170.677834 -285.239626) (xy 170.633372 -285.260724) (xy 170.586101 -285.274416) (xy 170.537246 -285.280348)
			(xy 170.488071 -285.278367) (xy 170.439852 -285.268523) (xy 170.393836 -285.251071) (xy 170.351215 -285.226464)
			(xy 170.313094 -285.195339) (xy 170.280459 -285.158502) (xy 170.254156 -285.116906) (xy 170.234865 -285.07163)
			(xy 170.223088 -285.023846) (xy 170.219128 -284.974792) (xy 169.88028 -284.974792) (xy 169.879785 -284.999399)
			(xy 169.87189 -285.047976) (xy 169.856306 -285.094657) (xy 169.833435 -285.138234) (xy 169.80387 -285.177578)
			(xy 169.768377 -285.21167) (xy 169.727874 -285.239626) (xy 169.683412 -285.260724) (xy 169.636141 -285.274416)
			(xy 169.587286 -285.280348) (xy 169.538111 -285.278367) (xy 169.489892 -285.268523) (xy 169.443876 -285.251071)
			(xy 169.401255 -285.226464) (xy 169.363134 -285.195339) (xy 169.330499 -285.158502) (xy 169.304196 -285.116906)
			(xy 169.284905 -285.07163) (xy 169.273128 -285.023846) (xy 169.269168 -284.974792) (xy 168.93032 -284.974792)
			(xy 168.929825 -284.999399) (xy 168.92193 -285.047976) (xy 168.906346 -285.094657) (xy 168.883475 -285.138234)
			(xy 168.85391 -285.177578) (xy 168.818417 -285.21167) (xy 168.777914 -285.239626) (xy 168.733452 -285.260724)
			(xy 168.686181 -285.274416) (xy 168.637326 -285.280348) (xy 168.588151 -285.278367) (xy 168.539932 -285.268523)
			(xy 168.493916 -285.251071) (xy 168.451295 -285.226464) (xy 168.413174 -285.195339) (xy 168.380539 -285.158502)
			(xy 168.354236 -285.116906) (xy 168.334945 -285.07163) (xy 168.323168 -285.023846) (xy 168.319208 -284.974792)
			(xy 167.98036 -284.974792) (xy 167.979865 -284.999399) (xy 167.97197 -285.047976) (xy 167.956386 -285.094657)
			(xy 167.933515 -285.138234) (xy 167.90395 -285.177578) (xy 167.868457 -285.21167) (xy 167.827954 -285.239626)
			(xy 167.783492 -285.260724) (xy 167.736221 -285.274416) (xy 167.687366 -285.280348) (xy 167.638191 -285.278367)
			(xy 167.589972 -285.268523) (xy 167.543956 -285.251071) (xy 167.501335 -285.226464) (xy 167.463214 -285.195339)
			(xy 167.430579 -285.158502) (xy 167.404276 -285.116906) (xy 167.384985 -285.07163) (xy 167.373208 -285.023846)
			(xy 167.369248 -284.974792) (xy 167.0304 -284.974792) (xy 167.029905 -284.999399) (xy 167.02201 -285.047976)
			(xy 167.006426 -285.094657) (xy 166.983555 -285.138234) (xy 166.95399 -285.177578) (xy 166.918497 -285.21167)
			(xy 166.877994 -285.239626) (xy 166.833532 -285.260724) (xy 166.786261 -285.274416) (xy 166.737406 -285.280348)
			(xy 166.688231 -285.278367) (xy 166.640012 -285.268523) (xy 166.593996 -285.251071) (xy 166.551375 -285.226464)
			(xy 166.513254 -285.195339) (xy 166.480619 -285.158502) (xy 166.454316 -285.116906) (xy 166.435025 -285.07163)
			(xy 166.423248 -285.023846) (xy 166.419288 -284.974792) (xy 166.080186 -284.974792) (xy 166.079691 -284.999399)
			(xy 166.071796 -285.047976) (xy 166.056212 -285.094657) (xy 166.033341 -285.138234) (xy 166.003776 -285.177578)
			(xy 165.968283 -285.21167) (xy 165.92778 -285.239626) (xy 165.883318 -285.260724) (xy 165.836047 -285.274416)
			(xy 165.787192 -285.280348) (xy 165.738017 -285.278367) (xy 165.689798 -285.268523) (xy 165.643782 -285.251071)
			(xy 165.601161 -285.226464) (xy 165.56304 -285.195339) (xy 165.530405 -285.158502) (xy 165.504102 -285.116906)
			(xy 165.484811 -285.07163) (xy 165.473034 -285.023846) (xy 165.469074 -284.974792) (xy 165.130226 -284.974792)
			(xy 165.129731 -284.999399) (xy 165.121836 -285.047976) (xy 165.106252 -285.094657) (xy 165.083381 -285.138234)
			(xy 165.053816 -285.177578) (xy 165.018323 -285.21167) (xy 164.97782 -285.239626) (xy 164.933358 -285.260724)
			(xy 164.886087 -285.274416) (xy 164.837232 -285.280348) (xy 164.788057 -285.278367) (xy 164.739838 -285.268523)
			(xy 164.693822 -285.251071) (xy 164.651201 -285.226464) (xy 164.61308 -285.195339) (xy 164.580445 -285.158502)
			(xy 164.554142 -285.116906) (xy 164.534851 -285.07163) (xy 164.523074 -285.023846) (xy 164.519114 -284.974792)
			(xy 164.353748 -284.974792) (xy 164.353748 -285.449772) (xy 189.69407 -285.449772) (xy 189.69803 -285.400718)
			(xy 189.709807 -285.352934) (xy 189.729098 -285.307658) (xy 189.755401 -285.266062) (xy 189.788036 -285.229225)
			(xy 189.826157 -285.1981) (xy 189.868778 -285.173493) (xy 189.914794 -285.156041) (xy 189.963013 -285.146197)
			(xy 190.012188 -285.144216) (xy 190.061043 -285.150148) (xy 190.108314 -285.16384) (xy 190.152776 -285.184938)
			(xy 190.193279 -285.212894) (xy 190.228772 -285.246986) (xy 190.258337 -285.28633) (xy 190.281208 -285.329907)
			(xy 190.296792 -285.376588) (xy 190.304687 -285.425165) (xy 190.305182 -285.449772) (xy 190.64403 -285.449772)
			(xy 190.64799 -285.400718) (xy 190.659767 -285.352934) (xy 190.679058 -285.307658) (xy 190.705361 -285.266062)
			(xy 190.737996 -285.229225) (xy 190.776117 -285.1981) (xy 190.818738 -285.173493) (xy 190.864754 -285.156041)
			(xy 190.912973 -285.146197) (xy 190.962148 -285.144216) (xy 191.011003 -285.150148) (xy 191.058274 -285.16384)
			(xy 191.102736 -285.184938) (xy 191.143239 -285.212894) (xy 191.178732 -285.246986) (xy 191.208297 -285.28633)
			(xy 191.231168 -285.329907) (xy 191.246752 -285.376588) (xy 191.254647 -285.425165) (xy 191.255142 -285.449772)
			(xy 191.594244 -285.449772) (xy 191.598204 -285.400718) (xy 191.609981 -285.352934) (xy 191.629272 -285.307658)
			(xy 191.655575 -285.266062) (xy 191.68821 -285.229225) (xy 191.726331 -285.1981) (xy 191.768952 -285.173493)
			(xy 191.814968 -285.156041) (xy 191.863187 -285.146197) (xy 191.912362 -285.144216) (xy 191.961217 -285.150148)
			(xy 192.008488 -285.16384) (xy 192.05295 -285.184938) (xy 192.093453 -285.212894) (xy 192.128946 -285.246986)
			(xy 192.158511 -285.28633) (xy 192.181382 -285.329907) (xy 192.196966 -285.376588) (xy 192.204861 -285.425165)
			(xy 192.205356 -285.449772) (xy 192.544204 -285.449772) (xy 192.548164 -285.400718) (xy 192.559941 -285.352934)
			(xy 192.579232 -285.307658) (xy 192.605535 -285.266062) (xy 192.63817 -285.229225) (xy 192.676291 -285.1981)
			(xy 192.718912 -285.173493) (xy 192.764928 -285.156041) (xy 192.813147 -285.146197) (xy 192.862322 -285.144216)
			(xy 192.911177 -285.150148) (xy 192.958448 -285.16384) (xy 193.00291 -285.184938) (xy 193.043413 -285.212894)
			(xy 193.078906 -285.246986) (xy 193.108471 -285.28633) (xy 193.131342 -285.329907) (xy 193.146926 -285.376588)
			(xy 193.154821 -285.425165) (xy 193.155316 -285.449772) (xy 193.494164 -285.449772) (xy 193.498124 -285.400718)
			(xy 193.509901 -285.352934) (xy 193.529192 -285.307658) (xy 193.555495 -285.266062) (xy 193.58813 -285.229225)
			(xy 193.626251 -285.1981) (xy 193.668872 -285.173493) (xy 193.714888 -285.156041) (xy 193.763107 -285.146197)
			(xy 193.812282 -285.144216) (xy 193.861137 -285.150148) (xy 193.908408 -285.16384) (xy 193.95287 -285.184938)
			(xy 193.993373 -285.212894) (xy 194.028866 -285.246986) (xy 194.058431 -285.28633) (xy 194.081302 -285.329907)
			(xy 194.096886 -285.376588) (xy 194.104781 -285.425165) (xy 194.105276 -285.449772) (xy 194.444124 -285.449772)
			(xy 194.448084 -285.400718) (xy 194.459861 -285.352934) (xy 194.479152 -285.307658) (xy 194.505455 -285.266062)
			(xy 194.53809 -285.229225) (xy 194.576211 -285.1981) (xy 194.618832 -285.173493) (xy 194.664848 -285.156041)
			(xy 194.713067 -285.146197) (xy 194.762242 -285.144216) (xy 194.811097 -285.150148) (xy 194.858368 -285.16384)
			(xy 194.90283 -285.184938) (xy 194.943333 -285.212894) (xy 194.978826 -285.246986) (xy 195.008391 -285.28633)
			(xy 195.031262 -285.329907) (xy 195.046846 -285.376588) (xy 195.054741 -285.425165) (xy 195.055236 -285.449772)
			(xy 195.394084 -285.449772) (xy 195.398044 -285.400718) (xy 195.409821 -285.352934) (xy 195.429112 -285.307658)
			(xy 195.455415 -285.266062) (xy 195.48805 -285.229225) (xy 195.526171 -285.1981) (xy 195.568792 -285.173493)
			(xy 195.614808 -285.156041) (xy 195.663027 -285.146197) (xy 195.712202 -285.144216) (xy 195.761057 -285.150148)
			(xy 195.808328 -285.16384) (xy 195.85279 -285.184938) (xy 195.893293 -285.212894) (xy 195.928786 -285.246986)
			(xy 195.958351 -285.28633) (xy 195.981222 -285.329907) (xy 195.996806 -285.376588) (xy 196.004701 -285.425165)
			(xy 196.005196 -285.449772) (xy 196.344044 -285.449772) (xy 196.348004 -285.400718) (xy 196.359781 -285.352934)
			(xy 196.379072 -285.307658) (xy 196.405375 -285.266062) (xy 196.43801 -285.229225) (xy 196.476131 -285.1981)
			(xy 196.518752 -285.173493) (xy 196.564768 -285.156041) (xy 196.612987 -285.146197) (xy 196.662162 -285.144216)
			(xy 196.711017 -285.150148) (xy 196.758288 -285.16384) (xy 196.80275 -285.184938) (xy 196.843253 -285.212894)
			(xy 196.878746 -285.246986) (xy 196.908311 -285.28633) (xy 196.931182 -285.329907) (xy 196.946766 -285.376588)
			(xy 196.954661 -285.425165) (xy 196.955156 -285.449772) (xy 196.954661 -285.474379) (xy 196.954482 -285.47548)
			(xy 197.273414 -285.47548) (xy 197.273414 -285.424064) (xy 197.281457 -285.373282) (xy 197.297345 -285.324383)
			(xy 197.320688 -285.278571) (xy 197.350909 -285.236975) (xy 197.387265 -285.200619) (xy 197.428861 -285.170398)
			(xy 197.474673 -285.147055) (xy 197.523572 -285.131167) (xy 197.574354 -285.123124) (xy 197.62577 -285.123124)
			(xy 197.676552 -285.131167) (xy 197.725451 -285.147055) (xy 197.771263 -285.170398) (xy 197.812859 -285.200619)
			(xy 197.849215 -285.236975) (xy 197.879436 -285.278571) (xy 197.902779 -285.324383) (xy 197.918667 -285.373282)
			(xy 197.92671 -285.424064) (xy 197.927214 -285.449772) (xy 197.92671 -285.47548) (xy 198.223374 -285.47548)
			(xy 198.223374 -285.424064) (xy 198.231417 -285.373282) (xy 198.247305 -285.324383) (xy 198.270648 -285.278571)
			(xy 198.300869 -285.236975) (xy 198.337225 -285.200619) (xy 198.378821 -285.170398) (xy 198.424633 -285.147055)
			(xy 198.473532 -285.131167) (xy 198.524314 -285.123124) (xy 198.57573 -285.123124) (xy 198.626512 -285.131167)
			(xy 198.675411 -285.147055) (xy 198.721223 -285.170398) (xy 198.762819 -285.200619) (xy 198.799175 -285.236975)
			(xy 198.829396 -285.278571) (xy 198.852739 -285.324383) (xy 198.868627 -285.373282) (xy 198.87667 -285.424064)
			(xy 198.877174 -285.449772) (xy 198.877169 -285.450026) (xy 199.194432 -285.450026) (xy 199.198392 -285.400972)
			(xy 199.210169 -285.353188) (xy 199.22946 -285.307912) (xy 199.255763 -285.266316) (xy 199.288398 -285.229479)
			(xy 199.326519 -285.198354) (xy 199.36914 -285.173747) (xy 199.415156 -285.156295) (xy 199.463375 -285.146451)
			(xy 199.51255 -285.14447) (xy 199.561405 -285.150402) (xy 199.608676 -285.164094) (xy 199.653138 -285.185192)
			(xy 199.693641 -285.213148) (xy 199.729134 -285.24724) (xy 199.758699 -285.286584) (xy 199.78157 -285.330161)
			(xy 199.797154 -285.376842) (xy 199.805049 -285.425419) (xy 199.805544 -285.450026) (xy 199.805077 -285.473258)
			(xy 224.751517 -285.473258) (xy 224.751517 -285.418742) (xy 224.759276 -285.364782) (xy 224.774636 -285.312475)
			(xy 224.797284 -285.262887) (xy 224.826759 -285.217027) (xy 224.862462 -285.175829) (xy 224.903664 -285.140132)
			(xy 224.949527 -285.110662) (xy 224.999118 -285.08802) (xy 225.051427 -285.072666) (xy 225.105388 -285.064914)
			(xy 225.132646 -285.064454) (xy 225.161385 -285.064962) (xy 225.218213 -285.07359) (xy 225.273103 -285.090645)
			(xy 225.324815 -285.115739) (xy 225.372177 -285.148307) (xy 225.393504 -285.167578) (xy 225.400616 -285.174182)
			(xy 225.418142 -285.181294) (xy 225.50755 -285.181294) (xy 225.525076 -285.174182) (xy 225.532188 -285.167578)
			(xy 225.553515 -285.148308) (xy 225.600878 -285.115743) (xy 225.652589 -285.090652) (xy 225.70748 -285.073602)
			(xy 225.764307 -285.06498) (xy 225.821785 -285.06498) (xy 225.878612 -285.073602) (xy 225.933503 -285.090652)
			(xy 225.985214 -285.115743) (xy 226.032577 -285.148308) (xy 226.053904 -285.167578) (xy 226.061016 -285.174182)
			(xy 226.078542 -285.181294) (xy 226.16795 -285.181294) (xy 226.185476 -285.174182) (xy 226.192588 -285.167578)
			(xy 226.213902 -285.148292) (xy 226.261267 -285.115726) (xy 226.312982 -285.090636) (xy 226.367876 -285.073589)
			(xy 226.424706 -285.064972) (xy 226.453446 -285.064454) (xy 226.483568 -285.065058) (xy 226.543063 -285.074531)
			(xy 226.60033 -285.093234) (xy 226.653948 -285.120702) (xy 226.702584 -285.156254) (xy 226.72421 -285.17723)
			(xy 226.731322 -285.184596) (xy 226.750118 -285.192216) (xy 226.842574 -285.192216) (xy 226.86137 -285.184596)
			(xy 226.868482 -285.17723) (xy 226.890097 -285.156239) (xy 226.938728 -285.12067) (xy 226.992347 -285.093192)
			(xy 227.049619 -285.074487) (xy 227.109121 -285.06502) (xy 227.139246 -285.064454) (xy 227.166492 -285.065019)
			(xy 227.22043 -285.07278) (xy 227.272714 -285.088138) (xy 227.32228 -285.110779) (xy 227.36812 -285.140244)
			(xy 227.409301 -285.175932) (xy 227.444984 -285.217117) (xy 227.474443 -285.26296) (xy 227.497078 -285.31253)
			(xy 227.512429 -285.364815) (xy 227.520184 -285.418754) (xy 227.520184 -285.473246) (xy 227.512429 -285.527185)
			(xy 227.497078 -285.57947) (xy 227.474443 -285.62904) (xy 227.444984 -285.674883) (xy 227.409301 -285.716068)
			(xy 227.36812 -285.751756) (xy 227.32228 -285.781221) (xy 227.272714 -285.803862) (xy 227.22043 -285.81922)
			(xy 227.166492 -285.826981) (xy 227.139246 -285.82747) (xy 227.109124 -285.826865) (xy 227.04963 -285.817391)
			(xy 226.992362 -285.798688) (xy 226.938745 -285.77122) (xy 226.890108 -285.735669) (xy 226.868482 -285.714694)
			(xy 226.86137 -285.707328) (xy 226.842574 -285.699708) (xy 226.750118 -285.699708) (xy 226.731322 -285.707328)
			(xy 226.72421 -285.714694) (xy 226.702603 -285.735694) (xy 226.653969 -285.77126) (xy 226.600349 -285.798736)
			(xy 226.543074 -285.81744) (xy 226.483572 -285.826905) (xy 226.453446 -285.82747) (xy 226.424707 -285.82696)
			(xy 226.36788 -285.818332) (xy 226.312989 -285.801277) (xy 226.261278 -285.776183) (xy 226.213915 -285.743617)
			(xy 226.192588 -285.724346) (xy 226.185476 -285.717742) (xy 226.16795 -285.71063) (xy 226.078542 -285.71063)
			(xy 226.061016 -285.717742) (xy 226.053904 -285.724346) (xy 226.032577 -285.743616) (xy 225.985214 -285.776181)
			(xy 225.933503 -285.801272) (xy 225.878612 -285.818322) (xy 225.821785 -285.826944) (xy 225.764307 -285.826944)
			(xy 225.70748 -285.818322) (xy 225.652589 -285.801272) (xy 225.600878 -285.776181) (xy 225.553515 -285.743616)
			(xy 225.532188 -285.724346) (xy 225.525076 -285.717742) (xy 225.50755 -285.71063) (xy 225.418142 -285.71063)
			(xy 225.400616 -285.717742) (xy 225.393504 -285.724346) (xy 225.372197 -285.74364) (xy 225.32483 -285.776203)
			(xy 225.273113 -285.801292) (xy 225.218218 -285.818337) (xy 225.161386 -285.826953) (xy 225.132646 -285.82747)
			(xy 225.105388 -285.827086) (xy 225.051427 -285.819334) (xy 224.999118 -285.80398) (xy 224.949527 -285.781338)
			(xy 224.903664 -285.751868) (xy 224.862462 -285.716171) (xy 224.826759 -285.674973) (xy 224.797284 -285.629113)
			(xy 224.774636 -285.579525) (xy 224.759276 -285.527218) (xy 224.751517 -285.473258) (xy 199.805077 -285.473258)
			(xy 199.805049 -285.474633) (xy 199.797154 -285.52321) (xy 199.78157 -285.569891) (xy 199.758699 -285.613468)
			(xy 199.729134 -285.652812) (xy 199.693641 -285.686904) (xy 199.653138 -285.71486) (xy 199.608676 -285.735958)
			(xy 199.561405 -285.74965) (xy 199.51255 -285.755582) (xy 199.463375 -285.753601) (xy 199.415156 -285.743757)
			(xy 199.36914 -285.726305) (xy 199.326519 -285.701698) (xy 199.288398 -285.670573) (xy 199.255763 -285.633736)
			(xy 199.22946 -285.59214) (xy 199.210169 -285.546864) (xy 199.198392 -285.49908) (xy 199.194432 -285.450026)
			(xy 198.877169 -285.450026) (xy 198.87667 -285.47548) (xy 198.868627 -285.526262) (xy 198.852739 -285.575161)
			(xy 198.829396 -285.620973) (xy 198.799175 -285.662569) (xy 198.762819 -285.698925) (xy 198.721223 -285.729146)
			(xy 198.675411 -285.752489) (xy 198.626512 -285.768377) (xy 198.57573 -285.77642) (xy 198.524314 -285.77642)
			(xy 198.473532 -285.768377) (xy 198.424633 -285.752489) (xy 198.378821 -285.729146) (xy 198.337225 -285.698925)
			(xy 198.300869 -285.662569) (xy 198.270648 -285.620973) (xy 198.247305 -285.575161) (xy 198.231417 -285.526262)
			(xy 198.223374 -285.47548) (xy 197.92671 -285.47548) (xy 197.918667 -285.526262) (xy 197.902779 -285.575161)
			(xy 197.879436 -285.620973) (xy 197.849215 -285.662569) (xy 197.812859 -285.698925) (xy 197.771263 -285.729146)
			(xy 197.725451 -285.752489) (xy 197.676552 -285.768377) (xy 197.62577 -285.77642) (xy 197.574354 -285.77642)
			(xy 197.523572 -285.768377) (xy 197.474673 -285.752489) (xy 197.428861 -285.729146) (xy 197.387265 -285.698925)
			(xy 197.350909 -285.662569) (xy 197.320688 -285.620973) (xy 197.297345 -285.575161) (xy 197.281457 -285.526262)
			(xy 197.273414 -285.47548) (xy 196.954482 -285.47548) (xy 196.946766 -285.522956) (xy 196.931182 -285.569637)
			(xy 196.908311 -285.613214) (xy 196.878746 -285.652558) (xy 196.843253 -285.68665) (xy 196.80275 -285.714606)
			(xy 196.758288 -285.735704) (xy 196.711017 -285.749396) (xy 196.662162 -285.755328) (xy 196.612987 -285.753347)
			(xy 196.564768 -285.743503) (xy 196.518752 -285.726051) (xy 196.476131 -285.701444) (xy 196.43801 -285.670319)
			(xy 196.405375 -285.633482) (xy 196.379072 -285.591886) (xy 196.359781 -285.54661) (xy 196.348004 -285.498826)
			(xy 196.344044 -285.449772) (xy 196.005196 -285.449772) (xy 196.004701 -285.474379) (xy 195.996806 -285.522956)
			(xy 195.981222 -285.569637) (xy 195.958351 -285.613214) (xy 195.928786 -285.652558) (xy 195.893293 -285.68665)
			(xy 195.85279 -285.714606) (xy 195.808328 -285.735704) (xy 195.761057 -285.749396) (xy 195.712202 -285.755328)
			(xy 195.663027 -285.753347) (xy 195.614808 -285.743503) (xy 195.568792 -285.726051) (xy 195.526171 -285.701444)
			(xy 195.48805 -285.670319) (xy 195.455415 -285.633482) (xy 195.429112 -285.591886) (xy 195.409821 -285.54661)
			(xy 195.398044 -285.498826) (xy 195.394084 -285.449772) (xy 195.055236 -285.449772) (xy 195.054741 -285.474379)
			(xy 195.046846 -285.522956) (xy 195.031262 -285.569637) (xy 195.008391 -285.613214) (xy 194.978826 -285.652558)
			(xy 194.943333 -285.68665) (xy 194.90283 -285.714606) (xy 194.858368 -285.735704) (xy 194.811097 -285.749396)
			(xy 194.762242 -285.755328) (xy 194.713067 -285.753347) (xy 194.664848 -285.743503) (xy 194.618832 -285.726051)
			(xy 194.576211 -285.701444) (xy 194.53809 -285.670319) (xy 194.505455 -285.633482) (xy 194.479152 -285.591886)
			(xy 194.459861 -285.54661) (xy 194.448084 -285.498826) (xy 194.444124 -285.449772) (xy 194.105276 -285.449772)
			(xy 194.104781 -285.474379) (xy 194.096886 -285.522956) (xy 194.081302 -285.569637) (xy 194.058431 -285.613214)
			(xy 194.028866 -285.652558) (xy 193.993373 -285.68665) (xy 193.95287 -285.714606) (xy 193.908408 -285.735704)
			(xy 193.861137 -285.749396) (xy 193.812282 -285.755328) (xy 193.763107 -285.753347) (xy 193.714888 -285.743503)
			(xy 193.668872 -285.726051) (xy 193.626251 -285.701444) (xy 193.58813 -285.670319) (xy 193.555495 -285.633482)
			(xy 193.529192 -285.591886) (xy 193.509901 -285.54661) (xy 193.498124 -285.498826) (xy 193.494164 -285.449772)
			(xy 193.155316 -285.449772) (xy 193.154821 -285.474379) (xy 193.146926 -285.522956) (xy 193.131342 -285.569637)
			(xy 193.108471 -285.613214) (xy 193.078906 -285.652558) (xy 193.043413 -285.68665) (xy 193.00291 -285.714606)
			(xy 192.958448 -285.735704) (xy 192.911177 -285.749396) (xy 192.862322 -285.755328) (xy 192.813147 -285.753347)
			(xy 192.764928 -285.743503) (xy 192.718912 -285.726051) (xy 192.676291 -285.701444) (xy 192.63817 -285.670319)
			(xy 192.605535 -285.633482) (xy 192.579232 -285.591886) (xy 192.559941 -285.54661) (xy 192.548164 -285.498826)
			(xy 192.544204 -285.449772) (xy 192.205356 -285.449772) (xy 192.204861 -285.474379) (xy 192.196966 -285.522956)
			(xy 192.181382 -285.569637) (xy 192.158511 -285.613214) (xy 192.128946 -285.652558) (xy 192.093453 -285.68665)
			(xy 192.05295 -285.714606) (xy 192.008488 -285.735704) (xy 191.961217 -285.749396) (xy 191.912362 -285.755328)
			(xy 191.863187 -285.753347) (xy 191.814968 -285.743503) (xy 191.768952 -285.726051) (xy 191.726331 -285.701444)
			(xy 191.68821 -285.670319) (xy 191.655575 -285.633482) (xy 191.629272 -285.591886) (xy 191.609981 -285.54661)
			(xy 191.598204 -285.498826) (xy 191.594244 -285.449772) (xy 191.255142 -285.449772) (xy 191.254647 -285.474379)
			(xy 191.246752 -285.522956) (xy 191.231168 -285.569637) (xy 191.208297 -285.613214) (xy 191.178732 -285.652558)
			(xy 191.143239 -285.68665) (xy 191.102736 -285.714606) (xy 191.058274 -285.735704) (xy 191.011003 -285.749396)
			(xy 190.962148 -285.755328) (xy 190.912973 -285.753347) (xy 190.864754 -285.743503) (xy 190.818738 -285.726051)
			(xy 190.776117 -285.701444) (xy 190.737996 -285.670319) (xy 190.705361 -285.633482) (xy 190.679058 -285.591886)
			(xy 190.659767 -285.54661) (xy 190.64799 -285.498826) (xy 190.64403 -285.449772) (xy 190.305182 -285.449772)
			(xy 190.304687 -285.474379) (xy 190.296792 -285.522956) (xy 190.281208 -285.569637) (xy 190.258337 -285.613214)
			(xy 190.228772 -285.652558) (xy 190.193279 -285.68665) (xy 190.152776 -285.714606) (xy 190.108314 -285.735704)
			(xy 190.061043 -285.749396) (xy 190.012188 -285.755328) (xy 189.963013 -285.753347) (xy 189.914794 -285.743503)
			(xy 189.868778 -285.726051) (xy 189.826157 -285.701444) (xy 189.788036 -285.670319) (xy 189.755401 -285.633482)
			(xy 189.729098 -285.591886) (xy 189.709807 -285.54661) (xy 189.69803 -285.498826) (xy 189.69407 -285.449772)
			(xy 164.353748 -285.449772) (xy 164.353748 -285.924752) (xy 164.519114 -285.924752) (xy 164.523074 -285.875698)
			(xy 164.534851 -285.827914) (xy 164.554142 -285.782638) (xy 164.580445 -285.741042) (xy 164.61308 -285.704205)
			(xy 164.651201 -285.67308) (xy 164.693822 -285.648473) (xy 164.739838 -285.631021) (xy 164.788057 -285.621177)
			(xy 164.837232 -285.619196) (xy 164.886087 -285.625128) (xy 164.933358 -285.63882) (xy 164.97782 -285.659918)
			(xy 165.018323 -285.687874) (xy 165.053816 -285.721966) (xy 165.083381 -285.76131) (xy 165.106252 -285.804887)
			(xy 165.121836 -285.851568) (xy 165.129731 -285.900145) (xy 165.130226 -285.924752) (xy 165.469074 -285.924752)
			(xy 165.473034 -285.875698) (xy 165.484811 -285.827914) (xy 165.504102 -285.782638) (xy 165.530405 -285.741042)
			(xy 165.56304 -285.704205) (xy 165.601161 -285.67308) (xy 165.643782 -285.648473) (xy 165.689798 -285.631021)
			(xy 165.738017 -285.621177) (xy 165.787192 -285.619196) (xy 165.836047 -285.625128) (xy 165.883318 -285.63882)
			(xy 165.92778 -285.659918) (xy 165.968283 -285.687874) (xy 166.003776 -285.721966) (xy 166.033341 -285.76131)
			(xy 166.056212 -285.804887) (xy 166.071796 -285.851568) (xy 166.079691 -285.900145) (xy 166.080186 -285.924752)
			(xy 166.419288 -285.924752) (xy 166.423248 -285.875698) (xy 166.435025 -285.827914) (xy 166.454316 -285.782638)
			(xy 166.480619 -285.741042) (xy 166.513254 -285.704205) (xy 166.551375 -285.67308) (xy 166.593996 -285.648473)
			(xy 166.640012 -285.631021) (xy 166.688231 -285.621177) (xy 166.737406 -285.619196) (xy 166.786261 -285.625128)
			(xy 166.833532 -285.63882) (xy 166.877994 -285.659918) (xy 166.918497 -285.687874) (xy 166.95399 -285.721966)
			(xy 166.983555 -285.76131) (xy 167.006426 -285.804887) (xy 167.02201 -285.851568) (xy 167.029905 -285.900145)
			(xy 167.0304 -285.924752) (xy 167.369248 -285.924752) (xy 167.373208 -285.875698) (xy 167.384985 -285.827914)
			(xy 167.404276 -285.782638) (xy 167.430579 -285.741042) (xy 167.463214 -285.704205) (xy 167.501335 -285.67308)
			(xy 167.543956 -285.648473) (xy 167.589972 -285.631021) (xy 167.638191 -285.621177) (xy 167.687366 -285.619196)
			(xy 167.736221 -285.625128) (xy 167.783492 -285.63882) (xy 167.827954 -285.659918) (xy 167.868457 -285.687874)
			(xy 167.90395 -285.721966) (xy 167.933515 -285.76131) (xy 167.956386 -285.804887) (xy 167.97197 -285.851568)
			(xy 167.979865 -285.900145) (xy 167.98036 -285.924752) (xy 168.319208 -285.924752) (xy 168.323168 -285.875698)
			(xy 168.334945 -285.827914) (xy 168.354236 -285.782638) (xy 168.380539 -285.741042) (xy 168.413174 -285.704205)
			(xy 168.451295 -285.67308) (xy 168.493916 -285.648473) (xy 168.539932 -285.631021) (xy 168.588151 -285.621177)
			(xy 168.637326 -285.619196) (xy 168.686181 -285.625128) (xy 168.733452 -285.63882) (xy 168.777914 -285.659918)
			(xy 168.818417 -285.687874) (xy 168.85391 -285.721966) (xy 168.883475 -285.76131) (xy 168.906346 -285.804887)
			(xy 168.92193 -285.851568) (xy 168.929825 -285.900145) (xy 168.93032 -285.924752) (xy 169.269168 -285.924752)
			(xy 169.273128 -285.875698) (xy 169.284905 -285.827914) (xy 169.304196 -285.782638) (xy 169.330499 -285.741042)
			(xy 169.363134 -285.704205) (xy 169.401255 -285.67308) (xy 169.443876 -285.648473) (xy 169.489892 -285.631021)
			(xy 169.538111 -285.621177) (xy 169.587286 -285.619196) (xy 169.636141 -285.625128) (xy 169.683412 -285.63882)
			(xy 169.727874 -285.659918) (xy 169.768377 -285.687874) (xy 169.80387 -285.721966) (xy 169.833435 -285.76131)
			(xy 169.856306 -285.804887) (xy 169.87189 -285.851568) (xy 169.879785 -285.900145) (xy 169.88028 -285.924752)
			(xy 170.219128 -285.924752) (xy 170.223088 -285.875698) (xy 170.234865 -285.827914) (xy 170.254156 -285.782638)
			(xy 170.280459 -285.741042) (xy 170.313094 -285.704205) (xy 170.351215 -285.67308) (xy 170.393836 -285.648473)
			(xy 170.439852 -285.631021) (xy 170.488071 -285.621177) (xy 170.537246 -285.619196) (xy 170.586101 -285.625128)
			(xy 170.633372 -285.63882) (xy 170.677834 -285.659918) (xy 170.718337 -285.687874) (xy 170.75383 -285.721966)
			(xy 170.783395 -285.76131) (xy 170.806266 -285.804887) (xy 170.82185 -285.851568) (xy 170.829745 -285.900145)
			(xy 170.83024 -285.924752) (xy 171.169088 -285.924752) (xy 171.173048 -285.875698) (xy 171.184825 -285.827914)
			(xy 171.204116 -285.782638) (xy 171.230419 -285.741042) (xy 171.263054 -285.704205) (xy 171.301175 -285.67308)
			(xy 171.343796 -285.648473) (xy 171.389812 -285.631021) (xy 171.438031 -285.621177) (xy 171.487206 -285.619196)
			(xy 171.536061 -285.625128) (xy 171.583332 -285.63882) (xy 171.627794 -285.659918) (xy 171.668297 -285.687874)
			(xy 171.70379 -285.721966) (xy 171.733355 -285.76131) (xy 171.756226 -285.804887) (xy 171.77181 -285.851568)
			(xy 171.779705 -285.900145) (xy 171.7802 -285.924752) (xy 172.119048 -285.924752) (xy 172.123008 -285.875698)
			(xy 172.134785 -285.827914) (xy 172.154076 -285.782638) (xy 172.180379 -285.741042) (xy 172.213014 -285.704205)
			(xy 172.251135 -285.67308) (xy 172.293756 -285.648473) (xy 172.339772 -285.631021) (xy 172.387991 -285.621177)
			(xy 172.437166 -285.619196) (xy 172.486021 -285.625128) (xy 172.533292 -285.63882) (xy 172.577754 -285.659918)
			(xy 172.618257 -285.687874) (xy 172.65375 -285.721966) (xy 172.683315 -285.76131) (xy 172.706186 -285.804887)
			(xy 172.72177 -285.851568) (xy 172.729665 -285.900145) (xy 172.73016 -285.924752) (xy 173.069262 -285.924752)
			(xy 173.073222 -285.875698) (xy 173.084999 -285.827914) (xy 173.10429 -285.782638) (xy 173.130593 -285.741042)
			(xy 173.163228 -285.704205) (xy 173.201349 -285.67308) (xy 173.24397 -285.648473) (xy 173.289986 -285.631021)
			(xy 173.338205 -285.621177) (xy 173.38738 -285.619196) (xy 173.436235 -285.625128) (xy 173.483506 -285.63882)
			(xy 173.527968 -285.659918) (xy 173.568471 -285.687874) (xy 173.603964 -285.721966) (xy 173.633529 -285.76131)
			(xy 173.6564 -285.804887) (xy 173.671984 -285.851568) (xy 173.679879 -285.900145) (xy 173.680374 -285.924752)
			(xy 174.019222 -285.924752) (xy 174.023182 -285.875698) (xy 174.034959 -285.827914) (xy 174.05425 -285.782638)
			(xy 174.080553 -285.741042) (xy 174.113188 -285.704205) (xy 174.151309 -285.67308) (xy 174.19393 -285.648473)
			(xy 174.239946 -285.631021) (xy 174.288165 -285.621177) (xy 174.33734 -285.619196) (xy 174.386195 -285.625128)
			(xy 174.433466 -285.63882) (xy 174.477928 -285.659918) (xy 174.518431 -285.687874) (xy 174.553924 -285.721966)
			(xy 174.583489 -285.76131) (xy 174.60636 -285.804887) (xy 174.621944 -285.851568) (xy 174.629839 -285.900145)
			(xy 174.630334 -285.924752) (xy 175.919142 -285.924752) (xy 175.923102 -285.875698) (xy 175.934879 -285.827914)
			(xy 175.95417 -285.782638) (xy 175.980473 -285.741042) (xy 176.013108 -285.704205) (xy 176.051229 -285.67308)
			(xy 176.09385 -285.648473) (xy 176.139866 -285.631021) (xy 176.188085 -285.621177) (xy 176.23726 -285.619196)
			(xy 176.286115 -285.625128) (xy 176.333386 -285.63882) (xy 176.377848 -285.659918) (xy 176.418351 -285.687874)
			(xy 176.453844 -285.721966) (xy 176.483409 -285.76131) (xy 176.50628 -285.804887) (xy 176.521864 -285.851568)
			(xy 176.529759 -285.900145) (xy 176.530254 -285.924752) (xy 176.869102 -285.924752) (xy 176.873062 -285.875698)
			(xy 176.884839 -285.827914) (xy 176.90413 -285.782638) (xy 176.930433 -285.741042) (xy 176.963068 -285.704205)
			(xy 177.001189 -285.67308) (xy 177.04381 -285.648473) (xy 177.089826 -285.631021) (xy 177.138045 -285.621177)
			(xy 177.18722 -285.619196) (xy 177.236075 -285.625128) (xy 177.283346 -285.63882) (xy 177.327808 -285.659918)
			(xy 177.368311 -285.687874) (xy 177.403804 -285.721966) (xy 177.433369 -285.76131) (xy 177.45624 -285.804887)
			(xy 177.471824 -285.851568) (xy 177.479719 -285.900145) (xy 177.480214 -285.924752) (xy 177.819062 -285.924752)
			(xy 177.823022 -285.875698) (xy 177.834799 -285.827914) (xy 177.85409 -285.782638) (xy 177.880393 -285.741042)
			(xy 177.913028 -285.704205) (xy 177.951149 -285.67308) (xy 177.99377 -285.648473) (xy 178.039786 -285.631021)
			(xy 178.088005 -285.621177) (xy 178.13718 -285.619196) (xy 178.186035 -285.625128) (xy 178.233306 -285.63882)
			(xy 178.277768 -285.659918) (xy 178.318271 -285.687874) (xy 178.353764 -285.721966) (xy 178.383329 -285.76131)
			(xy 178.4062 -285.804887) (xy 178.421784 -285.851568) (xy 178.429679 -285.900145) (xy 178.430174 -285.924752)
			(xy 178.769276 -285.924752) (xy 178.773236 -285.875698) (xy 178.785013 -285.827914) (xy 178.804304 -285.782638)
			(xy 178.830607 -285.741042) (xy 178.863242 -285.704205) (xy 178.901363 -285.67308) (xy 178.943984 -285.648473)
			(xy 178.99 -285.631021) (xy 179.038219 -285.621177) (xy 179.087394 -285.619196) (xy 179.136249 -285.625128)
			(xy 179.18352 -285.63882) (xy 179.227982 -285.659918) (xy 179.268485 -285.687874) (xy 179.303978 -285.721966)
			(xy 179.333543 -285.76131) (xy 179.356414 -285.804887) (xy 179.371998 -285.851568) (xy 179.379893 -285.900145)
			(xy 179.380388 -285.924752) (xy 179.719236 -285.924752) (xy 179.723196 -285.875698) (xy 179.734973 -285.827914)
			(xy 179.754264 -285.782638) (xy 179.780567 -285.741042) (xy 179.813202 -285.704205) (xy 179.851323 -285.67308)
			(xy 179.893944 -285.648473) (xy 179.93996 -285.631021) (xy 179.988179 -285.621177) (xy 180.037354 -285.619196)
			(xy 180.086209 -285.625128) (xy 180.13348 -285.63882) (xy 180.177942 -285.659918) (xy 180.218445 -285.687874)
			(xy 180.253938 -285.721966) (xy 180.283503 -285.76131) (xy 180.306374 -285.804887) (xy 180.321958 -285.851568)
			(xy 180.329853 -285.900145) (xy 180.330348 -285.924752) (xy 180.669196 -285.924752) (xy 180.673156 -285.875698)
			(xy 180.684933 -285.827914) (xy 180.704224 -285.782638) (xy 180.730527 -285.741042) (xy 180.763162 -285.704205)
			(xy 180.801283 -285.67308) (xy 180.843904 -285.648473) (xy 180.88992 -285.631021) (xy 180.938139 -285.621177)
			(xy 180.987314 -285.619196) (xy 181.036169 -285.625128) (xy 181.08344 -285.63882) (xy 181.127902 -285.659918)
			(xy 181.168405 -285.687874) (xy 181.203898 -285.721966) (xy 181.233463 -285.76131) (xy 181.256334 -285.804887)
			(xy 181.271918 -285.851568) (xy 181.279813 -285.900145) (xy 181.280308 -285.924752) (xy 181.619156 -285.924752)
			(xy 181.623116 -285.875698) (xy 181.634893 -285.827914) (xy 181.654184 -285.782638) (xy 181.680487 -285.741042)
			(xy 181.713122 -285.704205) (xy 181.751243 -285.67308) (xy 181.793864 -285.648473) (xy 181.83988 -285.631021)
			(xy 181.888099 -285.621177) (xy 181.937274 -285.619196) (xy 181.986129 -285.625128) (xy 182.0334 -285.63882)
			(xy 182.077862 -285.659918) (xy 182.118365 -285.687874) (xy 182.153858 -285.721966) (xy 182.183423 -285.76131)
			(xy 182.206294 -285.804887) (xy 182.221878 -285.851568) (xy 182.229773 -285.900145) (xy 182.230268 -285.924752)
			(xy 182.569116 -285.924752) (xy 182.573076 -285.875698) (xy 182.584853 -285.827914) (xy 182.604144 -285.782638)
			(xy 182.630447 -285.741042) (xy 182.663082 -285.704205) (xy 182.701203 -285.67308) (xy 182.743824 -285.648473)
			(xy 182.78984 -285.631021) (xy 182.838059 -285.621177) (xy 182.887234 -285.619196) (xy 182.936089 -285.625128)
			(xy 182.98336 -285.63882) (xy 183.027822 -285.659918) (xy 183.068325 -285.687874) (xy 183.103818 -285.721966)
			(xy 183.133383 -285.76131) (xy 183.156254 -285.804887) (xy 183.171838 -285.851568) (xy 183.179733 -285.900145)
			(xy 183.180228 -285.924752) (xy 183.519076 -285.924752) (xy 183.523036 -285.875698) (xy 183.534813 -285.827914)
			(xy 183.554104 -285.782638) (xy 183.580407 -285.741042) (xy 183.613042 -285.704205) (xy 183.651163 -285.67308)
			(xy 183.693784 -285.648473) (xy 183.7398 -285.631021) (xy 183.788019 -285.621177) (xy 183.837194 -285.619196)
			(xy 183.886049 -285.625128) (xy 183.93332 -285.63882) (xy 183.977782 -285.659918) (xy 184.018285 -285.687874)
			(xy 184.053778 -285.721966) (xy 184.083343 -285.76131) (xy 184.106214 -285.804887) (xy 184.121798 -285.851568)
			(xy 184.129693 -285.900145) (xy 184.130188 -285.924752) (xy 184.469036 -285.924752) (xy 184.472996 -285.875698)
			(xy 184.484773 -285.827914) (xy 184.504064 -285.782638) (xy 184.530367 -285.741042) (xy 184.563002 -285.704205)
			(xy 184.601123 -285.67308) (xy 184.643744 -285.648473) (xy 184.68976 -285.631021) (xy 184.737979 -285.621177)
			(xy 184.787154 -285.619196) (xy 184.836009 -285.625128) (xy 184.88328 -285.63882) (xy 184.927742 -285.659918)
			(xy 184.968245 -285.687874) (xy 185.003738 -285.721966) (xy 185.033303 -285.76131) (xy 185.056174 -285.804887)
			(xy 185.071758 -285.851568) (xy 185.079653 -285.900145) (xy 185.080148 -285.924752) (xy 185.41925 -285.924752)
			(xy 185.42321 -285.875698) (xy 185.434987 -285.827914) (xy 185.454278 -285.782638) (xy 185.480581 -285.741042)
			(xy 185.513216 -285.704205) (xy 185.551337 -285.67308) (xy 185.593958 -285.648473) (xy 185.639974 -285.631021)
			(xy 185.688193 -285.621177) (xy 185.737368 -285.619196) (xy 185.786223 -285.625128) (xy 185.833494 -285.63882)
			(xy 185.877956 -285.659918) (xy 185.918459 -285.687874) (xy 185.953952 -285.721966) (xy 185.983517 -285.76131)
			(xy 186.006388 -285.804887) (xy 186.021972 -285.851568) (xy 186.029867 -285.900145) (xy 186.030362 -285.924752)
			(xy 186.36921 -285.924752) (xy 186.37317 -285.875698) (xy 186.384947 -285.827914) (xy 186.404238 -285.782638)
			(xy 186.430541 -285.741042) (xy 186.463176 -285.704205) (xy 186.501297 -285.67308) (xy 186.543918 -285.648473)
			(xy 186.589934 -285.631021) (xy 186.638153 -285.621177) (xy 186.687328 -285.619196) (xy 186.736183 -285.625128)
			(xy 186.783454 -285.63882) (xy 186.827916 -285.659918) (xy 186.868419 -285.687874) (xy 186.903912 -285.721966)
			(xy 186.933477 -285.76131) (xy 186.956348 -285.804887) (xy 186.971932 -285.851568) (xy 186.979827 -285.900145)
			(xy 186.980322 -285.924752) (xy 186.979827 -285.949359) (xy 186.971932 -285.997936) (xy 186.956348 -286.044617)
			(xy 186.933477 -286.088194) (xy 186.903912 -286.127538) (xy 186.868419 -286.16163) (xy 186.827916 -286.189586)
			(xy 186.783454 -286.210684) (xy 186.736183 -286.224376) (xy 186.687328 -286.230308) (xy 186.638153 -286.228327)
			(xy 186.589934 -286.218483) (xy 186.543918 -286.201031) (xy 186.501297 -286.176424) (xy 186.463176 -286.145299)
			(xy 186.430541 -286.108462) (xy 186.404238 -286.066866) (xy 186.384947 -286.02159) (xy 186.37317 -285.973806)
			(xy 186.36921 -285.924752) (xy 186.030362 -285.924752) (xy 186.029867 -285.949359) (xy 186.021972 -285.997936)
			(xy 186.006388 -286.044617) (xy 185.983517 -286.088194) (xy 185.953952 -286.127538) (xy 185.918459 -286.16163)
			(xy 185.877956 -286.189586) (xy 185.833494 -286.210684) (xy 185.786223 -286.224376) (xy 185.737368 -286.230308)
			(xy 185.688193 -286.228327) (xy 185.639974 -286.218483) (xy 185.593958 -286.201031) (xy 185.551337 -286.176424)
			(xy 185.513216 -286.145299) (xy 185.480581 -286.108462) (xy 185.454278 -286.066866) (xy 185.434987 -286.02159)
			(xy 185.42321 -285.973806) (xy 185.41925 -285.924752) (xy 185.080148 -285.924752) (xy 185.079653 -285.949359)
			(xy 185.071758 -285.997936) (xy 185.056174 -286.044617) (xy 185.033303 -286.088194) (xy 185.003738 -286.127538)
			(xy 184.968245 -286.16163) (xy 184.927742 -286.189586) (xy 184.88328 -286.210684) (xy 184.836009 -286.224376)
			(xy 184.787154 -286.230308) (xy 184.737979 -286.228327) (xy 184.68976 -286.218483) (xy 184.643744 -286.201031)
			(xy 184.601123 -286.176424) (xy 184.563002 -286.145299) (xy 184.530367 -286.108462) (xy 184.504064 -286.066866)
			(xy 184.484773 -286.02159) (xy 184.472996 -285.973806) (xy 184.469036 -285.924752) (xy 184.130188 -285.924752)
			(xy 184.129693 -285.949359) (xy 184.121798 -285.997936) (xy 184.106214 -286.044617) (xy 184.083343 -286.088194)
			(xy 184.053778 -286.127538) (xy 184.018285 -286.16163) (xy 183.977782 -286.189586) (xy 183.93332 -286.210684)
			(xy 183.886049 -286.224376) (xy 183.837194 -286.230308) (xy 183.788019 -286.228327) (xy 183.7398 -286.218483)
			(xy 183.693784 -286.201031) (xy 183.651163 -286.176424) (xy 183.613042 -286.145299) (xy 183.580407 -286.108462)
			(xy 183.554104 -286.066866) (xy 183.534813 -286.02159) (xy 183.523036 -285.973806) (xy 183.519076 -285.924752)
			(xy 183.180228 -285.924752) (xy 183.179733 -285.949359) (xy 183.171838 -285.997936) (xy 183.156254 -286.044617)
			(xy 183.133383 -286.088194) (xy 183.103818 -286.127538) (xy 183.068325 -286.16163) (xy 183.027822 -286.189586)
			(xy 182.98336 -286.210684) (xy 182.936089 -286.224376) (xy 182.887234 -286.230308) (xy 182.838059 -286.228327)
			(xy 182.78984 -286.218483) (xy 182.743824 -286.201031) (xy 182.701203 -286.176424) (xy 182.663082 -286.145299)
			(xy 182.630447 -286.108462) (xy 182.604144 -286.066866) (xy 182.584853 -286.02159) (xy 182.573076 -285.973806)
			(xy 182.569116 -285.924752) (xy 182.230268 -285.924752) (xy 182.229773 -285.949359) (xy 182.221878 -285.997936)
			(xy 182.206294 -286.044617) (xy 182.183423 -286.088194) (xy 182.153858 -286.127538) (xy 182.118365 -286.16163)
			(xy 182.077862 -286.189586) (xy 182.0334 -286.210684) (xy 181.986129 -286.224376) (xy 181.937274 -286.230308)
			(xy 181.888099 -286.228327) (xy 181.83988 -286.218483) (xy 181.793864 -286.201031) (xy 181.751243 -286.176424)
			(xy 181.713122 -286.145299) (xy 181.680487 -286.108462) (xy 181.654184 -286.066866) (xy 181.634893 -286.02159)
			(xy 181.623116 -285.973806) (xy 181.619156 -285.924752) (xy 181.280308 -285.924752) (xy 181.279813 -285.949359)
			(xy 181.271918 -285.997936) (xy 181.256334 -286.044617) (xy 181.233463 -286.088194) (xy 181.203898 -286.127538)
			(xy 181.168405 -286.16163) (xy 181.127902 -286.189586) (xy 181.08344 -286.210684) (xy 181.036169 -286.224376)
			(xy 180.987314 -286.230308) (xy 180.938139 -286.228327) (xy 180.88992 -286.218483) (xy 180.843904 -286.201031)
			(xy 180.801283 -286.176424) (xy 180.763162 -286.145299) (xy 180.730527 -286.108462) (xy 180.704224 -286.066866)
			(xy 180.684933 -286.02159) (xy 180.673156 -285.973806) (xy 180.669196 -285.924752) (xy 180.330348 -285.924752)
			(xy 180.329853 -285.949359) (xy 180.321958 -285.997936) (xy 180.306374 -286.044617) (xy 180.283503 -286.088194)
			(xy 180.253938 -286.127538) (xy 180.218445 -286.16163) (xy 180.177942 -286.189586) (xy 180.13348 -286.210684)
			(xy 180.086209 -286.224376) (xy 180.037354 -286.230308) (xy 179.988179 -286.228327) (xy 179.93996 -286.218483)
			(xy 179.893944 -286.201031) (xy 179.851323 -286.176424) (xy 179.813202 -286.145299) (xy 179.780567 -286.108462)
			(xy 179.754264 -286.066866) (xy 179.734973 -286.02159) (xy 179.723196 -285.973806) (xy 179.719236 -285.924752)
			(xy 179.380388 -285.924752) (xy 179.379893 -285.949359) (xy 179.371998 -285.997936) (xy 179.356414 -286.044617)
			(xy 179.333543 -286.088194) (xy 179.303978 -286.127538) (xy 179.268485 -286.16163) (xy 179.227982 -286.189586)
			(xy 179.18352 -286.210684) (xy 179.136249 -286.224376) (xy 179.087394 -286.230308) (xy 179.038219 -286.228327)
			(xy 178.99 -286.218483) (xy 178.943984 -286.201031) (xy 178.901363 -286.176424) (xy 178.863242 -286.145299)
			(xy 178.830607 -286.108462) (xy 178.804304 -286.066866) (xy 178.785013 -286.02159) (xy 178.773236 -285.973806)
			(xy 178.769276 -285.924752) (xy 178.430174 -285.924752) (xy 178.429679 -285.949359) (xy 178.421784 -285.997936)
			(xy 178.4062 -286.044617) (xy 178.383329 -286.088194) (xy 178.353764 -286.127538) (xy 178.318271 -286.16163)
			(xy 178.277768 -286.189586) (xy 178.233306 -286.210684) (xy 178.186035 -286.224376) (xy 178.13718 -286.230308)
			(xy 178.088005 -286.228327) (xy 178.039786 -286.218483) (xy 177.99377 -286.201031) (xy 177.951149 -286.176424)
			(xy 177.913028 -286.145299) (xy 177.880393 -286.108462) (xy 177.85409 -286.066866) (xy 177.834799 -286.02159)
			(xy 177.823022 -285.973806) (xy 177.819062 -285.924752) (xy 177.480214 -285.924752) (xy 177.479719 -285.949359)
			(xy 177.471824 -285.997936) (xy 177.45624 -286.044617) (xy 177.433369 -286.088194) (xy 177.403804 -286.127538)
			(xy 177.368311 -286.16163) (xy 177.327808 -286.189586) (xy 177.283346 -286.210684) (xy 177.236075 -286.224376)
			(xy 177.18722 -286.230308) (xy 177.138045 -286.228327) (xy 177.089826 -286.218483) (xy 177.04381 -286.201031)
			(xy 177.001189 -286.176424) (xy 176.963068 -286.145299) (xy 176.930433 -286.108462) (xy 176.90413 -286.066866)
			(xy 176.884839 -286.02159) (xy 176.873062 -285.973806) (xy 176.869102 -285.924752) (xy 176.530254 -285.924752)
			(xy 176.529759 -285.949359) (xy 176.521864 -285.997936) (xy 176.50628 -286.044617) (xy 176.483409 -286.088194)
			(xy 176.453844 -286.127538) (xy 176.418351 -286.16163) (xy 176.377848 -286.189586) (xy 176.333386 -286.210684)
			(xy 176.286115 -286.224376) (xy 176.23726 -286.230308) (xy 176.188085 -286.228327) (xy 176.139866 -286.218483)
			(xy 176.09385 -286.201031) (xy 176.051229 -286.176424) (xy 176.013108 -286.145299) (xy 175.980473 -286.108462)
			(xy 175.95417 -286.066866) (xy 175.934879 -286.02159) (xy 175.923102 -285.973806) (xy 175.919142 -285.924752)
			(xy 174.630334 -285.924752) (xy 174.629839 -285.949359) (xy 174.621944 -285.997936) (xy 174.60636 -286.044617)
			(xy 174.583489 -286.088194) (xy 174.553924 -286.127538) (xy 174.518431 -286.16163) (xy 174.477928 -286.189586)
			(xy 174.433466 -286.210684) (xy 174.386195 -286.224376) (xy 174.33734 -286.230308) (xy 174.288165 -286.228327)
			(xy 174.239946 -286.218483) (xy 174.19393 -286.201031) (xy 174.151309 -286.176424) (xy 174.113188 -286.145299)
			(xy 174.080553 -286.108462) (xy 174.05425 -286.066866) (xy 174.034959 -286.02159) (xy 174.023182 -285.973806)
			(xy 174.019222 -285.924752) (xy 173.680374 -285.924752) (xy 173.679879 -285.949359) (xy 173.671984 -285.997936)
			(xy 173.6564 -286.044617) (xy 173.633529 -286.088194) (xy 173.603964 -286.127538) (xy 173.568471 -286.16163)
			(xy 173.527968 -286.189586) (xy 173.483506 -286.210684) (xy 173.436235 -286.224376) (xy 173.38738 -286.230308)
			(xy 173.338205 -286.228327) (xy 173.289986 -286.218483) (xy 173.24397 -286.201031) (xy 173.201349 -286.176424)
			(xy 173.163228 -286.145299) (xy 173.130593 -286.108462) (xy 173.10429 -286.066866) (xy 173.084999 -286.02159)
			(xy 173.073222 -285.973806) (xy 173.069262 -285.924752) (xy 172.73016 -285.924752) (xy 172.729665 -285.949359)
			(xy 172.72177 -285.997936) (xy 172.706186 -286.044617) (xy 172.683315 -286.088194) (xy 172.65375 -286.127538)
			(xy 172.618257 -286.16163) (xy 172.577754 -286.189586) (xy 172.533292 -286.210684) (xy 172.486021 -286.224376)
			(xy 172.437166 -286.230308) (xy 172.387991 -286.228327) (xy 172.339772 -286.218483) (xy 172.293756 -286.201031)
			(xy 172.251135 -286.176424) (xy 172.213014 -286.145299) (xy 172.180379 -286.108462) (xy 172.154076 -286.066866)
			(xy 172.134785 -286.02159) (xy 172.123008 -285.973806) (xy 172.119048 -285.924752) (xy 171.7802 -285.924752)
			(xy 171.779705 -285.949359) (xy 171.77181 -285.997936) (xy 171.756226 -286.044617) (xy 171.733355 -286.088194)
			(xy 171.70379 -286.127538) (xy 171.668297 -286.16163) (xy 171.627794 -286.189586) (xy 171.583332 -286.210684)
			(xy 171.536061 -286.224376) (xy 171.487206 -286.230308) (xy 171.438031 -286.228327) (xy 171.389812 -286.218483)
			(xy 171.343796 -286.201031) (xy 171.301175 -286.176424) (xy 171.263054 -286.145299) (xy 171.230419 -286.108462)
			(xy 171.204116 -286.066866) (xy 171.184825 -286.02159) (xy 171.173048 -285.973806) (xy 171.169088 -285.924752)
			(xy 170.83024 -285.924752) (xy 170.829745 -285.949359) (xy 170.82185 -285.997936) (xy 170.806266 -286.044617)
			(xy 170.783395 -286.088194) (xy 170.75383 -286.127538) (xy 170.718337 -286.16163) (xy 170.677834 -286.189586)
			(xy 170.633372 -286.210684) (xy 170.586101 -286.224376) (xy 170.537246 -286.230308) (xy 170.488071 -286.228327)
			(xy 170.439852 -286.218483) (xy 170.393836 -286.201031) (xy 170.351215 -286.176424) (xy 170.313094 -286.145299)
			(xy 170.280459 -286.108462) (xy 170.254156 -286.066866) (xy 170.234865 -286.02159) (xy 170.223088 -285.973806)
			(xy 170.219128 -285.924752) (xy 169.88028 -285.924752) (xy 169.879785 -285.949359) (xy 169.87189 -285.997936)
			(xy 169.856306 -286.044617) (xy 169.833435 -286.088194) (xy 169.80387 -286.127538) (xy 169.768377 -286.16163)
			(xy 169.727874 -286.189586) (xy 169.683412 -286.210684) (xy 169.636141 -286.224376) (xy 169.587286 -286.230308)
			(xy 169.538111 -286.228327) (xy 169.489892 -286.218483) (xy 169.443876 -286.201031) (xy 169.401255 -286.176424)
			(xy 169.363134 -286.145299) (xy 169.330499 -286.108462) (xy 169.304196 -286.066866) (xy 169.284905 -286.02159)
			(xy 169.273128 -285.973806) (xy 169.269168 -285.924752) (xy 168.93032 -285.924752) (xy 168.929825 -285.949359)
			(xy 168.92193 -285.997936) (xy 168.906346 -286.044617) (xy 168.883475 -286.088194) (xy 168.85391 -286.127538)
			(xy 168.818417 -286.16163) (xy 168.777914 -286.189586) (xy 168.733452 -286.210684) (xy 168.686181 -286.224376)
			(xy 168.637326 -286.230308) (xy 168.588151 -286.228327) (xy 168.539932 -286.218483) (xy 168.493916 -286.201031)
			(xy 168.451295 -286.176424) (xy 168.413174 -286.145299) (xy 168.380539 -286.108462) (xy 168.354236 -286.066866)
			(xy 168.334945 -286.02159) (xy 168.323168 -285.973806) (xy 168.319208 -285.924752) (xy 167.98036 -285.924752)
			(xy 167.979865 -285.949359) (xy 167.97197 -285.997936) (xy 167.956386 -286.044617) (xy 167.933515 -286.088194)
			(xy 167.90395 -286.127538) (xy 167.868457 -286.16163) (xy 167.827954 -286.189586) (xy 167.783492 -286.210684)
			(xy 167.736221 -286.224376) (xy 167.687366 -286.230308) (xy 167.638191 -286.228327) (xy 167.589972 -286.218483)
			(xy 167.543956 -286.201031) (xy 167.501335 -286.176424) (xy 167.463214 -286.145299) (xy 167.430579 -286.108462)
			(xy 167.404276 -286.066866) (xy 167.384985 -286.02159) (xy 167.373208 -285.973806) (xy 167.369248 -285.924752)
			(xy 167.0304 -285.924752) (xy 167.029905 -285.949359) (xy 167.02201 -285.997936) (xy 167.006426 -286.044617)
			(xy 166.983555 -286.088194) (xy 166.95399 -286.127538) (xy 166.918497 -286.16163) (xy 166.877994 -286.189586)
			(xy 166.833532 -286.210684) (xy 166.786261 -286.224376) (xy 166.737406 -286.230308) (xy 166.688231 -286.228327)
			(xy 166.640012 -286.218483) (xy 166.593996 -286.201031) (xy 166.551375 -286.176424) (xy 166.513254 -286.145299)
			(xy 166.480619 -286.108462) (xy 166.454316 -286.066866) (xy 166.435025 -286.02159) (xy 166.423248 -285.973806)
			(xy 166.419288 -285.924752) (xy 166.080186 -285.924752) (xy 166.079691 -285.949359) (xy 166.071796 -285.997936)
			(xy 166.056212 -286.044617) (xy 166.033341 -286.088194) (xy 166.003776 -286.127538) (xy 165.968283 -286.16163)
			(xy 165.92778 -286.189586) (xy 165.883318 -286.210684) (xy 165.836047 -286.224376) (xy 165.787192 -286.230308)
			(xy 165.738017 -286.228327) (xy 165.689798 -286.218483) (xy 165.643782 -286.201031) (xy 165.601161 -286.176424)
			(xy 165.56304 -286.145299) (xy 165.530405 -286.108462) (xy 165.504102 -286.066866) (xy 165.484811 -286.02159)
			(xy 165.473034 -285.973806) (xy 165.469074 -285.924752) (xy 165.130226 -285.924752) (xy 165.129731 -285.949359)
			(xy 165.121836 -285.997936) (xy 165.106252 -286.044617) (xy 165.083381 -286.088194) (xy 165.053816 -286.127538)
			(xy 165.018323 -286.16163) (xy 164.97782 -286.189586) (xy 164.933358 -286.210684) (xy 164.886087 -286.224376)
			(xy 164.837232 -286.230308) (xy 164.788057 -286.228327) (xy 164.739838 -286.218483) (xy 164.693822 -286.201031)
			(xy 164.651201 -286.176424) (xy 164.61308 -286.145299) (xy 164.580445 -286.108462) (xy 164.554142 -286.066866)
			(xy 164.534851 -286.02159) (xy 164.523074 -285.973806) (xy 164.519114 -285.924752) (xy 164.353748 -285.924752)
			(xy 164.353748 -286.399732) (xy 189.69407 -286.399732) (xy 189.69803 -286.350678) (xy 189.709807 -286.302894)
			(xy 189.729098 -286.257618) (xy 189.755401 -286.216022) (xy 189.788036 -286.179185) (xy 189.826157 -286.14806)
			(xy 189.868778 -286.123453) (xy 189.914794 -286.106001) (xy 189.963013 -286.096157) (xy 190.012188 -286.094176)
			(xy 190.061043 -286.100108) (xy 190.108314 -286.1138) (xy 190.152776 -286.134898) (xy 190.193279 -286.162854)
			(xy 190.228772 -286.196946) (xy 190.258337 -286.23629) (xy 190.281208 -286.279867) (xy 190.296792 -286.326548)
			(xy 190.304687 -286.375125) (xy 190.305182 -286.399732) (xy 190.644284 -286.399732) (xy 190.648244 -286.350678)
			(xy 190.660021 -286.302894) (xy 190.679312 -286.257618) (xy 190.705615 -286.216022) (xy 190.73825 -286.179185)
			(xy 190.776371 -286.14806) (xy 190.818992 -286.123453) (xy 190.865008 -286.106001) (xy 190.913227 -286.096157)
			(xy 190.962402 -286.094176) (xy 191.011257 -286.100108) (xy 191.058528 -286.1138) (xy 191.10299 -286.134898)
			(xy 191.143493 -286.162854) (xy 191.178986 -286.196946) (xy 191.208551 -286.23629) (xy 191.231422 -286.279867)
			(xy 191.247006 -286.326548) (xy 191.254901 -286.375125) (xy 191.255396 -286.399732) (xy 191.594244 -286.399732)
			(xy 191.598204 -286.350678) (xy 191.609981 -286.302894) (xy 191.629272 -286.257618) (xy 191.655575 -286.216022)
			(xy 191.68821 -286.179185) (xy 191.726331 -286.14806) (xy 191.768952 -286.123453) (xy 191.814968 -286.106001)
			(xy 191.863187 -286.096157) (xy 191.912362 -286.094176) (xy 191.961217 -286.100108) (xy 192.008488 -286.1138)
			(xy 192.05295 -286.134898) (xy 192.093453 -286.162854) (xy 192.128946 -286.196946) (xy 192.158511 -286.23629)
			(xy 192.181382 -286.279867) (xy 192.196966 -286.326548) (xy 192.204861 -286.375125) (xy 192.205356 -286.399732)
			(xy 192.205351 -286.399986) (xy 192.544204 -286.399986) (xy 192.548164 -286.350932) (xy 192.559941 -286.303148)
			(xy 192.579232 -286.257872) (xy 192.605535 -286.216276) (xy 192.63817 -286.179439) (xy 192.676291 -286.148314)
			(xy 192.718912 -286.123707) (xy 192.764928 -286.106255) (xy 192.813147 -286.096411) (xy 192.862322 -286.09443)
			(xy 192.911177 -286.100362) (xy 192.958448 -286.114054) (xy 193.00291 -286.135152) (xy 193.043413 -286.163108)
			(xy 193.078906 -286.1972) (xy 193.108471 -286.236544) (xy 193.131342 -286.280121) (xy 193.146926 -286.326802)
			(xy 193.154821 -286.375379) (xy 193.155316 -286.399986) (xy 193.494164 -286.399986) (xy 193.498124 -286.350932)
			(xy 193.509901 -286.303148) (xy 193.529192 -286.257872) (xy 193.555495 -286.216276) (xy 193.58813 -286.179439)
			(xy 193.626251 -286.148314) (xy 193.668872 -286.123707) (xy 193.714888 -286.106255) (xy 193.763107 -286.096411)
			(xy 193.812282 -286.09443) (xy 193.861137 -286.100362) (xy 193.908408 -286.114054) (xy 193.95287 -286.135152)
			(xy 193.993373 -286.163108) (xy 194.028866 -286.1972) (xy 194.058431 -286.236544) (xy 194.081302 -286.280121)
			(xy 194.096886 -286.326802) (xy 194.104781 -286.375379) (xy 194.105271 -286.399732) (xy 194.444124 -286.399732)
			(xy 194.448084 -286.350678) (xy 194.459861 -286.302894) (xy 194.479152 -286.257618) (xy 194.505455 -286.216022)
			(xy 194.53809 -286.179185) (xy 194.576211 -286.14806) (xy 194.618832 -286.123453) (xy 194.664848 -286.106001)
			(xy 194.713067 -286.096157) (xy 194.762242 -286.094176) (xy 194.811097 -286.100108) (xy 194.858368 -286.1138)
			(xy 194.90283 -286.134898) (xy 194.943333 -286.162854) (xy 194.978826 -286.196946) (xy 195.008391 -286.23629)
			(xy 195.031262 -286.279867) (xy 195.046846 -286.326548) (xy 195.054741 -286.375125) (xy 195.055236 -286.399732)
			(xy 195.054741 -286.424339) (xy 195.054562 -286.42544) (xy 195.37324 -286.42544) (xy 195.37324 -286.374024)
			(xy 195.381283 -286.323242) (xy 195.397171 -286.274343) (xy 195.420514 -286.228531) (xy 195.450735 -286.186935)
			(xy 195.487091 -286.150579) (xy 195.528687 -286.120358) (xy 195.574499 -286.097015) (xy 195.623398 -286.081127)
			(xy 195.67418 -286.073084) (xy 195.725596 -286.073084) (xy 195.776378 -286.081127) (xy 195.825277 -286.097015)
			(xy 195.871089 -286.120358) (xy 195.912685 -286.150579) (xy 195.949041 -286.186935) (xy 195.979262 -286.228531)
			(xy 196.002605 -286.274343) (xy 196.018493 -286.323242) (xy 196.026536 -286.374024) (xy 196.02704 -286.399732)
			(xy 196.026536 -286.42544) (xy 196.3232 -286.42544) (xy 196.3232 -286.374024) (xy 196.331243 -286.323242)
			(xy 196.347131 -286.274343) (xy 196.370474 -286.228531) (xy 196.400695 -286.186935) (xy 196.437051 -286.150579)
			(xy 196.478647 -286.120358) (xy 196.524459 -286.097015) (xy 196.573358 -286.081127) (xy 196.62414 -286.073084)
			(xy 196.675556 -286.073084) (xy 196.726338 -286.081127) (xy 196.775237 -286.097015) (xy 196.821049 -286.120358)
			(xy 196.862645 -286.150579) (xy 196.899001 -286.186935) (xy 196.929222 -286.228531) (xy 196.952565 -286.274343)
			(xy 196.968453 -286.323242) (xy 196.976496 -286.374024) (xy 196.977 -286.399732) (xy 197.294258 -286.399732)
			(xy 197.298218 -286.350678) (xy 197.309995 -286.302894) (xy 197.329286 -286.257618) (xy 197.355589 -286.216022)
			(xy 197.388224 -286.179185) (xy 197.426345 -286.14806) (xy 197.468966 -286.123453) (xy 197.514982 -286.106001)
			(xy 197.563201 -286.096157) (xy 197.612376 -286.094176) (xy 197.661231 -286.100108) (xy 197.708502 -286.1138)
			(xy 197.752964 -286.134898) (xy 197.793467 -286.162854) (xy 197.82896 -286.196946) (xy 197.858525 -286.23629)
			(xy 197.881396 -286.279867) (xy 197.89698 -286.326548) (xy 197.904875 -286.375125) (xy 197.90537 -286.399732)
			(xy 198.244218 -286.399732) (xy 198.248178 -286.350678) (xy 198.259955 -286.302894) (xy 198.279246 -286.257618)
			(xy 198.305549 -286.216022) (xy 198.338184 -286.179185) (xy 198.376305 -286.14806) (xy 198.418926 -286.123453)
			(xy 198.464942 -286.106001) (xy 198.513161 -286.096157) (xy 198.562336 -286.094176) (xy 198.611191 -286.100108)
			(xy 198.658462 -286.1138) (xy 198.702924 -286.134898) (xy 198.743427 -286.162854) (xy 198.77892 -286.196946)
			(xy 198.808485 -286.23629) (xy 198.831356 -286.279867) (xy 198.84694 -286.326548) (xy 198.854835 -286.375125)
			(xy 198.85533 -286.399732) (xy 198.854835 -286.424339) (xy 198.84694 -286.472916) (xy 198.831356 -286.519597)
			(xy 198.81708 -286.546798) (xy 207.650586 -286.546798) (xy 207.654657 -286.491176) (xy 207.666783 -286.436739)
			(xy 207.686706 -286.384648) (xy 207.714002 -286.336013) (xy 207.748088 -286.29187) (xy 207.788237 -286.253161)
			(xy 207.833595 -286.22071) (xy 207.883195 -286.195209) (xy 207.935979 -286.177202) (xy 207.990822 -286.167072)
			(xy 208.046556 -286.165035) (xy 208.101993 -286.171135) (xy 208.15595 -286.185241) (xy 208.207279 -286.207053)
			(xy 208.254885 -286.236107) (xy 208.297753 -286.271782) (xy 208.33497 -286.313319) (xy 208.365743 -286.359832)
			(xy 208.389415 -286.410329) (xy 208.405483 -286.463736) (xy 208.413603 -286.518912) (xy 208.414112 -286.546798)
			(xy 208.413603 -286.574684) (xy 208.405483 -286.62986) (xy 208.389415 -286.683267) (xy 208.365743 -286.733764)
			(xy 208.33497 -286.780277) (xy 208.297753 -286.821814) (xy 208.254885 -286.857489) (xy 208.207279 -286.886543)
			(xy 208.15595 -286.908355) (xy 208.101993 -286.922461) (xy 208.046556 -286.928561) (xy 207.990822 -286.926524)
			(xy 207.935979 -286.916394) (xy 207.883195 -286.898387) (xy 207.833595 -286.872886) (xy 207.788237 -286.840435)
			(xy 207.748088 -286.801726) (xy 207.714002 -286.757583) (xy 207.686706 -286.708948) (xy 207.666783 -286.656857)
			(xy 207.654657 -286.60242) (xy 207.650586 -286.546798) (xy 198.81708 -286.546798) (xy 198.808485 -286.563174)
			(xy 198.77892 -286.602518) (xy 198.743427 -286.63661) (xy 198.702924 -286.664566) (xy 198.658462 -286.685664)
			(xy 198.611191 -286.699356) (xy 198.562336 -286.705288) (xy 198.513161 -286.703307) (xy 198.464942 -286.693463)
			(xy 198.418926 -286.676011) (xy 198.376305 -286.651404) (xy 198.338184 -286.620279) (xy 198.305549 -286.583442)
			(xy 198.279246 -286.541846) (xy 198.259955 -286.49657) (xy 198.248178 -286.448786) (xy 198.244218 -286.399732)
			(xy 197.90537 -286.399732) (xy 197.904875 -286.424339) (xy 197.89698 -286.472916) (xy 197.881396 -286.519597)
			(xy 197.858525 -286.563174) (xy 197.82896 -286.602518) (xy 197.793467 -286.63661) (xy 197.752964 -286.664566)
			(xy 197.708502 -286.685664) (xy 197.661231 -286.699356) (xy 197.612376 -286.705288) (xy 197.563201 -286.703307)
			(xy 197.514982 -286.693463) (xy 197.468966 -286.676011) (xy 197.426345 -286.651404) (xy 197.388224 -286.620279)
			(xy 197.355589 -286.583442) (xy 197.329286 -286.541846) (xy 197.309995 -286.49657) (xy 197.298218 -286.448786)
			(xy 197.294258 -286.399732) (xy 196.977 -286.399732) (xy 196.976496 -286.42544) (xy 196.968453 -286.476222)
			(xy 196.952565 -286.525121) (xy 196.929222 -286.570933) (xy 196.899001 -286.612529) (xy 196.862645 -286.648885)
			(xy 196.821049 -286.679106) (xy 196.775237 -286.702449) (xy 196.726338 -286.718337) (xy 196.675556 -286.72638)
			(xy 196.62414 -286.72638) (xy 196.573358 -286.718337) (xy 196.524459 -286.702449) (xy 196.478647 -286.679106)
			(xy 196.437051 -286.648885) (xy 196.400695 -286.612529) (xy 196.370474 -286.570933) (xy 196.347131 -286.525121)
			(xy 196.331243 -286.476222) (xy 196.3232 -286.42544) (xy 196.026536 -286.42544) (xy 196.018493 -286.476222)
			(xy 196.002605 -286.525121) (xy 195.979262 -286.570933) (xy 195.949041 -286.612529) (xy 195.912685 -286.648885)
			(xy 195.871089 -286.679106) (xy 195.825277 -286.702449) (xy 195.776378 -286.718337) (xy 195.725596 -286.72638)
			(xy 195.67418 -286.72638) (xy 195.623398 -286.718337) (xy 195.574499 -286.702449) (xy 195.528687 -286.679106)
			(xy 195.487091 -286.648885) (xy 195.450735 -286.612529) (xy 195.420514 -286.570933) (xy 195.397171 -286.525121)
			(xy 195.381283 -286.476222) (xy 195.37324 -286.42544) (xy 195.054562 -286.42544) (xy 195.046846 -286.472916)
			(xy 195.031262 -286.519597) (xy 195.008391 -286.563174) (xy 194.978826 -286.602518) (xy 194.943333 -286.63661)
			(xy 194.90283 -286.664566) (xy 194.858368 -286.685664) (xy 194.811097 -286.699356) (xy 194.762242 -286.705288)
			(xy 194.713067 -286.703307) (xy 194.664848 -286.693463) (xy 194.618832 -286.676011) (xy 194.576211 -286.651404)
			(xy 194.53809 -286.620279) (xy 194.505455 -286.583442) (xy 194.479152 -286.541846) (xy 194.459861 -286.49657)
			(xy 194.448084 -286.448786) (xy 194.444124 -286.399732) (xy 194.105271 -286.399732) (xy 194.105276 -286.399986)
			(xy 194.104781 -286.424593) (xy 194.096886 -286.47317) (xy 194.081302 -286.519851) (xy 194.058431 -286.563428)
			(xy 194.028866 -286.602772) (xy 193.993373 -286.636864) (xy 193.95287 -286.66482) (xy 193.908408 -286.685918)
			(xy 193.861137 -286.69961) (xy 193.812282 -286.705542) (xy 193.763107 -286.703561) (xy 193.714888 -286.693717)
			(xy 193.668872 -286.676265) (xy 193.626251 -286.651658) (xy 193.58813 -286.620533) (xy 193.555495 -286.583696)
			(xy 193.529192 -286.5421) (xy 193.509901 -286.496824) (xy 193.498124 -286.44904) (xy 193.494164 -286.399986)
			(xy 193.155316 -286.399986) (xy 193.154821 -286.424593) (xy 193.146926 -286.47317) (xy 193.131342 -286.519851)
			(xy 193.108471 -286.563428) (xy 193.078906 -286.602772) (xy 193.043413 -286.636864) (xy 193.00291 -286.66482)
			(xy 192.958448 -286.685918) (xy 192.911177 -286.69961) (xy 192.862322 -286.705542) (xy 192.813147 -286.703561)
			(xy 192.764928 -286.693717) (xy 192.718912 -286.676265) (xy 192.676291 -286.651658) (xy 192.63817 -286.620533)
			(xy 192.605535 -286.583696) (xy 192.579232 -286.5421) (xy 192.559941 -286.496824) (xy 192.548164 -286.44904)
			(xy 192.544204 -286.399986) (xy 192.205351 -286.399986) (xy 192.204861 -286.424339) (xy 192.196966 -286.472916)
			(xy 192.181382 -286.519597) (xy 192.158511 -286.563174) (xy 192.128946 -286.602518) (xy 192.093453 -286.63661)
			(xy 192.05295 -286.664566) (xy 192.008488 -286.685664) (xy 191.961217 -286.699356) (xy 191.912362 -286.705288)
			(xy 191.863187 -286.703307) (xy 191.814968 -286.693463) (xy 191.768952 -286.676011) (xy 191.726331 -286.651404)
			(xy 191.68821 -286.620279) (xy 191.655575 -286.583442) (xy 191.629272 -286.541846) (xy 191.609981 -286.49657)
			(xy 191.598204 -286.448786) (xy 191.594244 -286.399732) (xy 191.255396 -286.399732) (xy 191.254901 -286.424339)
			(xy 191.247006 -286.472916) (xy 191.231422 -286.519597) (xy 191.208551 -286.563174) (xy 191.178986 -286.602518)
			(xy 191.143493 -286.63661) (xy 191.10299 -286.664566) (xy 191.058528 -286.685664) (xy 191.011257 -286.699356)
			(xy 190.962402 -286.705288) (xy 190.913227 -286.703307) (xy 190.865008 -286.693463) (xy 190.818992 -286.676011)
			(xy 190.776371 -286.651404) (xy 190.73825 -286.620279) (xy 190.705615 -286.583442) (xy 190.679312 -286.541846)
			(xy 190.660021 -286.49657) (xy 190.648244 -286.448786) (xy 190.644284 -286.399732) (xy 190.305182 -286.399732)
			(xy 190.304687 -286.424339) (xy 190.296792 -286.472916) (xy 190.281208 -286.519597) (xy 190.258337 -286.563174)
			(xy 190.228772 -286.602518) (xy 190.193279 -286.63661) (xy 190.152776 -286.664566) (xy 190.108314 -286.685664)
			(xy 190.061043 -286.699356) (xy 190.012188 -286.705288) (xy 189.963013 -286.703307) (xy 189.914794 -286.693463)
			(xy 189.868778 -286.676011) (xy 189.826157 -286.651404) (xy 189.788036 -286.620279) (xy 189.755401 -286.583442)
			(xy 189.729098 -286.541846) (xy 189.709807 -286.49657) (xy 189.69803 -286.448786) (xy 189.69407 -286.399732)
			(xy 164.353748 -286.399732) (xy 164.353748 -287.032954) (xy 164.354182 -287.043019) (xy 164.361916 -287.061604)
			(xy 164.368734 -287.069022) (xy 164.384228 -287.084516) (xy 164.391624 -287.091367) (xy 164.410223 -287.099105)
			(xy 164.420296 -287.099502) (xy 164.476684 -287.099502) (xy 164.485232 -287.099178) (xy 164.501375 -287.093555)
			(xy 164.514767 -287.08293) (xy 164.51961 -287.07588) (xy 164.52342 -287.06953) (xy 164.526407 -287.064508)
			(xy 164.530256 -287.053477) (xy 164.53104 -287.047686) (xy 164.532056 -287.039304) (xy 164.52723 -287.018984)
			(xy 164.524944 -287.014158) (xy 164.515235 -286.992251) (xy 164.501535 -286.946337) (xy 164.494615 -286.898924)
			(xy 164.49421 -286.874966) (xy 164.49472 -286.848979) (xy 164.50285 -286.797644) (xy 164.518911 -286.748214)
			(xy 164.542507 -286.701904) (xy 164.573057 -286.659856) (xy 164.609808 -286.623105) (xy 164.651856 -286.592555)
			(xy 164.698166 -286.568959) (xy 164.747596 -286.552898) (xy 164.798931 -286.544768) (xy 164.850905 -286.544768)
			(xy 164.90224 -286.552898) (xy 164.95167 -286.568959) (xy 164.99798 -286.592555) (xy 165.040028 -286.623105)
			(xy 165.076779 -286.659856) (xy 165.107329 -286.701904) (xy 165.130925 -286.748214) (xy 165.146986 -286.797644)
			(xy 165.155116 -286.848979) (xy 165.155626 -286.874966) (xy 165.15521 -286.898002) (xy 165.148729 -286.943616)
			(xy 165.13596 -286.987884) (xy 165.126924 -287.009078) (xy 165.123368 -287.016952) (xy 165.122606 -287.01873)
			(xy 165.119172 -287.026589) (xy 165.117255 -287.043621) (xy 165.121118 -287.060319) (xy 165.1254 -287.067752)
			(xy 165.16604 -287.132776) (xy 165.17112 -287.140904) (xy 165.175959 -287.148042) (xy 165.18941 -287.158815)
			(xy 165.205682 -287.164491) (xy 165.2143 -287.16478) (xy 165.385496 -287.16478) (xy 165.392608 -287.164272)
			(xy 165.405816 -287.162494) (xy 165.423596 -287.148778) (xy 165.428676 -287.140904) (xy 165.473634 -287.06953)
			(xy 165.476358 -287.064763) (xy 165.479942 -287.054387) (xy 165.480746 -287.048956) (xy 165.482016 -287.039812)
			(xy 165.47719 -287.018984) (xy 165.474904 -287.014158) (xy 165.465197 -286.992251) (xy 165.451498 -286.946336)
			(xy 165.444578 -286.898924) (xy 165.44417 -286.874966) (xy 165.44468 -286.848979) (xy 165.45281 -286.797644)
			(xy 165.468871 -286.748214) (xy 165.492467 -286.701904) (xy 165.523017 -286.659856) (xy 165.559768 -286.623105)
			(xy 165.601816 -286.592555) (xy 165.648126 -286.568959) (xy 165.697556 -286.552898) (xy 165.748891 -286.544768)
			(xy 165.800865 -286.544768) (xy 165.8522 -286.552898) (xy 165.90163 -286.568959) (xy 165.94794 -286.592555)
			(xy 165.989988 -286.623105) (xy 166.026739 -286.659856) (xy 166.057289 -286.701904) (xy 166.080885 -286.748214)
			(xy 166.096946 -286.797644) (xy 166.105076 -286.848979) (xy 166.105586 -286.874966) (xy 166.10517 -286.898002)
			(xy 166.098691 -286.943617) (xy 166.085924 -286.987885) (xy 166.076884 -287.009078) (xy 166.073328 -287.016952)
			(xy 166.072566 -287.01873) (xy 166.069129 -287.026588) (xy 166.067209 -287.043621) (xy 166.071077 -287.060319)
			(xy 166.07536 -287.067752) (xy 166.116 -287.132776) (xy 166.12108 -287.140904) (xy 166.125921 -287.148035)
			(xy 166.139376 -287.158792) (xy 166.155645 -287.164449) (xy 166.16426 -287.16478) (xy 184.385458 -287.16478)
			(xy 184.39257 -287.164272) (xy 184.405778 -287.162494) (xy 184.423558 -287.148778) (xy 184.428638 -287.140904)
			(xy 184.473596 -287.06953) (xy 184.476317 -287.064762) (xy 184.479897 -287.054386) (xy 184.480708 -287.048956)
			(xy 184.481978 -287.039812) (xy 184.477152 -287.018984) (xy 184.474866 -287.014158) (xy 184.46516 -286.992251)
			(xy 184.451463 -286.946336) (xy 184.444544 -286.898923) (xy 184.444132 -286.874966) (xy 184.444642 -286.848979)
			(xy 184.452772 -286.797644) (xy 184.468833 -286.748214) (xy 184.492429 -286.701904) (xy 184.522979 -286.659856)
			(xy 184.55973 -286.623105) (xy 184.601778 -286.592555) (xy 184.648088 -286.568959) (xy 184.697518 -286.552898)
			(xy 184.748853 -286.544768) (xy 184.800827 -286.544768) (xy 184.852162 -286.552898) (xy 184.901592 -286.568959)
			(xy 184.947902 -286.592555) (xy 184.98995 -286.623105) (xy 185.026701 -286.659856) (xy 185.057251 -286.701904)
			(xy 185.080847 -286.748214) (xy 185.096908 -286.797644) (xy 185.105038 -286.848979) (xy 185.105548 -286.874966)
			(xy 185.41925 -286.874966) (xy 185.42321 -286.825912) (xy 185.434987 -286.778128) (xy 185.454278 -286.732852)
			(xy 185.480581 -286.691256) (xy 185.513216 -286.654419) (xy 185.551337 -286.623294) (xy 185.593958 -286.598687)
			(xy 185.639974 -286.581235) (xy 185.688193 -286.571391) (xy 185.737368 -286.56941) (xy 185.786223 -286.575342)
			(xy 185.833494 -286.589034) (xy 185.877956 -286.610132) (xy 185.918459 -286.638088) (xy 185.953952 -286.67218)
			(xy 185.983517 -286.711524) (xy 186.006388 -286.755101) (xy 186.021972 -286.801782) (xy 186.029867 -286.850359)
			(xy 186.030362 -286.874966) (xy 186.36921 -286.874966) (xy 186.37317 -286.825912) (xy 186.384947 -286.778128)
			(xy 186.404238 -286.732852) (xy 186.430541 -286.691256) (xy 186.463176 -286.654419) (xy 186.501297 -286.623294)
			(xy 186.543918 -286.598687) (xy 186.589934 -286.581235) (xy 186.638153 -286.571391) (xy 186.687328 -286.56941)
			(xy 186.736183 -286.575342) (xy 186.783454 -286.589034) (xy 186.827916 -286.610132) (xy 186.868419 -286.638088)
			(xy 186.903912 -286.67218) (xy 186.933477 -286.711524) (xy 186.956348 -286.755101) (xy 186.971932 -286.801782)
			(xy 186.979827 -286.850359) (xy 186.980322 -286.874966) (xy 186.979827 -286.899573) (xy 186.971932 -286.94815)
			(xy 186.956348 -286.994831) (xy 186.933477 -287.038408) (xy 186.903912 -287.077752) (xy 186.868419 -287.111844)
			(xy 186.827916 -287.1398) (xy 186.783454 -287.160898) (xy 186.736183 -287.17459) (xy 186.687328 -287.180522)
			(xy 186.638153 -287.178541) (xy 186.589934 -287.168697) (xy 186.543918 -287.151245) (xy 186.501297 -287.126638)
			(xy 186.463176 -287.095513) (xy 186.430541 -287.058676) (xy 186.404238 -287.01708) (xy 186.384947 -286.971804)
			(xy 186.37317 -286.92402) (xy 186.36921 -286.874966) (xy 186.030362 -286.874966) (xy 186.029867 -286.899573)
			(xy 186.021972 -286.94815) (xy 186.006388 -286.994831) (xy 185.983517 -287.038408) (xy 185.953952 -287.077752)
			(xy 185.918459 -287.111844) (xy 185.877956 -287.1398) (xy 185.833494 -287.160898) (xy 185.786223 -287.17459)
			(xy 185.737368 -287.180522) (xy 185.688193 -287.178541) (xy 185.639974 -287.168697) (xy 185.593958 -287.151245)
			(xy 185.551337 -287.126638) (xy 185.513216 -287.095513) (xy 185.480581 -287.058676) (xy 185.454278 -287.01708)
			(xy 185.434987 -286.971804) (xy 185.42321 -286.92402) (xy 185.41925 -286.874966) (xy 185.105548 -286.874966)
			(xy 185.105548 -286.87522) (xy 185.105032 -286.901678) (xy 185.09661 -286.95392) (xy 185.079967 -287.004151)
			(xy 185.055529 -287.051086) (xy 185.023922 -287.093526) (xy 184.985954 -287.130384) (xy 184.964578 -287.145984)
			(xy 184.95518 -287.152588) (xy 184.944004 -287.171638) (xy 184.939178 -287.225232) (xy 184.939178 -287.22574)
			(xy 184.936384 -287.260284) (xy 184.93613 -287.264348) (xy 184.93613 -287.265364) (xy 184.936327 -287.272467)
			(xy 184.940196 -287.286134) (xy 184.94375 -287.292288) (xy 184.946798 -287.297114) (xy 184.99963 -287.349946)
			(xy 189.69407 -287.349946) (xy 189.69803 -287.300892) (xy 189.709807 -287.253108) (xy 189.729098 -287.207832)
			(xy 189.755401 -287.166236) (xy 189.788036 -287.129399) (xy 189.826157 -287.098274) (xy 189.868778 -287.073667)
			(xy 189.914794 -287.056215) (xy 189.963013 -287.046371) (xy 190.012188 -287.04439) (xy 190.061043 -287.050322)
			(xy 190.108314 -287.064014) (xy 190.152776 -287.085112) (xy 190.193279 -287.113068) (xy 190.228772 -287.14716)
			(xy 190.258337 -287.186504) (xy 190.281208 -287.230081) (xy 190.296792 -287.276762) (xy 190.304687 -287.325339)
			(xy 190.305182 -287.349946) (xy 190.64403 -287.349946) (xy 190.64799 -287.300892) (xy 190.659767 -287.253108)
			(xy 190.679058 -287.207832) (xy 190.705361 -287.166236) (xy 190.737996 -287.129399) (xy 190.776117 -287.098274)
			(xy 190.818738 -287.073667) (xy 190.864754 -287.056215) (xy 190.912973 -287.046371) (xy 190.962148 -287.04439)
			(xy 191.011003 -287.050322) (xy 191.058274 -287.064014) (xy 191.102736 -287.085112) (xy 191.143239 -287.113068)
			(xy 191.178732 -287.14716) (xy 191.208297 -287.186504) (xy 191.231168 -287.230081) (xy 191.246752 -287.276762)
			(xy 191.254647 -287.325339) (xy 191.255142 -287.349946) (xy 191.594244 -287.349946) (xy 191.598204 -287.300892)
			(xy 191.609981 -287.253108) (xy 191.629272 -287.207832) (xy 191.655575 -287.166236) (xy 191.68821 -287.129399)
			(xy 191.726331 -287.098274) (xy 191.768952 -287.073667) (xy 191.814968 -287.056215) (xy 191.863187 -287.046371)
			(xy 191.912362 -287.04439) (xy 191.961217 -287.050322) (xy 192.008488 -287.064014) (xy 192.05295 -287.085112)
			(xy 192.093453 -287.113068) (xy 192.128946 -287.14716) (xy 192.158511 -287.186504) (xy 192.181382 -287.230081)
			(xy 192.196966 -287.276762) (xy 192.204861 -287.325339) (xy 192.205356 -287.349946) (xy 192.544204 -287.349946)
			(xy 192.548164 -287.300892) (xy 192.559941 -287.253108) (xy 192.579232 -287.207832) (xy 192.605535 -287.166236)
			(xy 192.63817 -287.129399) (xy 192.676291 -287.098274) (xy 192.718912 -287.073667) (xy 192.764928 -287.056215)
			(xy 192.813147 -287.046371) (xy 192.862322 -287.04439) (xy 192.911177 -287.050322) (xy 192.958448 -287.064014)
			(xy 193.00291 -287.085112) (xy 193.043413 -287.113068) (xy 193.078906 -287.14716) (xy 193.108471 -287.186504)
			(xy 193.131342 -287.230081) (xy 193.146926 -287.276762) (xy 193.154821 -287.325339) (xy 193.155316 -287.349946)
			(xy 193.494164 -287.349946) (xy 193.498124 -287.300892) (xy 193.509901 -287.253108) (xy 193.529192 -287.207832)
			(xy 193.555495 -287.166236) (xy 193.58813 -287.129399) (xy 193.626251 -287.098274) (xy 193.668872 -287.073667)
			(xy 193.714888 -287.056215) (xy 193.763107 -287.046371) (xy 193.812282 -287.04439) (xy 193.861137 -287.050322)
			(xy 193.908408 -287.064014) (xy 193.95287 -287.085112) (xy 193.993373 -287.113068) (xy 194.028866 -287.14716)
			(xy 194.058431 -287.186504) (xy 194.081302 -287.230081) (xy 194.096886 -287.276762) (xy 194.104781 -287.325339)
			(xy 194.105276 -287.349946) (xy 194.444124 -287.349946) (xy 194.448084 -287.300892) (xy 194.459861 -287.253108)
			(xy 194.479152 -287.207832) (xy 194.505455 -287.166236) (xy 194.53809 -287.129399) (xy 194.576211 -287.098274)
			(xy 194.618832 -287.073667) (xy 194.664848 -287.056215) (xy 194.713067 -287.046371) (xy 194.762242 -287.04439)
			(xy 194.811097 -287.050322) (xy 194.858368 -287.064014) (xy 194.90283 -287.085112) (xy 194.943333 -287.113068)
			(xy 194.978826 -287.14716) (xy 195.008391 -287.186504) (xy 195.031262 -287.230081) (xy 195.046846 -287.276762)
			(xy 195.054741 -287.325339) (xy 195.055236 -287.349946) (xy 195.39383 -287.349946) (xy 195.39779 -287.300892)
			(xy 195.409567 -287.253108) (xy 195.428858 -287.207832) (xy 195.455161 -287.166236) (xy 195.487796 -287.129399)
			(xy 195.525917 -287.098274) (xy 195.568538 -287.073667) (xy 195.614554 -287.056215) (xy 195.662773 -287.046371)
			(xy 195.711948 -287.04439) (xy 195.760803 -287.050322) (xy 195.808074 -287.064014) (xy 195.852536 -287.085112)
			(xy 195.893039 -287.113068) (xy 195.928532 -287.14716) (xy 195.958097 -287.186504) (xy 195.980968 -287.230081)
			(xy 195.996552 -287.276762) (xy 196.004447 -287.325339) (xy 196.004942 -287.349946) (xy 196.344044 -287.349946)
			(xy 196.348004 -287.300892) (xy 196.359781 -287.253108) (xy 196.379072 -287.207832) (xy 196.405375 -287.166236)
			(xy 196.43801 -287.129399) (xy 196.476131 -287.098274) (xy 196.518752 -287.073667) (xy 196.564768 -287.056215)
			(xy 196.612987 -287.046371) (xy 196.662162 -287.04439) (xy 196.711017 -287.050322) (xy 196.758288 -287.064014)
			(xy 196.80275 -287.085112) (xy 196.843253 -287.113068) (xy 196.878746 -287.14716) (xy 196.908311 -287.186504)
			(xy 196.931182 -287.230081) (xy 196.946766 -287.276762) (xy 196.954661 -287.325339) (xy 196.955156 -287.349946)
			(xy 196.954661 -287.374553) (xy 196.954482 -287.375654) (xy 197.273414 -287.375654) (xy 197.273414 -287.324238)
			(xy 197.281457 -287.273456) (xy 197.297345 -287.224557) (xy 197.320688 -287.178745) (xy 197.350909 -287.137149)
			(xy 197.387265 -287.100793) (xy 197.428861 -287.070572) (xy 197.474673 -287.047229) (xy 197.523572 -287.031341)
			(xy 197.574354 -287.023298) (xy 197.62577 -287.023298) (xy 197.676552 -287.031341) (xy 197.725451 -287.047229)
			(xy 197.771263 -287.070572) (xy 197.812859 -287.100793) (xy 197.849215 -287.137149) (xy 197.879436 -287.178745)
			(xy 197.902779 -287.224557) (xy 197.918667 -287.273456) (xy 197.92671 -287.324238) (xy 197.927214 -287.349946)
			(xy 197.92671 -287.375654) (xy 198.223374 -287.375654) (xy 198.223374 -287.324238) (xy 198.231417 -287.273456)
			(xy 198.247305 -287.224557) (xy 198.270648 -287.178745) (xy 198.300869 -287.137149) (xy 198.337225 -287.100793)
			(xy 198.378821 -287.070572) (xy 198.424633 -287.047229) (xy 198.473532 -287.031341) (xy 198.524314 -287.023298)
			(xy 198.57573 -287.023298) (xy 198.626512 -287.031341) (xy 198.675411 -287.047229) (xy 198.721223 -287.070572)
			(xy 198.762819 -287.100793) (xy 198.799175 -287.137149) (xy 198.829396 -287.178745) (xy 198.852739 -287.224557)
			(xy 198.868627 -287.273456) (xy 198.87667 -287.324238) (xy 198.877174 -287.349946) (xy 198.877169 -287.3502)
			(xy 199.194432 -287.3502) (xy 199.198392 -287.301146) (xy 199.210169 -287.253362) (xy 199.22946 -287.208086)
			(xy 199.255763 -287.16649) (xy 199.288398 -287.129653) (xy 199.326519 -287.098528) (xy 199.36914 -287.073921)
			(xy 199.415156 -287.056469) (xy 199.463375 -287.046625) (xy 199.51255 -287.044644) (xy 199.561405 -287.050576)
			(xy 199.608676 -287.064268) (xy 199.626724 -287.072832) (xy 208.407506 -287.072832) (xy 208.411577 -287.01721)
			(xy 208.423703 -286.962773) (xy 208.443626 -286.910682) (xy 208.470922 -286.862047) (xy 208.505008 -286.817904)
			(xy 208.545157 -286.779195) (xy 208.590515 -286.746744) (xy 208.640115 -286.721243) (xy 208.692899 -286.703236)
			(xy 208.747742 -286.693106) (xy 208.803476 -286.691069) (xy 208.858913 -286.697169) (xy 208.91287 -286.711275)
			(xy 208.964199 -286.733087) (xy 209.011805 -286.762141) (xy 209.054673 -286.797816) (xy 209.09189 -286.839353)
			(xy 209.122663 -286.885866) (xy 209.146335 -286.936363) (xy 209.162403 -286.98977) (xy 209.170523 -287.044946)
			(xy 209.171032 -287.072832) (xy 209.170523 -287.100718) (xy 209.165839 -287.132547) (xy 216.952122 -287.132547)
			(xy 216.952122 -287.078053) (xy 216.959877 -287.024115) (xy 216.975229 -286.971829) (xy 216.997865 -286.922259)
			(xy 217.027325 -286.876416) (xy 217.063009 -286.835231) (xy 217.10419 -286.799544) (xy 217.150031 -286.77008)
			(xy 217.199599 -286.74744) (xy 217.251883 -286.732084) (xy 217.305821 -286.724324) (xy 217.333068 -286.723836)
			(xy 217.361808 -286.724335) (xy 217.418635 -286.732967) (xy 217.473526 -286.750023) (xy 217.525237 -286.77512)
			(xy 217.572599 -286.807688) (xy 217.593926 -286.82696) (xy 217.601038 -286.833564) (xy 217.618564 -286.840676)
			(xy 217.707972 -286.840676) (xy 217.725498 -286.833564) (xy 217.73261 -286.82696) (xy 217.753953 -286.807708)
			(xy 217.801311 -286.775138) (xy 217.853018 -286.750042) (xy 217.907905 -286.732987) (xy 217.96473 -286.724359)
			(xy 217.993468 -286.723836) (xy 218.02359 -286.724431) (xy 218.083085 -286.733907) (xy 218.140353 -286.752612)
			(xy 218.19397 -286.780082) (xy 218.242606 -286.815636) (xy 218.264232 -286.836612) (xy 218.271344 -286.843978)
			(xy 218.29014 -286.851598) (xy 218.382596 -286.851598) (xy 218.401392 -286.843978) (xy 218.408504 -286.836612)
			(xy 218.430106 -286.815607) (xy 218.478741 -286.780041) (xy 218.532363 -286.752566) (xy 218.589638 -286.733863)
			(xy 218.649142 -286.7244) (xy 218.679268 -286.723836) (xy 218.706638 -286.724312) (xy 218.760817 -286.732126)
			(xy 218.81332 -286.747612) (xy 218.863067 -286.770452) (xy 218.909034 -286.800175) (xy 218.929966 -286.817816)
			(xy 218.937078 -286.823912) (xy 218.954096 -286.830262) (xy 219.03944 -286.830262) (xy 219.056458 -286.823912)
			(xy 219.06357 -286.817816) (xy 219.084505 -286.80018) (xy 219.130476 -286.770467) (xy 219.180223 -286.74763)
			(xy 219.232724 -286.732139) (xy 219.286899 -286.72431) (xy 219.314268 -286.723836) (xy 219.341526 -286.724209)
			(xy 219.395486 -286.731963) (xy 219.447794 -286.747318) (xy 219.497384 -286.769961) (xy 219.543246 -286.799432)
			(xy 219.584448 -286.83513) (xy 219.620149 -286.876328) (xy 219.649623 -286.922188) (xy 219.672271 -286.971776)
			(xy 219.68763 -287.024083) (xy 219.695389 -287.078043) (xy 219.695389 -287.132546) (xy 220.945522 -287.132546)
			(xy 220.945522 -287.078054) (xy 220.953276 -287.024116) (xy 220.968628 -286.971831) (xy 220.991263 -286.922263)
			(xy 221.020722 -286.87642) (xy 221.056404 -286.835235) (xy 221.097584 -286.799548) (xy 221.143424 -286.770084)
			(xy 221.19299 -286.747443) (xy 221.245273 -286.732086) (xy 221.29921 -286.724325) (xy 221.326456 -286.723836)
			(xy 221.355195 -286.724343) (xy 221.412023 -286.732972) (xy 221.466913 -286.750027) (xy 221.518624 -286.775122)
			(xy 221.565987 -286.807689) (xy 221.587314 -286.82696) (xy 221.594426 -286.833564) (xy 221.611952 -286.840676)
			(xy 221.70136 -286.840676) (xy 221.718886 -286.833564) (xy 221.725998 -286.82696) (xy 221.747325 -286.80769)
			(xy 221.794688 -286.775125) (xy 221.846399 -286.750034) (xy 221.90129 -286.732984) (xy 221.958117 -286.724362)
			(xy 222.015595 -286.724362) (xy 222.072422 -286.732984) (xy 222.127313 -286.750034) (xy 222.179024 -286.775125)
			(xy 222.226387 -286.80769) (xy 222.247714 -286.82696) (xy 222.254826 -286.833564) (xy 222.272352 -286.840676)
			(xy 222.36176 -286.840676) (xy 222.379286 -286.833564) (xy 222.386398 -286.82696) (xy 222.407705 -286.807666)
			(xy 222.455072 -286.775102) (xy 222.506789 -286.750014) (xy 222.561684 -286.732969) (xy 222.618516 -286.724353)
			(xy 222.647256 -286.723836) (xy 222.677378 -286.724438) (xy 222.736873 -286.733912) (xy 222.79414 -286.752616)
			(xy 222.847758 -286.780085) (xy 222.896394 -286.815636) (xy 222.91802 -286.836612) (xy 222.925132 -286.843978)
			(xy 222.943928 -286.851598) (xy 223.036384 -286.851598) (xy 223.05518 -286.843978) (xy 223.062292 -286.836612)
			(xy 223.083899 -286.815613) (xy 223.132533 -286.780046) (xy 223.186153 -286.75257) (xy 223.243428 -286.733866)
			(xy 223.30293 -286.724401) (xy 223.333056 -286.723836) (xy 223.360314 -286.724208) (xy 223.414276 -286.731961)
			(xy 223.466585 -286.747315) (xy 223.516177 -286.769957) (xy 223.562041 -286.799428) (xy 223.603243 -286.835125)
			(xy 223.638946 -286.876324) (xy 223.668422 -286.922185) (xy 223.69107 -286.971773) (xy 223.70643 -287.024081)
			(xy 223.714189 -287.078042) (xy 223.714189 -287.132558) (xy 223.70643 -287.186519) (xy 223.69107 -287.238827)
			(xy 223.668422 -287.288415) (xy 223.638946 -287.334276) (xy 223.603243 -287.375475) (xy 223.562041 -287.411172)
			(xy 223.516177 -287.440643) (xy 223.466585 -287.463285) (xy 223.414276 -287.478639) (xy 223.360314 -287.486392)
			(xy 223.333056 -287.486852) (xy 223.302934 -287.486245) (xy 223.243439 -287.476773) (xy 223.186172 -287.45807)
			(xy 223.132554 -287.430602) (xy 223.083918 -287.395051) (xy 223.062292 -287.374076) (xy 223.05518 -287.36671)
			(xy 223.036384 -287.35909) (xy 222.943928 -287.35909) (xy 222.925132 -287.36671) (xy 222.91802 -287.374076)
			(xy 222.896406 -287.395068) (xy 222.847774 -287.430635) (xy 222.794155 -287.458114) (xy 222.736883 -287.476819)
			(xy 222.677381 -287.486286) (xy 222.647256 -287.486852) (xy 222.618517 -287.486341) (xy 222.561689 -287.477713)
			(xy 222.506799 -287.460659) (xy 222.455088 -287.435565) (xy 222.407725 -287.402999) (xy 222.386398 -287.383728)
			(xy 222.379286 -287.377124) (xy 222.36176 -287.370012) (xy 222.272352 -287.370012) (xy 222.254826 -287.377124)
			(xy 222.247714 -287.383728) (xy 222.226387 -287.402998) (xy 222.179024 -287.435563) (xy 222.127313 -287.460654)
			(xy 222.072422 -287.477704) (xy 222.015595 -287.486326) (xy 221.958117 -287.486326) (xy 221.90129 -287.477704)
			(xy 221.846399 -287.460654) (xy 221.794688 -287.435563) (xy 221.747325 -287.402998) (xy 221.725998 -287.383728)
			(xy 221.718886 -287.377124) (xy 221.70136 -287.370012) (xy 221.611952 -287.370012) (xy 221.594426 -287.377124)
			(xy 221.587314 -287.383728) (xy 221.566 -287.403014) (xy 221.518635 -287.435579) (xy 221.46692 -287.46067)
			(xy 221.412026 -287.477716) (xy 221.355196 -287.486334) (xy 221.326456 -287.486852) (xy 221.29921 -287.486275)
			(xy 221.245273 -287.478514) (xy 221.19299 -287.463157) (xy 221.143424 -287.440516) (xy 221.097584 -287.411052)
			(xy 221.056404 -287.375365) (xy 221.020722 -287.33418) (xy 220.991263 -287.288337) (xy 220.968628 -287.238769)
			(xy 220.953276 -287.186484) (xy 220.945522 -287.132546) (xy 219.695389 -287.132546) (xy 219.695389 -287.132557)
			(xy 219.68763 -287.186517) (xy 219.672271 -287.238824) (xy 219.649623 -287.288412) (xy 219.620149 -287.334272)
			(xy 219.584448 -287.37547) (xy 219.543246 -287.411168) (xy 219.497384 -287.440639) (xy 219.447794 -287.463282)
			(xy 219.395486 -287.478637) (xy 219.341526 -287.486391) (xy 219.314268 -287.486852) (xy 219.286897 -287.486416)
			(xy 219.232716 -287.478593) (xy 219.180212 -287.463097) (xy 219.130465 -287.440249) (xy 219.0845 -287.410517)
			(xy 219.06357 -287.392872) (xy 219.056458 -287.386776) (xy 219.03944 -287.380426) (xy 218.954096 -287.380426)
			(xy 218.937078 -287.386776) (xy 218.929966 -287.392872) (xy 218.909016 -287.410489) (xy 218.863049 -287.440205)
			(xy 218.813306 -287.463046) (xy 218.760809 -287.478542) (xy 218.706636 -287.486375) (xy 218.679268 -287.486852)
			(xy 218.649144 -287.486301) (xy 218.589647 -287.476815) (xy 218.532378 -287.458099) (xy 218.478762 -287.430619)
			(xy 218.430128 -287.395057) (xy 218.408504 -287.374076) (xy 218.401392 -287.36671) (xy 218.382596 -287.35909)
			(xy 218.29014 -287.35909) (xy 218.271344 -287.36671) (xy 218.264232 -287.374076) (xy 218.242612 -287.395062)
			(xy 218.193983 -287.43063) (xy 218.140365 -287.45811) (xy 218.083093 -287.476817) (xy 218.023593 -287.486285)
			(xy 217.993468 -287.486852) (xy 217.964729 -287.486334) (xy 217.907902 -287.477708) (xy 217.853012 -287.460656)
			(xy 217.8013 -287.435563) (xy 217.753937 -287.402998) (xy 217.73261 -287.383728) (xy 217.725498 -287.377124)
			(xy 217.707972 -287.370012) (xy 217.618564 -287.370012) (xy 217.601038 -287.377124) (xy 217.593926 -287.383728)
			(xy 217.572607 -287.403008) (xy 217.525243 -287.435574) (xy 217.47353 -287.460666) (xy 217.418637 -287.477714)
			(xy 217.361808 -287.486333) (xy 217.333068 -287.486852) (xy 217.305821 -287.486276) (xy 217.251883 -287.478516)
			(xy 217.199599 -287.46316) (xy 217.150031 -287.44052) (xy 217.10419 -287.411056) (xy 217.063009 -287.375369)
			(xy 217.027325 -287.334184) (xy 216.997865 -287.288341) (xy 216.975229 -287.238771) (xy 216.959877 -287.186485)
			(xy 216.952122 -287.132547) (xy 209.165839 -287.132547) (xy 209.162403 -287.155894) (xy 209.146335 -287.209301)
			(xy 209.122663 -287.259798) (xy 209.09189 -287.306311) (xy 209.054673 -287.347848) (xy 209.011805 -287.383523)
			(xy 208.964199 -287.412577) (xy 208.91287 -287.434389) (xy 208.858913 -287.448495) (xy 208.803476 -287.454595)
			(xy 208.747742 -287.452558) (xy 208.692899 -287.442428) (xy 208.640115 -287.424421) (xy 208.590515 -287.39892)
			(xy 208.545157 -287.366469) (xy 208.505008 -287.32776) (xy 208.470922 -287.283617) (xy 208.443626 -287.234982)
			(xy 208.423703 -287.182891) (xy 208.411577 -287.128454) (xy 208.407506 -287.072832) (xy 199.626724 -287.072832)
			(xy 199.653138 -287.085366) (xy 199.693641 -287.113322) (xy 199.729134 -287.147414) (xy 199.758699 -287.186758)
			(xy 199.78157 -287.230335) (xy 199.797154 -287.277016) (xy 199.805049 -287.325593) (xy 199.805544 -287.3502)
			(xy 199.805049 -287.374807) (xy 199.797154 -287.423384) (xy 199.78157 -287.470065) (xy 199.758699 -287.513642)
			(xy 199.729134 -287.552986) (xy 199.693641 -287.587078) (xy 199.653138 -287.615034) (xy 199.608676 -287.636132)
			(xy 199.561405 -287.649824) (xy 199.51255 -287.655756) (xy 199.463375 -287.653775) (xy 199.415156 -287.643931)
			(xy 199.36914 -287.626479) (xy 199.326519 -287.601872) (xy 199.288398 -287.570747) (xy 199.255763 -287.53391)
			(xy 199.22946 -287.492314) (xy 199.210169 -287.447038) (xy 199.198392 -287.399254) (xy 199.194432 -287.3502)
			(xy 198.877169 -287.3502) (xy 198.87667 -287.375654) (xy 198.868627 -287.426436) (xy 198.852739 -287.475335)
			(xy 198.829396 -287.521147) (xy 198.799175 -287.562743) (xy 198.762819 -287.599099) (xy 198.721223 -287.62932)
			(xy 198.675411 -287.652663) (xy 198.626512 -287.668551) (xy 198.57573 -287.676594) (xy 198.524314 -287.676594)
			(xy 198.473532 -287.668551) (xy 198.424633 -287.652663) (xy 198.378821 -287.62932) (xy 198.337225 -287.599099)
			(xy 198.300869 -287.562743) (xy 198.270648 -287.521147) (xy 198.247305 -287.475335) (xy 198.231417 -287.426436)
			(xy 198.223374 -287.375654) (xy 197.92671 -287.375654) (xy 197.918667 -287.426436) (xy 197.902779 -287.475335)
			(xy 197.879436 -287.521147) (xy 197.849215 -287.562743) (xy 197.812859 -287.599099) (xy 197.771263 -287.62932)
			(xy 197.725451 -287.652663) (xy 197.676552 -287.668551) (xy 197.62577 -287.676594) (xy 197.574354 -287.676594)
			(xy 197.523572 -287.668551) (xy 197.474673 -287.652663) (xy 197.428861 -287.62932) (xy 197.387265 -287.599099)
			(xy 197.350909 -287.562743) (xy 197.320688 -287.521147) (xy 197.297345 -287.475335) (xy 197.281457 -287.426436)
			(xy 197.273414 -287.375654) (xy 196.954482 -287.375654) (xy 196.946766 -287.42313) (xy 196.931182 -287.469811)
			(xy 196.908311 -287.513388) (xy 196.878746 -287.552732) (xy 196.843253 -287.586824) (xy 196.80275 -287.61478)
			(xy 196.758288 -287.635878) (xy 196.711017 -287.64957) (xy 196.662162 -287.655502) (xy 196.612987 -287.653521)
			(xy 196.564768 -287.643677) (xy 196.518752 -287.626225) (xy 196.476131 -287.601618) (xy 196.43801 -287.570493)
			(xy 196.405375 -287.533656) (xy 196.379072 -287.49206) (xy 196.359781 -287.446784) (xy 196.348004 -287.399)
			(xy 196.344044 -287.349946) (xy 196.004942 -287.349946) (xy 196.004447 -287.374553) (xy 195.996552 -287.42313)
			(xy 195.980968 -287.469811) (xy 195.958097 -287.513388) (xy 195.928532 -287.552732) (xy 195.893039 -287.586824)
			(xy 195.852536 -287.61478) (xy 195.808074 -287.635878) (xy 195.760803 -287.64957) (xy 195.711948 -287.655502)
			(xy 195.662773 -287.653521) (xy 195.614554 -287.643677) (xy 195.568538 -287.626225) (xy 195.525917 -287.601618)
			(xy 195.487796 -287.570493) (xy 195.455161 -287.533656) (xy 195.428858 -287.49206) (xy 195.409567 -287.446784)
			(xy 195.39779 -287.399) (xy 195.39383 -287.349946) (xy 195.055236 -287.349946) (xy 195.054741 -287.374553)
			(xy 195.046846 -287.42313) (xy 195.031262 -287.469811) (xy 195.008391 -287.513388) (xy 194.978826 -287.552732)
			(xy 194.943333 -287.586824) (xy 194.90283 -287.61478) (xy 194.858368 -287.635878) (xy 194.811097 -287.64957)
			(xy 194.762242 -287.655502) (xy 194.713067 -287.653521) (xy 194.664848 -287.643677) (xy 194.618832 -287.626225)
			(xy 194.576211 -287.601618) (xy 194.53809 -287.570493) (xy 194.505455 -287.533656) (xy 194.479152 -287.49206)
			(xy 194.459861 -287.446784) (xy 194.448084 -287.399) (xy 194.444124 -287.349946) (xy 194.105276 -287.349946)
			(xy 194.104781 -287.374553) (xy 194.096886 -287.42313) (xy 194.081302 -287.469811) (xy 194.058431 -287.513388)
			(xy 194.028866 -287.552732) (xy 193.993373 -287.586824) (xy 193.95287 -287.61478) (xy 193.908408 -287.635878)
			(xy 193.861137 -287.64957) (xy 193.812282 -287.655502) (xy 193.763107 -287.653521) (xy 193.714888 -287.643677)
			(xy 193.668872 -287.626225) (xy 193.626251 -287.601618) (xy 193.58813 -287.570493) (xy 193.555495 -287.533656)
			(xy 193.529192 -287.49206) (xy 193.509901 -287.446784) (xy 193.498124 -287.399) (xy 193.494164 -287.349946)
			(xy 193.155316 -287.349946) (xy 193.154821 -287.374553) (xy 193.146926 -287.42313) (xy 193.131342 -287.469811)
			(xy 193.108471 -287.513388) (xy 193.078906 -287.552732) (xy 193.043413 -287.586824) (xy 193.00291 -287.61478)
			(xy 192.958448 -287.635878) (xy 192.911177 -287.64957) (xy 192.862322 -287.655502) (xy 192.813147 -287.653521)
			(xy 192.764928 -287.643677) (xy 192.718912 -287.626225) (xy 192.676291 -287.601618) (xy 192.63817 -287.570493)
			(xy 192.605535 -287.533656) (xy 192.579232 -287.49206) (xy 192.559941 -287.446784) (xy 192.548164 -287.399)
			(xy 192.544204 -287.349946) (xy 192.205356 -287.349946) (xy 192.204861 -287.374553) (xy 192.196966 -287.42313)
			(xy 192.181382 -287.469811) (xy 192.158511 -287.513388) (xy 192.128946 -287.552732) (xy 192.093453 -287.586824)
			(xy 192.05295 -287.61478) (xy 192.008488 -287.635878) (xy 191.961217 -287.64957) (xy 191.912362 -287.655502)
			(xy 191.863187 -287.653521) (xy 191.814968 -287.643677) (xy 191.768952 -287.626225) (xy 191.726331 -287.601618)
			(xy 191.68821 -287.570493) (xy 191.655575 -287.533656) (xy 191.629272 -287.49206) (xy 191.609981 -287.446784)
			(xy 191.598204 -287.399) (xy 191.594244 -287.349946) (xy 191.255142 -287.349946) (xy 191.254647 -287.374553)
			(xy 191.246752 -287.42313) (xy 191.231168 -287.469811) (xy 191.208297 -287.513388) (xy 191.178732 -287.552732)
			(xy 191.143239 -287.586824) (xy 191.102736 -287.61478) (xy 191.058274 -287.635878) (xy 191.011003 -287.64957)
			(xy 190.962148 -287.655502) (xy 190.912973 -287.653521) (xy 190.864754 -287.643677) (xy 190.818738 -287.626225)
			(xy 190.776117 -287.601618) (xy 190.737996 -287.570493) (xy 190.705361 -287.533656) (xy 190.679058 -287.49206)
			(xy 190.659767 -287.446784) (xy 190.64799 -287.399) (xy 190.64403 -287.349946) (xy 190.305182 -287.349946)
			(xy 190.304687 -287.374553) (xy 190.296792 -287.42313) (xy 190.281208 -287.469811) (xy 190.258337 -287.513388)
			(xy 190.228772 -287.552732) (xy 190.193279 -287.586824) (xy 190.152776 -287.61478) (xy 190.108314 -287.635878)
			(xy 190.061043 -287.64957) (xy 190.012188 -287.655502) (xy 189.963013 -287.653521) (xy 189.914794 -287.643677)
			(xy 189.868778 -287.626225) (xy 189.826157 -287.601618) (xy 189.788036 -287.570493) (xy 189.755401 -287.533656)
			(xy 189.729098 -287.49206) (xy 189.709807 -287.446784) (xy 189.69803 -287.399) (xy 189.69407 -287.349946)
			(xy 184.99963 -287.349946) (xy 185.47461 -287.824926) (xy 186.36921 -287.824926) (xy 186.37317 -287.775872)
			(xy 186.384947 -287.728088) (xy 186.404238 -287.682812) (xy 186.430541 -287.641216) (xy 186.463176 -287.604379)
			(xy 186.501297 -287.573254) (xy 186.543918 -287.548647) (xy 186.589934 -287.531195) (xy 186.638153 -287.521351)
			(xy 186.687328 -287.51937) (xy 186.736183 -287.525302) (xy 186.783454 -287.538994) (xy 186.827916 -287.560092)
			(xy 186.868419 -287.588048) (xy 186.903912 -287.62214) (xy 186.933477 -287.661484) (xy 186.956348 -287.705061)
			(xy 186.971932 -287.751742) (xy 186.979827 -287.800319) (xy 186.980322 -287.824926) (xy 186.979827 -287.849533)
			(xy 186.971932 -287.89811) (xy 186.956348 -287.944791) (xy 186.933477 -287.988368) (xy 186.903912 -288.027712)
			(xy 186.868419 -288.061804) (xy 186.827916 -288.08976) (xy 186.783454 -288.110858) (xy 186.736183 -288.12455)
			(xy 186.687328 -288.130482) (xy 186.638153 -288.128501) (xy 186.589934 -288.118657) (xy 186.543918 -288.101205)
			(xy 186.501297 -288.076598) (xy 186.463176 -288.045473) (xy 186.430541 -288.008636) (xy 186.404238 -287.96704)
			(xy 186.384947 -287.921764) (xy 186.37317 -287.87398) (xy 186.36921 -287.824926) (xy 185.47461 -287.824926)
			(xy 185.51017 -287.860486) (xy 185.517006 -287.867888) (xy 185.524714 -287.886486) (xy 185.525156 -287.896554)
			(xy 185.525156 -288.299906) (xy 189.69407 -288.299906) (xy 189.69803 -288.250852) (xy 189.709807 -288.203068)
			(xy 189.729098 -288.157792) (xy 189.755401 -288.116196) (xy 189.788036 -288.079359) (xy 189.826157 -288.048234)
			(xy 189.868778 -288.023627) (xy 189.914794 -288.006175) (xy 189.963013 -287.996331) (xy 190.012188 -287.99435)
			(xy 190.061043 -288.000282) (xy 190.108314 -288.013974) (xy 190.152776 -288.035072) (xy 190.193279 -288.063028)
			(xy 190.228772 -288.09712) (xy 190.258337 -288.136464) (xy 190.281208 -288.180041) (xy 190.296792 -288.226722)
			(xy 190.304687 -288.275299) (xy 190.305182 -288.299906) (xy 190.644284 -288.299906) (xy 190.648244 -288.250852)
			(xy 190.660021 -288.203068) (xy 190.679312 -288.157792) (xy 190.705615 -288.116196) (xy 190.73825 -288.079359)
			(xy 190.776371 -288.048234) (xy 190.818992 -288.023627) (xy 190.865008 -288.006175) (xy 190.913227 -287.996331)
			(xy 190.962402 -287.99435) (xy 191.011257 -288.000282) (xy 191.058528 -288.013974) (xy 191.10299 -288.035072)
			(xy 191.143493 -288.063028) (xy 191.178986 -288.09712) (xy 191.208551 -288.136464) (xy 191.231422 -288.180041)
			(xy 191.247006 -288.226722) (xy 191.254901 -288.275299) (xy 191.255396 -288.299906) (xy 191.594244 -288.299906)
			(xy 191.598204 -288.250852) (xy 191.609981 -288.203068) (xy 191.629272 -288.157792) (xy 191.655575 -288.116196)
			(xy 191.68821 -288.079359) (xy 191.726331 -288.048234) (xy 191.768952 -288.023627) (xy 191.814968 -288.006175)
			(xy 191.863187 -287.996331) (xy 191.912362 -287.99435) (xy 191.961217 -288.000282) (xy 192.008488 -288.013974)
			(xy 192.05295 -288.035072) (xy 192.093453 -288.063028) (xy 192.128946 -288.09712) (xy 192.158511 -288.136464)
			(xy 192.181382 -288.180041) (xy 192.196966 -288.226722) (xy 192.204861 -288.275299) (xy 192.205356 -288.299906)
			(xy 192.544204 -288.299906) (xy 192.548164 -288.250852) (xy 192.559941 -288.203068) (xy 192.579232 -288.157792)
			(xy 192.605535 -288.116196) (xy 192.63817 -288.079359) (xy 192.676291 -288.048234) (xy 192.718912 -288.023627)
			(xy 192.764928 -288.006175) (xy 192.813147 -287.996331) (xy 192.862322 -287.99435) (xy 192.911177 -288.000282)
			(xy 192.958448 -288.013974) (xy 193.00291 -288.035072) (xy 193.043413 -288.063028) (xy 193.078906 -288.09712)
			(xy 193.108471 -288.136464) (xy 193.131342 -288.180041) (xy 193.146926 -288.226722) (xy 193.154821 -288.275299)
			(xy 193.155316 -288.299906) (xy 193.494164 -288.299906) (xy 193.498124 -288.250852) (xy 193.509901 -288.203068)
			(xy 193.529192 -288.157792) (xy 193.555495 -288.116196) (xy 193.58813 -288.079359) (xy 193.626251 -288.048234)
			(xy 193.668872 -288.023627) (xy 193.714888 -288.006175) (xy 193.763107 -287.996331) (xy 193.812282 -287.99435)
			(xy 193.861137 -288.000282) (xy 193.908408 -288.013974) (xy 193.95287 -288.035072) (xy 193.993373 -288.063028)
			(xy 194.028866 -288.09712) (xy 194.058431 -288.136464) (xy 194.081302 -288.180041) (xy 194.096886 -288.226722)
			(xy 194.104781 -288.275299) (xy 194.105276 -288.299906) (xy 194.444124 -288.299906) (xy 194.448084 -288.250852)
			(xy 194.459861 -288.203068) (xy 194.479152 -288.157792) (xy 194.505455 -288.116196) (xy 194.53809 -288.079359)
			(xy 194.576211 -288.048234) (xy 194.618832 -288.023627) (xy 194.664848 -288.006175) (xy 194.713067 -287.996331)
			(xy 194.762242 -287.99435) (xy 194.811097 -288.000282) (xy 194.858368 -288.013974) (xy 194.90283 -288.035072)
			(xy 194.943333 -288.063028) (xy 194.978826 -288.09712) (xy 195.008391 -288.136464) (xy 195.031262 -288.180041)
			(xy 195.046846 -288.226722) (xy 195.054741 -288.275299) (xy 195.055236 -288.299906) (xy 195.054741 -288.324513)
			(xy 195.054562 -288.325614) (xy 195.37324 -288.325614) (xy 195.37324 -288.274198) (xy 195.381283 -288.223416)
			(xy 195.397171 -288.174517) (xy 195.420514 -288.128705) (xy 195.450735 -288.087109) (xy 195.487091 -288.050753)
			(xy 195.528687 -288.020532) (xy 195.574499 -287.997189) (xy 195.623398 -287.981301) (xy 195.67418 -287.973258)
			(xy 195.725596 -287.973258) (xy 195.776378 -287.981301) (xy 195.825277 -287.997189) (xy 195.871089 -288.020532)
			(xy 195.912685 -288.050753) (xy 195.949041 -288.087109) (xy 195.979262 -288.128705) (xy 196.002605 -288.174517)
			(xy 196.018493 -288.223416) (xy 196.026536 -288.274198) (xy 196.02704 -288.299906) (xy 196.026536 -288.325614)
			(xy 196.3232 -288.325614) (xy 196.3232 -288.274198) (xy 196.331243 -288.223416) (xy 196.347131 -288.174517)
			(xy 196.370474 -288.128705) (xy 196.400695 -288.087109) (xy 196.437051 -288.050753) (xy 196.478647 -288.020532)
			(xy 196.524459 -287.997189) (xy 196.573358 -287.981301) (xy 196.62414 -287.973258) (xy 196.675556 -287.973258)
			(xy 196.726338 -287.981301) (xy 196.775237 -287.997189) (xy 196.821049 -288.020532) (xy 196.862645 -288.050753)
			(xy 196.899001 -288.087109) (xy 196.929222 -288.128705) (xy 196.952565 -288.174517) (xy 196.968453 -288.223416)
			(xy 196.976496 -288.274198) (xy 196.977 -288.299906) (xy 197.294258 -288.299906) (xy 197.298218 -288.250852)
			(xy 197.309995 -288.203068) (xy 197.329286 -288.157792) (xy 197.355589 -288.116196) (xy 197.388224 -288.079359)
			(xy 197.426345 -288.048234) (xy 197.468966 -288.023627) (xy 197.514982 -288.006175) (xy 197.563201 -287.996331)
			(xy 197.612376 -287.99435) (xy 197.661231 -288.000282) (xy 197.708502 -288.013974) (xy 197.752964 -288.035072)
			(xy 197.793467 -288.063028) (xy 197.82896 -288.09712) (xy 197.858525 -288.136464) (xy 197.881396 -288.180041)
			(xy 197.89698 -288.226722) (xy 197.904875 -288.275299) (xy 197.90537 -288.299906) (xy 198.244218 -288.299906)
			(xy 198.248178 -288.250852) (xy 198.259955 -288.203068) (xy 198.279246 -288.157792) (xy 198.305549 -288.116196)
			(xy 198.338184 -288.079359) (xy 198.376305 -288.048234) (xy 198.418926 -288.023627) (xy 198.464942 -288.006175)
			(xy 198.513161 -287.996331) (xy 198.562336 -287.99435) (xy 198.611191 -288.000282) (xy 198.658462 -288.013974)
			(xy 198.702924 -288.035072) (xy 198.743427 -288.063028) (xy 198.77892 -288.09712) (xy 198.808485 -288.136464)
			(xy 198.831356 -288.180041) (xy 198.84694 -288.226722) (xy 198.850472 -288.248452) (xy 203.696044 -288.248452)
			(xy 203.696044 -288.193948) (xy 203.7038 -288.139999) (xy 203.719155 -288.087702) (xy 203.741795 -288.038123)
			(xy 203.77126 -287.992271) (xy 203.806951 -287.951078) (xy 203.84814 -287.915383) (xy 203.89399 -287.885913)
			(xy 203.943567 -287.863268) (xy 203.995862 -287.847908) (xy 204.04981 -287.840146) (xy 204.077062 -287.839658)
			(xy 204.103177 -287.840144) (xy 204.154919 -287.847276) (xy 204.205204 -287.861399) (xy 204.253093 -287.882248)
			(xy 204.297691 -287.909434) (xy 204.338165 -287.942449) (xy 204.373757 -287.980675) (xy 204.403803 -288.023399)
			(xy 204.416152 -288.046414) (xy 204.422756 -288.059368) (xy 204.446886 -288.0741) (xy 204.566266 -288.0741)
			(xy 204.590396 -288.059368) (xy 204.597 -288.046414) (xy 204.609391 -288.023419) (xy 204.639416 -287.980676)
			(xy 204.674993 -287.942432) (xy 204.715458 -287.909401) (xy 204.760052 -287.882202) (xy 204.807941 -287.861344)
			(xy 204.858228 -287.847218) (xy 204.909973 -287.840087) (xy 204.93609 -287.839658) (xy 204.961212 -287.840047)
			(xy 205.011024 -287.846613) (xy 205.059543 -287.859658) (xy 205.105932 -287.878956) (xy 205.12786 -287.89122)
			(xy 205.139036 -287.897824) (xy 205.164436 -287.898586) (xy 205.264004 -287.84804) (xy 205.278482 -287.827212)
			(xy 205.279752 -287.814004) (xy 205.283201 -287.786244) (xy 205.297162 -287.732078) (xy 205.31888 -287.680529)
			(xy 205.347889 -287.632702) (xy 205.383569 -287.589622) (xy 205.425154 -287.552211) (xy 205.471755 -287.52127)
			(xy 205.522373 -287.497462) (xy 205.575923 -287.481298) (xy 205.63126 -287.473123) (xy 205.659228 -287.472628)
			(xy 205.686481 -287.473044) (xy 205.74043 -287.480804) (xy 205.792727 -287.496163) (xy 205.842305 -287.518808)
			(xy 205.888156 -287.548278) (xy 205.929347 -287.583973) (xy 205.965039 -287.625166) (xy 205.994505 -287.67102)
			(xy 206.017147 -287.7206) (xy 206.032502 -287.772897) (xy 206.040258 -287.826847) (xy 206.040258 -287.881353)
			(xy 206.032502 -287.935303) (xy 206.017147 -287.9876) (xy 205.994505 -288.03718) (xy 205.965039 -288.083034)
			(xy 205.929347 -288.124227) (xy 205.888156 -288.159922) (xy 205.842305 -288.189392) (xy 205.792727 -288.212037)
			(xy 205.74043 -288.227396) (xy 205.686481 -288.235156) (xy 205.659228 -288.235644) (xy 205.634107 -288.235246)
			(xy 205.584295 -288.228684) (xy 205.535775 -288.215641) (xy 205.489386 -288.196345) (xy 205.467458 -288.184082)
			(xy 205.456282 -288.177478) (xy 205.430882 -288.176716) (xy 205.331314 -288.227262) (xy 205.316836 -288.24809)
			(xy 205.316801 -288.248453) (xy 206.587044 -288.248453) (xy 206.587044 -288.193947) (xy 206.594801 -288.139995)
			(xy 206.610157 -288.087697) (xy 206.632799 -288.038116) (xy 206.662267 -287.992262) (xy 206.697961 -287.951068)
			(xy 206.739154 -287.915373) (xy 206.785007 -287.885904) (xy 206.834587 -287.86326) (xy 206.886885 -287.847903)
			(xy 206.940837 -287.840145) (xy 206.96809 -287.839658) (xy 206.982048 -287.839771) (xy 207.009889 -287.841808)
			(xy 207.023716 -287.843722) (xy 207.034384 -287.845246) (xy 207.054196 -287.839912) (xy 207.128872 -287.781492)
			(xy 207.138778 -287.763458) (xy 207.139794 -287.75279) (xy 207.143 -287.724799) (xy 207.156498 -287.670104)
			(xy 207.177896 -287.617989) (xy 207.206728 -287.569589) (xy 207.242367 -287.525958) (xy 207.284037 -287.488045)
			(xy 207.330832 -287.456676) (xy 207.381733 -287.432532) (xy 207.435632 -287.416139) (xy 207.491356 -287.407854)
			(xy 207.519524 -287.40735) (xy 207.546385 -287.407833) (xy 207.599576 -287.415373) (xy 207.651183 -287.4303)
			(xy 207.700186 -287.452318) (xy 207.745615 -287.480993) (xy 207.786573 -287.515758) (xy 207.822249 -287.555924)
			(xy 207.851937 -287.600698) (xy 207.875051 -287.649194) (xy 207.891134 -287.700453) (xy 207.895952 -287.726882)
			(xy 207.89773 -287.738058) (xy 207.909922 -287.756092) (xy 207.942568 -287.77625) (xy 226.333058 -287.77625)
			(xy 226.333058 -287.72175) (xy 226.340813 -287.667803) (xy 226.356167 -287.61551) (xy 226.378805 -287.565933)
			(xy 226.408269 -287.520083) (xy 226.443957 -287.478892) (xy 226.485143 -287.443199) (xy 226.530989 -287.413729)
			(xy 226.580563 -287.391084) (xy 226.632855 -287.375724) (xy 226.6868 -287.367961) (xy 226.71405 -287.367472)
			(xy 226.744172 -287.368068) (xy 226.803668 -287.377542) (xy 226.860936 -287.396247) (xy 226.914553 -287.423717)
			(xy 226.963188 -287.459271) (xy 226.984814 -287.480248) (xy 226.991926 -287.487614) (xy 227.010722 -287.495234)
			(xy 227.103178 -287.495234) (xy 227.121974 -287.487614) (xy 227.129086 -287.480248) (xy 227.150702 -287.459258)
			(xy 227.199332 -287.423689) (xy 227.252951 -287.39621) (xy 227.310223 -287.377504) (xy 227.369725 -287.368037)
			(xy 227.39985 -287.367472) (xy 227.427104 -287.367972) (xy 227.481057 -287.375723) (xy 227.533358 -287.391074)
			(xy 227.582942 -287.413712) (xy 227.628799 -287.443177) (xy 227.669996 -287.478869) (xy 227.705693 -287.520061)
			(xy 227.735164 -287.565914) (xy 227.757809 -287.615495) (xy 227.773167 -287.667794) (xy 227.780925 -287.721746)
			(xy 227.780925 -287.776254) (xy 227.773167 -287.830206) (xy 227.757809 -287.882505) (xy 227.735164 -287.932086)
			(xy 227.705693 -287.977939) (xy 227.669996 -288.019131) (xy 227.628799 -288.054823) (xy 227.582942 -288.084288)
			(xy 227.533358 -288.106926) (xy 227.481057 -288.122277) (xy 227.427104 -288.130028) (xy 227.39985 -288.130488)
			(xy 227.369727 -288.129903) (xy 227.31023 -288.120428) (xy 227.252962 -288.101722) (xy 227.199345 -288.074248)
			(xy 227.150711 -288.038691) (xy 227.129086 -288.017712) (xy 227.121974 -288.010346) (xy 227.103178 -288.002726)
			(xy 227.010722 -288.002726) (xy 226.991926 -288.010346) (xy 226.984814 -288.017712) (xy 226.963208 -288.038713)
			(xy 226.914574 -288.074278) (xy 226.860953 -288.101754) (xy 226.803678 -288.120457) (xy 226.744176 -288.129923)
			(xy 226.71405 -288.130488) (xy 226.6868 -288.130039) (xy 226.632855 -288.122276) (xy 226.580563 -288.106916)
			(xy 226.530989 -288.084271) (xy 226.485143 -288.054801) (xy 226.443957 -288.019108) (xy 226.408269 -287.977917)
			(xy 226.378805 -287.932067) (xy 226.356167 -287.88249) (xy 226.340813 -287.830197) (xy 226.333058 -287.77625)
			(xy 207.942568 -287.77625) (xy 207.99425 -287.808162) (xy 208.01584 -287.810702) (xy 208.026508 -287.8074)
			(xy 208.054198 -287.799338) (xy 208.111211 -287.790659) (xy 208.140046 -287.790128) (xy 208.167298 -287.790545)
			(xy 208.221246 -287.798308) (xy 208.27354 -287.813668) (xy 208.323116 -287.836314) (xy 208.368965 -287.865784)
			(xy 208.410153 -287.901479) (xy 208.445843 -287.942672) (xy 208.475308 -287.988525) (xy 208.497948 -288.038103)
			(xy 208.513302 -288.0904) (xy 208.521058 -288.144348) (xy 208.521058 -288.198852) (xy 208.513302 -288.252801)
			(xy 208.497948 -288.305097) (xy 208.475308 -288.354675) (xy 208.445843 -288.400528) (xy 208.410153 -288.441721)
			(xy 208.368965 -288.477416) (xy 208.323116 -288.506886) (xy 208.27354 -288.529532) (xy 208.221246 -288.544892)
			(xy 208.167298 -288.552655) (xy 208.140046 -288.553144) (xy 208.113184 -288.552693) (xy 208.059992 -288.545149)
			(xy 208.008383 -288.530218) (xy 207.95938 -288.508196) (xy 207.913951 -288.479517) (xy 207.872993 -288.444749)
			(xy 207.837318 -288.404579) (xy 207.80763 -288.359803) (xy 207.784517 -288.311304) (xy 207.768436 -288.260043)
			(xy 207.763618 -288.233612) (xy 207.76184 -288.222436) (xy 207.749648 -288.204402) (xy 207.66532 -288.152332)
			(xy 207.64373 -288.149792) (xy 207.633062 -288.153094) (xy 207.605373 -288.161162) (xy 207.548359 -288.169838)
			(xy 207.519524 -288.170366) (xy 207.505566 -288.170251) (xy 207.477725 -288.168215) (xy 207.463898 -288.166302)
			(xy 207.45323 -288.164778) (xy 207.433418 -288.170112) (xy 207.358742 -288.228532) (xy 207.348836 -288.246566)
			(xy 207.34782 -288.257234) (xy 207.34462 -288.285225) (xy 207.33112 -288.33992) (xy 207.30972 -288.392034)
			(xy 207.280886 -288.440432) (xy 207.245246 -288.484063) (xy 207.203575 -288.521975) (xy 207.156781 -288.553345)
			(xy 207.10588 -288.577489) (xy 207.051982 -288.593883) (xy 206.996258 -288.602169) (xy 206.96809 -288.602674)
			(xy 206.940837 -288.602255) (xy 206.886885 -288.594497) (xy 206.834587 -288.57914) (xy 206.785007 -288.556496)
			(xy 206.739154 -288.527027) (xy 206.697961 -288.491332) (xy 206.662267 -288.450138) (xy 206.632799 -288.404284)
			(xy 206.610157 -288.354703) (xy 206.594801 -288.302405) (xy 206.587044 -288.248453) (xy 205.316801 -288.248453)
			(xy 205.315566 -288.261298) (xy 205.312101 -288.289055) (xy 205.298141 -288.34322) (xy 205.276424 -288.394768)
			(xy 205.247416 -288.442594) (xy 205.211738 -288.485674) (xy 205.170155 -288.523085) (xy 205.123556 -288.554026)
			(xy 205.072941 -288.577835) (xy 205.019392 -288.594001) (xy 204.964058 -288.602178) (xy 204.93609 -288.602674)
			(xy 204.909972 -288.602264) (xy 204.858225 -288.595124) (xy 204.807936 -288.580992) (xy 204.760045 -288.560133)
			(xy 204.715447 -288.532936) (xy 204.674975 -288.499911) (xy 204.639386 -288.461673) (xy 204.609346 -288.418938)
			(xy 204.597 -288.395918) (xy 204.590396 -288.382964) (xy 204.566266 -288.368232) (xy 204.446886 -288.368232)
			(xy 204.422756 -288.382964) (xy 204.416152 -288.395918) (xy 204.40381 -288.418941) (xy 204.373777 -288.461683)
			(xy 204.338192 -288.499926) (xy 204.29772 -288.532954) (xy 204.25312 -288.560149) (xy 204.205224 -288.581002)
			(xy 204.154931 -288.595123) (xy 204.103181 -288.602248) (xy 204.077062 -288.602674) (xy 204.04981 -288.602254)
			(xy 203.995862 -288.594492) (xy 203.943567 -288.579132) (xy 203.89399 -288.556487) (xy 203.84814 -288.527017)
			(xy 203.806951 -288.491322) (xy 203.77126 -288.450129) (xy 203.741795 -288.404277) (xy 203.719155 -288.354698)
			(xy 203.7038 -288.302401) (xy 203.696044 -288.248452) (xy 198.850472 -288.248452) (xy 198.854835 -288.275299)
			(xy 198.85533 -288.299906) (xy 198.854835 -288.324513) (xy 198.84694 -288.37309) (xy 198.831356 -288.419771)
			(xy 198.808485 -288.463348) (xy 198.77892 -288.502692) (xy 198.743427 -288.536784) (xy 198.702924 -288.56474)
			(xy 198.658462 -288.585838) (xy 198.611191 -288.59953) (xy 198.562336 -288.605462) (xy 198.513161 -288.603481)
			(xy 198.464942 -288.593637) (xy 198.418926 -288.576185) (xy 198.376305 -288.551578) (xy 198.338184 -288.520453)
			(xy 198.305549 -288.483616) (xy 198.279246 -288.44202) (xy 198.259955 -288.396744) (xy 198.248178 -288.34896)
			(xy 198.244218 -288.299906) (xy 197.90537 -288.299906) (xy 197.904875 -288.324513) (xy 197.89698 -288.37309)
			(xy 197.881396 -288.419771) (xy 197.858525 -288.463348) (xy 197.82896 -288.502692) (xy 197.793467 -288.536784)
			(xy 197.752964 -288.56474) (xy 197.708502 -288.585838) (xy 197.661231 -288.59953) (xy 197.612376 -288.605462)
			(xy 197.563201 -288.603481) (xy 197.514982 -288.593637) (xy 197.468966 -288.576185) (xy 197.426345 -288.551578)
			(xy 197.388224 -288.520453) (xy 197.355589 -288.483616) (xy 197.329286 -288.44202) (xy 197.309995 -288.396744)
			(xy 197.298218 -288.34896) (xy 197.294258 -288.299906) (xy 196.977 -288.299906) (xy 196.976496 -288.325614)
			(xy 196.968453 -288.376396) (xy 196.952565 -288.425295) (xy 196.929222 -288.471107) (xy 196.899001 -288.512703)
			(xy 196.862645 -288.549059) (xy 196.821049 -288.57928) (xy 196.775237 -288.602623) (xy 196.726338 -288.618511)
			(xy 196.675556 -288.626554) (xy 196.62414 -288.626554) (xy 196.573358 -288.618511) (xy 196.524459 -288.602623)
			(xy 196.478647 -288.57928) (xy 196.437051 -288.549059) (xy 196.400695 -288.512703) (xy 196.370474 -288.471107)
			(xy 196.347131 -288.425295) (xy 196.331243 -288.376396) (xy 196.3232 -288.325614) (xy 196.026536 -288.325614)
			(xy 196.018493 -288.376396) (xy 196.002605 -288.425295) (xy 195.979262 -288.471107) (xy 195.949041 -288.512703)
			(xy 195.912685 -288.549059) (xy 195.871089 -288.57928) (xy 195.825277 -288.602623) (xy 195.776378 -288.618511)
			(xy 195.725596 -288.626554) (xy 195.67418 -288.626554) (xy 195.623398 -288.618511) (xy 195.574499 -288.602623)
			(xy 195.528687 -288.57928) (xy 195.487091 -288.549059) (xy 195.450735 -288.512703) (xy 195.420514 -288.471107)
			(xy 195.397171 -288.425295) (xy 195.381283 -288.376396) (xy 195.37324 -288.325614) (xy 195.054562 -288.325614)
			(xy 195.046846 -288.37309) (xy 195.031262 -288.419771) (xy 195.008391 -288.463348) (xy 194.978826 -288.502692)
			(xy 194.943333 -288.536784) (xy 194.90283 -288.56474) (xy 194.858368 -288.585838) (xy 194.811097 -288.59953)
			(xy 194.762242 -288.605462) (xy 194.713067 -288.603481) (xy 194.664848 -288.593637) (xy 194.618832 -288.576185)
			(xy 194.576211 -288.551578) (xy 194.53809 -288.520453) (xy 194.505455 -288.483616) (xy 194.479152 -288.44202)
			(xy 194.459861 -288.396744) (xy 194.448084 -288.34896) (xy 194.444124 -288.299906) (xy 194.105276 -288.299906)
			(xy 194.104781 -288.324513) (xy 194.096886 -288.37309) (xy 194.081302 -288.419771) (xy 194.058431 -288.463348)
			(xy 194.028866 -288.502692) (xy 193.993373 -288.536784) (xy 193.95287 -288.56474) (xy 193.908408 -288.585838)
			(xy 193.861137 -288.59953) (xy 193.812282 -288.605462) (xy 193.763107 -288.603481) (xy 193.714888 -288.593637)
			(xy 193.668872 -288.576185) (xy 193.626251 -288.551578) (xy 193.58813 -288.520453) (xy 193.555495 -288.483616)
			(xy 193.529192 -288.44202) (xy 193.509901 -288.396744) (xy 193.498124 -288.34896) (xy 193.494164 -288.299906)
			(xy 193.155316 -288.299906) (xy 193.154821 -288.324513) (xy 193.146926 -288.37309) (xy 193.131342 -288.419771)
			(xy 193.108471 -288.463348) (xy 193.078906 -288.502692) (xy 193.043413 -288.536784) (xy 193.00291 -288.56474)
			(xy 192.958448 -288.585838) (xy 192.911177 -288.59953) (xy 192.862322 -288.605462) (xy 192.813147 -288.603481)
			(xy 192.764928 -288.593637) (xy 192.718912 -288.576185) (xy 192.676291 -288.551578) (xy 192.63817 -288.520453)
			(xy 192.605535 -288.483616) (xy 192.579232 -288.44202) (xy 192.559941 -288.396744) (xy 192.548164 -288.34896)
			(xy 192.544204 -288.299906) (xy 192.205356 -288.299906) (xy 192.204861 -288.324513) (xy 192.196966 -288.37309)
			(xy 192.181382 -288.419771) (xy 192.158511 -288.463348) (xy 192.128946 -288.502692) (xy 192.093453 -288.536784)
			(xy 192.05295 -288.56474) (xy 192.008488 -288.585838) (xy 191.961217 -288.59953) (xy 191.912362 -288.605462)
			(xy 191.863187 -288.603481) (xy 191.814968 -288.593637) (xy 191.768952 -288.576185) (xy 191.726331 -288.551578)
			(xy 191.68821 -288.520453) (xy 191.655575 -288.483616) (xy 191.629272 -288.44202) (xy 191.609981 -288.396744)
			(xy 191.598204 -288.34896) (xy 191.594244 -288.299906) (xy 191.255396 -288.299906) (xy 191.254901 -288.324513)
			(xy 191.247006 -288.37309) (xy 191.231422 -288.419771) (xy 191.208551 -288.463348) (xy 191.178986 -288.502692)
			(xy 191.143493 -288.536784) (xy 191.10299 -288.56474) (xy 191.058528 -288.585838) (xy 191.011257 -288.59953)
			(xy 190.962402 -288.605462) (xy 190.913227 -288.603481) (xy 190.865008 -288.593637) (xy 190.818992 -288.576185)
			(xy 190.776371 -288.551578) (xy 190.73825 -288.520453) (xy 190.705615 -288.483616) (xy 190.679312 -288.44202)
			(xy 190.660021 -288.396744) (xy 190.648244 -288.34896) (xy 190.644284 -288.299906) (xy 190.305182 -288.299906)
			(xy 190.304687 -288.324513) (xy 190.296792 -288.37309) (xy 190.281208 -288.419771) (xy 190.258337 -288.463348)
			(xy 190.228772 -288.502692) (xy 190.193279 -288.536784) (xy 190.152776 -288.56474) (xy 190.108314 -288.585838)
			(xy 190.061043 -288.59953) (xy 190.012188 -288.605462) (xy 189.963013 -288.603481) (xy 189.914794 -288.593637)
			(xy 189.868778 -288.576185) (xy 189.826157 -288.551578) (xy 189.788036 -288.520453) (xy 189.755401 -288.483616)
			(xy 189.729098 -288.44202) (xy 189.709807 -288.396744) (xy 189.69803 -288.34896) (xy 189.69407 -288.299906)
			(xy 185.525156 -288.299906) (xy 185.525156 -288.353754) (xy 185.525736 -288.364954) (xy 185.535215 -288.385251)
			(xy 185.543444 -288.39287) (xy 185.543952 -288.393378) (xy 185.616088 -288.450528) (xy 185.63844 -288.455608)
			(xy 185.64987 -288.452814) (xy 185.668338 -288.448771) (xy 185.705897 -288.444448) (xy 185.7248 -288.444178)
			(xy 185.725054 -288.444178) (xy 185.751047 -288.444658) (xy 185.802393 -288.452784) (xy 185.851836 -288.468842)
			(xy 185.898157 -288.492439) (xy 185.940217 -288.522991) (xy 185.976979 -288.559748) (xy 186.007537 -288.601803)
			(xy 186.03114 -288.648122) (xy 186.047206 -288.697562) (xy 186.055339 -288.748907) (xy 186.055339 -288.774886)
			(xy 186.36921 -288.774886) (xy 186.37317 -288.725832) (xy 186.384947 -288.678048) (xy 186.404238 -288.632772)
			(xy 186.430541 -288.591176) (xy 186.463176 -288.554339) (xy 186.501297 -288.523214) (xy 186.543918 -288.498607)
			(xy 186.589934 -288.481155) (xy 186.638153 -288.471311) (xy 186.687328 -288.46933) (xy 186.736183 -288.475262)
			(xy 186.783454 -288.488954) (xy 186.827916 -288.510052) (xy 186.868419 -288.538008) (xy 186.903912 -288.5721)
			(xy 186.933477 -288.611444) (xy 186.956348 -288.655021) (xy 186.971932 -288.701702) (xy 186.979827 -288.750279)
			(xy 186.980322 -288.774886) (xy 187.31917 -288.774886) (xy 187.32313 -288.725832) (xy 187.334907 -288.678048)
			(xy 187.354198 -288.632772) (xy 187.380501 -288.591176) (xy 187.413136 -288.554339) (xy 187.451257 -288.523214)
			(xy 187.493878 -288.498607) (xy 187.539894 -288.481155) (xy 187.588113 -288.471311) (xy 187.637288 -288.46933)
			(xy 187.686143 -288.475262) (xy 187.733414 -288.488954) (xy 187.777876 -288.510052) (xy 187.818379 -288.538008)
			(xy 187.853872 -288.5721) (xy 187.883437 -288.611444) (xy 187.906308 -288.655021) (xy 187.921892 -288.701702)
			(xy 187.929787 -288.750279) (xy 187.930282 -288.774886) (xy 188.26913 -288.774886) (xy 188.27309 -288.725832)
			(xy 188.284867 -288.678048) (xy 188.304158 -288.632772) (xy 188.330461 -288.591176) (xy 188.363096 -288.554339)
			(xy 188.401217 -288.523214) (xy 188.443838 -288.498607) (xy 188.489854 -288.481155) (xy 188.538073 -288.471311)
			(xy 188.587248 -288.46933) (xy 188.636103 -288.475262) (xy 188.683374 -288.488954) (xy 188.727836 -288.510052)
			(xy 188.768339 -288.538008) (xy 188.803832 -288.5721) (xy 188.833397 -288.611444) (xy 188.856268 -288.655021)
			(xy 188.871852 -288.701702) (xy 188.879747 -288.750279) (xy 188.880242 -288.774886) (xy 188.879747 -288.799493)
			(xy 188.871852 -288.84807) (xy 188.856268 -288.894751) (xy 188.833397 -288.938328) (xy 188.803832 -288.977672)
			(xy 188.768339 -289.011764) (xy 188.727836 -289.03972) (xy 188.683374 -289.060818) (xy 188.636103 -289.07451)
			(xy 188.587248 -289.080442) (xy 188.538073 -289.078461) (xy 188.489854 -289.068617) (xy 188.443838 -289.051165)
			(xy 188.401217 -289.026558) (xy 188.363096 -288.995433) (xy 188.330461 -288.958596) (xy 188.304158 -288.917)
			(xy 188.284867 -288.871724) (xy 188.27309 -288.82394) (xy 188.26913 -288.774886) (xy 187.930282 -288.774886)
			(xy 187.929787 -288.799493) (xy 187.921892 -288.84807) (xy 187.906308 -288.894751) (xy 187.883437 -288.938328)
			(xy 187.853872 -288.977672) (xy 187.818379 -289.011764) (xy 187.777876 -289.03972) (xy 187.733414 -289.060818)
			(xy 187.686143 -289.07451) (xy 187.637288 -289.080442) (xy 187.588113 -289.078461) (xy 187.539894 -289.068617)
			(xy 187.493878 -289.051165) (xy 187.451257 -289.026558) (xy 187.413136 -288.995433) (xy 187.380501 -288.958596)
			(xy 187.354198 -288.917) (xy 187.334907 -288.871724) (xy 187.32313 -288.82394) (xy 187.31917 -288.774886)
			(xy 186.980322 -288.774886) (xy 186.979827 -288.799493) (xy 186.971932 -288.84807) (xy 186.956348 -288.894751)
			(xy 186.933477 -288.938328) (xy 186.903912 -288.977672) (xy 186.868419 -289.011764) (xy 186.827916 -289.03972)
			(xy 186.783454 -289.060818) (xy 186.736183 -289.07451) (xy 186.687328 -289.080442) (xy 186.638153 -289.078461)
			(xy 186.589934 -289.068617) (xy 186.543918 -289.051165) (xy 186.501297 -289.026558) (xy 186.463176 -288.995433)
			(xy 186.430541 -288.958596) (xy 186.404238 -288.917) (xy 186.384947 -288.871724) (xy 186.37317 -288.82394)
			(xy 186.36921 -288.774886) (xy 186.055339 -288.774886) (xy 186.055339 -288.800893) (xy 186.047206 -288.852238)
			(xy 186.03114 -288.901678) (xy 186.007537 -288.947997) (xy 185.976979 -288.990052) (xy 185.940217 -289.026809)
			(xy 185.898157 -289.057361) (xy 185.851836 -289.080958) (xy 185.802393 -289.097016) (xy 185.751047 -289.105142)
			(xy 185.725054 -289.105594) (xy 185.7248 -289.105594) (xy 185.705898 -289.105305) (xy 185.668343 -289.100972)
			(xy 185.64987 -289.096958) (xy 185.63844 -289.094164) (xy 185.616088 -289.099244) (xy 185.54446 -289.15614)
			(xy 185.535741 -289.163716) (xy 185.525678 -289.18448) (xy 185.525156 -289.196018) (xy 185.525156 -289.303714)
			(xy 185.525748 -289.314908) (xy 185.535243 -289.335186) (xy 185.543444 -289.34283) (xy 185.543952 -289.343338)
			(xy 185.616088 -289.400488) (xy 185.63844 -289.405568) (xy 185.64987 -289.402774) (xy 185.668338 -289.398732)
			(xy 185.705897 -289.394409) (xy 185.7248 -289.394138) (xy 185.725054 -289.394138) (xy 185.751042 -289.394618)
			(xy 185.802379 -289.402742) (xy 185.851813 -289.418798) (xy 185.898126 -289.44239) (xy 185.940178 -289.472937)
			(xy 185.976933 -289.509687) (xy 186.007486 -289.551735) (xy 186.031084 -289.598045) (xy 186.047147 -289.647476)
			(xy 186.055279 -289.698812) (xy 186.055279 -289.724846) (xy 186.36921 -289.724846) (xy 186.37317 -289.675792)
			(xy 186.384947 -289.628008) (xy 186.404238 -289.582732) (xy 186.430541 -289.541136) (xy 186.463176 -289.504299)
			(xy 186.501297 -289.473174) (xy 186.543918 -289.448567) (xy 186.589934 -289.431115) (xy 186.638153 -289.421271)
			(xy 186.687328 -289.41929) (xy 186.736183 -289.425222) (xy 186.783454 -289.438914) (xy 186.827916 -289.460012)
			(xy 186.868419 -289.487968) (xy 186.903912 -289.52206) (xy 186.933477 -289.561404) (xy 186.956348 -289.604981)
			(xy 186.971932 -289.651662) (xy 186.979827 -289.700239) (xy 186.980322 -289.724846) (xy 187.31917 -289.724846)
			(xy 187.32313 -289.675792) (xy 187.334907 -289.628008) (xy 187.354198 -289.582732) (xy 187.380501 -289.541136)
			(xy 187.413136 -289.504299) (xy 187.451257 -289.473174) (xy 187.493878 -289.448567) (xy 187.539894 -289.431115)
			(xy 187.588113 -289.421271) (xy 187.637288 -289.41929) (xy 187.686143 -289.425222) (xy 187.733414 -289.438914)
			(xy 187.777876 -289.460012) (xy 187.818379 -289.487968) (xy 187.853872 -289.52206) (xy 187.883437 -289.561404)
			(xy 187.906308 -289.604981) (xy 187.921892 -289.651662) (xy 187.929787 -289.700239) (xy 187.930282 -289.724846)
			(xy 188.26913 -289.724846) (xy 188.27309 -289.675792) (xy 188.284867 -289.628008) (xy 188.304158 -289.582732)
			(xy 188.330461 -289.541136) (xy 188.363096 -289.504299) (xy 188.401217 -289.473174) (xy 188.443838 -289.448567)
			(xy 188.489854 -289.431115) (xy 188.538073 -289.421271) (xy 188.587248 -289.41929) (xy 188.636103 -289.425222)
			(xy 188.683374 -289.438914) (xy 188.727836 -289.460012) (xy 188.768339 -289.487968) (xy 188.803832 -289.52206)
			(xy 188.833397 -289.561404) (xy 188.856268 -289.604981) (xy 188.871852 -289.651662) (xy 188.879747 -289.700239)
			(xy 188.880074 -289.716508) (xy 189.219227 -289.716508) (xy 189.224595 -289.667167) (xy 189.237875 -289.619344)
			(xy 189.258716 -289.574299) (xy 189.28657 -289.53322) (xy 189.320702 -289.497187) (xy 189.360214 -289.467151)
			(xy 189.404065 -289.443903) (xy 189.451099 -289.428054) (xy 189.500078 -289.420024) (xy 189.524894 -289.419538)
			(xy 189.539077 -289.419715) (xy 189.567317 -289.422387) (xy 189.581282 -289.424872) (xy 189.593728 -289.427158)
			(xy 189.61735 -289.419792) (xy 189.69482 -289.342322) (xy 189.702186 -289.3187) (xy 189.6999 -289.306254)
			(xy 189.697421 -289.292289) (xy 189.694751 -289.264049) (xy 189.694566 -289.249866) (xy 189.695088 -289.224611)
			(xy 189.703401 -289.174789) (xy 189.719802 -289.127015) (xy 189.743843 -289.082592) (xy 189.774867 -289.042732)
			(xy 189.812029 -289.008522) (xy 189.854315 -288.980896) (xy 189.900571 -288.960606) (xy 189.949536 -288.948206)
			(xy 189.999874 -288.944035) (xy 190.050212 -288.948206) (xy 190.099177 -288.960606) (xy 190.145433 -288.980896)
			(xy 190.187719 -289.008522) (xy 190.224881 -289.042732) (xy 190.255905 -289.082592) (xy 190.279946 -289.127015)
			(xy 190.296347 -289.174789) (xy 190.30466 -289.224611) (xy 190.305182 -289.249866) (xy 190.305001 -289.264049)
			(xy 190.302332 -289.292289) (xy 190.299848 -289.306254) (xy 190.297562 -289.3187) (xy 190.304928 -289.342576)
			(xy 190.382144 -289.419792) (xy 190.406274 -289.427158) (xy 190.418466 -289.424872) (xy 190.432494 -289.422381)
			(xy 190.460862 -289.419713) (xy 190.475108 -289.419538) (xy 190.499927 -289.419986) (xy 190.548912 -289.428018)
			(xy 190.595952 -289.443868) (xy 190.639808 -289.46712) (xy 190.679325 -289.49716) (xy 190.713461 -289.533197)
			(xy 190.741318 -289.574282) (xy 190.762162 -289.619332) (xy 190.775442 -289.667161) (xy 190.780811 -289.716509)
			(xy 190.780359 -289.724846) (xy 192.069224 -289.724846) (xy 192.073184 -289.675792) (xy 192.084961 -289.628008)
			(xy 192.104252 -289.582732) (xy 192.130555 -289.541136) (xy 192.16319 -289.504299) (xy 192.201311 -289.473174)
			(xy 192.243932 -289.448567) (xy 192.289948 -289.431115) (xy 192.338167 -289.421271) (xy 192.387342 -289.41929)
			(xy 192.436197 -289.425222) (xy 192.483468 -289.438914) (xy 192.52793 -289.460012) (xy 192.568433 -289.487968)
			(xy 192.603926 -289.52206) (xy 192.633491 -289.561404) (xy 192.656362 -289.604981) (xy 192.671946 -289.651662)
			(xy 192.679841 -289.700239) (xy 192.680336 -289.724846) (xy 193.019184 -289.724846) (xy 193.023144 -289.675792)
			(xy 193.034921 -289.628008) (xy 193.054212 -289.582732) (xy 193.080515 -289.541136) (xy 193.11315 -289.504299)
			(xy 193.151271 -289.473174) (xy 193.193892 -289.448567) (xy 193.239908 -289.431115) (xy 193.288127 -289.421271)
			(xy 193.337302 -289.41929) (xy 193.386157 -289.425222) (xy 193.433428 -289.438914) (xy 193.47789 -289.460012)
			(xy 193.518393 -289.487968) (xy 193.553886 -289.52206) (xy 193.583451 -289.561404) (xy 193.606322 -289.604981)
			(xy 193.621906 -289.651662) (xy 193.629801 -289.700239) (xy 193.630296 -289.724846) (xy 193.969144 -289.724846)
			(xy 193.973104 -289.675792) (xy 193.984881 -289.628008) (xy 194.004172 -289.582732) (xy 194.030475 -289.541136)
			(xy 194.06311 -289.504299) (xy 194.101231 -289.473174) (xy 194.143852 -289.448567) (xy 194.189868 -289.431115)
			(xy 194.238087 -289.421271) (xy 194.287262 -289.41929) (xy 194.336117 -289.425222) (xy 194.383388 -289.438914)
			(xy 194.42785 -289.460012) (xy 194.468353 -289.487968) (xy 194.503846 -289.52206) (xy 194.533411 -289.561404)
			(xy 194.556282 -289.604981) (xy 194.571866 -289.651662) (xy 194.579761 -289.700239) (xy 194.580088 -289.716499)
			(xy 194.919228 -289.716499) (xy 194.924597 -289.667157) (xy 194.937878 -289.619334) (xy 194.958721 -289.57429)
			(xy 194.986577 -289.533211) (xy 195.020711 -289.497179) (xy 195.060225 -289.467144) (xy 195.104077 -289.443897)
			(xy 195.151112 -289.428051) (xy 195.200092 -289.420023) (xy 195.224908 -289.419538) (xy 195.239091 -289.419713)
			(xy 195.267331 -289.422386) (xy 195.281296 -289.424872) (xy 195.293742 -289.427158) (xy 195.317364 -289.419792)
			(xy 195.394834 -289.342322) (xy 195.4022 -289.3187) (xy 195.399914 -289.306254) (xy 195.397435 -289.292288)
			(xy 195.394765 -289.264049) (xy 195.39458 -289.249866) (xy 195.395102 -289.224611) (xy 195.403415 -289.174789)
			(xy 195.419816 -289.127015) (xy 195.443857 -289.082592) (xy 195.474881 -289.042732) (xy 195.512043 -289.008522)
			(xy 195.554329 -288.980896) (xy 195.600585 -288.960606) (xy 195.64955 -288.948206) (xy 195.699888 -288.944035)
			(xy 195.750226 -288.948206) (xy 195.799191 -288.960606) (xy 195.845447 -288.980896) (xy 195.887733 -289.008522)
			(xy 195.924895 -289.042732) (xy 195.955919 -289.082592) (xy 195.957233 -289.08502) (xy 201.887834 -289.08502)
			(xy 201.891905 -289.029398) (xy 201.904031 -288.974961) (xy 201.923954 -288.92287) (xy 201.95125 -288.874235)
			(xy 201.985336 -288.830092) (xy 202.025485 -288.791383) (xy 202.070843 -288.758932) (xy 202.120443 -288.733431)
			(xy 202.173227 -288.715424) (xy 202.22807 -288.705294) (xy 202.283804 -288.703257) (xy 202.339241 -288.709357)
			(xy 202.393198 -288.723463) (xy 202.444527 -288.745275) (xy 202.492133 -288.774329) (xy 202.535001 -288.810004)
			(xy 202.553604 -288.830766) (xy 209.253072 -288.830766) (xy 209.257143 -288.775144) (xy 209.269269 -288.720707)
			(xy 209.289192 -288.668616) (xy 209.316488 -288.619981) (xy 209.350574 -288.575838) (xy 209.390723 -288.537129)
			(xy 209.436081 -288.504678) (xy 209.485681 -288.479177) (xy 209.538465 -288.46117) (xy 209.593308 -288.45104)
			(xy 209.649042 -288.449003) (xy 209.704479 -288.455103) (xy 209.758436 -288.469209) (xy 209.809765 -288.491021)
			(xy 209.857371 -288.520075) (xy 209.900239 -288.55575) (xy 209.937456 -288.597287) (xy 209.968229 -288.6438)
			(xy 209.984942 -288.679453) (xy 227.781559 -288.679453) (xy 227.781559 -288.624947) (xy 227.789317 -288.570995)
			(xy 227.804673 -288.518697) (xy 227.827316 -288.469117) (xy 227.856785 -288.423264) (xy 227.89248 -288.382071)
			(xy 227.933673 -288.346378) (xy 227.979527 -288.31691) (xy 228.029108 -288.294269) (xy 228.081407 -288.278914)
			(xy 228.135359 -288.271159) (xy 228.162612 -288.270696) (xy 228.189216 -288.271137) (xy 228.24191 -288.278521)
			(xy 228.293065 -288.293156) (xy 228.34169 -288.31476) (xy 228.38684 -288.342913) (xy 228.427639 -288.377068)
			(xy 228.463295 -288.416562) (xy 228.478588 -288.438336) (xy 228.486079 -288.448296) (xy 228.508053 -288.460003)
			(xy 228.520498 -288.460688) (xy 228.604826 -288.460688) (xy 228.617276 -288.460012) (xy 228.639254 -288.448307)
			(xy 228.646736 -288.438336) (xy 228.662058 -288.416586) (xy 228.69772 -288.377106) (xy 228.738519 -288.342962)
			(xy 228.783664 -288.314814) (xy 228.832281 -288.293208) (xy 228.883427 -288.278563) (xy 228.936111 -288.271163)
			(xy 228.962712 -288.270696) (xy 228.991375 -288.271229) (xy 229.048055 -288.279806) (xy 229.102814 -288.296764)
			(xy 229.154421 -288.321724) (xy 229.178358 -288.337498) (xy 229.186994 -288.34334) (xy 229.206298 -288.347404)
			(xy 229.296722 -288.330894) (xy 229.313232 -288.320226) (xy 229.319074 -288.311844) (xy 229.334965 -288.289939)
			(xy 229.371937 -288.25042) (xy 229.392734 -288.233104) (xy 229.40264 -288.22523) (xy 229.412292 -288.203386)
			(xy 229.406958 -288.096452) (xy 229.39502 -288.075624) (xy 229.384606 -288.068766) (xy 229.362139 -288.053604)
			(xy 229.321344 -288.017916) (xy 229.286012 -287.976814) (xy 229.256852 -287.931124) (xy 229.234454 -287.881767)
			(xy 229.219267 -287.829737) (xy 229.211598 -287.776081) (xy 229.211124 -287.74898) (xy 229.21161 -287.721729)
			(xy 229.219366 -287.667781) (xy 229.234721 -287.615486) (xy 229.257363 -287.565909) (xy 229.286829 -287.520059)
			(xy 229.32252 -287.478868) (xy 229.363711 -287.443177) (xy 229.409561 -287.413711) (xy 229.459138 -287.391069)
			(xy 229.511433 -287.375714) (xy 229.565381 -287.367958) (xy 229.619883 -287.367958) (xy 229.673831 -287.375714)
			(xy 229.726126 -287.391069) (xy 229.775703 -287.413711) (xy 229.821553 -287.443177) (xy 229.862744 -287.478868)
			(xy 229.898435 -287.520059) (xy 229.927901 -287.565909) (xy 229.950543 -287.615486) (xy 229.965898 -287.667781)
			(xy 229.973654 -287.721729) (xy 229.97414 -287.74898) (xy 229.97358 -287.777382) (xy 229.965173 -287.83356)
			(xy 229.948526 -287.887869) (xy 229.924009 -287.939109) (xy 229.892163 -287.986146) (xy 229.853694 -288.02794)
			(xy 229.8319 -288.04616) (xy 229.821994 -288.054034) (xy 229.812342 -288.075878) (xy 229.817676 -288.182812)
			(xy 229.829614 -288.20364) (xy 229.840028 -288.210498) (xy 229.862464 -288.225705) (xy 229.903262 -288.261383)
			(xy 229.938599 -288.302476) (xy 229.967763 -288.348158) (xy 229.990167 -288.397509) (xy 230.005359 -288.449534)
			(xy 230.013033 -288.503185) (xy 230.01351 -288.530284) (xy 230.01303 -288.557536) (xy 230.005275 -288.611487)
			(xy 229.989921 -288.663784) (xy 229.967281 -288.713364) (xy 229.937815 -288.759217) (xy 229.902123 -288.80041)
			(xy 229.860931 -288.836104) (xy 229.81508 -288.865572) (xy 229.765501 -288.888215) (xy 229.713204 -288.903571)
			(xy 229.659254 -288.911329) (xy 229.632002 -288.911792) (xy 229.603339 -288.911254) (xy 229.546659 -288.902679)
			(xy 229.4919 -288.885722) (xy 229.440293 -288.860764) (xy 229.416356 -288.84499) (xy 229.40772 -288.839148)
			(xy 229.388416 -288.835084) (xy 229.297992 -288.851594) (xy 229.281482 -288.862262) (xy 229.27564 -288.870644)
			(xy 229.260267 -288.89188) (xy 229.224637 -288.930334) (xy 229.18408 -288.963553) (xy 229.139359 -288.99091)
			(xy 229.091317 -289.011892) (xy 229.040855 -289.026103) (xy 228.988924 -289.033277) (xy 228.962712 -289.033712)
			(xy 228.936109 -289.033249) (xy 228.883416 -289.025869) (xy 228.832261 -289.011237) (xy 228.783636 -288.989636)
			(xy 228.738486 -288.961487) (xy 228.697686 -288.927336) (xy 228.66203 -288.887845) (xy 228.646736 -288.866072)
			(xy 228.639232 -288.856124) (xy 228.617268 -288.84441) (xy 228.604826 -288.84372) (xy 228.520498 -288.84372)
			(xy 228.508041 -288.844348) (xy 228.486064 -288.856087) (xy 228.478588 -288.866072) (xy 228.463316 -288.887859)
			(xy 228.427646 -288.927338) (xy 228.386838 -288.961479) (xy 228.341684 -288.989622) (xy 228.293059 -289.011222)
			(xy 228.241906 -289.025859) (xy 228.189215 -289.03325) (xy 228.162612 -289.033712) (xy 228.135359 -289.033241)
			(xy 228.081407 -289.025486) (xy 228.029108 -289.010131) (xy 227.979527 -288.98749) (xy 227.933673 -288.958022)
			(xy 227.89248 -288.922329) (xy 227.856785 -288.881136) (xy 227.827316 -288.835283) (xy 227.804673 -288.785703)
			(xy 227.789317 -288.733405) (xy 227.781559 -288.679453) (xy 209.984942 -288.679453) (xy 209.991901 -288.694297)
			(xy 210.007969 -288.747704) (xy 210.016089 -288.80288) (xy 210.016598 -288.830766) (xy 210.016089 -288.858652)
			(xy 210.007969 -288.913828) (xy 209.991901 -288.967235) (xy 209.968229 -289.017732) (xy 209.937456 -289.064245)
			(xy 209.900239 -289.105782) (xy 209.857371 -289.141457) (xy 209.809765 -289.170511) (xy 209.758436 -289.192323)
			(xy 209.704479 -289.206429) (xy 209.649042 -289.212529) (xy 209.593308 -289.210492) (xy 209.538465 -289.200362)
			(xy 209.485681 -289.182355) (xy 209.436081 -289.156854) (xy 209.390723 -289.124403) (xy 209.350574 -289.085694)
			(xy 209.316488 -289.041551) (xy 209.289192 -288.992916) (xy 209.269269 -288.940825) (xy 209.257143 -288.886388)
			(xy 209.253072 -288.830766) (xy 202.553604 -288.830766) (xy 202.572218 -288.851541) (xy 202.602991 -288.898054)
			(xy 202.626663 -288.948551) (xy 202.642731 -289.001958) (xy 202.650851 -289.057134) (xy 202.65136 -289.08502)
			(xy 202.650851 -289.112906) (xy 202.642731 -289.168082) (xy 202.626663 -289.221489) (xy 202.602991 -289.271986)
			(xy 202.572218 -289.318499) (xy 202.535001 -289.360036) (xy 202.492133 -289.395711) (xy 202.454715 -289.418547)
			(xy 218.298322 -289.418547) (xy 218.298322 -289.364053) (xy 218.306077 -289.310115) (xy 218.321429 -289.257829)
			(xy 218.344065 -289.208259) (xy 218.373525 -289.162416) (xy 218.409209 -289.121231) (xy 218.45039 -289.085544)
			(xy 218.496231 -289.05608) (xy 218.545799 -289.03344) (xy 218.598083 -289.018084) (xy 218.652021 -289.010324)
			(xy 218.679268 -289.009836) (xy 218.706638 -289.010312) (xy 218.760817 -289.018126) (xy 218.81332 -289.033612)
			(xy 218.863067 -289.056452) (xy 218.909034 -289.086175) (xy 218.929966 -289.103816) (xy 218.937078 -289.109912)
			(xy 218.954096 -289.116262) (xy 219.03944 -289.116262) (xy 219.056458 -289.109912) (xy 219.06357 -289.103816)
			(xy 219.084505 -289.08618) (xy 219.130476 -289.056467) (xy 219.180223 -289.03363) (xy 219.232724 -289.018139)
			(xy 219.286899 -289.01031) (xy 219.314268 -289.009836) (xy 219.341526 -289.010209) (xy 219.395486 -289.017963)
			(xy 219.447794 -289.033318) (xy 219.497384 -289.055961) (xy 219.543246 -289.085432) (xy 219.584448 -289.12113)
			(xy 219.620149 -289.162328) (xy 219.649623 -289.208188) (xy 219.672271 -289.257776) (xy 219.68763 -289.310083)
			(xy 219.695389 -289.364043) (xy 219.695389 -289.418546) (xy 220.259722 -289.418546) (xy 220.259722 -289.364054)
			(xy 220.267476 -289.310116) (xy 220.282828 -289.257831) (xy 220.305463 -289.208263) (xy 220.334922 -289.16242)
			(xy 220.370604 -289.121235) (xy 220.411784 -289.085548) (xy 220.457624 -289.056084) (xy 220.50719 -289.033443)
			(xy 220.559473 -289.018086) (xy 220.61341 -289.010325) (xy 220.640656 -289.009836) (xy 220.670778 -289.010438)
			(xy 220.730273 -289.019912) (xy 220.78754 -289.038616) (xy 220.841158 -289.066085) (xy 220.889794 -289.101636)
			(xy 220.91142 -289.122612) (xy 220.918532 -289.129978) (xy 220.937328 -289.137598) (xy 221.029784 -289.137598)
			(xy 221.04858 -289.129978) (xy 221.055692 -289.122612) (xy 221.077299 -289.101613) (xy 221.125933 -289.066046)
			(xy 221.179553 -289.03857) (xy 221.236828 -289.019866) (xy 221.29633 -289.010401) (xy 221.326456 -289.009836)
			(xy 221.353714 -289.010208) (xy 221.407676 -289.017961) (xy 221.459985 -289.033315) (xy 221.509577 -289.055957)
			(xy 221.555441 -289.085428) (xy 221.596643 -289.121125) (xy 221.632346 -289.162324) (xy 221.661822 -289.208185)
			(xy 221.68447 -289.257773) (xy 221.69983 -289.310081) (xy 221.707589 -289.364042) (xy 221.707589 -289.418558)
			(xy 221.69983 -289.472519) (xy 221.68447 -289.524827) (xy 221.661822 -289.574415) (xy 221.632346 -289.620276)
			(xy 221.596643 -289.661475) (xy 221.555441 -289.697172) (xy 221.509577 -289.726643) (xy 221.459985 -289.749285)
			(xy 221.407676 -289.764639) (xy 221.353714 -289.772392) (xy 221.326456 -289.772852) (xy 221.296334 -289.772245)
			(xy 221.236839 -289.762773) (xy 221.179572 -289.74407) (xy 221.125954 -289.716602) (xy 221.077318 -289.681051)
			(xy 221.055692 -289.660076) (xy 221.04858 -289.65271) (xy 221.029784 -289.64509) (xy 220.937328 -289.64509)
			(xy 220.918532 -289.65271) (xy 220.91142 -289.660076) (xy 220.889806 -289.681068) (xy 220.841174 -289.716635)
			(xy 220.787555 -289.744114) (xy 220.730283 -289.762819) (xy 220.670781 -289.772286) (xy 220.640656 -289.772852)
			(xy 220.61341 -289.772275) (xy 220.559473 -289.764514) (xy 220.50719 -289.749157) (xy 220.457624 -289.726516)
			(xy 220.411784 -289.697052) (xy 220.370604 -289.661365) (xy 220.334922 -289.62018) (xy 220.305463 -289.574337)
			(xy 220.282828 -289.524769) (xy 220.267476 -289.472484) (xy 220.259722 -289.418546) (xy 219.695389 -289.418546)
			(xy 219.695389 -289.418557) (xy 219.68763 -289.472517) (xy 219.672271 -289.524824) (xy 219.649623 -289.574412)
			(xy 219.620149 -289.620272) (xy 219.584448 -289.66147) (xy 219.543246 -289.697168) (xy 219.497384 -289.726639)
			(xy 219.447794 -289.749282) (xy 219.395486 -289.764637) (xy 219.341526 -289.772391) (xy 219.314268 -289.772852)
			(xy 219.286897 -289.772416) (xy 219.232716 -289.764593) (xy 219.180212 -289.749097) (xy 219.130465 -289.726249)
			(xy 219.0845 -289.696517) (xy 219.06357 -289.678872) (xy 219.056458 -289.672776) (xy 219.03944 -289.666426)
			(xy 218.954096 -289.666426) (xy 218.937078 -289.672776) (xy 218.929966 -289.678872) (xy 218.909016 -289.696489)
			(xy 218.863049 -289.726205) (xy 218.813306 -289.749046) (xy 218.760809 -289.764542) (xy 218.706636 -289.772375)
			(xy 218.679268 -289.772852) (xy 218.652021 -289.772276) (xy 218.598083 -289.764516) (xy 218.545799 -289.74916)
			(xy 218.496231 -289.72652) (xy 218.45039 -289.697056) (xy 218.409209 -289.661369) (xy 218.373525 -289.620184)
			(xy 218.344065 -289.574341) (xy 218.321429 -289.524771) (xy 218.306077 -289.472485) (xy 218.298322 -289.418547)
			(xy 202.454715 -289.418547) (xy 202.444527 -289.424765) (xy 202.393198 -289.446577) (xy 202.339241 -289.460683)
			(xy 202.283804 -289.466783) (xy 202.22807 -289.464746) (xy 202.173227 -289.454616) (xy 202.120443 -289.436609)
			(xy 202.070843 -289.411108) (xy 202.025485 -289.378657) (xy 201.985336 -289.339948) (xy 201.95125 -289.295805)
			(xy 201.923954 -289.24717) (xy 201.904031 -289.195079) (xy 201.891905 -289.140642) (xy 201.887834 -289.08502)
			(xy 195.957233 -289.08502) (xy 195.97996 -289.127015) (xy 195.996361 -289.174789) (xy 196.004674 -289.224611)
			(xy 196.005196 -289.249866) (xy 196.005015 -289.264049) (xy 196.002346 -289.292289) (xy 195.999862 -289.306254)
			(xy 195.997576 -289.3187) (xy 196.004942 -289.342322) (xy 196.082412 -289.419792) (xy 196.106034 -289.427158)
			(xy 196.11848 -289.424872) (xy 196.132445 -289.422388) (xy 196.160685 -289.419721) (xy 196.174868 -289.419538)
			(xy 196.199691 -289.419943) (xy 196.248685 -289.42797) (xy 196.295734 -289.443817) (xy 196.3396 -289.467067)
			(xy 196.379126 -289.497107) (xy 196.413272 -289.533147) (xy 196.441138 -289.574235) (xy 196.461989 -289.619291)
			(xy 196.475276 -289.667126) (xy 196.48065 -289.716481) (xy 196.480197 -289.724846) (xy 196.819278 -289.724846)
			(xy 196.823238 -289.675792) (xy 196.835015 -289.628008) (xy 196.854306 -289.582732) (xy 196.880609 -289.541136)
			(xy 196.913244 -289.504299) (xy 196.951365 -289.473174) (xy 196.993986 -289.448567) (xy 197.040002 -289.431115)
			(xy 197.088221 -289.421271) (xy 197.137396 -289.41929) (xy 197.186251 -289.425222) (xy 197.233522 -289.438914)
			(xy 197.277984 -289.460012) (xy 197.318487 -289.487968) (xy 197.35398 -289.52206) (xy 197.383545 -289.561404)
			(xy 197.406416 -289.604981) (xy 197.422 -289.651662) (xy 197.429895 -289.700239) (xy 197.43039 -289.724846)
			(xy 197.769238 -289.724846) (xy 197.773198 -289.675792) (xy 197.784975 -289.628008) (xy 197.804266 -289.582732)
			(xy 197.830569 -289.541136) (xy 197.863204 -289.504299) (xy 197.901325 -289.473174) (xy 197.943946 -289.448567)
			(xy 197.989962 -289.431115) (xy 198.038181 -289.421271) (xy 198.087356 -289.41929) (xy 198.136211 -289.425222)
			(xy 198.183482 -289.438914) (xy 198.227944 -289.460012) (xy 198.268447 -289.487968) (xy 198.30394 -289.52206)
			(xy 198.333505 -289.561404) (xy 198.356376 -289.604981) (xy 198.37196 -289.651662) (xy 198.379855 -289.700239)
			(xy 198.38035 -289.724846) (xy 198.719198 -289.724846) (xy 198.723158 -289.675792) (xy 198.734935 -289.628008)
			(xy 198.754226 -289.582732) (xy 198.780529 -289.541136) (xy 198.813164 -289.504299) (xy 198.851285 -289.473174)
			(xy 198.893906 -289.448567) (xy 198.939922 -289.431115) (xy 198.988141 -289.421271) (xy 199.037316 -289.41929)
			(xy 199.086171 -289.425222) (xy 199.133442 -289.438914) (xy 199.177904 -289.460012) (xy 199.218407 -289.487968)
			(xy 199.2539 -289.52206) (xy 199.283465 -289.561404) (xy 199.306336 -289.604981) (xy 199.32192 -289.651662)
			(xy 199.329815 -289.700239) (xy 199.33031 -289.724846) (xy 199.329815 -289.749453) (xy 199.32192 -289.79803)
			(xy 199.306336 -289.844711) (xy 199.283465 -289.888288) (xy 199.2539 -289.927632) (xy 199.218407 -289.961724)
			(xy 199.177904 -289.98968) (xy 199.133442 -290.010778) (xy 199.086171 -290.02447) (xy 199.037316 -290.030402)
			(xy 198.988141 -290.028421) (xy 198.939922 -290.018577) (xy 198.893906 -290.001125) (xy 198.851285 -289.976518)
			(xy 198.813164 -289.945393) (xy 198.780529 -289.908556) (xy 198.754226 -289.86696) (xy 198.734935 -289.821684)
			(xy 198.723158 -289.7739) (xy 198.719198 -289.724846) (xy 198.38035 -289.724846) (xy 198.379855 -289.749453)
			(xy 198.37196 -289.79803) (xy 198.356376 -289.844711) (xy 198.333505 -289.888288) (xy 198.30394 -289.927632)
			(xy 198.268447 -289.961724) (xy 198.227944 -289.98968) (xy 198.183482 -290.010778) (xy 198.136211 -290.02447)
			(xy 198.087356 -290.030402) (xy 198.038181 -290.028421) (xy 197.989962 -290.018577) (xy 197.943946 -290.001125)
			(xy 197.901325 -289.976518) (xy 197.863204 -289.945393) (xy 197.830569 -289.908556) (xy 197.804266 -289.86696)
			(xy 197.784975 -289.821684) (xy 197.773198 -289.7739) (xy 197.769238 -289.724846) (xy 197.43039 -289.724846)
			(xy 197.429895 -289.749453) (xy 197.422 -289.79803) (xy 197.406416 -289.844711) (xy 197.383545 -289.888288)
			(xy 197.35398 -289.927632) (xy 197.318487 -289.961724) (xy 197.277984 -289.98968) (xy 197.233522 -290.010778)
			(xy 197.186251 -290.02447) (xy 197.137396 -290.030402) (xy 197.088221 -290.028421) (xy 197.040002 -290.018577)
			(xy 196.993986 -290.001125) (xy 196.951365 -289.976518) (xy 196.913244 -289.945393) (xy 196.880609 -289.908556)
			(xy 196.854306 -289.86696) (xy 196.835015 -289.821684) (xy 196.823238 -289.7739) (xy 196.819278 -289.724846)
			(xy 196.480197 -289.724846) (xy 196.477968 -289.766055) (xy 196.467301 -289.814542) (xy 196.448931 -289.860664)
			(xy 196.423341 -289.903207) (xy 196.391205 -289.94105) (xy 196.353371 -289.973195) (xy 196.310834 -289.998796)
			(xy 196.264716 -290.017178) (xy 196.216232 -290.027857) (xy 196.166659 -290.030552) (xy 196.117303 -290.025191)
			(xy 196.069464 -290.011916) (xy 196.024403 -289.991076) (xy 195.983308 -289.963221) (xy 195.94726 -289.929084)
			(xy 195.917209 -289.889565) (xy 195.893948 -289.845706) (xy 195.878089 -289.79866) (xy 195.87005 -289.749669)
			(xy 195.86956 -289.724846) (xy 195.869744 -289.710663) (xy 195.872411 -289.682423) (xy 195.874894 -289.668458)
			(xy 195.87718 -289.656012) (xy 195.869814 -289.63239) (xy 195.792344 -289.55492) (xy 195.768722 -289.547554)
			(xy 195.756276 -289.54984) (xy 195.74231 -289.552315) (xy 195.71407 -289.554988) (xy 195.699888 -289.555174)
			(xy 195.685705 -289.555) (xy 195.657465 -289.552326) (xy 195.6435 -289.54984) (xy 195.631054 -289.547554)
			(xy 195.607432 -289.55492) (xy 195.529962 -289.63239) (xy 195.522596 -289.656012) (xy 195.524882 -289.668458)
			(xy 195.527362 -289.682423) (xy 195.530032 -289.710663) (xy 195.530216 -289.724846) (xy 195.529673 -289.749662)
			(xy 195.521636 -289.79864) (xy 195.505781 -289.845673) (xy 195.482527 -289.889521) (xy 195.452485 -289.929029)
			(xy 195.416447 -289.963157) (xy 195.375363 -289.991005) (xy 195.330315 -290.01184) (xy 195.282489 -290.025113)
			(xy 195.233147 -290.030474) (xy 195.183587 -290.027781) (xy 195.135116 -290.017107) (xy 195.08901 -289.998731)
			(xy 195.046484 -289.973139) (xy 195.008658 -289.941004) (xy 194.97653 -289.903172) (xy 194.950945 -289.860642)
			(xy 194.932577 -289.814533) (xy 194.921911 -289.766059) (xy 194.919228 -289.716499) (xy 194.580088 -289.716499)
			(xy 194.580256 -289.724846) (xy 194.579761 -289.749453) (xy 194.571866 -289.79803) (xy 194.556282 -289.844711)
			(xy 194.533411 -289.888288) (xy 194.503846 -289.927632) (xy 194.468353 -289.961724) (xy 194.42785 -289.98968)
			(xy 194.383388 -290.010778) (xy 194.336117 -290.02447) (xy 194.287262 -290.030402) (xy 194.238087 -290.028421)
			(xy 194.189868 -290.018577) (xy 194.143852 -290.001125) (xy 194.101231 -289.976518) (xy 194.06311 -289.945393)
			(xy 194.030475 -289.908556) (xy 194.004172 -289.86696) (xy 193.984881 -289.821684) (xy 193.973104 -289.7739)
			(xy 193.969144 -289.724846) (xy 193.630296 -289.724846) (xy 193.629801 -289.749453) (xy 193.621906 -289.79803)
			(xy 193.606322 -289.844711) (xy 193.583451 -289.888288) (xy 193.553886 -289.927632) (xy 193.518393 -289.961724)
			(xy 193.47789 -289.98968) (xy 193.433428 -290.010778) (xy 193.386157 -290.02447) (xy 193.337302 -290.030402)
			(xy 193.288127 -290.028421) (xy 193.239908 -290.018577) (xy 193.193892 -290.001125) (xy 193.151271 -289.976518)
			(xy 193.11315 -289.945393) (xy 193.080515 -289.908556) (xy 193.054212 -289.86696) (xy 193.034921 -289.821684)
			(xy 193.023144 -289.7739) (xy 193.019184 -289.724846) (xy 192.680336 -289.724846) (xy 192.679841 -289.749453)
			(xy 192.671946 -289.79803) (xy 192.656362 -289.844711) (xy 192.633491 -289.888288) (xy 192.603926 -289.927632)
			(xy 192.568433 -289.961724) (xy 192.52793 -289.98968) (xy 192.483468 -290.010778) (xy 192.436197 -290.02447)
			(xy 192.387342 -290.030402) (xy 192.338167 -290.028421) (xy 192.289948 -290.018577) (xy 192.243932 -290.001125)
			(xy 192.201311 -289.976518) (xy 192.16319 -289.945393) (xy 192.130555 -289.908556) (xy 192.104252 -289.86696)
			(xy 192.084961 -289.821684) (xy 192.073184 -289.7739) (xy 192.069224 -289.724846) (xy 190.780359 -289.724846)
			(xy 190.778125 -289.766075) (xy 190.767456 -289.814553) (xy 190.749085 -289.860667) (xy 190.723496 -289.903202)
			(xy 190.691363 -289.941036) (xy 190.653532 -289.973174) (xy 190.611001 -289.998768) (xy 190.564889 -290.017145)
			(xy 190.516412 -290.02782) (xy 190.466847 -290.030512) (xy 190.417499 -290.025149) (xy 190.369668 -290.011875)
			(xy 190.324615 -289.991037) (xy 190.283527 -289.963185) (xy 190.247485 -289.929053) (xy 190.21744 -289.88954)
			(xy 190.194183 -289.845687) (xy 190.178327 -289.798649) (xy 190.17029 -289.749665) (xy 190.1698 -289.724846)
			(xy 190.169983 -289.710663) (xy 190.172651 -289.682423) (xy 190.175134 -289.668458) (xy 190.17742 -289.656012)
			(xy 190.170054 -289.632136) (xy 190.092838 -289.55492) (xy 190.068708 -289.547554) (xy 190.056516 -289.54984)
			(xy 190.042486 -289.55232) (xy 190.01412 -289.554995) (xy 189.999874 -289.555174) (xy 189.985691 -289.555002)
			(xy 189.957451 -289.552327) (xy 189.943486 -289.54984) (xy 189.93104 -289.547554) (xy 189.907418 -289.55492)
			(xy 189.829948 -289.63239) (xy 189.822582 -289.656012) (xy 189.824868 -289.668458) (xy 189.827348 -289.682423)
			(xy 189.830018 -289.710663) (xy 189.830202 -289.724846) (xy 189.829673 -289.749662) (xy 189.821636 -289.79864)
			(xy 189.805782 -289.845672) (xy 189.782528 -289.88952) (xy 189.752486 -289.929028) (xy 189.716449 -289.963156)
			(xy 189.675366 -289.991004) (xy 189.630318 -290.011839) (xy 189.582493 -290.025112) (xy 189.533151 -290.030474)
			(xy 189.483592 -290.027782) (xy 189.435121 -290.017108) (xy 189.389015 -289.998734) (xy 189.346489 -289.973142)
			(xy 189.308663 -289.941008) (xy 189.276534 -289.903179) (xy 189.250948 -289.860649) (xy 189.23258 -289.814541)
			(xy 189.221913 -289.766068) (xy 189.219227 -289.716508) (xy 188.880074 -289.716508) (xy 188.880242 -289.724846)
			(xy 188.879747 -289.749453) (xy 188.871852 -289.79803) (xy 188.856268 -289.844711) (xy 188.833397 -289.888288)
			(xy 188.803832 -289.927632) (xy 188.768339 -289.961724) (xy 188.727836 -289.98968) (xy 188.683374 -290.010778)
			(xy 188.636103 -290.02447) (xy 188.587248 -290.030402) (xy 188.538073 -290.028421) (xy 188.489854 -290.018577)
			(xy 188.443838 -290.001125) (xy 188.401217 -289.976518) (xy 188.363096 -289.945393) (xy 188.330461 -289.908556)
			(xy 188.304158 -289.86696) (xy 188.284867 -289.821684) (xy 188.27309 -289.7739) (xy 188.26913 -289.724846)
			(xy 187.930282 -289.724846) (xy 187.929787 -289.749453) (xy 187.921892 -289.79803) (xy 187.906308 -289.844711)
			(xy 187.883437 -289.888288) (xy 187.853872 -289.927632) (xy 187.818379 -289.961724) (xy 187.777876 -289.98968)
			(xy 187.733414 -290.010778) (xy 187.686143 -290.02447) (xy 187.637288 -290.030402) (xy 187.588113 -290.028421)
			(xy 187.539894 -290.018577) (xy 187.493878 -290.001125) (xy 187.451257 -289.976518) (xy 187.413136 -289.945393)
			(xy 187.380501 -289.908556) (xy 187.354198 -289.86696) (xy 187.334907 -289.821684) (xy 187.32313 -289.7739)
			(xy 187.31917 -289.724846) (xy 186.980322 -289.724846) (xy 186.979827 -289.749453) (xy 186.971932 -289.79803)
			(xy 186.956348 -289.844711) (xy 186.933477 -289.888288) (xy 186.903912 -289.927632) (xy 186.868419 -289.961724)
			(xy 186.827916 -289.98968) (xy 186.783454 -290.010778) (xy 186.736183 -290.02447) (xy 186.687328 -290.030402)
			(xy 186.638153 -290.028421) (xy 186.589934 -290.018577) (xy 186.543918 -290.001125) (xy 186.501297 -289.976518)
			(xy 186.463176 -289.945393) (xy 186.430541 -289.908556) (xy 186.404238 -289.86696) (xy 186.384947 -289.821684)
			(xy 186.37317 -289.7739) (xy 186.36921 -289.724846) (xy 186.055279 -289.724846) (xy 186.055279 -289.750788)
			(xy 186.047147 -289.802124) (xy 186.031084 -289.851555) (xy 186.007486 -289.897865) (xy 185.976933 -289.939913)
			(xy 185.940178 -289.976663) (xy 185.898126 -290.00721) (xy 185.851813 -290.030802) (xy 185.802379 -290.046858)
			(xy 185.751042 -290.054982) (xy 185.725054 -290.055554) (xy 185.7248 -290.055554) (xy 185.705898 -290.055265)
			(xy 185.668343 -290.050932) (xy 185.64987 -290.046918) (xy 185.63844 -290.044124) (xy 185.616088 -290.049204)
			(xy 185.54446 -290.1061) (xy 185.535751 -290.11368) (xy 185.525712 -290.134445) (xy 185.525156 -290.145978)
			(xy 185.525156 -290.253674) (xy 185.52574 -290.264872) (xy 185.535225 -290.285163) (xy 185.543444 -290.29279)
			(xy 185.543952 -290.293298) (xy 185.616088 -290.350448) (xy 185.63844 -290.355528) (xy 185.64987 -290.352734)
			(xy 185.668338 -290.348691) (xy 185.705897 -290.344367) (xy 185.7248 -290.344098) (xy 185.725054 -290.344098)
			(xy 185.751045 -290.344578) (xy 185.802388 -290.352703) (xy 185.851828 -290.368761) (xy 185.898147 -290.392356)
			(xy 185.940204 -290.422907) (xy 185.976963 -290.459661) (xy 186.00752 -290.501714) (xy 186.031121 -290.548029)
			(xy 186.047186 -290.597467) (xy 186.055319 -290.648809) (xy 186.055319 -290.674806) (xy 186.36921 -290.674806)
			(xy 186.37317 -290.625752) (xy 186.384947 -290.577968) (xy 186.404238 -290.532692) (xy 186.430541 -290.491096)
			(xy 186.463176 -290.454259) (xy 186.501297 -290.423134) (xy 186.543918 -290.398527) (xy 186.589934 -290.381075)
			(xy 186.638153 -290.371231) (xy 186.687328 -290.36925) (xy 186.736183 -290.375182) (xy 186.783454 -290.388874)
			(xy 186.827916 -290.409972) (xy 186.868419 -290.437928) (xy 186.903912 -290.47202) (xy 186.933477 -290.511364)
			(xy 186.956348 -290.554941) (xy 186.971932 -290.601622) (xy 186.979827 -290.650199) (xy 186.980322 -290.674806)
			(xy 187.31917 -290.674806) (xy 187.32313 -290.625752) (xy 187.334907 -290.577968) (xy 187.354198 -290.532692)
			(xy 187.380501 -290.491096) (xy 187.413136 -290.454259) (xy 187.451257 -290.423134) (xy 187.493878 -290.398527)
			(xy 187.539894 -290.381075) (xy 187.588113 -290.371231) (xy 187.637288 -290.36925) (xy 187.686143 -290.375182)
			(xy 187.733414 -290.388874) (xy 187.777876 -290.409972) (xy 187.818379 -290.437928) (xy 187.853872 -290.47202)
			(xy 187.883437 -290.511364) (xy 187.906308 -290.554941) (xy 187.921892 -290.601622) (xy 187.929787 -290.650199)
			(xy 187.930282 -290.674806) (xy 188.26913 -290.674806) (xy 188.27309 -290.625752) (xy 188.284867 -290.577968)
			(xy 188.304158 -290.532692) (xy 188.330461 -290.491096) (xy 188.363096 -290.454259) (xy 188.401217 -290.423134)
			(xy 188.443838 -290.398527) (xy 188.489854 -290.381075) (xy 188.538073 -290.371231) (xy 188.587248 -290.36925)
			(xy 188.636103 -290.375182) (xy 188.683374 -290.388874) (xy 188.727836 -290.409972) (xy 188.768339 -290.437928)
			(xy 188.803832 -290.47202) (xy 188.833397 -290.511364) (xy 188.856268 -290.554941) (xy 188.871852 -290.601622)
			(xy 188.879747 -290.650199) (xy 188.880242 -290.674806) (xy 189.21909 -290.674806) (xy 189.22305 -290.625752)
			(xy 189.234827 -290.577968) (xy 189.254118 -290.532692) (xy 189.280421 -290.491096) (xy 189.313056 -290.454259)
			(xy 189.351177 -290.423134) (xy 189.393798 -290.398527) (xy 189.439814 -290.381075) (xy 189.488033 -290.371231)
			(xy 189.537208 -290.36925) (xy 189.586063 -290.375182) (xy 189.633334 -290.388874) (xy 189.677796 -290.409972)
			(xy 189.718299 -290.437928) (xy 189.753792 -290.47202) (xy 189.783357 -290.511364) (xy 189.806228 -290.554941)
			(xy 189.821812 -290.601622) (xy 189.829707 -290.650199) (xy 189.830202 -290.674806) (xy 190.16905 -290.674806)
			(xy 190.17301 -290.625752) (xy 190.184787 -290.577968) (xy 190.204078 -290.532692) (xy 190.230381 -290.491096)
			(xy 190.263016 -290.454259) (xy 190.301137 -290.423134) (xy 190.343758 -290.398527) (xy 190.389774 -290.381075)
			(xy 190.437993 -290.371231) (xy 190.487168 -290.36925) (xy 190.536023 -290.375182) (xy 190.583294 -290.388874)
			(xy 190.627756 -290.409972) (xy 190.668259 -290.437928) (xy 190.703752 -290.47202) (xy 190.733317 -290.511364)
			(xy 190.756188 -290.554941) (xy 190.771772 -290.601622) (xy 190.779667 -290.650199) (xy 190.780162 -290.674806)
			(xy 191.119264 -290.674806) (xy 191.123224 -290.625752) (xy 191.135001 -290.577968) (xy 191.154292 -290.532692)
			(xy 191.180595 -290.491096) (xy 191.21323 -290.454259) (xy 191.251351 -290.423134) (xy 191.293972 -290.398527)
			(xy 191.339988 -290.381075) (xy 191.388207 -290.371231) (xy 191.437382 -290.36925) (xy 191.486237 -290.375182)
			(xy 191.533508 -290.388874) (xy 191.57797 -290.409972) (xy 191.618473 -290.437928) (xy 191.653966 -290.47202)
			(xy 191.683531 -290.511364) (xy 191.706402 -290.554941) (xy 191.721986 -290.601622) (xy 191.729881 -290.650199)
			(xy 191.730376 -290.674806) (xy 192.069224 -290.674806) (xy 192.073184 -290.625752) (xy 192.084961 -290.577968)
			(xy 192.104252 -290.532692) (xy 192.130555 -290.491096) (xy 192.16319 -290.454259) (xy 192.201311 -290.423134)
			(xy 192.243932 -290.398527) (xy 192.289948 -290.381075) (xy 192.338167 -290.371231) (xy 192.387342 -290.36925)
			(xy 192.436197 -290.375182) (xy 192.483468 -290.388874) (xy 192.52793 -290.409972) (xy 192.568433 -290.437928)
			(xy 192.603926 -290.47202) (xy 192.633491 -290.511364) (xy 192.656362 -290.554941) (xy 192.671946 -290.601622)
			(xy 192.679841 -290.650199) (xy 192.680336 -290.674806) (xy 193.019184 -290.674806) (xy 193.023144 -290.625752)
			(xy 193.034921 -290.577968) (xy 193.054212 -290.532692) (xy 193.080515 -290.491096) (xy 193.11315 -290.454259)
			(xy 193.151271 -290.423134) (xy 193.193892 -290.398527) (xy 193.239908 -290.381075) (xy 193.288127 -290.371231)
			(xy 193.337302 -290.36925) (xy 193.386157 -290.375182) (xy 193.433428 -290.388874) (xy 193.47789 -290.409972)
			(xy 193.518393 -290.437928) (xy 193.553886 -290.47202) (xy 193.583451 -290.511364) (xy 193.606322 -290.554941)
			(xy 193.621906 -290.601622) (xy 193.629801 -290.650199) (xy 193.630296 -290.674806) (xy 193.969144 -290.674806)
			(xy 193.973104 -290.625752) (xy 193.984881 -290.577968) (xy 194.004172 -290.532692) (xy 194.030475 -290.491096)
			(xy 194.06311 -290.454259) (xy 194.101231 -290.423134) (xy 194.143852 -290.398527) (xy 194.189868 -290.381075)
			(xy 194.238087 -290.371231) (xy 194.287262 -290.36925) (xy 194.336117 -290.375182) (xy 194.383388 -290.388874)
			(xy 194.42785 -290.409972) (xy 194.468353 -290.437928) (xy 194.503846 -290.47202) (xy 194.533411 -290.511364)
			(xy 194.556282 -290.554941) (xy 194.571866 -290.601622) (xy 194.579761 -290.650199) (xy 194.580256 -290.674806)
			(xy 194.919104 -290.674806) (xy 194.923064 -290.625752) (xy 194.934841 -290.577968) (xy 194.954132 -290.532692)
			(xy 194.980435 -290.491096) (xy 195.01307 -290.454259) (xy 195.051191 -290.423134) (xy 195.093812 -290.398527)
			(xy 195.139828 -290.381075) (xy 195.188047 -290.371231) (xy 195.237222 -290.36925) (xy 195.286077 -290.375182)
			(xy 195.333348 -290.388874) (xy 195.37781 -290.409972) (xy 195.418313 -290.437928) (xy 195.453806 -290.47202)
			(xy 195.483371 -290.511364) (xy 195.506242 -290.554941) (xy 195.521826 -290.601622) (xy 195.529721 -290.650199)
			(xy 195.530216 -290.674806) (xy 195.869064 -290.674806) (xy 195.873024 -290.625752) (xy 195.884801 -290.577968)
			(xy 195.904092 -290.532692) (xy 195.930395 -290.491096) (xy 195.96303 -290.454259) (xy 196.001151 -290.423134)
			(xy 196.043772 -290.398527) (xy 196.089788 -290.381075) (xy 196.138007 -290.371231) (xy 196.187182 -290.36925)
			(xy 196.236037 -290.375182) (xy 196.283308 -290.388874) (xy 196.32777 -290.409972) (xy 196.368273 -290.437928)
			(xy 196.403766 -290.47202) (xy 196.433331 -290.511364) (xy 196.456202 -290.554941) (xy 196.471786 -290.601622)
			(xy 196.479681 -290.650199) (xy 196.480176 -290.674806) (xy 196.819278 -290.674806) (xy 196.823238 -290.625752)
			(xy 196.835015 -290.577968) (xy 196.854306 -290.532692) (xy 196.880609 -290.491096) (xy 196.913244 -290.454259)
			(xy 196.951365 -290.423134) (xy 196.993986 -290.398527) (xy 197.040002 -290.381075) (xy 197.088221 -290.371231)
			(xy 197.137396 -290.36925) (xy 197.186251 -290.375182) (xy 197.233522 -290.388874) (xy 197.277984 -290.409972)
			(xy 197.318487 -290.437928) (xy 197.35398 -290.47202) (xy 197.383545 -290.511364) (xy 197.406416 -290.554941)
			(xy 197.422 -290.601622) (xy 197.429895 -290.650199) (xy 197.43039 -290.674806) (xy 197.769238 -290.674806)
			(xy 197.773198 -290.625752) (xy 197.784975 -290.577968) (xy 197.804266 -290.532692) (xy 197.830569 -290.491096)
			(xy 197.863204 -290.454259) (xy 197.901325 -290.423134) (xy 197.943946 -290.398527) (xy 197.989962 -290.381075)
			(xy 198.038181 -290.371231) (xy 198.087356 -290.36925) (xy 198.136211 -290.375182) (xy 198.183482 -290.388874)
			(xy 198.227944 -290.409972) (xy 198.268447 -290.437928) (xy 198.30394 -290.47202) (xy 198.333505 -290.511364)
			(xy 198.356376 -290.554941) (xy 198.37196 -290.601622) (xy 198.379855 -290.650199) (xy 198.38035 -290.674806)
			(xy 198.719198 -290.674806) (xy 198.723158 -290.625752) (xy 198.734935 -290.577968) (xy 198.754226 -290.532692)
			(xy 198.780529 -290.491096) (xy 198.813164 -290.454259) (xy 198.851285 -290.423134) (xy 198.893906 -290.398527)
			(xy 198.939922 -290.381075) (xy 198.988141 -290.371231) (xy 199.037316 -290.36925) (xy 199.086171 -290.375182)
			(xy 199.133442 -290.388874) (xy 199.177904 -290.409972) (xy 199.19176 -290.419536) (xy 201.25385 -290.419536)
			(xy 201.257921 -290.363914) (xy 201.270047 -290.309477) (xy 201.28997 -290.257386) (xy 201.317266 -290.208751)
			(xy 201.351352 -290.164608) (xy 201.391501 -290.125899) (xy 201.436859 -290.093448) (xy 201.486459 -290.067947)
			(xy 201.539243 -290.04994) (xy 201.594086 -290.03981) (xy 201.64982 -290.037773) (xy 201.705257 -290.043873)
			(xy 201.759214 -290.057979) (xy 201.810543 -290.079791) (xy 201.858149 -290.108845) (xy 201.901017 -290.14452)
			(xy 201.938234 -290.186057) (xy 201.969007 -290.23257) (xy 201.971161 -290.237164) (xy 205.26451 -290.237164)
			(xy 205.268581 -290.181542) (xy 205.280707 -290.127105) (xy 205.30063 -290.075014) (xy 205.327926 -290.026379)
			(xy 205.362012 -289.982236) (xy 205.402161 -289.943527) (xy 205.447519 -289.911076) (xy 205.497119 -289.885575)
			(xy 205.549903 -289.867568) (xy 205.604746 -289.857438) (xy 205.66048 -289.855401) (xy 205.715917 -289.861501)
			(xy 205.769874 -289.875607) (xy 205.821203 -289.897419) (xy 205.868809 -289.926473) (xy 205.911677 -289.962148)
			(xy 205.948894 -290.003685) (xy 205.979667 -290.050198) (xy 206.003339 -290.100695) (xy 206.019407 -290.154102)
			(xy 206.027527 -290.209278) (xy 206.028036 -290.237164) (xy 206.027527 -290.26505) (xy 206.019407 -290.320226)
			(xy 206.003339 -290.373633) (xy 205.979667 -290.42413) (xy 205.948894 -290.470643) (xy 205.911677 -290.51218)
			(xy 205.868809 -290.547855) (xy 205.821203 -290.576909) (xy 205.769874 -290.598721) (xy 205.715917 -290.612827)
			(xy 205.66048 -290.618927) (xy 205.604746 -290.61689) (xy 205.549903 -290.60676) (xy 205.497119 -290.588753)
			(xy 205.447519 -290.563252) (xy 205.402161 -290.530801) (xy 205.362012 -290.492092) (xy 205.327926 -290.447949)
			(xy 205.30063 -290.399314) (xy 205.280707 -290.347223) (xy 205.268581 -290.292786) (xy 205.26451 -290.237164)
			(xy 201.971161 -290.237164) (xy 201.992679 -290.283067) (xy 202.008747 -290.336474) (xy 202.016867 -290.39165)
			(xy 202.017376 -290.419536) (xy 202.016867 -290.447422) (xy 202.008747 -290.502598) (xy 201.992679 -290.556005)
			(xy 201.969007 -290.606502) (xy 201.938234 -290.653015) (xy 201.901017 -290.694552) (xy 201.858149 -290.730227)
			(xy 201.810543 -290.759281) (xy 201.759214 -290.781093) (xy 201.705257 -290.795199) (xy 201.64982 -290.801299)
			(xy 201.594086 -290.799262) (xy 201.539243 -290.789132) (xy 201.486459 -290.771125) (xy 201.436859 -290.745624)
			(xy 201.391501 -290.713173) (xy 201.351352 -290.674464) (xy 201.317266 -290.630321) (xy 201.28997 -290.581686)
			(xy 201.270047 -290.529595) (xy 201.257921 -290.475158) (xy 201.25385 -290.419536) (xy 199.19176 -290.419536)
			(xy 199.218407 -290.437928) (xy 199.2539 -290.47202) (xy 199.283465 -290.511364) (xy 199.306336 -290.554941)
			(xy 199.32192 -290.601622) (xy 199.329815 -290.650199) (xy 199.33031 -290.674806) (xy 199.329815 -290.699413)
			(xy 199.32192 -290.74799) (xy 199.306336 -290.794671) (xy 199.283465 -290.838248) (xy 199.2539 -290.877592)
			(xy 199.218407 -290.911684) (xy 199.177904 -290.93964) (xy 199.133442 -290.960738) (xy 199.086171 -290.97443)
			(xy 199.037316 -290.980362) (xy 198.988141 -290.978381) (xy 198.939922 -290.968537) (xy 198.893906 -290.951085)
			(xy 198.851285 -290.926478) (xy 198.813164 -290.895353) (xy 198.780529 -290.858516) (xy 198.754226 -290.81692)
			(xy 198.734935 -290.771644) (xy 198.723158 -290.72386) (xy 198.719198 -290.674806) (xy 198.38035 -290.674806)
			(xy 198.379855 -290.699413) (xy 198.37196 -290.74799) (xy 198.356376 -290.794671) (xy 198.333505 -290.838248)
			(xy 198.30394 -290.877592) (xy 198.268447 -290.911684) (xy 198.227944 -290.93964) (xy 198.183482 -290.960738)
			(xy 198.136211 -290.97443) (xy 198.087356 -290.980362) (xy 198.038181 -290.978381) (xy 197.989962 -290.968537)
			(xy 197.943946 -290.951085) (xy 197.901325 -290.926478) (xy 197.863204 -290.895353) (xy 197.830569 -290.858516)
			(xy 197.804266 -290.81692) (xy 197.784975 -290.771644) (xy 197.773198 -290.72386) (xy 197.769238 -290.674806)
			(xy 197.43039 -290.674806) (xy 197.429895 -290.699413) (xy 197.422 -290.74799) (xy 197.406416 -290.794671)
			(xy 197.383545 -290.838248) (xy 197.35398 -290.877592) (xy 197.318487 -290.911684) (xy 197.277984 -290.93964)
			(xy 197.233522 -290.960738) (xy 197.186251 -290.97443) (xy 197.137396 -290.980362) (xy 197.088221 -290.978381)
			(xy 197.040002 -290.968537) (xy 196.993986 -290.951085) (xy 196.951365 -290.926478) (xy 196.913244 -290.895353)
			(xy 196.880609 -290.858516) (xy 196.854306 -290.81692) (xy 196.835015 -290.771644) (xy 196.823238 -290.72386)
			(xy 196.819278 -290.674806) (xy 196.480176 -290.674806) (xy 196.479681 -290.699413) (xy 196.471786 -290.74799)
			(xy 196.456202 -290.794671) (xy 196.433331 -290.838248) (xy 196.403766 -290.877592) (xy 196.368273 -290.911684)
			(xy 196.32777 -290.93964) (xy 196.283308 -290.960738) (xy 196.236037 -290.97443) (xy 196.187182 -290.980362)
			(xy 196.138007 -290.978381) (xy 196.089788 -290.968537) (xy 196.043772 -290.951085) (xy 196.001151 -290.926478)
			(xy 195.96303 -290.895353) (xy 195.930395 -290.858516) (xy 195.904092 -290.81692) (xy 195.884801 -290.771644)
			(xy 195.873024 -290.72386) (xy 195.869064 -290.674806) (xy 195.530216 -290.674806) (xy 195.529721 -290.699413)
			(xy 195.521826 -290.74799) (xy 195.506242 -290.794671) (xy 195.483371 -290.838248) (xy 195.453806 -290.877592)
			(xy 195.418313 -290.911684) (xy 195.37781 -290.93964) (xy 195.333348 -290.960738) (xy 195.286077 -290.97443)
			(xy 195.237222 -290.980362) (xy 195.188047 -290.978381) (xy 195.139828 -290.968537) (xy 195.093812 -290.951085)
			(xy 195.051191 -290.926478) (xy 195.01307 -290.895353) (xy 194.980435 -290.858516) (xy 194.954132 -290.81692)
			(xy 194.934841 -290.771644) (xy 194.923064 -290.72386) (xy 194.919104 -290.674806) (xy 194.580256 -290.674806)
			(xy 194.579761 -290.699413) (xy 194.571866 -290.74799) (xy 194.556282 -290.794671) (xy 194.533411 -290.838248)
			(xy 194.503846 -290.877592) (xy 194.468353 -290.911684) (xy 194.42785 -290.93964) (xy 194.383388 -290.960738)
			(xy 194.336117 -290.97443) (xy 194.287262 -290.980362) (xy 194.238087 -290.978381) (xy 194.189868 -290.968537)
			(xy 194.143852 -290.951085) (xy 194.101231 -290.926478) (xy 194.06311 -290.895353) (xy 194.030475 -290.858516)
			(xy 194.004172 -290.81692) (xy 193.984881 -290.771644) (xy 193.973104 -290.72386) (xy 193.969144 -290.674806)
			(xy 193.630296 -290.674806) (xy 193.629801 -290.699413) (xy 193.621906 -290.74799) (xy 193.606322 -290.794671)
			(xy 193.583451 -290.838248) (xy 193.553886 -290.877592) (xy 193.518393 -290.911684) (xy 193.47789 -290.93964)
			(xy 193.433428 -290.960738) (xy 193.386157 -290.97443) (xy 193.337302 -290.980362) (xy 193.288127 -290.978381)
			(xy 193.239908 -290.968537) (xy 193.193892 -290.951085) (xy 193.151271 -290.926478) (xy 193.11315 -290.895353)
			(xy 193.080515 -290.858516) (xy 193.054212 -290.81692) (xy 193.034921 -290.771644) (xy 193.023144 -290.72386)
			(xy 193.019184 -290.674806) (xy 192.680336 -290.674806) (xy 192.679841 -290.699413) (xy 192.671946 -290.74799)
			(xy 192.656362 -290.794671) (xy 192.633491 -290.838248) (xy 192.603926 -290.877592) (xy 192.568433 -290.911684)
			(xy 192.52793 -290.93964) (xy 192.483468 -290.960738) (xy 192.436197 -290.97443) (xy 192.387342 -290.980362)
			(xy 192.338167 -290.978381) (xy 192.289948 -290.968537) (xy 192.243932 -290.951085) (xy 192.201311 -290.926478)
			(xy 192.16319 -290.895353) (xy 192.130555 -290.858516) (xy 192.104252 -290.81692) (xy 192.084961 -290.771644)
			(xy 192.073184 -290.72386) (xy 192.069224 -290.674806) (xy 191.730376 -290.674806) (xy 191.729881 -290.699413)
			(xy 191.721986 -290.74799) (xy 191.706402 -290.794671) (xy 191.683531 -290.838248) (xy 191.653966 -290.877592)
			(xy 191.618473 -290.911684) (xy 191.57797 -290.93964) (xy 191.533508 -290.960738) (xy 191.486237 -290.97443)
			(xy 191.437382 -290.980362) (xy 191.388207 -290.978381) (xy 191.339988 -290.968537) (xy 191.293972 -290.951085)
			(xy 191.251351 -290.926478) (xy 191.21323 -290.895353) (xy 191.180595 -290.858516) (xy 191.154292 -290.81692)
			(xy 191.135001 -290.771644) (xy 191.123224 -290.72386) (xy 191.119264 -290.674806) (xy 190.780162 -290.674806)
			(xy 190.779667 -290.699413) (xy 190.771772 -290.74799) (xy 190.756188 -290.794671) (xy 190.733317 -290.838248)
			(xy 190.703752 -290.877592) (xy 190.668259 -290.911684) (xy 190.627756 -290.93964) (xy 190.583294 -290.960738)
			(xy 190.536023 -290.97443) (xy 190.487168 -290.980362) (xy 190.437993 -290.978381) (xy 190.389774 -290.968537)
			(xy 190.343758 -290.951085) (xy 190.301137 -290.926478) (xy 190.263016 -290.895353) (xy 190.230381 -290.858516)
			(xy 190.204078 -290.81692) (xy 190.184787 -290.771644) (xy 190.17301 -290.72386) (xy 190.16905 -290.674806)
			(xy 189.830202 -290.674806) (xy 189.829707 -290.699413) (xy 189.821812 -290.74799) (xy 189.806228 -290.794671)
			(xy 189.783357 -290.838248) (xy 189.753792 -290.877592) (xy 189.718299 -290.911684) (xy 189.677796 -290.93964)
			(xy 189.633334 -290.960738) (xy 189.586063 -290.97443) (xy 189.537208 -290.980362) (xy 189.488033 -290.978381)
			(xy 189.439814 -290.968537) (xy 189.393798 -290.951085) (xy 189.351177 -290.926478) (xy 189.313056 -290.895353)
			(xy 189.280421 -290.858516) (xy 189.254118 -290.81692) (xy 189.234827 -290.771644) (xy 189.22305 -290.72386)
			(xy 189.21909 -290.674806) (xy 188.880242 -290.674806) (xy 188.879747 -290.699413) (xy 188.871852 -290.74799)
			(xy 188.856268 -290.794671) (xy 188.833397 -290.838248) (xy 188.803832 -290.877592) (xy 188.768339 -290.911684)
			(xy 188.727836 -290.93964) (xy 188.683374 -290.960738) (xy 188.636103 -290.97443) (xy 188.587248 -290.980362)
			(xy 188.538073 -290.978381) (xy 188.489854 -290.968537) (xy 188.443838 -290.951085) (xy 188.401217 -290.926478)
			(xy 188.363096 -290.895353) (xy 188.330461 -290.858516) (xy 188.304158 -290.81692) (xy 188.284867 -290.771644)
			(xy 188.27309 -290.72386) (xy 188.26913 -290.674806) (xy 187.930282 -290.674806) (xy 187.929787 -290.699413)
			(xy 187.921892 -290.74799) (xy 187.906308 -290.794671) (xy 187.883437 -290.838248) (xy 187.853872 -290.877592)
			(xy 187.818379 -290.911684) (xy 187.777876 -290.93964) (xy 187.733414 -290.960738) (xy 187.686143 -290.97443)
			(xy 187.637288 -290.980362) (xy 187.588113 -290.978381) (xy 187.539894 -290.968537) (xy 187.493878 -290.951085)
			(xy 187.451257 -290.926478) (xy 187.413136 -290.895353) (xy 187.380501 -290.858516) (xy 187.354198 -290.81692)
			(xy 187.334907 -290.771644) (xy 187.32313 -290.72386) (xy 187.31917 -290.674806) (xy 186.980322 -290.674806)
			(xy 186.979827 -290.699413) (xy 186.971932 -290.74799) (xy 186.956348 -290.794671) (xy 186.933477 -290.838248)
			(xy 186.903912 -290.877592) (xy 186.868419 -290.911684) (xy 186.827916 -290.93964) (xy 186.783454 -290.960738)
			(xy 186.736183 -290.97443) (xy 186.687328 -290.980362) (xy 186.638153 -290.978381) (xy 186.589934 -290.968537)
			(xy 186.543918 -290.951085) (xy 186.501297 -290.926478) (xy 186.463176 -290.895353) (xy 186.430541 -290.858516)
			(xy 186.404238 -290.81692) (xy 186.384947 -290.771644) (xy 186.37317 -290.72386) (xy 186.36921 -290.674806)
			(xy 186.055319 -290.674806) (xy 186.055319 -290.700791) (xy 186.047186 -290.752133) (xy 186.031121 -290.801571)
			(xy 186.00752 -290.847886) (xy 185.976963 -290.889939) (xy 185.940204 -290.926693) (xy 185.898147 -290.957244)
			(xy 185.851828 -290.980839) (xy 185.802388 -290.996897) (xy 185.751045 -291.005022) (xy 185.725054 -291.005514)
			(xy 185.7248 -291.005514) (xy 185.705898 -291.005225) (xy 185.668343 -291.000891) (xy 185.64987 -290.996878)
			(xy 185.63844 -290.994084) (xy 185.616088 -290.999164) (xy 185.54446 -291.05606) (xy 185.535744 -291.063637)
			(xy 185.525689 -291.084402) (xy 185.525156 -291.095938) (xy 185.525156 -291.203634) (xy 185.525732 -291.214836)
			(xy 185.535206 -291.235139) (xy 185.539045 -291.238686) (xy 202.096622 -291.238686) (xy 202.100693 -291.183064)
			(xy 202.112819 -291.128627) (xy 202.132742 -291.076536) (xy 202.160038 -291.027901) (xy 202.194124 -290.983758)
			(xy 202.234273 -290.945049) (xy 202.279631 -290.912598) (xy 202.329231 -290.887097) (xy 202.382015 -290.86909)
			(xy 202.436858 -290.85896) (xy 202.492592 -290.856923) (xy 202.548029 -290.863023) (xy 202.601986 -290.877129)
			(xy 202.653315 -290.898941) (xy 202.655301 -290.900153) (xy 227.087881 -290.900153) (xy 227.087881 -290.845647)
			(xy 227.095639 -290.791697) (xy 227.110996 -290.739399) (xy 227.133639 -290.68982) (xy 227.163109 -290.643968)
			(xy 227.198804 -290.602777) (xy 227.239999 -290.567086) (xy 227.285853 -290.537621) (xy 227.335435 -290.514982)
			(xy 227.387734 -290.499631) (xy 227.441685 -290.491879) (xy 227.468938 -290.491418) (xy 227.496307 -290.491916)
			(xy 227.550485 -290.499725) (xy 227.602988 -290.515207) (xy 227.652735 -290.538042) (xy 227.698703 -290.56776)
			(xy 227.719636 -290.585398) (xy 227.726748 -290.591494) (xy 227.743766 -290.597844) (xy 227.82911 -290.597844)
			(xy 227.846128 -290.591494) (xy 227.85324 -290.585398) (xy 227.874184 -290.567773) (xy 227.920153 -290.538059)
			(xy 227.969898 -290.515221) (xy 228.022396 -290.499726) (xy 228.07657 -290.491894) (xy 228.103938 -290.491418)
			(xy 228.131189 -290.491854) (xy 228.185137 -290.499616) (xy 228.23743 -290.514975) (xy 228.287006 -290.53762)
			(xy 228.332855 -290.56709) (xy 228.374043 -290.602783) (xy 228.409733 -290.643976) (xy 228.439198 -290.689827)
			(xy 228.461838 -290.739405) (xy 228.477192 -290.791701) (xy 228.484948 -290.845649) (xy 228.484948 -290.900151)
			(xy 228.484948 -290.900153) (xy 228.827781 -290.900153) (xy 228.827781 -290.845647) (xy 228.835539 -290.791697)
			(xy 228.850896 -290.739399) (xy 228.873539 -290.68982) (xy 228.903009 -290.643968) (xy 228.938704 -290.602777)
			(xy 228.979899 -290.567086) (xy 229.025753 -290.537621) (xy 229.075335 -290.514982) (xy 229.127634 -290.499631)
			(xy 229.181585 -290.491879) (xy 229.208838 -290.491418) (xy 229.236207 -290.491916) (xy 229.290385 -290.499725)
			(xy 229.342888 -290.515207) (xy 229.392635 -290.538042) (xy 229.438603 -290.56776) (xy 229.459536 -290.585398)
			(xy 229.466648 -290.591494) (xy 229.483666 -290.597844) (xy 229.56901 -290.597844) (xy 229.586028 -290.591494)
			(xy 229.59314 -290.585398) (xy 229.614084 -290.567773) (xy 229.660053 -290.538059) (xy 229.709798 -290.515221)
			(xy 229.762296 -290.499726) (xy 229.81647 -290.491894) (xy 229.843838 -290.491418) (xy 229.871089 -290.491854)
			(xy 229.925037 -290.499616) (xy 229.97733 -290.514975) (xy 230.026906 -290.53762) (xy 230.072755 -290.56709)
			(xy 230.113943 -290.602783) (xy 230.149633 -290.643976) (xy 230.179098 -290.689827) (xy 230.201738 -290.739405)
			(xy 230.217092 -290.791701) (xy 230.224848 -290.845649) (xy 230.224848 -290.900151) (xy 230.217092 -290.954099)
			(xy 230.201738 -291.006395) (xy 230.179098 -291.055973) (xy 230.149633 -291.101824) (xy 230.113943 -291.143017)
			(xy 230.072755 -291.17871) (xy 230.026906 -291.20818) (xy 229.97733 -291.230825) (xy 229.925037 -291.246184)
			(xy 229.871089 -291.253946) (xy 229.843838 -291.254434) (xy 229.816468 -291.253962) (xy 229.762288 -291.246148)
			(xy 229.709785 -291.230661) (xy 229.660038 -291.20782) (xy 229.614071 -291.178096) (xy 229.59314 -291.160454)
			(xy 229.586028 -291.154358) (xy 229.56901 -291.148008) (xy 229.483666 -291.148008) (xy 229.466648 -291.154358)
			(xy 229.459536 -291.160454) (xy 229.438595 -291.178083) (xy 229.392626 -291.207798) (xy 229.34288 -291.230636)
			(xy 229.290381 -291.24613) (xy 229.236207 -291.253959) (xy 229.208838 -291.254434) (xy 229.181585 -291.253921)
			(xy 229.127634 -291.246169) (xy 229.075335 -291.230818) (xy 229.025753 -291.208179) (xy 228.979899 -291.178714)
			(xy 228.938704 -291.143023) (xy 228.903009 -291.101832) (xy 228.873539 -291.05598) (xy 228.850896 -291.006401)
			(xy 228.835539 -290.954103) (xy 228.827781 -290.900153) (xy 228.484948 -290.900153) (xy 228.477192 -290.954099)
			(xy 228.461838 -291.006395) (xy 228.439198 -291.055973) (xy 228.409733 -291.101824) (xy 228.374043 -291.143017)
			(xy 228.332855 -291.17871) (xy 228.287006 -291.20818) (xy 228.23743 -291.230825) (xy 228.185137 -291.246184)
			(xy 228.131189 -291.253946) (xy 228.103938 -291.254434) (xy 228.076568 -291.253962) (xy 228.022388 -291.246148)
			(xy 227.969885 -291.230661) (xy 227.920138 -291.20782) (xy 227.874171 -291.178096) (xy 227.85324 -291.160454)
			(xy 227.846128 -291.154358) (xy 227.82911 -291.148008) (xy 227.743766 -291.148008) (xy 227.726748 -291.154358)
			(xy 227.719636 -291.160454) (xy 227.698695 -291.178083) (xy 227.652726 -291.207798) (xy 227.60298 -291.230636)
			(xy 227.550481 -291.24613) (xy 227.496307 -291.253959) (xy 227.468938 -291.254434) (xy 227.441685 -291.253921)
			(xy 227.387734 -291.246169) (xy 227.335435 -291.230818) (xy 227.285853 -291.208179) (xy 227.239999 -291.178714)
			(xy 227.198804 -291.143023) (xy 227.163109 -291.101832) (xy 227.133639 -291.05598) (xy 227.110996 -291.006401)
			(xy 227.095639 -290.954103) (xy 227.087881 -290.900153) (xy 202.655301 -290.900153) (xy 202.700921 -290.927995)
			(xy 202.743789 -290.96367) (xy 202.781006 -291.005207) (xy 202.811779 -291.05172) (xy 202.835451 -291.102217)
			(xy 202.851519 -291.155624) (xy 202.859639 -291.2108) (xy 202.860148 -291.238686) (xy 202.859639 -291.266572)
			(xy 202.851519 -291.321748) (xy 202.835451 -291.375155) (xy 202.811779 -291.425652) (xy 202.781006 -291.472165)
			(xy 202.743789 -291.513702) (xy 202.700921 -291.549377) (xy 202.653315 -291.578431) (xy 202.621384 -291.592)
			(xy 204.54188 -291.592) (xy 204.545951 -291.536378) (xy 204.558077 -291.481941) (xy 204.578 -291.42985)
			(xy 204.605296 -291.381215) (xy 204.639382 -291.337072) (xy 204.679531 -291.298363) (xy 204.724889 -291.265912)
			(xy 204.774489 -291.240411) (xy 204.827273 -291.222404) (xy 204.882116 -291.212274) (xy 204.93785 -291.210237)
			(xy 204.993287 -291.216337) (xy 205.047244 -291.230443) (xy 205.098573 -291.252255) (xy 205.146179 -291.281309)
			(xy 205.189047 -291.316984) (xy 205.226264 -291.358521) (xy 205.257037 -291.405034) (xy 205.280709 -291.455531)
			(xy 205.296777 -291.508938) (xy 205.304897 -291.564114) (xy 205.305406 -291.592) (xy 205.304897 -291.619886)
			(xy 205.296777 -291.675062) (xy 205.280709 -291.728469) (xy 205.257037 -291.778966) (xy 205.226264 -291.825479)
			(xy 205.189047 -291.867016) (xy 205.146179 -291.902691) (xy 205.098573 -291.931745) (xy 205.047244 -291.953557)
			(xy 204.993287 -291.967663) (xy 204.93785 -291.973763) (xy 204.882116 -291.971726) (xy 204.827273 -291.961596)
			(xy 204.774489 -291.943589) (xy 204.724889 -291.918088) (xy 204.679531 -291.885637) (xy 204.639382 -291.846928)
			(xy 204.605296 -291.802785) (xy 204.578 -291.75415) (xy 204.558077 -291.702059) (xy 204.545951 -291.647622)
			(xy 204.54188 -291.592) (xy 202.621384 -291.592) (xy 202.601986 -291.600243) (xy 202.548029 -291.614349)
			(xy 202.492592 -291.620449) (xy 202.436858 -291.618412) (xy 202.382015 -291.608282) (xy 202.329231 -291.590275)
			(xy 202.279631 -291.564774) (xy 202.234273 -291.532323) (xy 202.194124 -291.493614) (xy 202.160038 -291.449471)
			(xy 202.132742 -291.400836) (xy 202.112819 -291.348745) (xy 202.100693 -291.294308) (xy 202.096622 -291.238686)
			(xy 185.539045 -291.238686) (xy 185.543444 -291.24275) (xy 185.543952 -291.243258) (xy 185.616088 -291.300408)
			(xy 185.63844 -291.305488) (xy 185.64987 -291.302694) (xy 185.668338 -291.298651) (xy 185.705897 -291.294328)
			(xy 185.7248 -291.294058) (xy 185.725054 -291.294058) (xy 185.751048 -291.294538) (xy 185.802398 -291.302664)
			(xy 185.851843 -291.318724) (xy 185.898168 -291.342322) (xy 185.94023 -291.372876) (xy 185.976994 -291.409635)
			(xy 186.007554 -291.451693) (xy 186.031158 -291.498014) (xy 186.047225 -291.547458) (xy 186.055359 -291.598806)
			(xy 186.055359 -291.624766) (xy 186.36921 -291.624766) (xy 186.37317 -291.575712) (xy 186.384947 -291.527928)
			(xy 186.404238 -291.482652) (xy 186.430541 -291.441056) (xy 186.463176 -291.404219) (xy 186.501297 -291.373094)
			(xy 186.543918 -291.348487) (xy 186.589934 -291.331035) (xy 186.638153 -291.321191) (xy 186.687328 -291.31921)
			(xy 186.736183 -291.325142) (xy 186.783454 -291.338834) (xy 186.827916 -291.359932) (xy 186.868419 -291.387888)
			(xy 186.903912 -291.42198) (xy 186.933477 -291.461324) (xy 186.956348 -291.504901) (xy 186.971932 -291.551582)
			(xy 186.979827 -291.600159) (xy 186.980322 -291.624766) (xy 187.31917 -291.624766) (xy 187.32313 -291.575712)
			(xy 187.334907 -291.527928) (xy 187.354198 -291.482652) (xy 187.380501 -291.441056) (xy 187.413136 -291.404219)
			(xy 187.451257 -291.373094) (xy 187.493878 -291.348487) (xy 187.539894 -291.331035) (xy 187.588113 -291.321191)
			(xy 187.637288 -291.31921) (xy 187.686143 -291.325142) (xy 187.733414 -291.338834) (xy 187.777876 -291.359932)
			(xy 187.818379 -291.387888) (xy 187.853872 -291.42198) (xy 187.883437 -291.461324) (xy 187.906308 -291.504901)
			(xy 187.921892 -291.551582) (xy 187.929787 -291.600159) (xy 187.930282 -291.624766) (xy 188.26913 -291.624766)
			(xy 188.27309 -291.575712) (xy 188.284867 -291.527928) (xy 188.304158 -291.482652) (xy 188.330461 -291.441056)
			(xy 188.363096 -291.404219) (xy 188.401217 -291.373094) (xy 188.443838 -291.348487) (xy 188.489854 -291.331035)
			(xy 188.538073 -291.321191) (xy 188.587248 -291.31921) (xy 188.636103 -291.325142) (xy 188.683374 -291.338834)
			(xy 188.727836 -291.359932) (xy 188.768339 -291.387888) (xy 188.803832 -291.42198) (xy 188.833397 -291.461324)
			(xy 188.856268 -291.504901) (xy 188.871852 -291.551582) (xy 188.879747 -291.600159) (xy 188.880242 -291.624766)
			(xy 189.21909 -291.624766) (xy 189.22305 -291.575712) (xy 189.234827 -291.527928) (xy 189.254118 -291.482652)
			(xy 189.280421 -291.441056) (xy 189.313056 -291.404219) (xy 189.351177 -291.373094) (xy 189.393798 -291.348487)
			(xy 189.439814 -291.331035) (xy 189.488033 -291.321191) (xy 189.537208 -291.31921) (xy 189.586063 -291.325142)
			(xy 189.633334 -291.338834) (xy 189.677796 -291.359932) (xy 189.718299 -291.387888) (xy 189.753792 -291.42198)
			(xy 189.783357 -291.461324) (xy 189.806228 -291.504901) (xy 189.821812 -291.551582) (xy 189.829707 -291.600159)
			(xy 189.830202 -291.624766) (xy 190.169304 -291.624766) (xy 190.173264 -291.575712) (xy 190.185041 -291.527928)
			(xy 190.204332 -291.482652) (xy 190.230635 -291.441056) (xy 190.26327 -291.404219) (xy 190.301391 -291.373094)
			(xy 190.344012 -291.348487) (xy 190.390028 -291.331035) (xy 190.438247 -291.321191) (xy 190.487422 -291.31921)
			(xy 190.536277 -291.325142) (xy 190.583548 -291.338834) (xy 190.62801 -291.359932) (xy 190.668513 -291.387888)
			(xy 190.704006 -291.42198) (xy 190.733571 -291.461324) (xy 190.756442 -291.504901) (xy 190.772026 -291.551582)
			(xy 190.779921 -291.600159) (xy 190.780416 -291.624766) (xy 192.069224 -291.624766) (xy 192.073184 -291.575712)
			(xy 192.084961 -291.527928) (xy 192.104252 -291.482652) (xy 192.130555 -291.441056) (xy 192.16319 -291.404219)
			(xy 192.201311 -291.373094) (xy 192.243932 -291.348487) (xy 192.289948 -291.331035) (xy 192.338167 -291.321191)
			(xy 192.387342 -291.31921) (xy 192.436197 -291.325142) (xy 192.483468 -291.338834) (xy 192.52793 -291.359932)
			(xy 192.568433 -291.387888) (xy 192.603926 -291.42198) (xy 192.633491 -291.461324) (xy 192.656362 -291.504901)
			(xy 192.671946 -291.551582) (xy 192.679841 -291.600159) (xy 192.680336 -291.624766) (xy 193.019184 -291.624766)
			(xy 193.023144 -291.575712) (xy 193.034921 -291.527928) (xy 193.054212 -291.482652) (xy 193.080515 -291.441056)
			(xy 193.11315 -291.404219) (xy 193.151271 -291.373094) (xy 193.193892 -291.348487) (xy 193.239908 -291.331035)
			(xy 193.288127 -291.321191) (xy 193.337302 -291.31921) (xy 193.386157 -291.325142) (xy 193.433428 -291.338834)
			(xy 193.47789 -291.359932) (xy 193.518393 -291.387888) (xy 193.553886 -291.42198) (xy 193.583451 -291.461324)
			(xy 193.606322 -291.504901) (xy 193.621906 -291.551582) (xy 193.629801 -291.600159) (xy 193.630296 -291.624766)
			(xy 193.969144 -291.624766) (xy 193.973104 -291.575712) (xy 193.984881 -291.527928) (xy 194.004172 -291.482652)
			(xy 194.030475 -291.441056) (xy 194.06311 -291.404219) (xy 194.101231 -291.373094) (xy 194.143852 -291.348487)
			(xy 194.189868 -291.331035) (xy 194.238087 -291.321191) (xy 194.287262 -291.31921) (xy 194.336117 -291.325142)
			(xy 194.383388 -291.338834) (xy 194.42785 -291.359932) (xy 194.468353 -291.387888) (xy 194.503846 -291.42198)
			(xy 194.533411 -291.461324) (xy 194.556282 -291.504901) (xy 194.571866 -291.551582) (xy 194.579761 -291.600159)
			(xy 194.580256 -291.624766) (xy 194.919104 -291.624766) (xy 194.923064 -291.575712) (xy 194.934841 -291.527928)
			(xy 194.954132 -291.482652) (xy 194.980435 -291.441056) (xy 195.01307 -291.404219) (xy 195.051191 -291.373094)
			(xy 195.093812 -291.348487) (xy 195.139828 -291.331035) (xy 195.188047 -291.321191) (xy 195.237222 -291.31921)
			(xy 195.286077 -291.325142) (xy 195.333348 -291.338834) (xy 195.37781 -291.359932) (xy 195.418313 -291.387888)
			(xy 195.453806 -291.42198) (xy 195.483371 -291.461324) (xy 195.506242 -291.504901) (xy 195.521826 -291.551582)
			(xy 195.529721 -291.600159) (xy 195.530216 -291.624766) (xy 195.869064 -291.624766) (xy 195.873024 -291.575712)
			(xy 195.884801 -291.527928) (xy 195.904092 -291.482652) (xy 195.930395 -291.441056) (xy 195.96303 -291.404219)
			(xy 196.001151 -291.373094) (xy 196.043772 -291.348487) (xy 196.089788 -291.331035) (xy 196.138007 -291.321191)
			(xy 196.187182 -291.31921) (xy 196.236037 -291.325142) (xy 196.283308 -291.338834) (xy 196.32777 -291.359932)
			(xy 196.368273 -291.387888) (xy 196.403766 -291.42198) (xy 196.433331 -291.461324) (xy 196.456202 -291.504901)
			(xy 196.471786 -291.551582) (xy 196.479681 -291.600159) (xy 196.480176 -291.624766) (xy 196.819278 -291.624766)
			(xy 196.823238 -291.575712) (xy 196.835015 -291.527928) (xy 196.854306 -291.482652) (xy 196.880609 -291.441056)
			(xy 196.913244 -291.404219) (xy 196.951365 -291.373094) (xy 196.993986 -291.348487) (xy 197.040002 -291.331035)
			(xy 197.088221 -291.321191) (xy 197.137396 -291.31921) (xy 197.186251 -291.325142) (xy 197.233522 -291.338834)
			(xy 197.277984 -291.359932) (xy 197.318487 -291.387888) (xy 197.35398 -291.42198) (xy 197.383545 -291.461324)
			(xy 197.406416 -291.504901) (xy 197.422 -291.551582) (xy 197.429895 -291.600159) (xy 197.43039 -291.624766)
			(xy 197.769238 -291.624766) (xy 197.773198 -291.575712) (xy 197.784975 -291.527928) (xy 197.804266 -291.482652)
			(xy 197.830569 -291.441056) (xy 197.863204 -291.404219) (xy 197.901325 -291.373094) (xy 197.943946 -291.348487)
			(xy 197.989962 -291.331035) (xy 198.038181 -291.321191) (xy 198.087356 -291.31921) (xy 198.136211 -291.325142)
			(xy 198.183482 -291.338834) (xy 198.227944 -291.359932) (xy 198.268447 -291.387888) (xy 198.30394 -291.42198)
			(xy 198.333505 -291.461324) (xy 198.356376 -291.504901) (xy 198.37196 -291.551582) (xy 198.379855 -291.600159)
			(xy 198.38035 -291.624766) (xy 198.719198 -291.624766) (xy 198.723158 -291.575712) (xy 198.734935 -291.527928)
			(xy 198.754226 -291.482652) (xy 198.780529 -291.441056) (xy 198.813164 -291.404219) (xy 198.851285 -291.373094)
			(xy 198.893906 -291.348487) (xy 198.939922 -291.331035) (xy 198.988141 -291.321191) (xy 199.037316 -291.31921)
			(xy 199.086171 -291.325142) (xy 199.133442 -291.338834) (xy 199.177904 -291.359932) (xy 199.218407 -291.387888)
			(xy 199.2539 -291.42198) (xy 199.283465 -291.461324) (xy 199.306336 -291.504901) (xy 199.32192 -291.551582)
			(xy 199.329815 -291.600159) (xy 199.33031 -291.624766) (xy 199.329815 -291.649373) (xy 199.32192 -291.69795)
			(xy 199.306336 -291.744631) (xy 199.283465 -291.788208) (xy 199.2539 -291.827552) (xy 199.218407 -291.861644)
			(xy 199.177904 -291.8896) (xy 199.133442 -291.910698) (xy 199.086171 -291.92439) (xy 199.037316 -291.930322)
			(xy 198.988141 -291.928341) (xy 198.939922 -291.918497) (xy 198.893906 -291.901045) (xy 198.851285 -291.876438)
			(xy 198.813164 -291.845313) (xy 198.780529 -291.808476) (xy 198.754226 -291.76688) (xy 198.734935 -291.721604)
			(xy 198.723158 -291.67382) (xy 198.719198 -291.624766) (xy 198.38035 -291.624766) (xy 198.379855 -291.649373)
			(xy 198.37196 -291.69795) (xy 198.356376 -291.744631) (xy 198.333505 -291.788208) (xy 198.30394 -291.827552)
			(xy 198.268447 -291.861644) (xy 198.227944 -291.8896) (xy 198.183482 -291.910698) (xy 198.136211 -291.92439)
			(xy 198.087356 -291.930322) (xy 198.038181 -291.928341) (xy 197.989962 -291.918497) (xy 197.943946 -291.901045)
			(xy 197.901325 -291.876438) (xy 197.863204 -291.845313) (xy 197.830569 -291.808476) (xy 197.804266 -291.76688)
			(xy 197.784975 -291.721604) (xy 197.773198 -291.67382) (xy 197.769238 -291.624766) (xy 197.43039 -291.624766)
			(xy 197.429895 -291.649373) (xy 197.422 -291.69795) (xy 197.406416 -291.744631) (xy 197.383545 -291.788208)
			(xy 197.35398 -291.827552) (xy 197.318487 -291.861644) (xy 197.277984 -291.8896) (xy 197.233522 -291.910698)
			(xy 197.186251 -291.92439) (xy 197.137396 -291.930322) (xy 197.088221 -291.928341) (xy 197.040002 -291.918497)
			(xy 196.993986 -291.901045) (xy 196.951365 -291.876438) (xy 196.913244 -291.845313) (xy 196.880609 -291.808476)
			(xy 196.854306 -291.76688) (xy 196.835015 -291.721604) (xy 196.823238 -291.67382) (xy 196.819278 -291.624766)
			(xy 196.480176 -291.624766) (xy 196.479681 -291.649373) (xy 196.471786 -291.69795) (xy 196.456202 -291.744631)
			(xy 196.433331 -291.788208) (xy 196.403766 -291.827552) (xy 196.368273 -291.861644) (xy 196.32777 -291.8896)
			(xy 196.283308 -291.910698) (xy 196.236037 -291.92439) (xy 196.187182 -291.930322) (xy 196.138007 -291.928341)
			(xy 196.089788 -291.918497) (xy 196.043772 -291.901045) (xy 196.001151 -291.876438) (xy 195.96303 -291.845313)
			(xy 195.930395 -291.808476) (xy 195.904092 -291.76688) (xy 195.884801 -291.721604) (xy 195.873024 -291.67382)
			(xy 195.869064 -291.624766) (xy 195.530216 -291.624766) (xy 195.529721 -291.649373) (xy 195.521826 -291.69795)
			(xy 195.506242 -291.744631) (xy 195.483371 -291.788208) (xy 195.453806 -291.827552) (xy 195.418313 -291.861644)
			(xy 195.37781 -291.8896) (xy 195.333348 -291.910698) (xy 195.286077 -291.92439) (xy 195.237222 -291.930322)
			(xy 195.188047 -291.928341) (xy 195.139828 -291.918497) (xy 195.093812 -291.901045) (xy 195.051191 -291.876438)
			(xy 195.01307 -291.845313) (xy 194.980435 -291.808476) (xy 194.954132 -291.76688) (xy 194.934841 -291.721604)
			(xy 194.923064 -291.67382) (xy 194.919104 -291.624766) (xy 194.580256 -291.624766) (xy 194.579761 -291.649373)
			(xy 194.571866 -291.69795) (xy 194.556282 -291.744631) (xy 194.533411 -291.788208) (xy 194.503846 -291.827552)
			(xy 194.468353 -291.861644) (xy 194.42785 -291.8896) (xy 194.383388 -291.910698) (xy 194.336117 -291.92439)
			(xy 194.287262 -291.930322) (xy 194.238087 -291.928341) (xy 194.189868 -291.918497) (xy 194.143852 -291.901045)
			(xy 194.101231 -291.876438) (xy 194.06311 -291.845313) (xy 194.030475 -291.808476) (xy 194.004172 -291.76688)
			(xy 193.984881 -291.721604) (xy 193.973104 -291.67382) (xy 193.969144 -291.624766) (xy 193.630296 -291.624766)
			(xy 193.629801 -291.649373) (xy 193.621906 -291.69795) (xy 193.606322 -291.744631) (xy 193.583451 -291.788208)
			(xy 193.553886 -291.827552) (xy 193.518393 -291.861644) (xy 193.47789 -291.8896) (xy 193.433428 -291.910698)
			(xy 193.386157 -291.92439) (xy 193.337302 -291.930322) (xy 193.288127 -291.928341) (xy 193.239908 -291.918497)
			(xy 193.193892 -291.901045) (xy 193.151271 -291.876438) (xy 193.11315 -291.845313) (xy 193.080515 -291.808476)
			(xy 193.054212 -291.76688) (xy 193.034921 -291.721604) (xy 193.023144 -291.67382) (xy 193.019184 -291.624766)
			(xy 192.680336 -291.624766) (xy 192.679841 -291.649373) (xy 192.671946 -291.69795) (xy 192.656362 -291.744631)
			(xy 192.633491 -291.788208) (xy 192.603926 -291.827552) (xy 192.568433 -291.861644) (xy 192.52793 -291.8896)
			(xy 192.483468 -291.910698) (xy 192.436197 -291.92439) (xy 192.387342 -291.930322) (xy 192.338167 -291.928341)
			(xy 192.289948 -291.918497) (xy 192.243932 -291.901045) (xy 192.201311 -291.876438) (xy 192.16319 -291.845313)
			(xy 192.130555 -291.808476) (xy 192.104252 -291.76688) (xy 192.084961 -291.721604) (xy 192.073184 -291.67382)
			(xy 192.069224 -291.624766) (xy 190.780416 -291.624766) (xy 190.779921 -291.649373) (xy 190.772026 -291.69795)
			(xy 190.756442 -291.744631) (xy 190.733571 -291.788208) (xy 190.704006 -291.827552) (xy 190.668513 -291.861644)
			(xy 190.62801 -291.8896) (xy 190.583548 -291.910698) (xy 190.536277 -291.92439) (xy 190.487422 -291.930322)
			(xy 190.438247 -291.928341) (xy 190.390028 -291.918497) (xy 190.344012 -291.901045) (xy 190.301391 -291.876438)
			(xy 190.26327 -291.845313) (xy 190.230635 -291.808476) (xy 190.204332 -291.76688) (xy 190.185041 -291.721604)
			(xy 190.173264 -291.67382) (xy 190.169304 -291.624766) (xy 189.830202 -291.624766) (xy 189.829707 -291.649373)
			(xy 189.821812 -291.69795) (xy 189.806228 -291.744631) (xy 189.783357 -291.788208) (xy 189.753792 -291.827552)
			(xy 189.718299 -291.861644) (xy 189.677796 -291.8896) (xy 189.633334 -291.910698) (xy 189.586063 -291.92439)
			(xy 189.537208 -291.930322) (xy 189.488033 -291.928341) (xy 189.439814 -291.918497) (xy 189.393798 -291.901045)
			(xy 189.351177 -291.876438) (xy 189.313056 -291.845313) (xy 189.280421 -291.808476) (xy 189.254118 -291.76688)
			(xy 189.234827 -291.721604) (xy 189.22305 -291.67382) (xy 189.21909 -291.624766) (xy 188.880242 -291.624766)
			(xy 188.879747 -291.649373) (xy 188.871852 -291.69795) (xy 188.856268 -291.744631) (xy 188.833397 -291.788208)
			(xy 188.803832 -291.827552) (xy 188.768339 -291.861644) (xy 188.727836 -291.8896) (xy 188.683374 -291.910698)
			(xy 188.636103 -291.92439) (xy 188.587248 -291.930322) (xy 188.538073 -291.928341) (xy 188.489854 -291.918497)
			(xy 188.443838 -291.901045) (xy 188.401217 -291.876438) (xy 188.363096 -291.845313) (xy 188.330461 -291.808476)
			(xy 188.304158 -291.76688) (xy 188.284867 -291.721604) (xy 188.27309 -291.67382) (xy 188.26913 -291.624766)
			(xy 187.930282 -291.624766) (xy 187.929787 -291.649373) (xy 187.921892 -291.69795) (xy 187.906308 -291.744631)
			(xy 187.883437 -291.788208) (xy 187.853872 -291.827552) (xy 187.818379 -291.861644) (xy 187.777876 -291.8896)
			(xy 187.733414 -291.910698) (xy 187.686143 -291.92439) (xy 187.637288 -291.930322) (xy 187.588113 -291.928341)
			(xy 187.539894 -291.918497) (xy 187.493878 -291.901045) (xy 187.451257 -291.876438) (xy 187.413136 -291.845313)
			(xy 187.380501 -291.808476) (xy 187.354198 -291.76688) (xy 187.334907 -291.721604) (xy 187.32313 -291.67382)
			(xy 187.31917 -291.624766) (xy 186.980322 -291.624766) (xy 186.979827 -291.649373) (xy 186.971932 -291.69795)
			(xy 186.956348 -291.744631) (xy 186.933477 -291.788208) (xy 186.903912 -291.827552) (xy 186.868419 -291.861644)
			(xy 186.827916 -291.8896) (xy 186.783454 -291.910698) (xy 186.736183 -291.92439) (xy 186.687328 -291.930322)
			(xy 186.638153 -291.928341) (xy 186.589934 -291.918497) (xy 186.543918 -291.901045) (xy 186.501297 -291.876438)
			(xy 186.463176 -291.845313) (xy 186.430541 -291.808476) (xy 186.404238 -291.76688) (xy 186.384947 -291.721604)
			(xy 186.37317 -291.67382) (xy 186.36921 -291.624766) (xy 186.055359 -291.624766) (xy 186.055359 -291.650794)
			(xy 186.047225 -291.702143) (xy 186.031158 -291.751586) (xy 186.007554 -291.797907) (xy 185.976994 -291.839965)
			(xy 185.94023 -291.876724) (xy 185.898168 -291.907278) (xy 185.851843 -291.930876) (xy 185.802398 -291.946936)
			(xy 185.751048 -291.955062) (xy 185.725054 -291.955474) (xy 185.7248 -291.955474) (xy 185.705898 -291.955185)
			(xy 185.668343 -291.950852) (xy 185.64987 -291.946838) (xy 185.63844 -291.944044) (xy 185.616088 -291.949124)
			(xy 185.54446 -292.00602) (xy 185.535755 -292.013601) (xy 185.525723 -292.034366) (xy 185.525156 -292.045898)
			(xy 185.525156 -292.122098) (xy 209.357468 -292.122098) (xy 209.357886 -292.095493) (xy 209.365269 -292.042797)
			(xy 209.379907 -291.991639) (xy 209.401514 -291.943013) (xy 209.429671 -291.897863) (xy 209.463831 -291.857065)
			(xy 209.503331 -291.821413) (xy 209.525108 -291.806122) (xy 209.536541 -291.797728) (xy 209.554741 -291.775997)
			(xy 209.56626 -291.750097) (xy 209.570205 -291.722027) (xy 209.566274 -291.693955) (xy 209.55477 -291.668049)
			(xy 209.536581 -291.646309) (xy 209.525108 -291.637974) (xy 209.50331 -291.622718) (xy 209.463833 -291.587044)
			(xy 209.429693 -291.546233) (xy 209.401551 -291.501076) (xy 209.379953 -291.452449) (xy 209.365318 -291.401294)
			(xy 209.357929 -291.348602) (xy 209.357468 -291.321998) (xy 209.357954 -291.294747) (xy 209.36571 -291.240799)
			(xy 209.381065 -291.188504) (xy 209.403707 -291.138927) (xy 209.433173 -291.093077) (xy 209.468864 -291.051886)
			(xy 209.510055 -291.016195) (xy 209.555905 -290.986729) (xy 209.605482 -290.964087) (xy 209.657777 -290.948732)
			(xy 209.711725 -290.940976) (xy 209.766227 -290.940976) (xy 209.820175 -290.948732) (xy 209.87247 -290.964087)
			(xy 209.922047 -290.986729) (xy 209.967897 -291.016195) (xy 210.009088 -291.051886) (xy 210.044779 -291.093077)
			(xy 210.074245 -291.138927) (xy 210.096887 -291.188504) (xy 210.112242 -291.240799) (xy 210.119998 -291.294747)
			(xy 210.120484 -291.321998) (xy 210.120041 -291.348602) (xy 210.112659 -291.401296) (xy 210.098024 -291.452452)
			(xy 210.076421 -291.501077) (xy 210.048268 -291.546227) (xy 210.014113 -291.587026) (xy 209.974619 -291.622681)
			(xy 209.952844 -291.637974) (xy 209.950643 -291.639553) (xy 218.343175 -291.639553) (xy 218.343175 -291.585047)
			(xy 218.350933 -291.531097) (xy 218.366289 -291.4788) (xy 218.388932 -291.429221) (xy 218.418401 -291.383369)
			(xy 218.454096 -291.342177) (xy 218.495289 -291.306486) (xy 218.541143 -291.27702) (xy 218.590724 -291.25438)
			(xy 218.643022 -291.239027) (xy 218.696973 -291.231274) (xy 218.724226 -291.230812) (xy 218.751597 -291.23126)
			(xy 218.805777 -291.239082) (xy 218.85828 -291.254575) (xy 218.908027 -291.277421) (xy 218.953993 -291.307149)
			(xy 218.974924 -291.324792) (xy 218.982036 -291.330888) (xy 218.999054 -291.337238) (xy 219.084398 -291.337238)
			(xy 219.101416 -291.330888) (xy 219.108528 -291.324792) (xy 219.129475 -291.307172) (xy 219.175444 -291.277458)
			(xy 219.225188 -291.254618) (xy 219.277685 -291.239122) (xy 219.331858 -291.231289) (xy 219.359226 -291.230812)
			(xy 219.386477 -291.23126) (xy 219.440425 -291.23902) (xy 219.49272 -291.254378) (xy 219.542296 -291.277022)
			(xy 219.588146 -291.30649) (xy 219.629335 -291.342183) (xy 219.665026 -291.383375) (xy 219.694491 -291.429227)
			(xy 219.717131 -291.478805) (xy 219.732486 -291.5311) (xy 219.740242 -291.585049) (xy 219.740242 -291.639549)
			(xy 220.096598 -291.639549) (xy 220.096598 -291.585051) (xy 220.104354 -291.531107) (xy 220.119708 -291.478816)
			(xy 220.142347 -291.429242) (xy 220.17181 -291.383395) (xy 220.207499 -291.342207) (xy 220.248685 -291.306518)
			(xy 220.294532 -291.277052) (xy 220.344105 -291.254412) (xy 220.396395 -291.239057) (xy 220.450339 -291.231299)
			(xy 220.477588 -291.230812) (xy 220.504958 -291.231282) (xy 220.559137 -291.239099) (xy 220.61164 -291.254587)
			(xy 220.661387 -291.277427) (xy 220.707354 -291.307151) (xy 220.728286 -291.324792) (xy 220.735398 -291.330888)
			(xy 220.752416 -291.337238) (xy 220.83776 -291.337238) (xy 220.854778 -291.330888) (xy 220.86189 -291.324792)
			(xy 220.882814 -291.307143) (xy 220.928789 -291.277433) (xy 220.978539 -291.254599) (xy 221.031041 -291.23911)
			(xy 221.085218 -291.231285) (xy 221.112588 -291.230812) (xy 221.139843 -291.231234) (xy 221.193798 -291.23899)
			(xy 221.2461 -291.254346) (xy 221.295684 -291.276989) (xy 221.341541 -291.306458) (xy 221.382738 -291.342154)
			(xy 221.418435 -291.383349) (xy 221.447905 -291.429205) (xy 221.47055 -291.478789) (xy 221.485907 -291.53109)
			(xy 221.493665 -291.585045) (xy 221.493665 -291.639555) (xy 221.485907 -291.69351) (xy 221.47055 -291.745811)
			(xy 221.447905 -291.795395) (xy 221.418435 -291.841251) (xy 221.382738 -291.882446) (xy 221.341541 -291.918142)
			(xy 221.295684 -291.947611) (xy 221.2461 -291.970254) (xy 221.193798 -291.98561) (xy 221.139843 -291.993366)
			(xy 221.112588 -291.993828) (xy 221.085217 -291.993387) (xy 221.031036 -291.985565) (xy 220.978532 -291.970072)
			(xy 220.928785 -291.947224) (xy 220.88282 -291.917493) (xy 220.86189 -291.899848) (xy 220.854778 -291.893752)
			(xy 220.83776 -291.887402) (xy 220.752416 -291.887402) (xy 220.735398 -291.893752) (xy 220.728286 -291.899848)
			(xy 220.707326 -291.917452) (xy 220.661361 -291.947171) (xy 220.611621 -291.970015) (xy 220.559126 -291.985514)
			(xy 220.504955 -291.99335) (xy 220.477588 -291.993828) (xy 220.450339 -291.993301) (xy 220.396395 -291.985543)
			(xy 220.344105 -291.970188) (xy 220.294532 -291.947548) (xy 220.248685 -291.918082) (xy 220.207499 -291.882393)
			(xy 220.17181 -291.841205) (xy 220.142347 -291.795358) (xy 220.119708 -291.745784) (xy 220.104354 -291.693493)
			(xy 220.096598 -291.639549) (xy 219.740242 -291.639549) (xy 219.740242 -291.639551) (xy 219.732486 -291.6935)
			(xy 219.717131 -291.745795) (xy 219.694491 -291.795373) (xy 219.665026 -291.841225) (xy 219.629335 -291.882417)
			(xy 219.588146 -291.91811) (xy 219.542296 -291.947578) (xy 219.49272 -291.970222) (xy 219.440425 -291.98558)
			(xy 219.386477 -291.99334) (xy 219.359226 -291.993828) (xy 219.331855 -291.993364) (xy 219.277676 -291.985549)
			(xy 219.225172 -291.97006) (xy 219.175425 -291.947217) (xy 219.129459 -291.917491) (xy 219.108528 -291.899848)
			(xy 219.101416 -291.893752) (xy 219.084398 -291.887402) (xy 218.999054 -291.887402) (xy 218.982036 -291.893752)
			(xy 218.974924 -291.899848) (xy 218.953987 -291.917481) (xy 218.908016 -291.947196) (xy 218.85827 -291.970034)
			(xy 218.80577 -291.985526) (xy 218.751595 -291.993354) (xy 218.724226 -291.993828) (xy 218.696973 -291.993326)
			(xy 218.643022 -291.985573) (xy 218.590724 -291.97022) (xy 218.541143 -291.94758) (xy 218.495289 -291.918114)
			(xy 218.454096 -291.882423) (xy 218.418401 -291.841231) (xy 218.388932 -291.795379) (xy 218.366289 -291.7458)
			(xy 218.350933 -291.693503) (xy 218.343175 -291.639553) (xy 209.950643 -291.639553) (xy 209.941313 -291.646246)
			(xy 209.9231 -291.668001) (xy 209.911581 -291.693929) (xy 209.907644 -291.722027) (xy 209.911595 -291.750123)
			(xy 209.923129 -291.776045) (xy 209.941353 -291.79779) (xy 209.952844 -291.806122) (xy 209.97463 -291.821396)
			(xy 210.014109 -291.857065) (xy 210.048252 -291.897872) (xy 210.076396 -291.943026) (xy 210.097996 -291.991651)
			(xy 210.112633 -292.042804) (xy 210.120023 -292.095495) (xy 210.120484 -292.122098) (xy 210.119998 -292.149349)
			(xy 210.112242 -292.203297) (xy 210.096887 -292.255592) (xy 210.074245 -292.305169) (xy 210.044779 -292.351019)
			(xy 210.009088 -292.39221) (xy 209.967897 -292.427901) (xy 209.922047 -292.457367) (xy 209.87247 -292.480009)
			(xy 209.820175 -292.495364) (xy 209.766227 -292.50312) (xy 209.711725 -292.50312) (xy 209.657777 -292.495364)
			(xy 209.605482 -292.480009) (xy 209.555905 -292.457367) (xy 209.510055 -292.427901) (xy 209.468864 -292.39221)
			(xy 209.433173 -292.351019) (xy 209.403707 -292.305169) (xy 209.381065 -292.255592) (xy 209.36571 -292.203297)
			(xy 209.357954 -292.149349) (xy 209.357468 -292.122098) (xy 185.525156 -292.122098) (xy 185.525156 -292.153594)
			(xy 185.525744 -292.16479) (xy 185.535234 -292.185074) (xy 185.543444 -292.19271) (xy 185.543952 -292.193218)
			(xy 185.616088 -292.250368) (xy 185.63844 -292.255448) (xy 185.64987 -292.252654) (xy 185.668338 -292.248611)
			(xy 185.705897 -292.244287) (xy 185.7248 -292.244018) (xy 185.725054 -292.244018) (xy 185.751044 -292.244498)
			(xy 185.802384 -292.252622) (xy 185.85182 -292.268679) (xy 185.898136 -292.292273) (xy 185.940191 -292.322822)
			(xy 185.976948 -292.359574) (xy 186.007503 -292.401624) (xy 186.031103 -292.447937) (xy 186.047167 -292.497372)
			(xy 186.055299 -292.54871) (xy 186.055299 -292.57498) (xy 186.36921 -292.57498) (xy 186.37317 -292.525926)
			(xy 186.384947 -292.478142) (xy 186.404238 -292.432866) (xy 186.430541 -292.39127) (xy 186.463176 -292.354433)
			(xy 186.501297 -292.323308) (xy 186.543918 -292.298701) (xy 186.589934 -292.281249) (xy 186.638153 -292.271405)
			(xy 186.687328 -292.269424) (xy 186.736183 -292.275356) (xy 186.783454 -292.289048) (xy 186.827916 -292.310146)
			(xy 186.868419 -292.338102) (xy 186.903912 -292.372194) (xy 186.933477 -292.411538) (xy 186.956348 -292.455115)
			(xy 186.971932 -292.501796) (xy 186.979827 -292.550373) (xy 186.980317 -292.574726) (xy 187.31917 -292.574726)
			(xy 187.32313 -292.525672) (xy 187.334907 -292.477888) (xy 187.354198 -292.432612) (xy 187.380501 -292.391016)
			(xy 187.413136 -292.354179) (xy 187.451257 -292.323054) (xy 187.493878 -292.298447) (xy 187.539894 -292.280995)
			(xy 187.588113 -292.271151) (xy 187.637288 -292.26917) (xy 187.686143 -292.275102) (xy 187.733414 -292.288794)
			(xy 187.777876 -292.309892) (xy 187.818379 -292.337848) (xy 187.853872 -292.37194) (xy 187.883437 -292.411284)
			(xy 187.906308 -292.454861) (xy 187.921892 -292.501542) (xy 187.929787 -292.550119) (xy 187.930282 -292.574726)
			(xy 188.26913 -292.574726) (xy 188.27309 -292.525672) (xy 188.284867 -292.477888) (xy 188.304158 -292.432612)
			(xy 188.330461 -292.391016) (xy 188.363096 -292.354179) (xy 188.401217 -292.323054) (xy 188.443838 -292.298447)
			(xy 188.489854 -292.280995) (xy 188.538073 -292.271151) (xy 188.587248 -292.26917) (xy 188.636103 -292.275102)
			(xy 188.683374 -292.288794) (xy 188.727836 -292.309892) (xy 188.768339 -292.337848) (xy 188.803832 -292.37194)
			(xy 188.833397 -292.411284) (xy 188.856268 -292.454861) (xy 188.871852 -292.501542) (xy 188.879747 -292.550119)
			(xy 188.880242 -292.574726) (xy 189.21909 -292.574726) (xy 189.22305 -292.525672) (xy 189.234827 -292.477888)
			(xy 189.254118 -292.432612) (xy 189.280421 -292.391016) (xy 189.313056 -292.354179) (xy 189.351177 -292.323054)
			(xy 189.393798 -292.298447) (xy 189.439814 -292.280995) (xy 189.488033 -292.271151) (xy 189.537208 -292.26917)
			(xy 189.586063 -292.275102) (xy 189.633334 -292.288794) (xy 189.677796 -292.309892) (xy 189.718299 -292.337848)
			(xy 189.753792 -292.37194) (xy 189.783357 -292.411284) (xy 189.806228 -292.454861) (xy 189.821812 -292.501542)
			(xy 189.829707 -292.550119) (xy 189.830202 -292.574726) (xy 190.16905 -292.574726) (xy 190.17301 -292.525672)
			(xy 190.184787 -292.477888) (xy 190.204078 -292.432612) (xy 190.230381 -292.391016) (xy 190.263016 -292.354179)
			(xy 190.301137 -292.323054) (xy 190.343758 -292.298447) (xy 190.389774 -292.280995) (xy 190.437993 -292.271151)
			(xy 190.487168 -292.26917) (xy 190.536023 -292.275102) (xy 190.583294 -292.288794) (xy 190.627756 -292.309892)
			(xy 190.668259 -292.337848) (xy 190.703752 -292.37194) (xy 190.733317 -292.411284) (xy 190.756188 -292.454861)
			(xy 190.771772 -292.501542) (xy 190.779667 -292.550119) (xy 190.780162 -292.574726) (xy 191.119264 -292.574726)
			(xy 191.123224 -292.525672) (xy 191.135001 -292.477888) (xy 191.154292 -292.432612) (xy 191.180595 -292.391016)
			(xy 191.21323 -292.354179) (xy 191.251351 -292.323054) (xy 191.293972 -292.298447) (xy 191.339988 -292.280995)
			(xy 191.388207 -292.271151) (xy 191.437382 -292.26917) (xy 191.486237 -292.275102) (xy 191.533508 -292.288794)
			(xy 191.57797 -292.309892) (xy 191.618473 -292.337848) (xy 191.653966 -292.37194) (xy 191.683531 -292.411284)
			(xy 191.706402 -292.454861) (xy 191.721986 -292.501542) (xy 191.729881 -292.550119) (xy 191.730376 -292.574726)
			(xy 192.069224 -292.574726) (xy 192.073184 -292.525672) (xy 192.084961 -292.477888) (xy 192.104252 -292.432612)
			(xy 192.130555 -292.391016) (xy 192.16319 -292.354179) (xy 192.201311 -292.323054) (xy 192.243932 -292.298447)
			(xy 192.289948 -292.280995) (xy 192.338167 -292.271151) (xy 192.387342 -292.26917) (xy 192.436197 -292.275102)
			(xy 192.483468 -292.288794) (xy 192.52793 -292.309892) (xy 192.568433 -292.337848) (xy 192.603926 -292.37194)
			(xy 192.633491 -292.411284) (xy 192.656362 -292.454861) (xy 192.671946 -292.501542) (xy 192.679841 -292.550119)
			(xy 192.680336 -292.574726) (xy 193.019184 -292.574726) (xy 193.023144 -292.525672) (xy 193.034921 -292.477888)
			(xy 193.054212 -292.432612) (xy 193.080515 -292.391016) (xy 193.11315 -292.354179) (xy 193.151271 -292.323054)
			(xy 193.193892 -292.298447) (xy 193.239908 -292.280995) (xy 193.288127 -292.271151) (xy 193.337302 -292.26917)
			(xy 193.386157 -292.275102) (xy 193.433428 -292.288794) (xy 193.47789 -292.309892) (xy 193.518393 -292.337848)
			(xy 193.553886 -292.37194) (xy 193.583451 -292.411284) (xy 193.606322 -292.454861) (xy 193.621906 -292.501542)
			(xy 193.629801 -292.550119) (xy 193.630296 -292.574726) (xy 193.969144 -292.574726) (xy 193.973104 -292.525672)
			(xy 193.984881 -292.477888) (xy 194.004172 -292.432612) (xy 194.030475 -292.391016) (xy 194.06311 -292.354179)
			(xy 194.101231 -292.323054) (xy 194.143852 -292.298447) (xy 194.189868 -292.280995) (xy 194.238087 -292.271151)
			(xy 194.287262 -292.26917) (xy 194.336117 -292.275102) (xy 194.383388 -292.288794) (xy 194.42785 -292.309892)
			(xy 194.468353 -292.337848) (xy 194.503846 -292.37194) (xy 194.533411 -292.411284) (xy 194.556282 -292.454861)
			(xy 194.571866 -292.501542) (xy 194.579761 -292.550119) (xy 194.580256 -292.574726) (xy 194.919104 -292.574726)
			(xy 194.923064 -292.525672) (xy 194.934841 -292.477888) (xy 194.954132 -292.432612) (xy 194.980435 -292.391016)
			(xy 195.01307 -292.354179) (xy 195.051191 -292.323054) (xy 195.093812 -292.298447) (xy 195.139828 -292.280995)
			(xy 195.188047 -292.271151) (xy 195.237222 -292.26917) (xy 195.286077 -292.275102) (xy 195.333348 -292.288794)
			(xy 195.37781 -292.309892) (xy 195.418313 -292.337848) (xy 195.453806 -292.37194) (xy 195.483371 -292.411284)
			(xy 195.506242 -292.454861) (xy 195.521826 -292.501542) (xy 195.529721 -292.550119) (xy 195.530216 -292.574726)
			(xy 195.869064 -292.574726) (xy 195.873024 -292.525672) (xy 195.884801 -292.477888) (xy 195.904092 -292.432612)
			(xy 195.930395 -292.391016) (xy 195.96303 -292.354179) (xy 196.001151 -292.323054) (xy 196.043772 -292.298447)
			(xy 196.089788 -292.280995) (xy 196.138007 -292.271151) (xy 196.187182 -292.26917) (xy 196.236037 -292.275102)
			(xy 196.283308 -292.288794) (xy 196.32777 -292.309892) (xy 196.368273 -292.337848) (xy 196.403766 -292.37194)
			(xy 196.433331 -292.411284) (xy 196.456202 -292.454861) (xy 196.471786 -292.501542) (xy 196.479681 -292.550119)
			(xy 196.480176 -292.574726) (xy 196.819278 -292.574726) (xy 196.823238 -292.525672) (xy 196.835015 -292.477888)
			(xy 196.854306 -292.432612) (xy 196.880609 -292.391016) (xy 196.913244 -292.354179) (xy 196.951365 -292.323054)
			(xy 196.993986 -292.298447) (xy 197.040002 -292.280995) (xy 197.088221 -292.271151) (xy 197.137396 -292.26917)
			(xy 197.186251 -292.275102) (xy 197.233522 -292.288794) (xy 197.277984 -292.309892) (xy 197.318487 -292.337848)
			(xy 197.35398 -292.37194) (xy 197.383545 -292.411284) (xy 197.406416 -292.454861) (xy 197.422 -292.501542)
			(xy 197.429895 -292.550119) (xy 197.43039 -292.574726) (xy 197.430385 -292.57498) (xy 197.769238 -292.57498)
			(xy 197.773198 -292.525926) (xy 197.784975 -292.478142) (xy 197.804266 -292.432866) (xy 197.830569 -292.39127)
			(xy 197.863204 -292.354433) (xy 197.901325 -292.323308) (xy 197.943946 -292.298701) (xy 197.989962 -292.281249)
			(xy 198.038181 -292.271405) (xy 198.087356 -292.269424) (xy 198.136211 -292.275356) (xy 198.183482 -292.289048)
			(xy 198.227944 -292.310146) (xy 198.268447 -292.338102) (xy 198.30394 -292.372194) (xy 198.333505 -292.411538)
			(xy 198.356376 -292.455115) (xy 198.37196 -292.501796) (xy 198.379855 -292.550373) (xy 198.38035 -292.57498)
			(xy 198.719198 -292.57498) (xy 198.723158 -292.525926) (xy 198.734935 -292.478142) (xy 198.754226 -292.432866)
			(xy 198.780529 -292.39127) (xy 198.813164 -292.354433) (xy 198.851285 -292.323308) (xy 198.893906 -292.298701)
			(xy 198.939922 -292.281249) (xy 198.988141 -292.271405) (xy 199.037316 -292.269424) (xy 199.086171 -292.275356)
			(xy 199.133442 -292.289048) (xy 199.177904 -292.310146) (xy 199.218407 -292.338102) (xy 199.2539 -292.372194)
			(xy 199.283465 -292.411538) (xy 199.306336 -292.455115) (xy 199.32192 -292.501796) (xy 199.329815 -292.550373)
			(xy 199.33031 -292.57498) (xy 199.329815 -292.599587) (xy 199.32192 -292.648164) (xy 199.306336 -292.694845)
			(xy 199.283465 -292.738422) (xy 199.2539 -292.777766) (xy 199.218407 -292.811858) (xy 199.177904 -292.839814)
			(xy 199.133442 -292.860912) (xy 199.086171 -292.874604) (xy 199.037316 -292.880536) (xy 198.988141 -292.878555)
			(xy 198.939922 -292.868711) (xy 198.893906 -292.851259) (xy 198.851285 -292.826652) (xy 198.813164 -292.795527)
			(xy 198.780529 -292.75869) (xy 198.754226 -292.717094) (xy 198.734935 -292.671818) (xy 198.723158 -292.624034)
			(xy 198.719198 -292.57498) (xy 198.38035 -292.57498) (xy 198.379855 -292.599587) (xy 198.37196 -292.648164)
			(xy 198.356376 -292.694845) (xy 198.333505 -292.738422) (xy 198.30394 -292.777766) (xy 198.268447 -292.811858)
			(xy 198.227944 -292.839814) (xy 198.183482 -292.860912) (xy 198.136211 -292.874604) (xy 198.087356 -292.880536)
			(xy 198.038181 -292.878555) (xy 197.989962 -292.868711) (xy 197.943946 -292.851259) (xy 197.901325 -292.826652)
			(xy 197.863204 -292.795527) (xy 197.830569 -292.75869) (xy 197.804266 -292.717094) (xy 197.784975 -292.671818)
			(xy 197.773198 -292.624034) (xy 197.769238 -292.57498) (xy 197.430385 -292.57498) (xy 197.429895 -292.599333)
			(xy 197.422 -292.64791) (xy 197.406416 -292.694591) (xy 197.383545 -292.738168) (xy 197.35398 -292.777512)
			(xy 197.318487 -292.811604) (xy 197.277984 -292.83956) (xy 197.233522 -292.860658) (xy 197.186251 -292.87435)
			(xy 197.137396 -292.880282) (xy 197.088221 -292.878301) (xy 197.040002 -292.868457) (xy 196.993986 -292.851005)
			(xy 196.951365 -292.826398) (xy 196.913244 -292.795273) (xy 196.880609 -292.758436) (xy 196.854306 -292.71684)
			(xy 196.835015 -292.671564) (xy 196.823238 -292.62378) (xy 196.819278 -292.574726) (xy 196.480176 -292.574726)
			(xy 196.479681 -292.599333) (xy 196.471786 -292.64791) (xy 196.456202 -292.694591) (xy 196.433331 -292.738168)
			(xy 196.403766 -292.777512) (xy 196.368273 -292.811604) (xy 196.32777 -292.83956) (xy 196.283308 -292.860658)
			(xy 196.236037 -292.87435) (xy 196.187182 -292.880282) (xy 196.138007 -292.878301) (xy 196.089788 -292.868457)
			(xy 196.043772 -292.851005) (xy 196.001151 -292.826398) (xy 195.96303 -292.795273) (xy 195.930395 -292.758436)
			(xy 195.904092 -292.71684) (xy 195.884801 -292.671564) (xy 195.873024 -292.62378) (xy 195.869064 -292.574726)
			(xy 195.530216 -292.574726) (xy 195.529721 -292.599333) (xy 195.521826 -292.64791) (xy 195.506242 -292.694591)
			(xy 195.483371 -292.738168) (xy 195.453806 -292.777512) (xy 195.418313 -292.811604) (xy 195.37781 -292.83956)
			(xy 195.333348 -292.860658) (xy 195.286077 -292.87435) (xy 195.237222 -292.880282) (xy 195.188047 -292.878301)
			(xy 195.139828 -292.868457) (xy 195.093812 -292.851005) (xy 195.051191 -292.826398) (xy 195.01307 -292.795273)
			(xy 194.980435 -292.758436) (xy 194.954132 -292.71684) (xy 194.934841 -292.671564) (xy 194.923064 -292.62378)
			(xy 194.919104 -292.574726) (xy 194.580256 -292.574726) (xy 194.579761 -292.599333) (xy 194.571866 -292.64791)
			(xy 194.556282 -292.694591) (xy 194.533411 -292.738168) (xy 194.503846 -292.777512) (xy 194.468353 -292.811604)
			(xy 194.42785 -292.83956) (xy 194.383388 -292.860658) (xy 194.336117 -292.87435) (xy 194.287262 -292.880282)
			(xy 194.238087 -292.878301) (xy 194.189868 -292.868457) (xy 194.143852 -292.851005) (xy 194.101231 -292.826398)
			(xy 194.06311 -292.795273) (xy 194.030475 -292.758436) (xy 194.004172 -292.71684) (xy 193.984881 -292.671564)
			(xy 193.973104 -292.62378) (xy 193.969144 -292.574726) (xy 193.630296 -292.574726) (xy 193.629801 -292.599333)
			(xy 193.621906 -292.64791) (xy 193.606322 -292.694591) (xy 193.583451 -292.738168) (xy 193.553886 -292.777512)
			(xy 193.518393 -292.811604) (xy 193.47789 -292.83956) (xy 193.433428 -292.860658) (xy 193.386157 -292.87435)
			(xy 193.337302 -292.880282) (xy 193.288127 -292.878301) (xy 193.239908 -292.868457) (xy 193.193892 -292.851005)
			(xy 193.151271 -292.826398) (xy 193.11315 -292.795273) (xy 193.080515 -292.758436) (xy 193.054212 -292.71684)
			(xy 193.034921 -292.671564) (xy 193.023144 -292.62378) (xy 193.019184 -292.574726) (xy 192.680336 -292.574726)
			(xy 192.679841 -292.599333) (xy 192.671946 -292.64791) (xy 192.656362 -292.694591) (xy 192.633491 -292.738168)
			(xy 192.603926 -292.777512) (xy 192.568433 -292.811604) (xy 192.52793 -292.83956) (xy 192.483468 -292.860658)
			(xy 192.436197 -292.87435) (xy 192.387342 -292.880282) (xy 192.338167 -292.878301) (xy 192.289948 -292.868457)
			(xy 192.243932 -292.851005) (xy 192.201311 -292.826398) (xy 192.16319 -292.795273) (xy 192.130555 -292.758436)
			(xy 192.104252 -292.71684) (xy 192.084961 -292.671564) (xy 192.073184 -292.62378) (xy 192.069224 -292.574726)
			(xy 191.730376 -292.574726) (xy 191.729881 -292.599333) (xy 191.721986 -292.64791) (xy 191.706402 -292.694591)
			(xy 191.683531 -292.738168) (xy 191.653966 -292.777512) (xy 191.618473 -292.811604) (xy 191.57797 -292.83956)
			(xy 191.533508 -292.860658) (xy 191.486237 -292.87435) (xy 191.437382 -292.880282) (xy 191.388207 -292.878301)
			(xy 191.339988 -292.868457) (xy 191.293972 -292.851005) (xy 191.251351 -292.826398) (xy 191.21323 -292.795273)
			(xy 191.180595 -292.758436) (xy 191.154292 -292.71684) (xy 191.135001 -292.671564) (xy 191.123224 -292.62378)
			(xy 191.119264 -292.574726) (xy 190.780162 -292.574726) (xy 190.779667 -292.599333) (xy 190.771772 -292.64791)
			(xy 190.756188 -292.694591) (xy 190.733317 -292.738168) (xy 190.703752 -292.777512) (xy 190.668259 -292.811604)
			(xy 190.627756 -292.83956) (xy 190.583294 -292.860658) (xy 190.536023 -292.87435) (xy 190.487168 -292.880282)
			(xy 190.437993 -292.878301) (xy 190.389774 -292.868457) (xy 190.343758 -292.851005) (xy 190.301137 -292.826398)
			(xy 190.263016 -292.795273) (xy 190.230381 -292.758436) (xy 190.204078 -292.71684) (xy 190.184787 -292.671564)
			(xy 190.17301 -292.62378) (xy 190.16905 -292.574726) (xy 189.830202 -292.574726) (xy 189.829707 -292.599333)
			(xy 189.821812 -292.64791) (xy 189.806228 -292.694591) (xy 189.783357 -292.738168) (xy 189.753792 -292.777512)
			(xy 189.718299 -292.811604) (xy 189.677796 -292.83956) (xy 189.633334 -292.860658) (xy 189.586063 -292.87435)
			(xy 189.537208 -292.880282) (xy 189.488033 -292.878301) (xy 189.439814 -292.868457) (xy 189.393798 -292.851005)
			(xy 189.351177 -292.826398) (xy 189.313056 -292.795273) (xy 189.280421 -292.758436) (xy 189.254118 -292.71684)
			(xy 189.234827 -292.671564) (xy 189.22305 -292.62378) (xy 189.21909 -292.574726) (xy 188.880242 -292.574726)
			(xy 188.879747 -292.599333) (xy 188.871852 -292.64791) (xy 188.856268 -292.694591) (xy 188.833397 -292.738168)
			(xy 188.803832 -292.777512) (xy 188.768339 -292.811604) (xy 188.727836 -292.83956) (xy 188.683374 -292.860658)
			(xy 188.636103 -292.87435) (xy 188.587248 -292.880282) (xy 188.538073 -292.878301) (xy 188.489854 -292.868457)
			(xy 188.443838 -292.851005) (xy 188.401217 -292.826398) (xy 188.363096 -292.795273) (xy 188.330461 -292.758436)
			(xy 188.304158 -292.71684) (xy 188.284867 -292.671564) (xy 188.27309 -292.62378) (xy 188.26913 -292.574726)
			(xy 187.930282 -292.574726) (xy 187.929787 -292.599333) (xy 187.921892 -292.64791) (xy 187.906308 -292.694591)
			(xy 187.883437 -292.738168) (xy 187.853872 -292.777512) (xy 187.818379 -292.811604) (xy 187.777876 -292.83956)
			(xy 187.733414 -292.860658) (xy 187.686143 -292.87435) (xy 187.637288 -292.880282) (xy 187.588113 -292.878301)
			(xy 187.539894 -292.868457) (xy 187.493878 -292.851005) (xy 187.451257 -292.826398) (xy 187.413136 -292.795273)
			(xy 187.380501 -292.758436) (xy 187.354198 -292.71684) (xy 187.334907 -292.671564) (xy 187.32313 -292.62378)
			(xy 187.31917 -292.574726) (xy 186.980317 -292.574726) (xy 186.980322 -292.57498) (xy 186.979827 -292.599587)
			(xy 186.971932 -292.648164) (xy 186.956348 -292.694845) (xy 186.933477 -292.738422) (xy 186.903912 -292.777766)
			(xy 186.868419 -292.811858) (xy 186.827916 -292.839814) (xy 186.783454 -292.860912) (xy 186.736183 -292.874604)
			(xy 186.687328 -292.880536) (xy 186.638153 -292.878555) (xy 186.589934 -292.868711) (xy 186.543918 -292.851259)
			(xy 186.501297 -292.826652) (xy 186.463176 -292.795527) (xy 186.430541 -292.75869) (xy 186.404238 -292.717094)
			(xy 186.384947 -292.671818) (xy 186.37317 -292.624034) (xy 186.36921 -292.57498) (xy 186.055299 -292.57498)
			(xy 186.055299 -292.60069) (xy 186.047167 -292.652028) (xy 186.031103 -292.701463) (xy 186.007503 -292.747776)
			(xy 185.976948 -292.789826) (xy 185.940191 -292.826578) (xy 185.898136 -292.857127) (xy 185.85182 -292.880721)
			(xy 185.802384 -292.896778) (xy 185.751044 -292.904902) (xy 185.725054 -292.905434) (xy 185.7248 -292.905434)
			(xy 185.705898 -292.905145) (xy 185.668343 -292.900812) (xy 185.64987 -292.896798) (xy 185.63844 -292.894004)
			(xy 185.616088 -292.899084) (xy 185.54446 -292.95598) (xy 185.535748 -292.963559) (xy 185.525701 -292.984323)
			(xy 185.525156 -292.995858) (xy 185.525156 -293.103808) (xy 185.525747 -293.115003) (xy 185.53524 -293.135283)
			(xy 185.543444 -293.142924) (xy 185.543952 -293.143432) (xy 185.616088 -293.200582) (xy 185.63844 -293.205662)
			(xy 185.64987 -293.202868) (xy 185.668338 -293.198824) (xy 185.705897 -293.1945) (xy 185.7248 -293.194232)
			(xy 185.725054 -293.194232) (xy 185.751042 -293.194712) (xy 185.80238 -293.202836) (xy 185.851815 -293.218892)
			(xy 185.898129 -293.242485) (xy 185.940182 -293.273033) (xy 185.976938 -293.309783) (xy 186.007491 -293.351832)
			(xy 186.03109 -293.398142) (xy 186.047153 -293.447575) (xy 186.055285 -293.498912) (xy 186.055285 -293.52494)
			(xy 186.36921 -293.52494) (xy 186.37317 -293.475886) (xy 186.384947 -293.428102) (xy 186.404238 -293.382826)
			(xy 186.430541 -293.34123) (xy 186.463176 -293.304393) (xy 186.501297 -293.273268) (xy 186.543918 -293.248661)
			(xy 186.589934 -293.231209) (xy 186.638153 -293.221365) (xy 186.687328 -293.219384) (xy 186.736183 -293.225316)
			(xy 186.783454 -293.239008) (xy 186.827916 -293.260106) (xy 186.868419 -293.288062) (xy 186.903912 -293.322154)
			(xy 186.933477 -293.361498) (xy 186.956348 -293.405075) (xy 186.971932 -293.451756) (xy 186.979827 -293.500333)
			(xy 186.980322 -293.52494) (xy 187.31917 -293.52494) (xy 187.32313 -293.475886) (xy 187.334907 -293.428102)
			(xy 187.354198 -293.382826) (xy 187.380501 -293.34123) (xy 187.413136 -293.304393) (xy 187.451257 -293.273268)
			(xy 187.493878 -293.248661) (xy 187.539894 -293.231209) (xy 187.588113 -293.221365) (xy 187.637288 -293.219384)
			(xy 187.686143 -293.225316) (xy 187.733414 -293.239008) (xy 187.777876 -293.260106) (xy 187.818379 -293.288062)
			(xy 187.853872 -293.322154) (xy 187.883437 -293.361498) (xy 187.906308 -293.405075) (xy 187.921892 -293.451756)
			(xy 187.929787 -293.500333) (xy 187.930282 -293.52494) (xy 189.21909 -293.52494) (xy 189.22305 -293.475886)
			(xy 189.234827 -293.428102) (xy 189.254118 -293.382826) (xy 189.280421 -293.34123) (xy 189.313056 -293.304393)
			(xy 189.351177 -293.273268) (xy 189.393798 -293.248661) (xy 189.439814 -293.231209) (xy 189.488033 -293.221365)
			(xy 189.537208 -293.219384) (xy 189.586063 -293.225316) (xy 189.633334 -293.239008) (xy 189.677796 -293.260106)
			(xy 189.718299 -293.288062) (xy 189.753792 -293.322154) (xy 189.783357 -293.361498) (xy 189.806228 -293.405075)
			(xy 189.821812 -293.451756) (xy 189.829707 -293.500333) (xy 189.830202 -293.52494) (xy 190.169304 -293.52494)
			(xy 190.173264 -293.475886) (xy 190.185041 -293.428102) (xy 190.204332 -293.382826) (xy 190.230635 -293.34123)
			(xy 190.26327 -293.304393) (xy 190.301391 -293.273268) (xy 190.344012 -293.248661) (xy 190.390028 -293.231209)
			(xy 190.438247 -293.221365) (xy 190.487422 -293.219384) (xy 190.536277 -293.225316) (xy 190.583548 -293.239008)
			(xy 190.62801 -293.260106) (xy 190.668513 -293.288062) (xy 190.704006 -293.322154) (xy 190.733571 -293.361498)
			(xy 190.756442 -293.405075) (xy 190.772026 -293.451756) (xy 190.779921 -293.500333) (xy 190.780416 -293.52494)
			(xy 191.119264 -293.52494) (xy 191.123224 -293.475886) (xy 191.135001 -293.428102) (xy 191.154292 -293.382826)
			(xy 191.180595 -293.34123) (xy 191.21323 -293.304393) (xy 191.251351 -293.273268) (xy 191.293972 -293.248661)
			(xy 191.339988 -293.231209) (xy 191.388207 -293.221365) (xy 191.437382 -293.219384) (xy 191.486237 -293.225316)
			(xy 191.533508 -293.239008) (xy 191.57797 -293.260106) (xy 191.618473 -293.288062) (xy 191.653966 -293.322154)
			(xy 191.683531 -293.361498) (xy 191.706402 -293.405075) (xy 191.721986 -293.451756) (xy 191.729881 -293.500333)
			(xy 191.730376 -293.52494) (xy 192.069224 -293.52494) (xy 192.073184 -293.475886) (xy 192.084961 -293.428102)
			(xy 192.104252 -293.382826) (xy 192.130555 -293.34123) (xy 192.16319 -293.304393) (xy 192.201311 -293.273268)
			(xy 192.243932 -293.248661) (xy 192.289948 -293.231209) (xy 192.338167 -293.221365) (xy 192.387342 -293.219384)
			(xy 192.436197 -293.225316) (xy 192.483468 -293.239008) (xy 192.52793 -293.260106) (xy 192.568433 -293.288062)
			(xy 192.603926 -293.322154) (xy 192.633491 -293.361498) (xy 192.656362 -293.405075) (xy 192.671946 -293.451756)
			(xy 192.679841 -293.500333) (xy 192.680336 -293.52494) (xy 193.019184 -293.52494) (xy 193.023144 -293.475886)
			(xy 193.034921 -293.428102) (xy 193.054212 -293.382826) (xy 193.080515 -293.34123) (xy 193.11315 -293.304393)
			(xy 193.151271 -293.273268) (xy 193.193892 -293.248661) (xy 193.239908 -293.231209) (xy 193.288127 -293.221365)
			(xy 193.337302 -293.219384) (xy 193.386157 -293.225316) (xy 193.433428 -293.239008) (xy 193.47789 -293.260106)
			(xy 193.518393 -293.288062) (xy 193.553886 -293.322154) (xy 193.583451 -293.361498) (xy 193.606322 -293.405075)
			(xy 193.621906 -293.451756) (xy 193.629801 -293.500333) (xy 193.630296 -293.52494) (xy 193.969144 -293.52494)
			(xy 193.973104 -293.475886) (xy 193.984881 -293.428102) (xy 194.004172 -293.382826) (xy 194.030475 -293.34123)
			(xy 194.06311 -293.304393) (xy 194.101231 -293.273268) (xy 194.143852 -293.248661) (xy 194.189868 -293.231209)
			(xy 194.238087 -293.221365) (xy 194.287262 -293.219384) (xy 194.336117 -293.225316) (xy 194.383388 -293.239008)
			(xy 194.42785 -293.260106) (xy 194.468353 -293.288062) (xy 194.503846 -293.322154) (xy 194.533411 -293.361498)
			(xy 194.556282 -293.405075) (xy 194.571866 -293.451756) (xy 194.579761 -293.500333) (xy 194.580256 -293.52494)
			(xy 194.919104 -293.52494) (xy 194.923064 -293.475886) (xy 194.934841 -293.428102) (xy 194.954132 -293.382826)
			(xy 194.980435 -293.34123) (xy 195.01307 -293.304393) (xy 195.051191 -293.273268) (xy 195.093812 -293.248661)
			(xy 195.139828 -293.231209) (xy 195.188047 -293.221365) (xy 195.237222 -293.219384) (xy 195.286077 -293.225316)
			(xy 195.333348 -293.239008) (xy 195.37781 -293.260106) (xy 195.418313 -293.288062) (xy 195.453806 -293.322154)
			(xy 195.483371 -293.361498) (xy 195.506242 -293.405075) (xy 195.521826 -293.451756) (xy 195.529721 -293.500333)
			(xy 195.530216 -293.52494) (xy 195.869064 -293.52494) (xy 195.873024 -293.475886) (xy 195.884801 -293.428102)
			(xy 195.904092 -293.382826) (xy 195.930395 -293.34123) (xy 195.96303 -293.304393) (xy 196.001151 -293.273268)
			(xy 196.043772 -293.248661) (xy 196.089788 -293.231209) (xy 196.138007 -293.221365) (xy 196.187182 -293.219384)
			(xy 196.236037 -293.225316) (xy 196.283308 -293.239008) (xy 196.32777 -293.260106) (xy 196.368273 -293.288062)
			(xy 196.403766 -293.322154) (xy 196.433331 -293.361498) (xy 196.456202 -293.405075) (xy 196.471786 -293.451756)
			(xy 196.479681 -293.500333) (xy 196.480176 -293.52494) (xy 196.819278 -293.52494) (xy 196.823238 -293.475886)
			(xy 196.835015 -293.428102) (xy 196.854306 -293.382826) (xy 196.880609 -293.34123) (xy 196.913244 -293.304393)
			(xy 196.951365 -293.273268) (xy 196.993986 -293.248661) (xy 197.040002 -293.231209) (xy 197.088221 -293.221365)
			(xy 197.137396 -293.219384) (xy 197.186251 -293.225316) (xy 197.233522 -293.239008) (xy 197.277984 -293.260106)
			(xy 197.318487 -293.288062) (xy 197.35398 -293.322154) (xy 197.383545 -293.361498) (xy 197.406416 -293.405075)
			(xy 197.422 -293.451756) (xy 197.429895 -293.500333) (xy 197.43039 -293.52494) (xy 197.769238 -293.52494)
			(xy 197.773198 -293.475886) (xy 197.784975 -293.428102) (xy 197.804266 -293.382826) (xy 197.830569 -293.34123)
			(xy 197.863204 -293.304393) (xy 197.901325 -293.273268) (xy 197.943946 -293.248661) (xy 197.989962 -293.231209)
			(xy 198.038181 -293.221365) (xy 198.087356 -293.219384) (xy 198.136211 -293.225316) (xy 198.183482 -293.239008)
			(xy 198.227944 -293.260106) (xy 198.268447 -293.288062) (xy 198.30394 -293.322154) (xy 198.333505 -293.361498)
			(xy 198.356376 -293.405075) (xy 198.37196 -293.451756) (xy 198.379855 -293.500333) (xy 198.38035 -293.52494)
			(xy 198.719198 -293.52494) (xy 198.723158 -293.475886) (xy 198.734935 -293.428102) (xy 198.754226 -293.382826)
			(xy 198.780529 -293.34123) (xy 198.813164 -293.304393) (xy 198.851285 -293.273268) (xy 198.893906 -293.248661)
			(xy 198.939922 -293.231209) (xy 198.988141 -293.221365) (xy 199.037316 -293.219384) (xy 199.086171 -293.225316)
			(xy 199.133442 -293.239008) (xy 199.177904 -293.260106) (xy 199.218407 -293.288062) (xy 199.2539 -293.322154)
			(xy 199.283465 -293.361498) (xy 199.306336 -293.405075) (xy 199.32192 -293.451756) (xy 199.329815 -293.500333)
			(xy 199.33031 -293.52494) (xy 199.329815 -293.549547) (xy 199.32192 -293.598124) (xy 199.306336 -293.644805)
			(xy 199.283465 -293.688382) (xy 199.2539 -293.727726) (xy 199.218407 -293.761818) (xy 199.177904 -293.789774)
			(xy 199.133442 -293.810872) (xy 199.086171 -293.824564) (xy 199.037316 -293.830496) (xy 198.988141 -293.828515)
			(xy 198.939922 -293.818671) (xy 198.893906 -293.801219) (xy 198.851285 -293.776612) (xy 198.813164 -293.745487)
			(xy 198.780529 -293.70865) (xy 198.754226 -293.667054) (xy 198.734935 -293.621778) (xy 198.723158 -293.573994)
			(xy 198.719198 -293.52494) (xy 198.38035 -293.52494) (xy 198.379855 -293.549547) (xy 198.37196 -293.598124)
			(xy 198.356376 -293.644805) (xy 198.333505 -293.688382) (xy 198.30394 -293.727726) (xy 198.268447 -293.761818)
			(xy 198.227944 -293.789774) (xy 198.183482 -293.810872) (xy 198.136211 -293.824564) (xy 198.087356 -293.830496)
			(xy 198.038181 -293.828515) (xy 197.989962 -293.818671) (xy 197.943946 -293.801219) (xy 197.901325 -293.776612)
			(xy 197.863204 -293.745487) (xy 197.830569 -293.70865) (xy 197.804266 -293.667054) (xy 197.784975 -293.621778)
			(xy 197.773198 -293.573994) (xy 197.769238 -293.52494) (xy 197.43039 -293.52494) (xy 197.429895 -293.549547)
			(xy 197.422 -293.598124) (xy 197.406416 -293.644805) (xy 197.383545 -293.688382) (xy 197.35398 -293.727726)
			(xy 197.318487 -293.761818) (xy 197.277984 -293.789774) (xy 197.233522 -293.810872) (xy 197.186251 -293.824564)
			(xy 197.137396 -293.830496) (xy 197.088221 -293.828515) (xy 197.040002 -293.818671) (xy 196.993986 -293.801219)
			(xy 196.951365 -293.776612) (xy 196.913244 -293.745487) (xy 196.880609 -293.70865) (xy 196.854306 -293.667054)
			(xy 196.835015 -293.621778) (xy 196.823238 -293.573994) (xy 196.819278 -293.52494) (xy 196.480176 -293.52494)
			(xy 196.479681 -293.549547) (xy 196.471786 -293.598124) (xy 196.456202 -293.644805) (xy 196.433331 -293.688382)
			(xy 196.403766 -293.727726) (xy 196.368273 -293.761818) (xy 196.32777 -293.789774) (xy 196.283308 -293.810872)
			(xy 196.236037 -293.824564) (xy 196.187182 -293.830496) (xy 196.138007 -293.828515) (xy 196.089788 -293.818671)
			(xy 196.043772 -293.801219) (xy 196.001151 -293.776612) (xy 195.96303 -293.745487) (xy 195.930395 -293.70865)
			(xy 195.904092 -293.667054) (xy 195.884801 -293.621778) (xy 195.873024 -293.573994) (xy 195.869064 -293.52494)
			(xy 195.530216 -293.52494) (xy 195.529721 -293.549547) (xy 195.521826 -293.598124) (xy 195.506242 -293.644805)
			(xy 195.483371 -293.688382) (xy 195.453806 -293.727726) (xy 195.418313 -293.761818) (xy 195.37781 -293.789774)
			(xy 195.333348 -293.810872) (xy 195.286077 -293.824564) (xy 195.237222 -293.830496) (xy 195.188047 -293.828515)
			(xy 195.139828 -293.818671) (xy 195.093812 -293.801219) (xy 195.051191 -293.776612) (xy 195.01307 -293.745487)
			(xy 194.980435 -293.70865) (xy 194.954132 -293.667054) (xy 194.934841 -293.621778) (xy 194.923064 -293.573994)
			(xy 194.919104 -293.52494) (xy 194.580256 -293.52494) (xy 194.579761 -293.549547) (xy 194.571866 -293.598124)
			(xy 194.556282 -293.644805) (xy 194.533411 -293.688382) (xy 194.503846 -293.727726) (xy 194.468353 -293.761818)
			(xy 194.42785 -293.789774) (xy 194.383388 -293.810872) (xy 194.336117 -293.824564) (xy 194.287262 -293.830496)
			(xy 194.238087 -293.828515) (xy 194.189868 -293.818671) (xy 194.143852 -293.801219) (xy 194.101231 -293.776612)
			(xy 194.06311 -293.745487) (xy 194.030475 -293.70865) (xy 194.004172 -293.667054) (xy 193.984881 -293.621778)
			(xy 193.973104 -293.573994) (xy 193.969144 -293.52494) (xy 193.630296 -293.52494) (xy 193.629801 -293.549547)
			(xy 193.621906 -293.598124) (xy 193.606322 -293.644805) (xy 193.583451 -293.688382) (xy 193.553886 -293.727726)
			(xy 193.518393 -293.761818) (xy 193.47789 -293.789774) (xy 193.433428 -293.810872) (xy 193.386157 -293.824564)
			(xy 193.337302 -293.830496) (xy 193.288127 -293.828515) (xy 193.239908 -293.818671) (xy 193.193892 -293.801219)
			(xy 193.151271 -293.776612) (xy 193.11315 -293.745487) (xy 193.080515 -293.70865) (xy 193.054212 -293.667054)
			(xy 193.034921 -293.621778) (xy 193.023144 -293.573994) (xy 193.019184 -293.52494) (xy 192.680336 -293.52494)
			(xy 192.679841 -293.549547) (xy 192.671946 -293.598124) (xy 192.656362 -293.644805) (xy 192.633491 -293.688382)
			(xy 192.603926 -293.727726) (xy 192.568433 -293.761818) (xy 192.52793 -293.789774) (xy 192.483468 -293.810872)
			(xy 192.436197 -293.824564) (xy 192.387342 -293.830496) (xy 192.338167 -293.828515) (xy 192.289948 -293.818671)
			(xy 192.243932 -293.801219) (xy 192.201311 -293.776612) (xy 192.16319 -293.745487) (xy 192.130555 -293.70865)
			(xy 192.104252 -293.667054) (xy 192.084961 -293.621778) (xy 192.073184 -293.573994) (xy 192.069224 -293.52494)
			(xy 191.730376 -293.52494) (xy 191.729881 -293.549547) (xy 191.721986 -293.598124) (xy 191.706402 -293.644805)
			(xy 191.683531 -293.688382) (xy 191.653966 -293.727726) (xy 191.618473 -293.761818) (xy 191.57797 -293.789774)
			(xy 191.533508 -293.810872) (xy 191.486237 -293.824564) (xy 191.437382 -293.830496) (xy 191.388207 -293.828515)
			(xy 191.339988 -293.818671) (xy 191.293972 -293.801219) (xy 191.251351 -293.776612) (xy 191.21323 -293.745487)
			(xy 191.180595 -293.70865) (xy 191.154292 -293.667054) (xy 191.135001 -293.621778) (xy 191.123224 -293.573994)
			(xy 191.119264 -293.52494) (xy 190.780416 -293.52494) (xy 190.779921 -293.549547) (xy 190.772026 -293.598124)
			(xy 190.756442 -293.644805) (xy 190.733571 -293.688382) (xy 190.704006 -293.727726) (xy 190.668513 -293.761818)
			(xy 190.62801 -293.789774) (xy 190.583548 -293.810872) (xy 190.536277 -293.824564) (xy 190.487422 -293.830496)
			(xy 190.438247 -293.828515) (xy 190.390028 -293.818671) (xy 190.344012 -293.801219) (xy 190.301391 -293.776612)
			(xy 190.26327 -293.745487) (xy 190.230635 -293.70865) (xy 190.204332 -293.667054) (xy 190.185041 -293.621778)
			(xy 190.173264 -293.573994) (xy 190.169304 -293.52494) (xy 189.830202 -293.52494) (xy 189.829707 -293.549547)
			(xy 189.821812 -293.598124) (xy 189.806228 -293.644805) (xy 189.783357 -293.688382) (xy 189.753792 -293.727726)
			(xy 189.718299 -293.761818) (xy 189.677796 -293.789774) (xy 189.633334 -293.810872) (xy 189.586063 -293.824564)
			(xy 189.537208 -293.830496) (xy 189.488033 -293.828515) (xy 189.439814 -293.818671) (xy 189.393798 -293.801219)
			(xy 189.351177 -293.776612) (xy 189.313056 -293.745487) (xy 189.280421 -293.70865) (xy 189.254118 -293.667054)
			(xy 189.234827 -293.621778) (xy 189.22305 -293.573994) (xy 189.21909 -293.52494) (xy 187.930282 -293.52494)
			(xy 187.929787 -293.549547) (xy 187.921892 -293.598124) (xy 187.906308 -293.644805) (xy 187.883437 -293.688382)
			(xy 187.853872 -293.727726) (xy 187.818379 -293.761818) (xy 187.777876 -293.789774) (xy 187.733414 -293.810872)
			(xy 187.686143 -293.824564) (xy 187.637288 -293.830496) (xy 187.588113 -293.828515) (xy 187.539894 -293.818671)
			(xy 187.493878 -293.801219) (xy 187.451257 -293.776612) (xy 187.413136 -293.745487) (xy 187.380501 -293.70865)
			(xy 187.354198 -293.667054) (xy 187.334907 -293.621778) (xy 187.32313 -293.573994) (xy 187.31917 -293.52494)
			(xy 186.980322 -293.52494) (xy 186.979827 -293.549547) (xy 186.971932 -293.598124) (xy 186.956348 -293.644805)
			(xy 186.933477 -293.688382) (xy 186.903912 -293.727726) (xy 186.868419 -293.761818) (xy 186.827916 -293.789774)
			(xy 186.783454 -293.810872) (xy 186.736183 -293.824564) (xy 186.687328 -293.830496) (xy 186.638153 -293.828515)
			(xy 186.589934 -293.818671) (xy 186.543918 -293.801219) (xy 186.501297 -293.776612) (xy 186.463176 -293.745487)
			(xy 186.430541 -293.70865) (xy 186.404238 -293.667054) (xy 186.384947 -293.621778) (xy 186.37317 -293.573994)
			(xy 186.36921 -293.52494) (xy 186.055285 -293.52494) (xy 186.055285 -293.550888) (xy 186.047153 -293.602225)
			(xy 186.03109 -293.651658) (xy 186.007491 -293.697968) (xy 185.976938 -293.740017) (xy 185.940182 -293.776767)
			(xy 185.898129 -293.807315) (xy 185.851815 -293.830908) (xy 185.80238 -293.846964) (xy 185.751042 -293.855088)
			(xy 185.725054 -293.855648) (xy 185.7248 -293.855648) (xy 185.705898 -293.855359) (xy 185.668343 -293.851026)
			(xy 185.64987 -293.847012) (xy 185.63844 -293.844218) (xy 185.616088 -293.849298) (xy 185.54446 -293.906194)
			(xy 185.53575 -293.913773) (xy 185.525708 -293.934538) (xy 185.525156 -293.946072) (xy 185.525156 -294.053768)
			(xy 185.525739 -294.064967) (xy 185.535222 -294.085259) (xy 185.543444 -294.092884) (xy 185.543952 -294.093392)
			(xy 185.616088 -294.150542) (xy 185.63844 -294.155622) (xy 185.64987 -294.152828) (xy 185.668338 -294.148785)
			(xy 185.705897 -294.144461) (xy 185.7248 -294.144192) (xy 185.725054 -294.144192) (xy 185.751046 -294.144672)
			(xy 185.80239 -294.152797) (xy 185.85183 -294.168855) (xy 185.89815 -294.192451) (xy 185.940208 -294.223002)
			(xy 185.976968 -294.259757) (xy 186.007525 -294.301811) (xy 186.031127 -294.348127) (xy 186.047192 -294.397565)
			(xy 186.055325 -294.448908) (xy 186.055325 -294.4749) (xy 186.36921 -294.4749) (xy 186.37317 -294.425846)
			(xy 186.384947 -294.378062) (xy 186.404238 -294.332786) (xy 186.430541 -294.29119) (xy 186.463176 -294.254353)
			(xy 186.501297 -294.223228) (xy 186.543918 -294.198621) (xy 186.589934 -294.181169) (xy 186.638153 -294.171325)
			(xy 186.687328 -294.169344) (xy 186.736183 -294.175276) (xy 186.783454 -294.188968) (xy 186.827916 -294.210066)
			(xy 186.868419 -294.238022) (xy 186.903912 -294.272114) (xy 186.933477 -294.311458) (xy 186.956348 -294.355035)
			(xy 186.971932 -294.401716) (xy 186.979827 -294.450293) (xy 186.980322 -294.4749) (xy 187.31917 -294.4749)
			(xy 187.32313 -294.425846) (xy 187.334907 -294.378062) (xy 187.354198 -294.332786) (xy 187.380501 -294.29119)
			(xy 187.413136 -294.254353) (xy 187.451257 -294.223228) (xy 187.493878 -294.198621) (xy 187.539894 -294.181169)
			(xy 187.588113 -294.171325) (xy 187.637288 -294.169344) (xy 187.686143 -294.175276) (xy 187.733414 -294.188968)
			(xy 187.777876 -294.210066) (xy 187.818379 -294.238022) (xy 187.853872 -294.272114) (xy 187.883437 -294.311458)
			(xy 187.906308 -294.355035) (xy 187.921892 -294.401716) (xy 187.929787 -294.450293) (xy 187.930282 -294.4749)
			(xy 189.21909 -294.4749) (xy 189.22305 -294.425846) (xy 189.234827 -294.378062) (xy 189.254118 -294.332786)
			(xy 189.280421 -294.29119) (xy 189.313056 -294.254353) (xy 189.351177 -294.223228) (xy 189.393798 -294.198621)
			(xy 189.439814 -294.181169) (xy 189.488033 -294.171325) (xy 189.537208 -294.169344) (xy 189.586063 -294.175276)
			(xy 189.633334 -294.188968) (xy 189.677796 -294.210066) (xy 189.718299 -294.238022) (xy 189.753792 -294.272114)
			(xy 189.783357 -294.311458) (xy 189.806228 -294.355035) (xy 189.821812 -294.401716) (xy 189.829707 -294.450293)
			(xy 189.830202 -294.4749) (xy 190.16905 -294.4749) (xy 190.17301 -294.425846) (xy 190.184787 -294.378062)
			(xy 190.204078 -294.332786) (xy 190.230381 -294.29119) (xy 190.263016 -294.254353) (xy 190.301137 -294.223228)
			(xy 190.343758 -294.198621) (xy 190.389774 -294.181169) (xy 190.437993 -294.171325) (xy 190.487168 -294.169344)
			(xy 190.536023 -294.175276) (xy 190.583294 -294.188968) (xy 190.627756 -294.210066) (xy 190.668259 -294.238022)
			(xy 190.703752 -294.272114) (xy 190.733317 -294.311458) (xy 190.756188 -294.355035) (xy 190.771772 -294.401716)
			(xy 190.779667 -294.450293) (xy 190.780162 -294.4749) (xy 191.119264 -294.4749) (xy 191.123224 -294.425846)
			(xy 191.135001 -294.378062) (xy 191.154292 -294.332786) (xy 191.180595 -294.29119) (xy 191.21323 -294.254353)
			(xy 191.251351 -294.223228) (xy 191.293972 -294.198621) (xy 191.339988 -294.181169) (xy 191.388207 -294.171325)
			(xy 191.437382 -294.169344) (xy 191.486237 -294.175276) (xy 191.533508 -294.188968) (xy 191.57797 -294.210066)
			(xy 191.618473 -294.238022) (xy 191.653966 -294.272114) (xy 191.683531 -294.311458) (xy 191.706402 -294.355035)
			(xy 191.721986 -294.401716) (xy 191.729881 -294.450293) (xy 191.730376 -294.4749) (xy 192.069224 -294.4749)
			(xy 192.073184 -294.425846) (xy 192.084961 -294.378062) (xy 192.104252 -294.332786) (xy 192.130555 -294.29119)
			(xy 192.16319 -294.254353) (xy 192.201311 -294.223228) (xy 192.243932 -294.198621) (xy 192.289948 -294.181169)
			(xy 192.338167 -294.171325) (xy 192.387342 -294.169344) (xy 192.436197 -294.175276) (xy 192.483468 -294.188968)
			(xy 192.52793 -294.210066) (xy 192.568433 -294.238022) (xy 192.603926 -294.272114) (xy 192.633491 -294.311458)
			(xy 192.656362 -294.355035) (xy 192.671946 -294.401716) (xy 192.679841 -294.450293) (xy 192.680336 -294.4749)
			(xy 193.019184 -294.4749) (xy 193.023144 -294.425846) (xy 193.034921 -294.378062) (xy 193.054212 -294.332786)
			(xy 193.080515 -294.29119) (xy 193.11315 -294.254353) (xy 193.151271 -294.223228) (xy 193.193892 -294.198621)
			(xy 193.239908 -294.181169) (xy 193.288127 -294.171325) (xy 193.337302 -294.169344) (xy 193.386157 -294.175276)
			(xy 193.433428 -294.188968) (xy 193.47789 -294.210066) (xy 193.518393 -294.238022) (xy 193.553886 -294.272114)
			(xy 193.583451 -294.311458) (xy 193.606322 -294.355035) (xy 193.621906 -294.401716) (xy 193.629801 -294.450293)
			(xy 193.630296 -294.4749) (xy 193.969144 -294.4749) (xy 193.973104 -294.425846) (xy 193.984881 -294.378062)
			(xy 194.004172 -294.332786) (xy 194.030475 -294.29119) (xy 194.06311 -294.254353) (xy 194.101231 -294.223228)
			(xy 194.143852 -294.198621) (xy 194.189868 -294.181169) (xy 194.238087 -294.171325) (xy 194.287262 -294.169344)
			(xy 194.336117 -294.175276) (xy 194.383388 -294.188968) (xy 194.42785 -294.210066) (xy 194.468353 -294.238022)
			(xy 194.503846 -294.272114) (xy 194.533411 -294.311458) (xy 194.556282 -294.355035) (xy 194.571866 -294.401716)
			(xy 194.579761 -294.450293) (xy 194.580256 -294.4749) (xy 194.919104 -294.4749) (xy 194.923064 -294.425846)
			(xy 194.934841 -294.378062) (xy 194.954132 -294.332786) (xy 194.980435 -294.29119) (xy 195.01307 -294.254353)
			(xy 195.051191 -294.223228) (xy 195.093812 -294.198621) (xy 195.139828 -294.181169) (xy 195.188047 -294.171325)
			(xy 195.237222 -294.169344) (xy 195.286077 -294.175276) (xy 195.333348 -294.188968) (xy 195.37781 -294.210066)
			(xy 195.418313 -294.238022) (xy 195.453806 -294.272114) (xy 195.483371 -294.311458) (xy 195.506242 -294.355035)
			(xy 195.521826 -294.401716) (xy 195.529721 -294.450293) (xy 195.530216 -294.4749) (xy 195.869064 -294.4749)
			(xy 195.873024 -294.425846) (xy 195.884801 -294.378062) (xy 195.904092 -294.332786) (xy 195.930395 -294.29119)
			(xy 195.96303 -294.254353) (xy 196.001151 -294.223228) (xy 196.043772 -294.198621) (xy 196.089788 -294.181169)
			(xy 196.138007 -294.171325) (xy 196.187182 -294.169344) (xy 196.236037 -294.175276) (xy 196.283308 -294.188968)
			(xy 196.32777 -294.210066) (xy 196.368273 -294.238022) (xy 196.403766 -294.272114) (xy 196.433331 -294.311458)
			(xy 196.456202 -294.355035) (xy 196.471786 -294.401716) (xy 196.479681 -294.450293) (xy 196.480176 -294.4749)
			(xy 196.819278 -294.4749) (xy 196.823238 -294.425846) (xy 196.835015 -294.378062) (xy 196.854306 -294.332786)
			(xy 196.880609 -294.29119) (xy 196.913244 -294.254353) (xy 196.951365 -294.223228) (xy 196.993986 -294.198621)
			(xy 197.040002 -294.181169) (xy 197.088221 -294.171325) (xy 197.137396 -294.169344) (xy 197.186251 -294.175276)
			(xy 197.233522 -294.188968) (xy 197.277984 -294.210066) (xy 197.318487 -294.238022) (xy 197.35398 -294.272114)
			(xy 197.383545 -294.311458) (xy 197.406416 -294.355035) (xy 197.422 -294.401716) (xy 197.429895 -294.450293)
			(xy 197.43039 -294.4749) (xy 197.769238 -294.4749) (xy 197.773198 -294.425846) (xy 197.784975 -294.378062)
			(xy 197.804266 -294.332786) (xy 197.830569 -294.29119) (xy 197.863204 -294.254353) (xy 197.901325 -294.223228)
			(xy 197.943946 -294.198621) (xy 197.989962 -294.181169) (xy 198.038181 -294.171325) (xy 198.087356 -294.169344)
			(xy 198.136211 -294.175276) (xy 198.183482 -294.188968) (xy 198.227944 -294.210066) (xy 198.268447 -294.238022)
			(xy 198.30394 -294.272114) (xy 198.333505 -294.311458) (xy 198.356376 -294.355035) (xy 198.37196 -294.401716)
			(xy 198.379855 -294.450293) (xy 198.38035 -294.4749) (xy 198.719198 -294.4749) (xy 198.723158 -294.425846)
			(xy 198.734935 -294.378062) (xy 198.754226 -294.332786) (xy 198.780529 -294.29119) (xy 198.813164 -294.254353)
			(xy 198.851285 -294.223228) (xy 198.893906 -294.198621) (xy 198.939922 -294.181169) (xy 198.988141 -294.171325)
			(xy 199.037316 -294.169344) (xy 199.086171 -294.175276) (xy 199.133442 -294.188968) (xy 199.177904 -294.210066)
			(xy 199.218407 -294.238022) (xy 199.2539 -294.272114) (xy 199.283465 -294.311458) (xy 199.306336 -294.355035)
			(xy 199.32192 -294.401716) (xy 199.329815 -294.450293) (xy 199.33031 -294.4749) (xy 199.329815 -294.499507)
			(xy 199.32192 -294.548084) (xy 199.306336 -294.594765) (xy 199.283465 -294.638342) (xy 199.2539 -294.677686)
			(xy 199.220324 -294.709937) (xy 205.263126 -294.709937) (xy 205.263128 -294.655425) (xy 205.270889 -294.601469)
			(xy 205.28625 -294.549166) (xy 205.308898 -294.499582) (xy 205.338373 -294.453725) (xy 205.374074 -294.412531)
			(xy 205.415274 -294.376837) (xy 205.461135 -294.347369) (xy 205.510723 -294.324729) (xy 205.563028 -294.309376)
			(xy 205.616986 -294.301624) (xy 205.644242 -294.301164) (xy 205.669642 -294.301926) (xy 205.684375 -294.302413)
			(xy 205.713104 -294.29587) (xy 205.738771 -294.281399) (xy 205.759238 -294.260201) (xy 205.772802 -294.234043)
			(xy 205.778333 -294.205102) (xy 205.775372 -294.175786) (xy 205.770226 -294.161972) (xy 205.761062 -294.13877)
			(xy 205.748173 -294.090579) (xy 205.741674 -294.041119) (xy 205.74127 -294.016176) (xy 205.741804 -293.988927)
			(xy 205.749563 -293.934983) (xy 205.764921 -293.882692) (xy 205.787563 -293.83312) (xy 205.817031 -293.787274)
			(xy 205.852722 -293.746089) (xy 205.893912 -293.710402) (xy 205.939761 -293.680941) (xy 205.989337 -293.658304)
			(xy 206.041629 -293.642953) (xy 206.095574 -293.635201) (xy 206.150073 -293.635204) (xy 206.204017 -293.642963)
			(xy 206.256307 -293.65832) (xy 206.30588 -293.680963) (xy 206.351725 -293.71043) (xy 206.392911 -293.746122)
			(xy 206.428597 -293.787312) (xy 206.458059 -293.833161) (xy 206.480696 -293.882736) (xy 206.496047 -293.935028)
			(xy 206.502598 -293.980616) (xy 207.380838 -293.980616) (xy 207.384909 -293.924994) (xy 207.397035 -293.870557)
			(xy 207.416958 -293.818466) (xy 207.444254 -293.769831) (xy 207.47834 -293.725688) (xy 207.518489 -293.686979)
			(xy 207.563847 -293.654528) (xy 207.613447 -293.629027) (xy 207.666231 -293.61102) (xy 207.721074 -293.60089)
			(xy 207.776808 -293.598853) (xy 207.832245 -293.604953) (xy 207.886202 -293.619059) (xy 207.937531 -293.640871)
			(xy 207.985137 -293.669925) (xy 208.028005 -293.7056) (xy 208.065222 -293.747137) (xy 208.095995 -293.79365)
			(xy 208.119667 -293.844147) (xy 208.135735 -293.897554) (xy 208.143855 -293.95273) (xy 208.144364 -293.980616)
			(xy 208.143855 -294.008502) (xy 208.135735 -294.063678) (xy 208.119667 -294.117085) (xy 208.095995 -294.167582)
			(xy 208.065222 -294.214095) (xy 208.028005 -294.255632) (xy 207.985137 -294.291307) (xy 207.937531 -294.320361)
			(xy 207.886202 -294.342173) (xy 207.832245 -294.356279) (xy 207.776808 -294.362379) (xy 207.721074 -294.360342)
			(xy 207.666231 -294.350212) (xy 207.613447 -294.332205) (xy 207.563847 -294.306704) (xy 207.518489 -294.274253)
			(xy 207.47834 -294.235544) (xy 207.444254 -294.191401) (xy 207.416958 -294.142766) (xy 207.397035 -294.090675)
			(xy 207.384909 -294.036238) (xy 207.380838 -293.980616) (xy 206.502598 -293.980616) (xy 206.503799 -293.988973)
			(xy 206.503796 -294.043472) (xy 206.496037 -294.097416) (xy 206.48068 -294.149706) (xy 206.458037 -294.199279)
			(xy 206.42857 -294.245125) (xy 206.392878 -294.28631) (xy 206.351689 -294.321997) (xy 206.30584 -294.351459)
			(xy 206.256264 -294.374095) (xy 206.203972 -294.389446) (xy 206.150027 -294.397199) (xy 206.122778 -294.397684)
			(xy 206.097378 -294.396922) (xy 206.082647 -294.396524) (xy 206.05393 -294.403057) (xy 206.028272 -294.417516)
			(xy 206.00781 -294.438698) (xy 205.994245 -294.464839) (xy 205.988707 -294.493764) (xy 205.989493 -294.50157)
			(xy 206.636618 -294.50157) (xy 206.640689 -294.445948) (xy 206.652815 -294.391511) (xy 206.672738 -294.33942)
			(xy 206.700034 -294.290785) (xy 206.73412 -294.246642) (xy 206.774269 -294.207933) (xy 206.819627 -294.175482)
			(xy 206.869227 -294.149981) (xy 206.922011 -294.131974) (xy 206.976854 -294.121844) (xy 207.032588 -294.119807)
			(xy 207.088025 -294.125907) (xy 207.141982 -294.140013) (xy 207.193311 -294.161825) (xy 207.240917 -294.190879)
			(xy 207.283785 -294.226554) (xy 207.321002 -294.268091) (xy 207.351775 -294.314604) (xy 207.375447 -294.365101)
			(xy 207.391515 -294.418508) (xy 207.399635 -294.473684) (xy 207.400144 -294.50157) (xy 207.399635 -294.529456)
			(xy 207.391515 -294.584632) (xy 207.375447 -294.638039) (xy 207.351775 -294.688536) (xy 207.321002 -294.735049)
			(xy 207.283785 -294.776586) (xy 207.240917 -294.812261) (xy 207.193311 -294.841315) (xy 207.141982 -294.863127)
			(xy 207.088025 -294.877233) (xy 207.032588 -294.883333) (xy 206.976854 -294.881296) (xy 206.922011 -294.871166)
			(xy 206.869227 -294.853159) (xy 206.819627 -294.827658) (xy 206.774269 -294.795207) (xy 206.73412 -294.756498)
			(xy 206.700034 -294.712355) (xy 206.672738 -294.66372) (xy 206.652815 -294.611629) (xy 206.640689 -294.557192)
			(xy 206.636618 -294.50157) (xy 205.989493 -294.50157) (xy 205.991656 -294.523067) (xy 205.996794 -294.536876)
			(xy 206.005943 -294.560083) (xy 206.018838 -294.608272) (xy 206.025342 -294.65773) (xy 206.02575 -294.682672)
			(xy 206.025275 -294.709928) (xy 206.017521 -294.763886) (xy 206.002166 -294.81619) (xy 205.979524 -294.865777)
			(xy 205.950055 -294.911637) (xy 205.914359 -294.952836) (xy 205.873163 -294.988535) (xy 205.827306 -295.018008)
			(xy 205.777721 -295.040655) (xy 205.725418 -295.056014) (xy 205.671461 -295.063773) (xy 205.616949 -295.063773)
			(xy 205.562992 -295.056016) (xy 205.510688 -295.040658) (xy 205.461102 -295.018013) (xy 205.415244 -294.988541)
			(xy 205.374047 -294.952843) (xy 205.338351 -294.911645) (xy 205.30888 -294.865786) (xy 205.286237 -294.816199)
			(xy 205.270881 -294.763895) (xy 205.263126 -294.709937) (xy 199.220324 -294.709937) (xy 199.218407 -294.711778)
			(xy 199.177904 -294.739734) (xy 199.133442 -294.760832) (xy 199.086171 -294.774524) (xy 199.037316 -294.780456)
			(xy 198.988141 -294.778475) (xy 198.939922 -294.768631) (xy 198.893906 -294.751179) (xy 198.851285 -294.726572)
			(xy 198.813164 -294.695447) (xy 198.780529 -294.65861) (xy 198.754226 -294.617014) (xy 198.734935 -294.571738)
			(xy 198.723158 -294.523954) (xy 198.719198 -294.4749) (xy 198.38035 -294.4749) (xy 198.379855 -294.499507)
			(xy 198.37196 -294.548084) (xy 198.356376 -294.594765) (xy 198.333505 -294.638342) (xy 198.30394 -294.677686)
			(xy 198.268447 -294.711778) (xy 198.227944 -294.739734) (xy 198.183482 -294.760832) (xy 198.136211 -294.774524)
			(xy 198.087356 -294.780456) (xy 198.038181 -294.778475) (xy 197.989962 -294.768631) (xy 197.943946 -294.751179)
			(xy 197.901325 -294.726572) (xy 197.863204 -294.695447) (xy 197.830569 -294.65861) (xy 197.804266 -294.617014)
			(xy 197.784975 -294.571738) (xy 197.773198 -294.523954) (xy 197.769238 -294.4749) (xy 197.43039 -294.4749)
			(xy 197.429895 -294.499507) (xy 197.422 -294.548084) (xy 197.406416 -294.594765) (xy 197.383545 -294.638342)
			(xy 197.35398 -294.677686) (xy 197.318487 -294.711778) (xy 197.277984 -294.739734) (xy 197.233522 -294.760832)
			(xy 197.186251 -294.774524) (xy 197.137396 -294.780456) (xy 197.088221 -294.778475) (xy 197.040002 -294.768631)
			(xy 196.993986 -294.751179) (xy 196.951365 -294.726572) (xy 196.913244 -294.695447) (xy 196.880609 -294.65861)
			(xy 196.854306 -294.617014) (xy 196.835015 -294.571738) (xy 196.823238 -294.523954) (xy 196.819278 -294.4749)
			(xy 196.480176 -294.4749) (xy 196.479681 -294.499507) (xy 196.471786 -294.548084) (xy 196.456202 -294.594765)
			(xy 196.433331 -294.638342) (xy 196.403766 -294.677686) (xy 196.368273 -294.711778) (xy 196.32777 -294.739734)
			(xy 196.283308 -294.760832) (xy 196.236037 -294.774524) (xy 196.187182 -294.780456) (xy 196.138007 -294.778475)
			(xy 196.089788 -294.768631) (xy 196.043772 -294.751179) (xy 196.001151 -294.726572) (xy 195.96303 -294.695447)
			(xy 195.930395 -294.65861) (xy 195.904092 -294.617014) (xy 195.884801 -294.571738) (xy 195.873024 -294.523954)
			(xy 195.869064 -294.4749) (xy 195.530216 -294.4749) (xy 195.529721 -294.499507) (xy 195.521826 -294.548084)
			(xy 195.506242 -294.594765) (xy 195.483371 -294.638342) (xy 195.453806 -294.677686) (xy 195.418313 -294.711778)
			(xy 195.37781 -294.739734) (xy 195.333348 -294.760832) (xy 195.286077 -294.774524) (xy 195.237222 -294.780456)
			(xy 195.188047 -294.778475) (xy 195.139828 -294.768631) (xy 195.093812 -294.751179) (xy 195.051191 -294.726572)
			(xy 195.01307 -294.695447) (xy 194.980435 -294.65861) (xy 194.954132 -294.617014) (xy 194.934841 -294.571738)
			(xy 194.923064 -294.523954) (xy 194.919104 -294.4749) (xy 194.580256 -294.4749) (xy 194.579761 -294.499507)
			(xy 194.571866 -294.548084) (xy 194.556282 -294.594765) (xy 194.533411 -294.638342) (xy 194.503846 -294.677686)
			(xy 194.468353 -294.711778) (xy 194.42785 -294.739734) (xy 194.383388 -294.760832) (xy 194.336117 -294.774524)
			(xy 194.287262 -294.780456) (xy 194.238087 -294.778475) (xy 194.189868 -294.768631) (xy 194.143852 -294.751179)
			(xy 194.101231 -294.726572) (xy 194.06311 -294.695447) (xy 194.030475 -294.65861) (xy 194.004172 -294.617014)
			(xy 193.984881 -294.571738) (xy 193.973104 -294.523954) (xy 193.969144 -294.4749) (xy 193.630296 -294.4749)
			(xy 193.629801 -294.499507) (xy 193.621906 -294.548084) (xy 193.606322 -294.594765) (xy 193.583451 -294.638342)
			(xy 193.553886 -294.677686) (xy 193.518393 -294.711778) (xy 193.47789 -294.739734) (xy 193.433428 -294.760832)
			(xy 193.386157 -294.774524) (xy 193.337302 -294.780456) (xy 193.288127 -294.778475) (xy 193.239908 -294.768631)
			(xy 193.193892 -294.751179) (xy 193.151271 -294.726572) (xy 193.11315 -294.695447) (xy 193.080515 -294.65861)
			(xy 193.054212 -294.617014) (xy 193.034921 -294.571738) (xy 193.023144 -294.523954) (xy 193.019184 -294.4749)
			(xy 192.680336 -294.4749) (xy 192.679841 -294.499507) (xy 192.671946 -294.548084) (xy 192.656362 -294.594765)
			(xy 192.633491 -294.638342) (xy 192.603926 -294.677686) (xy 192.568433 -294.711778) (xy 192.52793 -294.739734)
			(xy 192.483468 -294.760832) (xy 192.436197 -294.774524) (xy 192.387342 -294.780456) (xy 192.338167 -294.778475)
			(xy 192.289948 -294.768631) (xy 192.243932 -294.751179) (xy 192.201311 -294.726572) (xy 192.16319 -294.695447)
			(xy 192.130555 -294.65861) (xy 192.104252 -294.617014) (xy 192.084961 -294.571738) (xy 192.073184 -294.523954)
			(xy 192.069224 -294.4749) (xy 191.730376 -294.4749) (xy 191.729881 -294.499507) (xy 191.721986 -294.548084)
			(xy 191.706402 -294.594765) (xy 191.683531 -294.638342) (xy 191.653966 -294.677686) (xy 191.618473 -294.711778)
			(xy 191.57797 -294.739734) (xy 191.533508 -294.760832) (xy 191.486237 -294.774524) (xy 191.437382 -294.780456)
			(xy 191.388207 -294.778475) (xy 191.339988 -294.768631) (xy 191.293972 -294.751179) (xy 191.251351 -294.726572)
			(xy 191.21323 -294.695447) (xy 191.180595 -294.65861) (xy 191.154292 -294.617014) (xy 191.135001 -294.571738)
			(xy 191.123224 -294.523954) (xy 191.119264 -294.4749) (xy 190.780162 -294.4749) (xy 190.779667 -294.499507)
			(xy 190.771772 -294.548084) (xy 190.756188 -294.594765) (xy 190.733317 -294.638342) (xy 190.703752 -294.677686)
			(xy 190.668259 -294.711778) (xy 190.627756 -294.739734) (xy 190.583294 -294.760832) (xy 190.536023 -294.774524)
			(xy 190.487168 -294.780456) (xy 190.437993 -294.778475) (xy 190.389774 -294.768631) (xy 190.343758 -294.751179)
			(xy 190.301137 -294.726572) (xy 190.263016 -294.695447) (xy 190.230381 -294.65861) (xy 190.204078 -294.617014)
			(xy 190.184787 -294.571738) (xy 190.17301 -294.523954) (xy 190.16905 -294.4749) (xy 189.830202 -294.4749)
			(xy 189.829707 -294.499507) (xy 189.821812 -294.548084) (xy 189.806228 -294.594765) (xy 189.783357 -294.638342)
			(xy 189.753792 -294.677686) (xy 189.718299 -294.711778) (xy 189.677796 -294.739734) (xy 189.633334 -294.760832)
			(xy 189.586063 -294.774524) (xy 189.537208 -294.780456) (xy 189.488033 -294.778475) (xy 189.439814 -294.768631)
			(xy 189.393798 -294.751179) (xy 189.351177 -294.726572) (xy 189.313056 -294.695447) (xy 189.280421 -294.65861)
			(xy 189.254118 -294.617014) (xy 189.234827 -294.571738) (xy 189.22305 -294.523954) (xy 189.21909 -294.4749)
			(xy 187.930282 -294.4749) (xy 187.929787 -294.499507) (xy 187.921892 -294.548084) (xy 187.906308 -294.594765)
			(xy 187.883437 -294.638342) (xy 187.853872 -294.677686) (xy 187.818379 -294.711778) (xy 187.777876 -294.739734)
			(xy 187.733414 -294.760832) (xy 187.686143 -294.774524) (xy 187.637288 -294.780456) (xy 187.588113 -294.778475)
			(xy 187.539894 -294.768631) (xy 187.493878 -294.751179) (xy 187.451257 -294.726572) (xy 187.413136 -294.695447)
			(xy 187.380501 -294.65861) (xy 187.354198 -294.617014) (xy 187.334907 -294.571738) (xy 187.32313 -294.523954)
			(xy 187.31917 -294.4749) (xy 186.980322 -294.4749) (xy 186.979827 -294.499507) (xy 186.971932 -294.548084)
			(xy 186.956348 -294.594765) (xy 186.933477 -294.638342) (xy 186.903912 -294.677686) (xy 186.868419 -294.711778)
			(xy 186.827916 -294.739734) (xy 186.783454 -294.760832) (xy 186.736183 -294.774524) (xy 186.687328 -294.780456)
			(xy 186.638153 -294.778475) (xy 186.589934 -294.768631) (xy 186.543918 -294.751179) (xy 186.501297 -294.726572)
			(xy 186.463176 -294.695447) (xy 186.430541 -294.65861) (xy 186.404238 -294.617014) (xy 186.384947 -294.571738)
			(xy 186.37317 -294.523954) (xy 186.36921 -294.4749) (xy 186.055325 -294.4749) (xy 186.055325 -294.500892)
			(xy 186.047192 -294.552235) (xy 186.031127 -294.601673) (xy 186.007525 -294.647989) (xy 185.976968 -294.690043)
			(xy 185.940208 -294.726798) (xy 185.89815 -294.757349) (xy 185.85183 -294.780945) (xy 185.80239 -294.797003)
			(xy 185.751046 -294.805128) (xy 185.725054 -294.805608) (xy 185.7248 -294.805608) (xy 185.705898 -294.805319)
			(xy 185.668343 -294.800985) (xy 185.64987 -294.796972) (xy 185.63844 -294.794178) (xy 185.616088 -294.799258)
			(xy 185.54446 -294.856154) (xy 185.535743 -294.863731) (xy 185.525685 -294.884495) (xy 185.525156 -294.896032)
			(xy 185.525156 -295.355518) (xy 208.715862 -295.355518) (xy 208.719933 -295.299896) (xy 208.732059 -295.245459)
			(xy 208.751982 -295.193368) (xy 208.779278 -295.144733) (xy 208.813364 -295.10059) (xy 208.853513 -295.061881)
			(xy 208.898871 -295.02943) (xy 208.948471 -295.003929) (xy 209.001255 -294.985922) (xy 209.056098 -294.975792)
			(xy 209.111832 -294.973755) (xy 209.167269 -294.979855) (xy 209.221226 -294.993961) (xy 209.272555 -295.015773)
			(xy 209.320161 -295.044827) (xy 209.363029 -295.080502) (xy 209.400246 -295.122039) (xy 209.431019 -295.168552)
			(xy 209.454691 -295.219049) (xy 209.470759 -295.272456) (xy 209.478879 -295.327632) (xy 209.479388 -295.355518)
			(xy 209.478879 -295.383404) (xy 209.470759 -295.43858) (xy 209.454691 -295.491987) (xy 209.431019 -295.542484)
			(xy 209.400246 -295.588997) (xy 209.363029 -295.630534) (xy 209.320161 -295.666209) (xy 209.272555 -295.695263)
			(xy 209.221226 -295.717075) (xy 209.167269 -295.731181) (xy 209.111832 -295.737281) (xy 209.056098 -295.735244)
			(xy 209.001255 -295.725114) (xy 208.948471 -295.707107) (xy 208.898871 -295.681606) (xy 208.853513 -295.649155)
			(xy 208.813364 -295.610446) (xy 208.779278 -295.566303) (xy 208.751982 -295.517668) (xy 208.732059 -295.465577)
			(xy 208.719933 -295.41114) (xy 208.715862 -295.355518) (xy 185.525156 -295.355518) (xy 185.525156 -295.953688)
			(xy 185.525743 -295.964885) (xy 185.535231 -295.985171) (xy 185.543444 -295.992804) (xy 185.543952 -295.993312)
			(xy 185.616088 -296.050462) (xy 185.63844 -296.055542) (xy 185.64987 -296.052748) (xy 185.668338 -296.048705)
			(xy 185.705897 -296.044381) (xy 185.7248 -296.044112) (xy 185.725054 -296.044112) (xy 185.751044 -296.044592)
			(xy 185.802385 -296.052717) (xy 185.851823 -296.068774) (xy 185.89814 -296.092368) (xy 185.940195 -296.122917)
			(xy 185.976953 -296.15967) (xy 186.007508 -296.201721) (xy 186.031109 -296.248035) (xy 186.047173 -296.29747)
			(xy 186.055305 -296.34881) (xy 186.055305 -296.37482) (xy 186.36921 -296.37482) (xy 186.37317 -296.325766)
			(xy 186.384947 -296.277982) (xy 186.404238 -296.232706) (xy 186.430541 -296.19111) (xy 186.463176 -296.154273)
			(xy 186.501297 -296.123148) (xy 186.543918 -296.098541) (xy 186.589934 -296.081089) (xy 186.638153 -296.071245)
			(xy 186.687328 -296.069264) (xy 186.736183 -296.075196) (xy 186.783454 -296.088888) (xy 186.827916 -296.109986)
			(xy 186.868419 -296.137942) (xy 186.903912 -296.172034) (xy 186.933477 -296.211378) (xy 186.956348 -296.254955)
			(xy 186.971932 -296.301636) (xy 186.979827 -296.350213) (xy 186.980322 -296.37482) (xy 187.31917 -296.37482)
			(xy 187.32313 -296.325766) (xy 187.334907 -296.277982) (xy 187.354198 -296.232706) (xy 187.380501 -296.19111)
			(xy 187.413136 -296.154273) (xy 187.451257 -296.123148) (xy 187.493878 -296.098541) (xy 187.539894 -296.081089)
			(xy 187.588113 -296.071245) (xy 187.637288 -296.069264) (xy 187.686143 -296.075196) (xy 187.733414 -296.088888)
			(xy 187.777876 -296.109986) (xy 187.818379 -296.137942) (xy 187.853872 -296.172034) (xy 187.883437 -296.211378)
			(xy 187.906308 -296.254955) (xy 187.921892 -296.301636) (xy 187.929787 -296.350213) (xy 187.930282 -296.37482)
			(xy 189.21909 -296.37482) (xy 189.22305 -296.325766) (xy 189.234827 -296.277982) (xy 189.254118 -296.232706)
			(xy 189.280421 -296.19111) (xy 189.313056 -296.154273) (xy 189.351177 -296.123148) (xy 189.393798 -296.098541)
			(xy 189.439814 -296.081089) (xy 189.488033 -296.071245) (xy 189.537208 -296.069264) (xy 189.586063 -296.075196)
			(xy 189.633334 -296.088888) (xy 189.677796 -296.109986) (xy 189.718299 -296.137942) (xy 189.753792 -296.172034)
			(xy 189.783357 -296.211378) (xy 189.806228 -296.254955) (xy 189.821812 -296.301636) (xy 189.829707 -296.350213)
			(xy 189.830202 -296.37482) (xy 190.16905 -296.37482) (xy 190.17301 -296.325766) (xy 190.184787 -296.277982)
			(xy 190.204078 -296.232706) (xy 190.230381 -296.19111) (xy 190.263016 -296.154273) (xy 190.301137 -296.123148)
			(xy 190.343758 -296.098541) (xy 190.389774 -296.081089) (xy 190.437993 -296.071245) (xy 190.487168 -296.069264)
			(xy 190.536023 -296.075196) (xy 190.583294 -296.088888) (xy 190.627756 -296.109986) (xy 190.668259 -296.137942)
			(xy 190.703752 -296.172034) (xy 190.733317 -296.211378) (xy 190.756188 -296.254955) (xy 190.771772 -296.301636)
			(xy 190.779667 -296.350213) (xy 190.780162 -296.37482) (xy 191.119264 -296.37482) (xy 191.123224 -296.325766)
			(xy 191.135001 -296.277982) (xy 191.154292 -296.232706) (xy 191.180595 -296.19111) (xy 191.21323 -296.154273)
			(xy 191.251351 -296.123148) (xy 191.293972 -296.098541) (xy 191.339988 -296.081089) (xy 191.388207 -296.071245)
			(xy 191.437382 -296.069264) (xy 191.486237 -296.075196) (xy 191.533508 -296.088888) (xy 191.57797 -296.109986)
			(xy 191.618473 -296.137942) (xy 191.653966 -296.172034) (xy 191.683531 -296.211378) (xy 191.706402 -296.254955)
			(xy 191.721986 -296.301636) (xy 191.729881 -296.350213) (xy 191.730376 -296.37482) (xy 192.069224 -296.37482)
			(xy 192.073184 -296.325766) (xy 192.084961 -296.277982) (xy 192.104252 -296.232706) (xy 192.130555 -296.19111)
			(xy 192.16319 -296.154273) (xy 192.201311 -296.123148) (xy 192.243932 -296.098541) (xy 192.289948 -296.081089)
			(xy 192.338167 -296.071245) (xy 192.387342 -296.069264) (xy 192.436197 -296.075196) (xy 192.483468 -296.088888)
			(xy 192.52793 -296.109986) (xy 192.568433 -296.137942) (xy 192.603926 -296.172034) (xy 192.633491 -296.211378)
			(xy 192.656362 -296.254955) (xy 192.671946 -296.301636) (xy 192.679841 -296.350213) (xy 192.680336 -296.37482)
			(xy 193.019184 -296.37482) (xy 193.023144 -296.325766) (xy 193.034921 -296.277982) (xy 193.054212 -296.232706)
			(xy 193.080515 -296.19111) (xy 193.11315 -296.154273) (xy 193.151271 -296.123148) (xy 193.193892 -296.098541)
			(xy 193.239908 -296.081089) (xy 193.288127 -296.071245) (xy 193.337302 -296.069264) (xy 193.386157 -296.075196)
			(xy 193.433428 -296.088888) (xy 193.47789 -296.109986) (xy 193.518393 -296.137942) (xy 193.553886 -296.172034)
			(xy 193.583451 -296.211378) (xy 193.606322 -296.254955) (xy 193.621906 -296.301636) (xy 193.629801 -296.350213)
			(xy 193.630296 -296.37482) (xy 193.969144 -296.37482) (xy 193.973104 -296.325766) (xy 193.984881 -296.277982)
			(xy 194.004172 -296.232706) (xy 194.030475 -296.19111) (xy 194.06311 -296.154273) (xy 194.101231 -296.123148)
			(xy 194.143852 -296.098541) (xy 194.189868 -296.081089) (xy 194.238087 -296.071245) (xy 194.287262 -296.069264)
			(xy 194.336117 -296.075196) (xy 194.383388 -296.088888) (xy 194.42785 -296.109986) (xy 194.468353 -296.137942)
			(xy 194.503846 -296.172034) (xy 194.533411 -296.211378) (xy 194.556282 -296.254955) (xy 194.571866 -296.301636)
			(xy 194.579761 -296.350213) (xy 194.580256 -296.37482) (xy 194.919104 -296.37482) (xy 194.923064 -296.325766)
			(xy 194.934841 -296.277982) (xy 194.954132 -296.232706) (xy 194.980435 -296.19111) (xy 195.01307 -296.154273)
			(xy 195.051191 -296.123148) (xy 195.093812 -296.098541) (xy 195.139828 -296.081089) (xy 195.188047 -296.071245)
			(xy 195.237222 -296.069264) (xy 195.286077 -296.075196) (xy 195.333348 -296.088888) (xy 195.37781 -296.109986)
			(xy 195.418313 -296.137942) (xy 195.453806 -296.172034) (xy 195.483371 -296.211378) (xy 195.506242 -296.254955)
			(xy 195.521826 -296.301636) (xy 195.529721 -296.350213) (xy 195.530216 -296.37482) (xy 195.869064 -296.37482)
			(xy 195.873024 -296.325766) (xy 195.884801 -296.277982) (xy 195.904092 -296.232706) (xy 195.930395 -296.19111)
			(xy 195.96303 -296.154273) (xy 196.001151 -296.123148) (xy 196.043772 -296.098541) (xy 196.089788 -296.081089)
			(xy 196.138007 -296.071245) (xy 196.187182 -296.069264) (xy 196.236037 -296.075196) (xy 196.283308 -296.088888)
			(xy 196.32777 -296.109986) (xy 196.368273 -296.137942) (xy 196.403766 -296.172034) (xy 196.433331 -296.211378)
			(xy 196.456202 -296.254955) (xy 196.471786 -296.301636) (xy 196.479681 -296.350213) (xy 196.480176 -296.37482)
			(xy 196.819278 -296.37482) (xy 196.823238 -296.325766) (xy 196.835015 -296.277982) (xy 196.854306 -296.232706)
			(xy 196.880609 -296.19111) (xy 196.913244 -296.154273) (xy 196.951365 -296.123148) (xy 196.993986 -296.098541)
			(xy 197.040002 -296.081089) (xy 197.088221 -296.071245) (xy 197.137396 -296.069264) (xy 197.186251 -296.075196)
			(xy 197.233522 -296.088888) (xy 197.277984 -296.109986) (xy 197.318487 -296.137942) (xy 197.35398 -296.172034)
			(xy 197.383545 -296.211378) (xy 197.406416 -296.254955) (xy 197.422 -296.301636) (xy 197.429895 -296.350213)
			(xy 197.43039 -296.37482) (xy 197.769238 -296.37482) (xy 197.773198 -296.325766) (xy 197.784975 -296.277982)
			(xy 197.804266 -296.232706) (xy 197.830569 -296.19111) (xy 197.863204 -296.154273) (xy 197.901325 -296.123148)
			(xy 197.943946 -296.098541) (xy 197.989962 -296.081089) (xy 198.038181 -296.071245) (xy 198.087356 -296.069264)
			(xy 198.136211 -296.075196) (xy 198.183482 -296.088888) (xy 198.227944 -296.109986) (xy 198.268447 -296.137942)
			(xy 198.30394 -296.172034) (xy 198.333505 -296.211378) (xy 198.356376 -296.254955) (xy 198.37196 -296.301636)
			(xy 198.379855 -296.350213) (xy 198.38035 -296.37482) (xy 198.719198 -296.37482) (xy 198.723158 -296.325766)
			(xy 198.734935 -296.277982) (xy 198.754226 -296.232706) (xy 198.780529 -296.19111) (xy 198.813164 -296.154273)
			(xy 198.851285 -296.123148) (xy 198.893906 -296.098541) (xy 198.939922 -296.081089) (xy 198.988141 -296.071245)
			(xy 199.037316 -296.069264) (xy 199.086171 -296.075196) (xy 199.133442 -296.088888) (xy 199.177904 -296.109986)
			(xy 199.218407 -296.137942) (xy 199.2539 -296.172034) (xy 199.283465 -296.211378) (xy 199.306336 -296.254955)
			(xy 199.32192 -296.301636) (xy 199.329815 -296.350213) (xy 199.33031 -296.37482) (xy 199.329815 -296.399427)
			(xy 199.32192 -296.448004) (xy 199.306336 -296.494685) (xy 199.283465 -296.538262) (xy 199.2539 -296.577606)
			(xy 199.218407 -296.611698) (xy 199.216416 -296.613072) (xy 205.362554 -296.613072) (xy 205.366625 -296.55745)
			(xy 205.378751 -296.503013) (xy 205.398674 -296.450922) (xy 205.42597 -296.402287) (xy 205.460056 -296.358144)
			(xy 205.500205 -296.319435) (xy 205.545563 -296.286984) (xy 205.595163 -296.261483) (xy 205.647947 -296.243476)
			(xy 205.70279 -296.233346) (xy 205.758524 -296.231309) (xy 205.813961 -296.237409) (xy 205.867918 -296.251515)
			(xy 205.919247 -296.273327) (xy 205.966853 -296.302381) (xy 206.009721 -296.338056) (xy 206.046938 -296.379593)
			(xy 206.077711 -296.426106) (xy 206.101383 -296.476603) (xy 206.117451 -296.53001) (xy 206.125571 -296.585186)
			(xy 206.12608 -296.613072) (xy 206.63738 -296.613072) (xy 206.641451 -296.55745) (xy 206.653577 -296.503013)
			(xy 206.6735 -296.450922) (xy 206.700796 -296.402287) (xy 206.734882 -296.358144) (xy 206.775031 -296.319435)
			(xy 206.820389 -296.286984) (xy 206.869989 -296.261483) (xy 206.922773 -296.243476) (xy 206.977616 -296.233346)
			(xy 207.03335 -296.231309) (xy 207.088787 -296.237409) (xy 207.142744 -296.251515) (xy 207.194073 -296.273327)
			(xy 207.241679 -296.302381) (xy 207.284547 -296.338056) (xy 207.321764 -296.379593) (xy 207.352537 -296.426106)
			(xy 207.376209 -296.476603) (xy 207.392277 -296.53001) (xy 207.400397 -296.585186) (xy 207.400906 -296.613072)
			(xy 207.400397 -296.640958) (xy 207.392277 -296.696134) (xy 207.376209 -296.749541) (xy 207.352537 -296.800038)
			(xy 207.321764 -296.846551) (xy 207.284547 -296.888088) (xy 207.241679 -296.923763) (xy 207.194073 -296.952817)
			(xy 207.142744 -296.974629) (xy 207.088787 -296.988735) (xy 207.03335 -296.994835) (xy 206.977616 -296.992798)
			(xy 206.922773 -296.982668) (xy 206.869989 -296.964661) (xy 206.820389 -296.93916) (xy 206.775031 -296.906709)
			(xy 206.734882 -296.868) (xy 206.700796 -296.823857) (xy 206.6735 -296.775222) (xy 206.653577 -296.723131)
			(xy 206.641451 -296.668694) (xy 206.63738 -296.613072) (xy 206.12608 -296.613072) (xy 206.125571 -296.640958)
			(xy 206.117451 -296.696134) (xy 206.101383 -296.749541) (xy 206.077711 -296.800038) (xy 206.046938 -296.846551)
			(xy 206.009721 -296.888088) (xy 205.966853 -296.923763) (xy 205.919247 -296.952817) (xy 205.867918 -296.974629)
			(xy 205.813961 -296.988735) (xy 205.758524 -296.994835) (xy 205.70279 -296.992798) (xy 205.647947 -296.982668)
			(xy 205.595163 -296.964661) (xy 205.545563 -296.93916) (xy 205.500205 -296.906709) (xy 205.460056 -296.868)
			(xy 205.42597 -296.823857) (xy 205.398674 -296.775222) (xy 205.378751 -296.723131) (xy 205.366625 -296.668694)
			(xy 205.362554 -296.613072) (xy 199.216416 -296.613072) (xy 199.177904 -296.639654) (xy 199.133442 -296.660752)
			(xy 199.086171 -296.674444) (xy 199.037316 -296.680376) (xy 198.988141 -296.678395) (xy 198.939922 -296.668551)
			(xy 198.893906 -296.651099) (xy 198.851285 -296.626492) (xy 198.813164 -296.595367) (xy 198.780529 -296.55853)
			(xy 198.754226 -296.516934) (xy 198.734935 -296.471658) (xy 198.723158 -296.423874) (xy 198.719198 -296.37482)
			(xy 198.38035 -296.37482) (xy 198.379855 -296.399427) (xy 198.37196 -296.448004) (xy 198.356376 -296.494685)
			(xy 198.333505 -296.538262) (xy 198.30394 -296.577606) (xy 198.268447 -296.611698) (xy 198.227944 -296.639654)
			(xy 198.183482 -296.660752) (xy 198.136211 -296.674444) (xy 198.087356 -296.680376) (xy 198.038181 -296.678395)
			(xy 197.989962 -296.668551) (xy 197.943946 -296.651099) (xy 197.901325 -296.626492) (xy 197.863204 -296.595367)
			(xy 197.830569 -296.55853) (xy 197.804266 -296.516934) (xy 197.784975 -296.471658) (xy 197.773198 -296.423874)
			(xy 197.769238 -296.37482) (xy 197.43039 -296.37482) (xy 197.429895 -296.399427) (xy 197.422 -296.448004)
			(xy 197.406416 -296.494685) (xy 197.383545 -296.538262) (xy 197.35398 -296.577606) (xy 197.318487 -296.611698)
			(xy 197.277984 -296.639654) (xy 197.233522 -296.660752) (xy 197.186251 -296.674444) (xy 197.137396 -296.680376)
			(xy 197.088221 -296.678395) (xy 197.040002 -296.668551) (xy 196.993986 -296.651099) (xy 196.951365 -296.626492)
			(xy 196.913244 -296.595367) (xy 196.880609 -296.55853) (xy 196.854306 -296.516934) (xy 196.835015 -296.471658)
			(xy 196.823238 -296.423874) (xy 196.819278 -296.37482) (xy 196.480176 -296.37482) (xy 196.479681 -296.399427)
			(xy 196.471786 -296.448004) (xy 196.456202 -296.494685) (xy 196.433331 -296.538262) (xy 196.403766 -296.577606)
			(xy 196.368273 -296.611698) (xy 196.32777 -296.639654) (xy 196.283308 -296.660752) (xy 196.236037 -296.674444)
			(xy 196.187182 -296.680376) (xy 196.138007 -296.678395) (xy 196.089788 -296.668551) (xy 196.043772 -296.651099)
			(xy 196.001151 -296.626492) (xy 195.96303 -296.595367) (xy 195.930395 -296.55853) (xy 195.904092 -296.516934)
			(xy 195.884801 -296.471658) (xy 195.873024 -296.423874) (xy 195.869064 -296.37482) (xy 195.530216 -296.37482)
			(xy 195.529721 -296.399427) (xy 195.521826 -296.448004) (xy 195.506242 -296.494685) (xy 195.483371 -296.538262)
			(xy 195.453806 -296.577606) (xy 195.418313 -296.611698) (xy 195.37781 -296.639654) (xy 195.333348 -296.660752)
			(xy 195.286077 -296.674444) (xy 195.237222 -296.680376) (xy 195.188047 -296.678395) (xy 195.139828 -296.668551)
			(xy 195.093812 -296.651099) (xy 195.051191 -296.626492) (xy 195.01307 -296.595367) (xy 194.980435 -296.55853)
			(xy 194.954132 -296.516934) (xy 194.934841 -296.471658) (xy 194.923064 -296.423874) (xy 194.919104 -296.37482)
			(xy 194.580256 -296.37482) (xy 194.579761 -296.399427) (xy 194.571866 -296.448004) (xy 194.556282 -296.494685)
			(xy 194.533411 -296.538262) (xy 194.503846 -296.577606) (xy 194.468353 -296.611698) (xy 194.42785 -296.639654)
			(xy 194.383388 -296.660752) (xy 194.336117 -296.674444) (xy 194.287262 -296.680376) (xy 194.238087 -296.678395)
			(xy 194.189868 -296.668551) (xy 194.143852 -296.651099) (xy 194.101231 -296.626492) (xy 194.06311 -296.595367)
			(xy 194.030475 -296.55853) (xy 194.004172 -296.516934) (xy 193.984881 -296.471658) (xy 193.973104 -296.423874)
			(xy 193.969144 -296.37482) (xy 193.630296 -296.37482) (xy 193.629801 -296.399427) (xy 193.621906 -296.448004)
			(xy 193.606322 -296.494685) (xy 193.583451 -296.538262) (xy 193.553886 -296.577606) (xy 193.518393 -296.611698)
			(xy 193.47789 -296.639654) (xy 193.433428 -296.660752) (xy 193.386157 -296.674444) (xy 193.337302 -296.680376)
			(xy 193.288127 -296.678395) (xy 193.239908 -296.668551) (xy 193.193892 -296.651099) (xy 193.151271 -296.626492)
			(xy 193.11315 -296.595367) (xy 193.080515 -296.55853) (xy 193.054212 -296.516934) (xy 193.034921 -296.471658)
			(xy 193.023144 -296.423874) (xy 193.019184 -296.37482) (xy 192.680336 -296.37482) (xy 192.679841 -296.399427)
			(xy 192.671946 -296.448004) (xy 192.656362 -296.494685) (xy 192.633491 -296.538262) (xy 192.603926 -296.577606)
			(xy 192.568433 -296.611698) (xy 192.52793 -296.639654) (xy 192.483468 -296.660752) (xy 192.436197 -296.674444)
			(xy 192.387342 -296.680376) (xy 192.338167 -296.678395) (xy 192.289948 -296.668551) (xy 192.243932 -296.651099)
			(xy 192.201311 -296.626492) (xy 192.16319 -296.595367) (xy 192.130555 -296.55853) (xy 192.104252 -296.516934)
			(xy 192.084961 -296.471658) (xy 192.073184 -296.423874) (xy 192.069224 -296.37482) (xy 191.730376 -296.37482)
			(xy 191.729881 -296.399427) (xy 191.721986 -296.448004) (xy 191.706402 -296.494685) (xy 191.683531 -296.538262)
			(xy 191.653966 -296.577606) (xy 191.618473 -296.611698) (xy 191.57797 -296.639654) (xy 191.533508 -296.660752)
			(xy 191.486237 -296.674444) (xy 191.437382 -296.680376) (xy 191.388207 -296.678395) (xy 191.339988 -296.668551)
			(xy 191.293972 -296.651099) (xy 191.251351 -296.626492) (xy 191.21323 -296.595367) (xy 191.180595 -296.55853)
			(xy 191.154292 -296.516934) (xy 191.135001 -296.471658) (xy 191.123224 -296.423874) (xy 191.119264 -296.37482)
			(xy 190.780162 -296.37482) (xy 190.779667 -296.399427) (xy 190.771772 -296.448004) (xy 190.756188 -296.494685)
			(xy 190.733317 -296.538262) (xy 190.703752 -296.577606) (xy 190.668259 -296.611698) (xy 190.627756 -296.639654)
			(xy 190.583294 -296.660752) (xy 190.536023 -296.674444) (xy 190.487168 -296.680376) (xy 190.437993 -296.678395)
			(xy 190.389774 -296.668551) (xy 190.343758 -296.651099) (xy 190.301137 -296.626492) (xy 190.263016 -296.595367)
			(xy 190.230381 -296.55853) (xy 190.204078 -296.516934) (xy 190.184787 -296.471658) (xy 190.17301 -296.423874)
			(xy 190.16905 -296.37482) (xy 189.830202 -296.37482) (xy 189.829707 -296.399427) (xy 189.821812 -296.448004)
			(xy 189.806228 -296.494685) (xy 189.783357 -296.538262) (xy 189.753792 -296.577606) (xy 189.718299 -296.611698)
			(xy 189.677796 -296.639654) (xy 189.633334 -296.660752) (xy 189.586063 -296.674444) (xy 189.537208 -296.680376)
			(xy 189.488033 -296.678395) (xy 189.439814 -296.668551) (xy 189.393798 -296.651099) (xy 189.351177 -296.626492)
			(xy 189.313056 -296.595367) (xy 189.280421 -296.55853) (xy 189.254118 -296.516934) (xy 189.234827 -296.471658)
			(xy 189.22305 -296.423874) (xy 189.21909 -296.37482) (xy 187.930282 -296.37482) (xy 187.929787 -296.399427)
			(xy 187.921892 -296.448004) (xy 187.906308 -296.494685) (xy 187.883437 -296.538262) (xy 187.853872 -296.577606)
			(xy 187.818379 -296.611698) (xy 187.777876 -296.639654) (xy 187.733414 -296.660752) (xy 187.686143 -296.674444)
			(xy 187.637288 -296.680376) (xy 187.588113 -296.678395) (xy 187.539894 -296.668551) (xy 187.493878 -296.651099)
			(xy 187.451257 -296.626492) (xy 187.413136 -296.595367) (xy 187.380501 -296.55853) (xy 187.354198 -296.516934)
			(xy 187.334907 -296.471658) (xy 187.32313 -296.423874) (xy 187.31917 -296.37482) (xy 186.980322 -296.37482)
			(xy 186.979827 -296.399427) (xy 186.971932 -296.448004) (xy 186.956348 -296.494685) (xy 186.933477 -296.538262)
			(xy 186.903912 -296.577606) (xy 186.868419 -296.611698) (xy 186.827916 -296.639654) (xy 186.783454 -296.660752)
			(xy 186.736183 -296.674444) (xy 186.687328 -296.680376) (xy 186.638153 -296.678395) (xy 186.589934 -296.668551)
			(xy 186.543918 -296.651099) (xy 186.501297 -296.626492) (xy 186.463176 -296.595367) (xy 186.430541 -296.55853)
			(xy 186.404238 -296.516934) (xy 186.384947 -296.471658) (xy 186.37317 -296.423874) (xy 186.36921 -296.37482)
			(xy 186.055305 -296.37482) (xy 186.055305 -296.40079) (xy 186.047173 -296.45213) (xy 186.031109 -296.501565)
			(xy 186.007508 -296.547879) (xy 185.976953 -296.58993) (xy 185.940195 -296.626683) (xy 185.89814 -296.657232)
			(xy 185.851823 -296.680826) (xy 185.802385 -296.696883) (xy 185.751044 -296.705008) (xy 185.725054 -296.705528)
			(xy 185.7248 -296.705528) (xy 185.705898 -296.705239) (xy 185.668343 -296.700905) (xy 185.64987 -296.696892)
			(xy 185.63844 -296.694098) (xy 185.616088 -296.699178) (xy 185.54446 -296.756074) (xy 185.535747 -296.763652)
			(xy 185.525697 -296.784417) (xy 185.525156 -296.795952) (xy 185.525156 -296.903648) (xy 185.525735 -296.914849)
			(xy 185.535213 -296.935147) (xy 185.543444 -296.942764) (xy 185.543952 -296.943272) (xy 185.616088 -297.000422)
			(xy 185.63844 -297.005502) (xy 185.64987 -297.002708) (xy 185.668338 -296.998665) (xy 185.705897 -296.994342)
			(xy 185.7248 -296.994072) (xy 185.725054 -296.994072) (xy 185.751047 -296.994552) (xy 185.802394 -297.002678)
			(xy 185.851838 -297.018737) (xy 185.89816 -297.042334) (xy 185.940221 -297.072887) (xy 185.976983 -297.109644)
			(xy 186.007542 -297.1517) (xy 186.031145 -297.198019) (xy 186.047211 -297.247461) (xy 186.055345 -297.298807)
			(xy 186.055345 -297.32478) (xy 186.36921 -297.32478) (xy 186.37317 -297.275726) (xy 186.384947 -297.227942)
			(xy 186.404238 -297.182666) (xy 186.430541 -297.14107) (xy 186.463176 -297.104233) (xy 186.501297 -297.073108)
			(xy 186.543918 -297.048501) (xy 186.589934 -297.031049) (xy 186.638153 -297.021205) (xy 186.687328 -297.019224)
			(xy 186.736183 -297.025156) (xy 186.783454 -297.038848) (xy 186.827916 -297.059946) (xy 186.868419 -297.087902)
			(xy 186.903912 -297.121994) (xy 186.933477 -297.161338) (xy 186.956348 -297.204915) (xy 186.971932 -297.251596)
			(xy 186.979827 -297.300173) (xy 186.980322 -297.32478) (xy 187.31917 -297.32478) (xy 187.32313 -297.275726)
			(xy 187.334907 -297.227942) (xy 187.354198 -297.182666) (xy 187.380501 -297.14107) (xy 187.413136 -297.104233)
			(xy 187.451257 -297.073108) (xy 187.493878 -297.048501) (xy 187.539894 -297.031049) (xy 187.588113 -297.021205)
			(xy 187.637288 -297.019224) (xy 187.686143 -297.025156) (xy 187.733414 -297.038848) (xy 187.777876 -297.059946)
			(xy 187.818379 -297.087902) (xy 187.853872 -297.121994) (xy 187.883437 -297.161338) (xy 187.906308 -297.204915)
			(xy 187.921892 -297.251596) (xy 187.929787 -297.300173) (xy 187.930282 -297.32478) (xy 189.21909 -297.32478)
			(xy 189.22305 -297.275726) (xy 189.234827 -297.227942) (xy 189.254118 -297.182666) (xy 189.280421 -297.14107)
			(xy 189.313056 -297.104233) (xy 189.351177 -297.073108) (xy 189.393798 -297.048501) (xy 189.439814 -297.031049)
			(xy 189.488033 -297.021205) (xy 189.537208 -297.019224) (xy 189.586063 -297.025156) (xy 189.633334 -297.038848)
			(xy 189.677796 -297.059946) (xy 189.718299 -297.087902) (xy 189.753792 -297.121994) (xy 189.783357 -297.161338)
			(xy 189.806228 -297.204915) (xy 189.821812 -297.251596) (xy 189.829707 -297.300173) (xy 189.830202 -297.32478)
			(xy 190.169304 -297.32478) (xy 190.173264 -297.275726) (xy 190.185041 -297.227942) (xy 190.204332 -297.182666)
			(xy 190.230635 -297.14107) (xy 190.26327 -297.104233) (xy 190.301391 -297.073108) (xy 190.344012 -297.048501)
			(xy 190.390028 -297.031049) (xy 190.438247 -297.021205) (xy 190.487422 -297.019224) (xy 190.536277 -297.025156)
			(xy 190.583548 -297.038848) (xy 190.62801 -297.059946) (xy 190.668513 -297.087902) (xy 190.704006 -297.121994)
			(xy 190.733571 -297.161338) (xy 190.756442 -297.204915) (xy 190.772026 -297.251596) (xy 190.779921 -297.300173)
			(xy 190.780416 -297.32478) (xy 191.119264 -297.32478) (xy 191.123224 -297.275726) (xy 191.135001 -297.227942)
			(xy 191.154292 -297.182666) (xy 191.180595 -297.14107) (xy 191.21323 -297.104233) (xy 191.251351 -297.073108)
			(xy 191.293972 -297.048501) (xy 191.339988 -297.031049) (xy 191.388207 -297.021205) (xy 191.437382 -297.019224)
			(xy 191.486237 -297.025156) (xy 191.533508 -297.038848) (xy 191.57797 -297.059946) (xy 191.618473 -297.087902)
			(xy 191.653966 -297.121994) (xy 191.683531 -297.161338) (xy 191.706402 -297.204915) (xy 191.721986 -297.251596)
			(xy 191.729881 -297.300173) (xy 191.730376 -297.32478) (xy 192.069224 -297.32478) (xy 192.073184 -297.275726)
			(xy 192.084961 -297.227942) (xy 192.104252 -297.182666) (xy 192.130555 -297.14107) (xy 192.16319 -297.104233)
			(xy 192.201311 -297.073108) (xy 192.243932 -297.048501) (xy 192.289948 -297.031049) (xy 192.338167 -297.021205)
			(xy 192.387342 -297.019224) (xy 192.436197 -297.025156) (xy 192.483468 -297.038848) (xy 192.52793 -297.059946)
			(xy 192.568433 -297.087902) (xy 192.603926 -297.121994) (xy 192.633491 -297.161338) (xy 192.656362 -297.204915)
			(xy 192.671946 -297.251596) (xy 192.679841 -297.300173) (xy 192.680336 -297.32478) (xy 193.019184 -297.32478)
			(xy 193.023144 -297.275726) (xy 193.034921 -297.227942) (xy 193.054212 -297.182666) (xy 193.080515 -297.14107)
			(xy 193.11315 -297.104233) (xy 193.151271 -297.073108) (xy 193.193892 -297.048501) (xy 193.239908 -297.031049)
			(xy 193.288127 -297.021205) (xy 193.337302 -297.019224) (xy 193.386157 -297.025156) (xy 193.433428 -297.038848)
			(xy 193.47789 -297.059946) (xy 193.518393 -297.087902) (xy 193.553886 -297.121994) (xy 193.583451 -297.161338)
			(xy 193.606322 -297.204915) (xy 193.621906 -297.251596) (xy 193.629801 -297.300173) (xy 193.630296 -297.32478)
			(xy 193.969144 -297.32478) (xy 193.973104 -297.275726) (xy 193.984881 -297.227942) (xy 194.004172 -297.182666)
			(xy 194.030475 -297.14107) (xy 194.06311 -297.104233) (xy 194.101231 -297.073108) (xy 194.143852 -297.048501)
			(xy 194.189868 -297.031049) (xy 194.238087 -297.021205) (xy 194.287262 -297.019224) (xy 194.336117 -297.025156)
			(xy 194.383388 -297.038848) (xy 194.42785 -297.059946) (xy 194.468353 -297.087902) (xy 194.503846 -297.121994)
			(xy 194.533411 -297.161338) (xy 194.556282 -297.204915) (xy 194.571866 -297.251596) (xy 194.579761 -297.300173)
			(xy 194.580256 -297.32478) (xy 194.919104 -297.32478) (xy 194.923064 -297.275726) (xy 194.934841 -297.227942)
			(xy 194.954132 -297.182666) (xy 194.980435 -297.14107) (xy 195.01307 -297.104233) (xy 195.051191 -297.073108)
			(xy 195.093812 -297.048501) (xy 195.139828 -297.031049) (xy 195.188047 -297.021205) (xy 195.237222 -297.019224)
			(xy 195.286077 -297.025156) (xy 195.333348 -297.038848) (xy 195.37781 -297.059946) (xy 195.418313 -297.087902)
			(xy 195.453806 -297.121994) (xy 195.483371 -297.161338) (xy 195.506242 -297.204915) (xy 195.521826 -297.251596)
			(xy 195.529721 -297.300173) (xy 195.530216 -297.32478) (xy 195.869064 -297.32478) (xy 195.873024 -297.275726)
			(xy 195.884801 -297.227942) (xy 195.904092 -297.182666) (xy 195.930395 -297.14107) (xy 195.96303 -297.104233)
			(xy 196.001151 -297.073108) (xy 196.043772 -297.048501) (xy 196.089788 -297.031049) (xy 196.138007 -297.021205)
			(xy 196.187182 -297.019224) (xy 196.236037 -297.025156) (xy 196.283308 -297.038848) (xy 196.32777 -297.059946)
			(xy 196.368273 -297.087902) (xy 196.403766 -297.121994) (xy 196.433331 -297.161338) (xy 196.456202 -297.204915)
			(xy 196.471786 -297.251596) (xy 196.479681 -297.300173) (xy 196.480176 -297.32478) (xy 196.819278 -297.32478)
			(xy 196.823238 -297.275726) (xy 196.835015 -297.227942) (xy 196.854306 -297.182666) (xy 196.880609 -297.14107)
			(xy 196.913244 -297.104233) (xy 196.951365 -297.073108) (xy 196.993986 -297.048501) (xy 197.040002 -297.031049)
			(xy 197.088221 -297.021205) (xy 197.137396 -297.019224) (xy 197.186251 -297.025156) (xy 197.233522 -297.038848)
			(xy 197.277984 -297.059946) (xy 197.318487 -297.087902) (xy 197.35398 -297.121994) (xy 197.383545 -297.161338)
			(xy 197.406416 -297.204915) (xy 197.422 -297.251596) (xy 197.429895 -297.300173) (xy 197.43039 -297.32478)
			(xy 197.769238 -297.32478) (xy 197.773198 -297.275726) (xy 197.784975 -297.227942) (xy 197.804266 -297.182666)
			(xy 197.830569 -297.14107) (xy 197.863204 -297.104233) (xy 197.901325 -297.073108) (xy 197.943946 -297.048501)
			(xy 197.989962 -297.031049) (xy 198.038181 -297.021205) (xy 198.087356 -297.019224) (xy 198.136211 -297.025156)
			(xy 198.183482 -297.038848) (xy 198.227944 -297.059946) (xy 198.268447 -297.087902) (xy 198.30394 -297.121994)
			(xy 198.333505 -297.161338) (xy 198.356376 -297.204915) (xy 198.37196 -297.251596) (xy 198.379855 -297.300173)
			(xy 198.38035 -297.32478) (xy 198.719198 -297.32478) (xy 198.723158 -297.275726) (xy 198.734935 -297.227942)
			(xy 198.754226 -297.182666) (xy 198.780529 -297.14107) (xy 198.813164 -297.104233) (xy 198.851285 -297.073108)
			(xy 198.893906 -297.048501) (xy 198.939922 -297.031049) (xy 198.988141 -297.021205) (xy 199.037316 -297.019224)
			(xy 199.086171 -297.025156) (xy 199.133442 -297.038848) (xy 199.177904 -297.059946) (xy 199.218407 -297.087902)
			(xy 199.2539 -297.121994) (xy 199.283465 -297.161338) (xy 199.306336 -297.204915) (xy 199.32192 -297.251596)
			(xy 199.329815 -297.300173) (xy 199.33031 -297.32478) (xy 199.329815 -297.349387) (xy 199.32192 -297.397964)
			(xy 199.306336 -297.444645) (xy 199.283465 -297.488222) (xy 199.2539 -297.527566) (xy 199.218407 -297.561658)
			(xy 199.177904 -297.589614) (xy 199.133442 -297.610712) (xy 199.086171 -297.624404) (xy 199.037316 -297.630336)
			(xy 198.988141 -297.628355) (xy 198.939922 -297.618511) (xy 198.893906 -297.601059) (xy 198.851285 -297.576452)
			(xy 198.813164 -297.545327) (xy 198.780529 -297.50849) (xy 198.754226 -297.466894) (xy 198.734935 -297.421618)
			(xy 198.723158 -297.373834) (xy 198.719198 -297.32478) (xy 198.38035 -297.32478) (xy 198.379855 -297.349387)
			(xy 198.37196 -297.397964) (xy 198.356376 -297.444645) (xy 198.333505 -297.488222) (xy 198.30394 -297.527566)
			(xy 198.268447 -297.561658) (xy 198.227944 -297.589614) (xy 198.183482 -297.610712) (xy 198.136211 -297.624404)
			(xy 198.087356 -297.630336) (xy 198.038181 -297.628355) (xy 197.989962 -297.618511) (xy 197.943946 -297.601059)
			(xy 197.901325 -297.576452) (xy 197.863204 -297.545327) (xy 197.830569 -297.50849) (xy 197.804266 -297.466894)
			(xy 197.784975 -297.421618) (xy 197.773198 -297.373834) (xy 197.769238 -297.32478) (xy 197.43039 -297.32478)
			(xy 197.429895 -297.349387) (xy 197.422 -297.397964) (xy 197.406416 -297.444645) (xy 197.383545 -297.488222)
			(xy 197.35398 -297.527566) (xy 197.318487 -297.561658) (xy 197.277984 -297.589614) (xy 197.233522 -297.610712)
			(xy 197.186251 -297.624404) (xy 197.137396 -297.630336) (xy 197.088221 -297.628355) (xy 197.040002 -297.618511)
			(xy 196.993986 -297.601059) (xy 196.951365 -297.576452) (xy 196.913244 -297.545327) (xy 196.880609 -297.50849)
			(xy 196.854306 -297.466894) (xy 196.835015 -297.421618) (xy 196.823238 -297.373834) (xy 196.819278 -297.32478)
			(xy 196.480176 -297.32478) (xy 196.479681 -297.349387) (xy 196.471786 -297.397964) (xy 196.456202 -297.444645)
			(xy 196.433331 -297.488222) (xy 196.403766 -297.527566) (xy 196.368273 -297.561658) (xy 196.32777 -297.589614)
			(xy 196.283308 -297.610712) (xy 196.236037 -297.624404) (xy 196.187182 -297.630336) (xy 196.138007 -297.628355)
			(xy 196.089788 -297.618511) (xy 196.043772 -297.601059) (xy 196.001151 -297.576452) (xy 195.96303 -297.545327)
			(xy 195.930395 -297.50849) (xy 195.904092 -297.466894) (xy 195.884801 -297.421618) (xy 195.873024 -297.373834)
			(xy 195.869064 -297.32478) (xy 195.530216 -297.32478) (xy 195.529721 -297.349387) (xy 195.521826 -297.397964)
			(xy 195.506242 -297.444645) (xy 195.483371 -297.488222) (xy 195.453806 -297.527566) (xy 195.418313 -297.561658)
			(xy 195.37781 -297.589614) (xy 195.333348 -297.610712) (xy 195.286077 -297.624404) (xy 195.237222 -297.630336)
			(xy 195.188047 -297.628355) (xy 195.139828 -297.618511) (xy 195.093812 -297.601059) (xy 195.051191 -297.576452)
			(xy 195.01307 -297.545327) (xy 194.980435 -297.50849) (xy 194.954132 -297.466894) (xy 194.934841 -297.421618)
			(xy 194.923064 -297.373834) (xy 194.919104 -297.32478) (xy 194.580256 -297.32478) (xy 194.579761 -297.349387)
			(xy 194.571866 -297.397964) (xy 194.556282 -297.444645) (xy 194.533411 -297.488222) (xy 194.503846 -297.527566)
			(xy 194.468353 -297.561658) (xy 194.42785 -297.589614) (xy 194.383388 -297.610712) (xy 194.336117 -297.624404)
			(xy 194.287262 -297.630336) (xy 194.238087 -297.628355) (xy 194.189868 -297.618511) (xy 194.143852 -297.601059)
			(xy 194.101231 -297.576452) (xy 194.06311 -297.545327) (xy 194.030475 -297.50849) (xy 194.004172 -297.466894)
			(xy 193.984881 -297.421618) (xy 193.973104 -297.373834) (xy 193.969144 -297.32478) (xy 193.630296 -297.32478)
			(xy 193.629801 -297.349387) (xy 193.621906 -297.397964) (xy 193.606322 -297.444645) (xy 193.583451 -297.488222)
			(xy 193.553886 -297.527566) (xy 193.518393 -297.561658) (xy 193.47789 -297.589614) (xy 193.433428 -297.610712)
			(xy 193.386157 -297.624404) (xy 193.337302 -297.630336) (xy 193.288127 -297.628355) (xy 193.239908 -297.618511)
			(xy 193.193892 -297.601059) (xy 193.151271 -297.576452) (xy 193.11315 -297.545327) (xy 193.080515 -297.50849)
			(xy 193.054212 -297.466894) (xy 193.034921 -297.421618) (xy 193.023144 -297.373834) (xy 193.019184 -297.32478)
			(xy 192.680336 -297.32478) (xy 192.679841 -297.349387) (xy 192.671946 -297.397964) (xy 192.656362 -297.444645)
			(xy 192.633491 -297.488222) (xy 192.603926 -297.527566) (xy 192.568433 -297.561658) (xy 192.52793 -297.589614)
			(xy 192.483468 -297.610712) (xy 192.436197 -297.624404) (xy 192.387342 -297.630336) (xy 192.338167 -297.628355)
			(xy 192.289948 -297.618511) (xy 192.243932 -297.601059) (xy 192.201311 -297.576452) (xy 192.16319 -297.545327)
			(xy 192.130555 -297.50849) (xy 192.104252 -297.466894) (xy 192.084961 -297.421618) (xy 192.073184 -297.373834)
			(xy 192.069224 -297.32478) (xy 191.730376 -297.32478) (xy 191.729881 -297.349387) (xy 191.721986 -297.397964)
			(xy 191.706402 -297.444645) (xy 191.683531 -297.488222) (xy 191.653966 -297.527566) (xy 191.618473 -297.561658)
			(xy 191.57797 -297.589614) (xy 191.533508 -297.610712) (xy 191.486237 -297.624404) (xy 191.437382 -297.630336)
			(xy 191.388207 -297.628355) (xy 191.339988 -297.618511) (xy 191.293972 -297.601059) (xy 191.251351 -297.576452)
			(xy 191.21323 -297.545327) (xy 191.180595 -297.50849) (xy 191.154292 -297.466894) (xy 191.135001 -297.421618)
			(xy 191.123224 -297.373834) (xy 191.119264 -297.32478) (xy 190.780416 -297.32478) (xy 190.779921 -297.349387)
			(xy 190.772026 -297.397964) (xy 190.756442 -297.444645) (xy 190.733571 -297.488222) (xy 190.704006 -297.527566)
			(xy 190.668513 -297.561658) (xy 190.62801 -297.589614) (xy 190.583548 -297.610712) (xy 190.536277 -297.624404)
			(xy 190.487422 -297.630336) (xy 190.438247 -297.628355) (xy 190.390028 -297.618511) (xy 190.344012 -297.601059)
			(xy 190.301391 -297.576452) (xy 190.26327 -297.545327) (xy 190.230635 -297.50849) (xy 190.204332 -297.466894)
			(xy 190.185041 -297.421618) (xy 190.173264 -297.373834) (xy 190.169304 -297.32478) (xy 189.830202 -297.32478)
			(xy 189.829707 -297.349387) (xy 189.821812 -297.397964) (xy 189.806228 -297.444645) (xy 189.783357 -297.488222)
			(xy 189.753792 -297.527566) (xy 189.718299 -297.561658) (xy 189.677796 -297.589614) (xy 189.633334 -297.610712)
			(xy 189.586063 -297.624404) (xy 189.537208 -297.630336) (xy 189.488033 -297.628355) (xy 189.439814 -297.618511)
			(xy 189.393798 -297.601059) (xy 189.351177 -297.576452) (xy 189.313056 -297.545327) (xy 189.280421 -297.50849)
			(xy 189.254118 -297.466894) (xy 189.234827 -297.421618) (xy 189.22305 -297.373834) (xy 189.21909 -297.32478)
			(xy 187.930282 -297.32478) (xy 187.929787 -297.349387) (xy 187.921892 -297.397964) (xy 187.906308 -297.444645)
			(xy 187.883437 -297.488222) (xy 187.853872 -297.527566) (xy 187.818379 -297.561658) (xy 187.777876 -297.589614)
			(xy 187.733414 -297.610712) (xy 187.686143 -297.624404) (xy 187.637288 -297.630336) (xy 187.588113 -297.628355)
			(xy 187.539894 -297.618511) (xy 187.493878 -297.601059) (xy 187.451257 -297.576452) (xy 187.413136 -297.545327)
			(xy 187.380501 -297.50849) (xy 187.354198 -297.466894) (xy 187.334907 -297.421618) (xy 187.32313 -297.373834)
			(xy 187.31917 -297.32478) (xy 186.980322 -297.32478) (xy 186.979827 -297.349387) (xy 186.971932 -297.397964)
			(xy 186.956348 -297.444645) (xy 186.933477 -297.488222) (xy 186.903912 -297.527566) (xy 186.868419 -297.561658)
			(xy 186.827916 -297.589614) (xy 186.783454 -297.610712) (xy 186.736183 -297.624404) (xy 186.687328 -297.630336)
			(xy 186.638153 -297.628355) (xy 186.589934 -297.618511) (xy 186.543918 -297.601059) (xy 186.501297 -297.576452)
			(xy 186.463176 -297.545327) (xy 186.430541 -297.50849) (xy 186.404238 -297.466894) (xy 186.384947 -297.421618)
			(xy 186.37317 -297.373834) (xy 186.36921 -297.32478) (xy 186.055345 -297.32478) (xy 186.055345 -297.350793)
			(xy 186.047211 -297.402139) (xy 186.031145 -297.451581) (xy 186.007542 -297.4979) (xy 185.976983 -297.539956)
			(xy 185.940221 -297.576713) (xy 185.89816 -297.607266) (xy 185.851838 -297.630863) (xy 185.802394 -297.646922)
			(xy 185.751047 -297.655048) (xy 185.725054 -297.655488) (xy 185.7248 -297.655488) (xy 185.705898 -297.655199)
			(xy 185.668343 -297.650866) (xy 185.64987 -297.646852) (xy 185.63844 -297.644058) (xy 185.616088 -297.649138)
			(xy 185.54446 -297.706034) (xy 185.53574 -297.71361) (xy 185.525674 -297.734374) (xy 185.525156 -297.745912)
			(xy 185.525156 -297.853608) (xy 185.525747 -297.864803) (xy 185.53524 -297.885083) (xy 185.543444 -297.892724)
			(xy 185.543952 -297.893232) (xy 185.616088 -297.950382) (xy 185.63844 -297.955462) (xy 185.64987 -297.952668)
			(xy 185.668338 -297.948624) (xy 185.705897 -297.9443) (xy 185.7248 -297.944032) (xy 185.725054 -297.944032)
			(xy 185.751042 -297.944512) (xy 185.80238 -297.952636) (xy 185.851815 -297.968692) (xy 185.898129 -297.992285)
			(xy 185.940182 -298.022833) (xy 185.976938 -298.059583) (xy 186.007491 -298.101632) (xy 186.03109 -298.147942)
			(xy 186.047153 -298.197375) (xy 186.055285 -298.248712) (xy 186.055285 -298.27474) (xy 186.36921 -298.27474)
			(xy 186.37317 -298.225686) (xy 186.384947 -298.177902) (xy 186.404238 -298.132626) (xy 186.430541 -298.09103)
			(xy 186.463176 -298.054193) (xy 186.501297 -298.023068) (xy 186.543918 -297.998461) (xy 186.589934 -297.981009)
			(xy 186.638153 -297.971165) (xy 186.687328 -297.969184) (xy 186.736183 -297.975116) (xy 186.783454 -297.988808)
			(xy 186.827916 -298.009906) (xy 186.868419 -298.037862) (xy 186.903912 -298.071954) (xy 186.933477 -298.111298)
			(xy 186.956348 -298.154875) (xy 186.971932 -298.201556) (xy 186.979827 -298.250133) (xy 186.980322 -298.27474)
			(xy 187.31917 -298.27474) (xy 187.32313 -298.225686) (xy 187.334907 -298.177902) (xy 187.354198 -298.132626)
			(xy 187.380501 -298.09103) (xy 187.413136 -298.054193) (xy 187.451257 -298.023068) (xy 187.493878 -297.998461)
			(xy 187.539894 -297.981009) (xy 187.588113 -297.971165) (xy 187.637288 -297.969184) (xy 187.686143 -297.975116)
			(xy 187.733414 -297.988808) (xy 187.777876 -298.009906) (xy 187.818379 -298.037862) (xy 187.853872 -298.071954)
			(xy 187.883437 -298.111298) (xy 187.906308 -298.154875) (xy 187.921892 -298.201556) (xy 187.929787 -298.250133)
			(xy 187.930282 -298.27474) (xy 189.21909 -298.27474) (xy 189.22305 -298.225686) (xy 189.234827 -298.177902)
			(xy 189.254118 -298.132626) (xy 189.280421 -298.09103) (xy 189.313056 -298.054193) (xy 189.351177 -298.023068)
			(xy 189.393798 -297.998461) (xy 189.439814 -297.981009) (xy 189.488033 -297.971165) (xy 189.537208 -297.969184)
			(xy 189.586063 -297.975116) (xy 189.633334 -297.988808) (xy 189.677796 -298.009906) (xy 189.718299 -298.037862)
			(xy 189.753792 -298.071954) (xy 189.783357 -298.111298) (xy 189.806228 -298.154875) (xy 189.821812 -298.201556)
			(xy 189.829707 -298.250133) (xy 189.830202 -298.27474) (xy 190.16905 -298.27474) (xy 190.17301 -298.225686)
			(xy 190.184787 -298.177902) (xy 190.204078 -298.132626) (xy 190.230381 -298.09103) (xy 190.263016 -298.054193)
			(xy 190.301137 -298.023068) (xy 190.343758 -297.998461) (xy 190.389774 -297.981009) (xy 190.437993 -297.971165)
			(xy 190.487168 -297.969184) (xy 190.536023 -297.975116) (xy 190.583294 -297.988808) (xy 190.627756 -298.009906)
			(xy 190.668259 -298.037862) (xy 190.703752 -298.071954) (xy 190.733317 -298.111298) (xy 190.756188 -298.154875)
			(xy 190.771772 -298.201556) (xy 190.779667 -298.250133) (xy 190.780162 -298.27474) (xy 191.119264 -298.27474)
			(xy 191.123224 -298.225686) (xy 191.135001 -298.177902) (xy 191.154292 -298.132626) (xy 191.180595 -298.09103)
			(xy 191.21323 -298.054193) (xy 191.251351 -298.023068) (xy 191.293972 -297.998461) (xy 191.339988 -297.981009)
			(xy 191.388207 -297.971165) (xy 191.437382 -297.969184) (xy 191.486237 -297.975116) (xy 191.533508 -297.988808)
			(xy 191.57797 -298.009906) (xy 191.618473 -298.037862) (xy 191.653966 -298.071954) (xy 191.683531 -298.111298)
			(xy 191.706402 -298.154875) (xy 191.721986 -298.201556) (xy 191.729881 -298.250133) (xy 191.730376 -298.27474)
			(xy 192.069224 -298.27474) (xy 192.073184 -298.225686) (xy 192.084961 -298.177902) (xy 192.104252 -298.132626)
			(xy 192.130555 -298.09103) (xy 192.16319 -298.054193) (xy 192.201311 -298.023068) (xy 192.243932 -297.998461)
			(xy 192.289948 -297.981009) (xy 192.338167 -297.971165) (xy 192.387342 -297.969184) (xy 192.436197 -297.975116)
			(xy 192.483468 -297.988808) (xy 192.52793 -298.009906) (xy 192.568433 -298.037862) (xy 192.603926 -298.071954)
			(xy 192.633491 -298.111298) (xy 192.656362 -298.154875) (xy 192.671946 -298.201556) (xy 192.679841 -298.250133)
			(xy 192.680336 -298.27474) (xy 193.019184 -298.27474) (xy 193.023144 -298.225686) (xy 193.034921 -298.177902)
			(xy 193.054212 -298.132626) (xy 193.080515 -298.09103) (xy 193.11315 -298.054193) (xy 193.151271 -298.023068)
			(xy 193.193892 -297.998461) (xy 193.239908 -297.981009) (xy 193.288127 -297.971165) (xy 193.337302 -297.969184)
			(xy 193.386157 -297.975116) (xy 193.433428 -297.988808) (xy 193.47789 -298.009906) (xy 193.518393 -298.037862)
			(xy 193.553886 -298.071954) (xy 193.583451 -298.111298) (xy 193.606322 -298.154875) (xy 193.621906 -298.201556)
			(xy 193.629801 -298.250133) (xy 193.630296 -298.27474) (xy 193.969144 -298.27474) (xy 193.973104 -298.225686)
			(xy 193.984881 -298.177902) (xy 194.004172 -298.132626) (xy 194.030475 -298.09103) (xy 194.06311 -298.054193)
			(xy 194.101231 -298.023068) (xy 194.143852 -297.998461) (xy 194.189868 -297.981009) (xy 194.238087 -297.971165)
			(xy 194.287262 -297.969184) (xy 194.336117 -297.975116) (xy 194.383388 -297.988808) (xy 194.42785 -298.009906)
			(xy 194.468353 -298.037862) (xy 194.503846 -298.071954) (xy 194.533411 -298.111298) (xy 194.556282 -298.154875)
			(xy 194.571866 -298.201556) (xy 194.579761 -298.250133) (xy 194.580256 -298.27474) (xy 194.919104 -298.27474)
			(xy 194.923064 -298.225686) (xy 194.934841 -298.177902) (xy 194.954132 -298.132626) (xy 194.980435 -298.09103)
			(xy 195.01307 -298.054193) (xy 195.051191 -298.023068) (xy 195.093812 -297.998461) (xy 195.139828 -297.981009)
			(xy 195.188047 -297.971165) (xy 195.237222 -297.969184) (xy 195.286077 -297.975116) (xy 195.333348 -297.988808)
			(xy 195.37781 -298.009906) (xy 195.418313 -298.037862) (xy 195.453806 -298.071954) (xy 195.483371 -298.111298)
			(xy 195.506242 -298.154875) (xy 195.521826 -298.201556) (xy 195.529721 -298.250133) (xy 195.530216 -298.27474)
			(xy 195.869064 -298.27474) (xy 195.873024 -298.225686) (xy 195.884801 -298.177902) (xy 195.904092 -298.132626)
			(xy 195.930395 -298.09103) (xy 195.96303 -298.054193) (xy 196.001151 -298.023068) (xy 196.043772 -297.998461)
			(xy 196.089788 -297.981009) (xy 196.138007 -297.971165) (xy 196.187182 -297.969184) (xy 196.236037 -297.975116)
			(xy 196.283308 -297.988808) (xy 196.32777 -298.009906) (xy 196.368273 -298.037862) (xy 196.403766 -298.071954)
			(xy 196.433331 -298.111298) (xy 196.456202 -298.154875) (xy 196.471786 -298.201556) (xy 196.479681 -298.250133)
			(xy 196.480176 -298.27474) (xy 196.819278 -298.27474) (xy 196.823238 -298.225686) (xy 196.835015 -298.177902)
			(xy 196.854306 -298.132626) (xy 196.880609 -298.09103) (xy 196.913244 -298.054193) (xy 196.951365 -298.023068)
			(xy 196.993986 -297.998461) (xy 197.040002 -297.981009) (xy 197.088221 -297.971165) (xy 197.137396 -297.969184)
			(xy 197.186251 -297.975116) (xy 197.233522 -297.988808) (xy 197.277984 -298.009906) (xy 197.318487 -298.037862)
			(xy 197.35398 -298.071954) (xy 197.383545 -298.111298) (xy 197.406416 -298.154875) (xy 197.422 -298.201556)
			(xy 197.429895 -298.250133) (xy 197.43039 -298.27474) (xy 197.769238 -298.27474) (xy 197.773198 -298.225686)
			(xy 197.784975 -298.177902) (xy 197.804266 -298.132626) (xy 197.830569 -298.09103) (xy 197.863204 -298.054193)
			(xy 197.901325 -298.023068) (xy 197.943946 -297.998461) (xy 197.989962 -297.981009) (xy 198.038181 -297.971165)
			(xy 198.087356 -297.969184) (xy 198.136211 -297.975116) (xy 198.183482 -297.988808) (xy 198.227944 -298.009906)
			(xy 198.268447 -298.037862) (xy 198.30394 -298.071954) (xy 198.333505 -298.111298) (xy 198.356376 -298.154875)
			(xy 198.37196 -298.201556) (xy 198.379855 -298.250133) (xy 198.38035 -298.27474) (xy 198.719198 -298.27474)
			(xy 198.723158 -298.225686) (xy 198.734935 -298.177902) (xy 198.754226 -298.132626) (xy 198.780529 -298.09103)
			(xy 198.813164 -298.054193) (xy 198.851285 -298.023068) (xy 198.893906 -297.998461) (xy 198.939922 -297.981009)
			(xy 198.988141 -297.971165) (xy 199.037316 -297.969184) (xy 199.086171 -297.975116) (xy 199.133442 -297.988808)
			(xy 199.177904 -298.009906) (xy 199.218407 -298.037862) (xy 199.2539 -298.071954) (xy 199.283465 -298.111298)
			(xy 199.306336 -298.154875) (xy 199.32192 -298.201556) (xy 199.329815 -298.250133) (xy 199.33031 -298.27474)
			(xy 199.329815 -298.299347) (xy 199.32192 -298.347924) (xy 199.321344 -298.349649) (xy 199.767688 -298.349649)
			(xy 199.767688 -298.296351) (xy 199.775631 -298.243647) (xy 199.791341 -298.192717) (xy 199.814467 -298.144696)
			(xy 199.844491 -298.100659) (xy 199.880743 -298.061588) (xy 199.922414 -298.028357) (xy 199.968572 -298.001708)
			(xy 200.018186 -297.982236) (xy 200.070148 -297.970376) (xy 200.123298 -297.966393) (xy 200.176448 -297.970376)
			(xy 200.22841 -297.982236) (xy 200.235858 -297.985159) (xy 200.882748 -297.985159) (xy 200.882748 -297.931861)
			(xy 200.890691 -297.879157) (xy 200.906401 -297.828227) (xy 200.929527 -297.780206) (xy 200.959551 -297.736169)
			(xy 200.995803 -297.697098) (xy 201.037474 -297.663867) (xy 201.083632 -297.637218) (xy 201.133246 -297.617746)
			(xy 201.185208 -297.605886) (xy 201.238358 -297.601903) (xy 201.291508 -297.605886) (xy 201.34347 -297.617746)
			(xy 201.393084 -297.637218) (xy 201.439242 -297.663867) (xy 201.473008 -297.690794) (xy 202.399644 -297.690794)
			(xy 202.403715 -297.635172) (xy 202.415841 -297.580735) (xy 202.435764 -297.528644) (xy 202.46306 -297.480009)
			(xy 202.497146 -297.435866) (xy 202.537295 -297.397157) (xy 202.582653 -297.364706) (xy 202.632253 -297.339205)
			(xy 202.685037 -297.321198) (xy 202.73988 -297.311068) (xy 202.795614 -297.309031) (xy 202.851051 -297.315131)
			(xy 202.905008 -297.329237) (xy 202.956337 -297.351049) (xy 202.995283 -297.374818) (xy 208.715862 -297.374818)
			(xy 208.719933 -297.319196) (xy 208.732059 -297.264759) (xy 208.751982 -297.212668) (xy 208.779278 -297.164033)
			(xy 208.813364 -297.11989) (xy 208.853513 -297.081181) (xy 208.898871 -297.04873) (xy 208.948471 -297.023229)
			(xy 209.001255 -297.005222) (xy 209.056098 -296.995092) (xy 209.111832 -296.993055) (xy 209.167269 -296.999155)
			(xy 209.221226 -297.013261) (xy 209.272555 -297.035073) (xy 209.320161 -297.064127) (xy 209.363029 -297.099802)
			(xy 209.400246 -297.141339) (xy 209.431019 -297.187852) (xy 209.454691 -297.238349) (xy 209.470759 -297.291756)
			(xy 209.478879 -297.346932) (xy 209.479388 -297.374818) (xy 209.478879 -297.402704) (xy 209.470759 -297.45788)
			(xy 209.454691 -297.511287) (xy 209.431019 -297.561784) (xy 209.400246 -297.608297) (xy 209.363029 -297.649834)
			(xy 209.320161 -297.685509) (xy 209.272555 -297.714563) (xy 209.221226 -297.736375) (xy 209.167269 -297.750481)
			(xy 209.111832 -297.756581) (xy 209.056098 -297.754544) (xy 209.001255 -297.744414) (xy 208.948471 -297.726407)
			(xy 208.898871 -297.700906) (xy 208.853513 -297.668455) (xy 208.813364 -297.629746) (xy 208.779278 -297.585603)
			(xy 208.751982 -297.536968) (xy 208.732059 -297.484877) (xy 208.719933 -297.43044) (xy 208.715862 -297.374818)
			(xy 202.995283 -297.374818) (xy 203.003943 -297.380103) (xy 203.046811 -297.415778) (xy 203.084028 -297.457315)
			(xy 203.114801 -297.503828) (xy 203.138473 -297.554325) (xy 203.154541 -297.607732) (xy 203.162661 -297.662908)
			(xy 203.16317 -297.690794) (xy 203.162661 -297.71868) (xy 203.154541 -297.773856) (xy 203.138473 -297.827263)
			(xy 203.114801 -297.87776) (xy 203.084028 -297.924273) (xy 203.046811 -297.96581) (xy 203.003943 -298.001485)
			(xy 202.956337 -298.030539) (xy 202.905008 -298.052351) (xy 202.851051 -298.066457) (xy 202.795614 -298.072557)
			(xy 202.73988 -298.07052) (xy 202.685037 -298.06039) (xy 202.632253 -298.042383) (xy 202.582653 -298.016882)
			(xy 202.537295 -297.984431) (xy 202.497146 -297.945722) (xy 202.46306 -297.901579) (xy 202.435764 -297.852944)
			(xy 202.415841 -297.800853) (xy 202.403715 -297.746416) (xy 202.399644 -297.690794) (xy 201.473008 -297.690794)
			(xy 201.480913 -297.697098) (xy 201.517165 -297.736169) (xy 201.547189 -297.780206) (xy 201.570315 -297.828227)
			(xy 201.586025 -297.879157) (xy 201.593968 -297.931861) (xy 201.594466 -297.95851) (xy 201.593968 -297.985159)
			(xy 201.586025 -298.037863) (xy 201.570315 -298.088793) (xy 201.547189 -298.136814) (xy 201.517165 -298.180851)
			(xy 201.480913 -298.219922) (xy 201.439242 -298.253153) (xy 201.393084 -298.279802) (xy 201.34347 -298.299274)
			(xy 201.291508 -298.311134) (xy 201.238358 -298.315118) (xy 201.185208 -298.311134) (xy 201.133246 -298.299274)
			(xy 201.083632 -298.279802) (xy 201.037474 -298.253153) (xy 200.995803 -298.219922) (xy 200.959551 -298.180851)
			(xy 200.929527 -298.136814) (xy 200.906401 -298.088793) (xy 200.890691 -298.037863) (xy 200.882748 -297.985159)
			(xy 200.235858 -297.985159) (xy 200.278024 -298.001708) (xy 200.324182 -298.028357) (xy 200.365853 -298.061588)
			(xy 200.402105 -298.100659) (xy 200.432129 -298.144696) (xy 200.455255 -298.192717) (xy 200.470965 -298.243647)
			(xy 200.478908 -298.296351) (xy 200.479406 -298.323) (xy 200.478908 -298.349649) (xy 200.470965 -298.402353)
			(xy 200.455255 -298.453283) (xy 200.432129 -298.501304) (xy 200.402105 -298.545341) (xy 200.365853 -298.584412)
			(xy 200.324182 -298.617643) (xy 200.278024 -298.644292) (xy 200.22841 -298.663764) (xy 200.176448 -298.675624)
			(xy 200.123298 -298.679608) (xy 200.070148 -298.675624) (xy 200.018186 -298.663764) (xy 199.968572 -298.644292)
			(xy 199.922414 -298.617643) (xy 199.880743 -298.584412) (xy 199.844491 -298.545341) (xy 199.814467 -298.501304)
			(xy 199.791341 -298.453283) (xy 199.775631 -298.402353) (xy 199.767688 -298.349649) (xy 199.321344 -298.349649)
			(xy 199.306336 -298.394605) (xy 199.283465 -298.438182) (xy 199.2539 -298.477526) (xy 199.218407 -298.511618)
			(xy 199.177904 -298.539574) (xy 199.133442 -298.560672) (xy 199.086171 -298.574364) (xy 199.037316 -298.580296)
			(xy 198.988141 -298.578315) (xy 198.939922 -298.568471) (xy 198.893906 -298.551019) (xy 198.851285 -298.526412)
			(xy 198.813164 -298.495287) (xy 198.780529 -298.45845) (xy 198.754226 -298.416854) (xy 198.734935 -298.371578)
			(xy 198.723158 -298.323794) (xy 198.719198 -298.27474) (xy 198.38035 -298.27474) (xy 198.379855 -298.299347)
			(xy 198.37196 -298.347924) (xy 198.356376 -298.394605) (xy 198.333505 -298.438182) (xy 198.30394 -298.477526)
			(xy 198.268447 -298.511618) (xy 198.227944 -298.539574) (xy 198.183482 -298.560672) (xy 198.136211 -298.574364)
			(xy 198.087356 -298.580296) (xy 198.038181 -298.578315) (xy 197.989962 -298.568471) (xy 197.943946 -298.551019)
			(xy 197.901325 -298.526412) (xy 197.863204 -298.495287) (xy 197.830569 -298.45845) (xy 197.804266 -298.416854)
			(xy 197.784975 -298.371578) (xy 197.773198 -298.323794) (xy 197.769238 -298.27474) (xy 197.43039 -298.27474)
			(xy 197.429895 -298.299347) (xy 197.422 -298.347924) (xy 197.406416 -298.394605) (xy 197.383545 -298.438182)
			(xy 197.35398 -298.477526) (xy 197.318487 -298.511618) (xy 197.277984 -298.539574) (xy 197.233522 -298.560672)
			(xy 197.186251 -298.574364) (xy 197.137396 -298.580296) (xy 197.088221 -298.578315) (xy 197.040002 -298.568471)
			(xy 196.993986 -298.551019) (xy 196.951365 -298.526412) (xy 196.913244 -298.495287) (xy 196.880609 -298.45845)
			(xy 196.854306 -298.416854) (xy 196.835015 -298.371578) (xy 196.823238 -298.323794) (xy 196.819278 -298.27474)
			(xy 196.480176 -298.27474) (xy 196.479681 -298.299347) (xy 196.471786 -298.347924) (xy 196.456202 -298.394605)
			(xy 196.433331 -298.438182) (xy 196.403766 -298.477526) (xy 196.368273 -298.511618) (xy 196.32777 -298.539574)
			(xy 196.283308 -298.560672) (xy 196.236037 -298.574364) (xy 196.187182 -298.580296) (xy 196.138007 -298.578315)
			(xy 196.089788 -298.568471) (xy 196.043772 -298.551019) (xy 196.001151 -298.526412) (xy 195.96303 -298.495287)
			(xy 195.930395 -298.45845) (xy 195.904092 -298.416854) (xy 195.884801 -298.371578) (xy 195.873024 -298.323794)
			(xy 195.869064 -298.27474) (xy 195.530216 -298.27474) (xy 195.529721 -298.299347) (xy 195.521826 -298.347924)
			(xy 195.506242 -298.394605) (xy 195.483371 -298.438182) (xy 195.453806 -298.477526) (xy 195.418313 -298.511618)
			(xy 195.37781 -298.539574) (xy 195.333348 -298.560672) (xy 195.286077 -298.574364) (xy 195.237222 -298.580296)
			(xy 195.188047 -298.578315) (xy 195.139828 -298.568471) (xy 195.093812 -298.551019) (xy 195.051191 -298.526412)
			(xy 195.01307 -298.495287) (xy 194.980435 -298.45845) (xy 194.954132 -298.416854) (xy 194.934841 -298.371578)
			(xy 194.923064 -298.323794) (xy 194.919104 -298.27474) (xy 194.580256 -298.27474) (xy 194.579761 -298.299347)
			(xy 194.571866 -298.347924) (xy 194.556282 -298.394605) (xy 194.533411 -298.438182) (xy 194.503846 -298.477526)
			(xy 194.468353 -298.511618) (xy 194.42785 -298.539574) (xy 194.383388 -298.560672) (xy 194.336117 -298.574364)
			(xy 194.287262 -298.580296) (xy 194.238087 -298.578315) (xy 194.189868 -298.568471) (xy 194.143852 -298.551019)
			(xy 194.101231 -298.526412) (xy 194.06311 -298.495287) (xy 194.030475 -298.45845) (xy 194.004172 -298.416854)
			(xy 193.984881 -298.371578) (xy 193.973104 -298.323794) (xy 193.969144 -298.27474) (xy 193.630296 -298.27474)
			(xy 193.629801 -298.299347) (xy 193.621906 -298.347924) (xy 193.606322 -298.394605) (xy 193.583451 -298.438182)
			(xy 193.553886 -298.477526) (xy 193.518393 -298.511618) (xy 193.47789 -298.539574) (xy 193.433428 -298.560672)
			(xy 193.386157 -298.574364) (xy 193.337302 -298.580296) (xy 193.288127 -298.578315) (xy 193.239908 -298.568471)
			(xy 193.193892 -298.551019) (xy 193.151271 -298.526412) (xy 193.11315 -298.495287) (xy 193.080515 -298.45845)
			(xy 193.054212 -298.416854) (xy 193.034921 -298.371578) (xy 193.023144 -298.323794) (xy 193.019184 -298.27474)
			(xy 192.680336 -298.27474) (xy 192.679841 -298.299347) (xy 192.671946 -298.347924) (xy 192.656362 -298.394605)
			(xy 192.633491 -298.438182) (xy 192.603926 -298.477526) (xy 192.568433 -298.511618) (xy 192.52793 -298.539574)
			(xy 192.483468 -298.560672) (xy 192.436197 -298.574364) (xy 192.387342 -298.580296) (xy 192.338167 -298.578315)
			(xy 192.289948 -298.568471) (xy 192.243932 -298.551019) (xy 192.201311 -298.526412) (xy 192.16319 -298.495287)
			(xy 192.130555 -298.45845) (xy 192.104252 -298.416854) (xy 192.084961 -298.371578) (xy 192.073184 -298.323794)
			(xy 192.069224 -298.27474) (xy 191.730376 -298.27474) (xy 191.729881 -298.299347) (xy 191.721986 -298.347924)
			(xy 191.706402 -298.394605) (xy 191.683531 -298.438182) (xy 191.653966 -298.477526) (xy 191.618473 -298.511618)
			(xy 191.57797 -298.539574) (xy 191.533508 -298.560672) (xy 191.486237 -298.574364) (xy 191.437382 -298.580296)
			(xy 191.388207 -298.578315) (xy 191.339988 -298.568471) (xy 191.293972 -298.551019) (xy 191.251351 -298.526412)
			(xy 191.21323 -298.495287) (xy 191.180595 -298.45845) (xy 191.154292 -298.416854) (xy 191.135001 -298.371578)
			(xy 191.123224 -298.323794) (xy 191.119264 -298.27474) (xy 190.780162 -298.27474) (xy 190.779667 -298.299347)
			(xy 190.771772 -298.347924) (xy 190.756188 -298.394605) (xy 190.733317 -298.438182) (xy 190.703752 -298.477526)
			(xy 190.668259 -298.511618) (xy 190.627756 -298.539574) (xy 190.583294 -298.560672) (xy 190.536023 -298.574364)
			(xy 190.487168 -298.580296) (xy 190.437993 -298.578315) (xy 190.389774 -298.568471) (xy 190.343758 -298.551019)
			(xy 190.301137 -298.526412) (xy 190.263016 -298.495287) (xy 190.230381 -298.45845) (xy 190.204078 -298.416854)
			(xy 190.184787 -298.371578) (xy 190.17301 -298.323794) (xy 190.16905 -298.27474) (xy 189.830202 -298.27474)
			(xy 189.829707 -298.299347) (xy 189.821812 -298.347924) (xy 189.806228 -298.394605) (xy 189.783357 -298.438182)
			(xy 189.753792 -298.477526) (xy 189.718299 -298.511618) (xy 189.677796 -298.539574) (xy 189.633334 -298.560672)
			(xy 189.586063 -298.574364) (xy 189.537208 -298.580296) (xy 189.488033 -298.578315) (xy 189.439814 -298.568471)
			(xy 189.393798 -298.551019) (xy 189.351177 -298.526412) (xy 189.313056 -298.495287) (xy 189.280421 -298.45845)
			(xy 189.254118 -298.416854) (xy 189.234827 -298.371578) (xy 189.22305 -298.323794) (xy 189.21909 -298.27474)
			(xy 187.930282 -298.27474) (xy 187.929787 -298.299347) (xy 187.921892 -298.347924) (xy 187.906308 -298.394605)
			(xy 187.883437 -298.438182) (xy 187.853872 -298.477526) (xy 187.818379 -298.511618) (xy 187.777876 -298.539574)
			(xy 187.733414 -298.560672) (xy 187.686143 -298.574364) (xy 187.637288 -298.580296) (xy 187.588113 -298.578315)
			(xy 187.539894 -298.568471) (xy 187.493878 -298.551019) (xy 187.451257 -298.526412) (xy 187.413136 -298.495287)
			(xy 187.380501 -298.45845) (xy 187.354198 -298.416854) (xy 187.334907 -298.371578) (xy 187.32313 -298.323794)
			(xy 187.31917 -298.27474) (xy 186.980322 -298.27474) (xy 186.979827 -298.299347) (xy 186.971932 -298.347924)
			(xy 186.956348 -298.394605) (xy 186.933477 -298.438182) (xy 186.903912 -298.477526) (xy 186.868419 -298.511618)
			(xy 186.827916 -298.539574) (xy 186.783454 -298.560672) (xy 186.736183 -298.574364) (xy 186.687328 -298.580296)
			(xy 186.638153 -298.578315) (xy 186.589934 -298.568471) (xy 186.543918 -298.551019) (xy 186.501297 -298.526412)
			(xy 186.463176 -298.495287) (xy 186.430541 -298.45845) (xy 186.404238 -298.416854) (xy 186.384947 -298.371578)
			(xy 186.37317 -298.323794) (xy 186.36921 -298.27474) (xy 186.055285 -298.27474) (xy 186.055285 -298.300688)
			(xy 186.047153 -298.352025) (xy 186.03109 -298.401458) (xy 186.007491 -298.447768) (xy 185.976938 -298.489817)
			(xy 185.940182 -298.526567) (xy 185.898129 -298.557115) (xy 185.851815 -298.580708) (xy 185.80238 -298.596764)
			(xy 185.751042 -298.604888) (xy 185.725054 -298.605448) (xy 185.7248 -298.605448) (xy 185.705898 -298.605159)
			(xy 185.668343 -298.600826) (xy 185.64987 -298.596812) (xy 185.63844 -298.594018) (xy 185.616088 -298.599098)
			(xy 185.54446 -298.655994) (xy 185.53575 -298.663573) (xy 185.525708 -298.684338) (xy 185.525156 -298.695872)
			(xy 185.525156 -298.69765) (xy 202.569062 -298.69765) (xy 202.573133 -298.642028) (xy 202.585259 -298.587591)
			(xy 202.605182 -298.5355) (xy 202.632478 -298.486865) (xy 202.666564 -298.442722) (xy 202.706713 -298.404013)
			(xy 202.752071 -298.371562) (xy 202.801671 -298.346061) (xy 202.854455 -298.328054) (xy 202.909298 -298.317924)
			(xy 202.965032 -298.315887) (xy 203.020469 -298.321987) (xy 203.074426 -298.336093) (xy 203.125755 -298.357905)
			(xy 203.173361 -298.386959) (xy 203.216229 -298.422634) (xy 203.253446 -298.464171) (xy 203.284219 -298.510684)
			(xy 203.307891 -298.561181) (xy 203.323959 -298.614588) (xy 203.332079 -298.669764) (xy 203.332588 -298.69765)
			(xy 203.332079 -298.725536) (xy 203.323959 -298.780712) (xy 203.307891 -298.834119) (xy 203.284219 -298.884616)
			(xy 203.253446 -298.931129) (xy 203.216229 -298.972666) (xy 203.173361 -299.008341) (xy 203.125755 -299.037395)
			(xy 203.074426 -299.059207) (xy 203.020469 -299.073313) (xy 202.965032 -299.079413) (xy 202.909298 -299.077376)
			(xy 202.854455 -299.067246) (xy 202.801671 -299.049239) (xy 202.752071 -299.023738) (xy 202.706713 -298.991287)
			(xy 202.666564 -298.952578) (xy 202.632478 -298.908435) (xy 202.605182 -298.8598) (xy 202.585259 -298.807709)
			(xy 202.573133 -298.753272) (xy 202.569062 -298.69765) (xy 185.525156 -298.69765) (xy 185.525156 -298.803822)
			(xy 185.525749 -298.815015) (xy 185.535246 -298.835291) (xy 185.543444 -298.842938) (xy 185.543952 -298.843446)
			(xy 185.616088 -298.900596) (xy 185.63844 -298.905676) (xy 185.64987 -298.902882) (xy 185.668338 -298.898839)
			(xy 185.705897 -298.894516) (xy 185.7248 -298.894246) (xy 185.725054 -298.894246) (xy 185.751049 -298.894726)
			(xy 185.802401 -298.902852) (xy 185.851848 -298.918913) (xy 185.898174 -298.942511) (xy 185.940238 -298.973067)
			(xy 185.977003 -299.009827) (xy 186.007564 -299.051887) (xy 186.031169 -299.098209) (xy 186.047237 -299.147655)
			(xy 186.055371 -299.199005) (xy 186.055371 -299.224954) (xy 186.36921 -299.224954) (xy 186.37317 -299.1759)
			(xy 186.384947 -299.128116) (xy 186.404238 -299.08284) (xy 186.430541 -299.041244) (xy 186.463176 -299.004407)
			(xy 186.501297 -298.973282) (xy 186.543918 -298.948675) (xy 186.589934 -298.931223) (xy 186.638153 -298.921379)
			(xy 186.687328 -298.919398) (xy 186.736183 -298.92533) (xy 186.783454 -298.939022) (xy 186.827916 -298.96012)
			(xy 186.868419 -298.988076) (xy 186.903912 -299.022168) (xy 186.933477 -299.061512) (xy 186.956348 -299.105089)
			(xy 186.971932 -299.15177) (xy 186.979827 -299.200347) (xy 186.980322 -299.224954) (xy 187.31917 -299.224954)
			(xy 187.32313 -299.1759) (xy 187.334907 -299.128116) (xy 187.354198 -299.08284) (xy 187.380501 -299.041244)
			(xy 187.413136 -299.004407) (xy 187.451257 -298.973282) (xy 187.493878 -298.948675) (xy 187.539894 -298.931223)
			(xy 187.588113 -298.921379) (xy 187.637288 -298.919398) (xy 187.686143 -298.92533) (xy 187.733414 -298.939022)
			(xy 187.777876 -298.96012) (xy 187.818379 -298.988076) (xy 187.853872 -299.022168) (xy 187.883437 -299.061512)
			(xy 187.906308 -299.105089) (xy 187.921892 -299.15177) (xy 187.929787 -299.200347) (xy 187.930282 -299.224954)
			(xy 188.26913 -299.224954) (xy 188.27309 -299.1759) (xy 188.284867 -299.128116) (xy 188.304158 -299.08284)
			(xy 188.330461 -299.041244) (xy 188.363096 -299.004407) (xy 188.401217 -298.973282) (xy 188.443838 -298.948675)
			(xy 188.489854 -298.931223) (xy 188.538073 -298.921379) (xy 188.587248 -298.919398) (xy 188.636103 -298.92533)
			(xy 188.683374 -298.939022) (xy 188.727836 -298.96012) (xy 188.768339 -298.988076) (xy 188.803832 -299.022168)
			(xy 188.833397 -299.061512) (xy 188.856268 -299.105089) (xy 188.871852 -299.15177) (xy 188.879747 -299.200347)
			(xy 188.880242 -299.224954) (xy 189.21909 -299.224954) (xy 189.22305 -299.1759) (xy 189.234827 -299.128116)
			(xy 189.254118 -299.08284) (xy 189.280421 -299.041244) (xy 189.313056 -299.004407) (xy 189.351177 -298.973282)
			(xy 189.393798 -298.948675) (xy 189.439814 -298.931223) (xy 189.488033 -298.921379) (xy 189.537208 -298.919398)
			(xy 189.586063 -298.92533) (xy 189.633334 -298.939022) (xy 189.677796 -298.96012) (xy 189.718299 -298.988076)
			(xy 189.753792 -299.022168) (xy 189.783357 -299.061512) (xy 189.806228 -299.105089) (xy 189.821812 -299.15177)
			(xy 189.829707 -299.200347) (xy 189.830202 -299.224954) (xy 192.069224 -299.224954) (xy 192.073184 -299.1759)
			(xy 192.084961 -299.128116) (xy 192.104252 -299.08284) (xy 192.130555 -299.041244) (xy 192.16319 -299.004407)
			(xy 192.201311 -298.973282) (xy 192.243932 -298.948675) (xy 192.289948 -298.931223) (xy 192.338167 -298.921379)
			(xy 192.387342 -298.919398) (xy 192.436197 -298.92533) (xy 192.483468 -298.939022) (xy 192.52793 -298.96012)
			(xy 192.568433 -298.988076) (xy 192.603926 -299.022168) (xy 192.633491 -299.061512) (xy 192.656362 -299.105089)
			(xy 192.671946 -299.15177) (xy 192.679841 -299.200347) (xy 192.680336 -299.224954) (xy 193.019184 -299.224954)
			(xy 193.023144 -299.1759) (xy 193.034921 -299.128116) (xy 193.054212 -299.08284) (xy 193.080515 -299.041244)
			(xy 193.11315 -299.004407) (xy 193.151271 -298.973282) (xy 193.193892 -298.948675) (xy 193.239908 -298.931223)
			(xy 193.288127 -298.921379) (xy 193.337302 -298.919398) (xy 193.386157 -298.92533) (xy 193.433428 -298.939022)
			(xy 193.47789 -298.96012) (xy 193.518393 -298.988076) (xy 193.553886 -299.022168) (xy 193.583451 -299.061512)
			(xy 193.606322 -299.105089) (xy 193.621906 -299.15177) (xy 193.629801 -299.200347) (xy 193.630296 -299.224954)
			(xy 193.969144 -299.224954) (xy 193.973104 -299.1759) (xy 193.984881 -299.128116) (xy 194.004172 -299.08284)
			(xy 194.030475 -299.041244) (xy 194.06311 -299.004407) (xy 194.101231 -298.973282) (xy 194.143852 -298.948675)
			(xy 194.189868 -298.931223) (xy 194.238087 -298.921379) (xy 194.287262 -298.919398) (xy 194.336117 -298.92533)
			(xy 194.383388 -298.939022) (xy 194.42785 -298.96012) (xy 194.468353 -298.988076) (xy 194.503846 -299.022168)
			(xy 194.533411 -299.061512) (xy 194.556282 -299.105089) (xy 194.571866 -299.15177) (xy 194.579761 -299.200347)
			(xy 194.580256 -299.224954) (xy 194.919104 -299.224954) (xy 194.923064 -299.1759) (xy 194.934841 -299.128116)
			(xy 194.954132 -299.08284) (xy 194.980435 -299.041244) (xy 195.01307 -299.004407) (xy 195.051191 -298.973282)
			(xy 195.093812 -298.948675) (xy 195.139828 -298.931223) (xy 195.188047 -298.921379) (xy 195.237222 -298.919398)
			(xy 195.286077 -298.92533) (xy 195.333348 -298.939022) (xy 195.37781 -298.96012) (xy 195.418313 -298.988076)
			(xy 195.453806 -299.022168) (xy 195.483371 -299.061512) (xy 195.506242 -299.105089) (xy 195.521826 -299.15177)
			(xy 195.529721 -299.200347) (xy 195.530216 -299.224954) (xy 195.869064 -299.224954) (xy 195.873024 -299.1759)
			(xy 195.884801 -299.128116) (xy 195.904092 -299.08284) (xy 195.930395 -299.041244) (xy 195.96303 -299.004407)
			(xy 196.001151 -298.973282) (xy 196.043772 -298.948675) (xy 196.089788 -298.931223) (xy 196.138007 -298.921379)
			(xy 196.187182 -298.919398) (xy 196.236037 -298.92533) (xy 196.283308 -298.939022) (xy 196.32777 -298.96012)
			(xy 196.368273 -298.988076) (xy 196.403766 -299.022168) (xy 196.433331 -299.061512) (xy 196.456202 -299.105089)
			(xy 196.471786 -299.15177) (xy 196.479681 -299.200347) (xy 196.480176 -299.224954) (xy 196.819278 -299.224954)
			(xy 196.823238 -299.1759) (xy 196.835015 -299.128116) (xy 196.854306 -299.08284) (xy 196.880609 -299.041244)
			(xy 196.913244 -299.004407) (xy 196.951365 -298.973282) (xy 196.993986 -298.948675) (xy 197.040002 -298.931223)
			(xy 197.088221 -298.921379) (xy 197.137396 -298.919398) (xy 197.186251 -298.92533) (xy 197.233522 -298.939022)
			(xy 197.277984 -298.96012) (xy 197.318487 -298.988076) (xy 197.35398 -299.022168) (xy 197.383545 -299.061512)
			(xy 197.406416 -299.105089) (xy 197.422 -299.15177) (xy 197.429895 -299.200347) (xy 197.43039 -299.224954)
			(xy 197.769238 -299.224954) (xy 197.773198 -299.1759) (xy 197.784975 -299.128116) (xy 197.804266 -299.08284)
			(xy 197.830569 -299.041244) (xy 197.863204 -299.004407) (xy 197.901325 -298.973282) (xy 197.943946 -298.948675)
			(xy 197.989962 -298.931223) (xy 198.038181 -298.921379) (xy 198.087356 -298.919398) (xy 198.136211 -298.92533)
			(xy 198.183482 -298.939022) (xy 198.227944 -298.96012) (xy 198.268447 -298.988076) (xy 198.30394 -299.022168)
			(xy 198.333505 -299.061512) (xy 198.356376 -299.105089) (xy 198.37196 -299.15177) (xy 198.379855 -299.200347)
			(xy 198.38035 -299.224954) (xy 198.719198 -299.224954) (xy 198.723158 -299.1759) (xy 198.734935 -299.128116)
			(xy 198.754226 -299.08284) (xy 198.780529 -299.041244) (xy 198.813164 -299.004407) (xy 198.851285 -298.973282)
			(xy 198.893906 -298.948675) (xy 198.939922 -298.931223) (xy 198.988141 -298.921379) (xy 199.037316 -298.919398)
			(xy 199.086171 -298.92533) (xy 199.133442 -298.939022) (xy 199.177904 -298.96012) (xy 199.218407 -298.988076)
			(xy 199.2539 -299.022168) (xy 199.283465 -299.061512) (xy 199.306336 -299.105089) (xy 199.32192 -299.15177)
			(xy 199.329815 -299.200347) (xy 199.33031 -299.224954) (xy 199.329815 -299.249561) (xy 199.326012 -299.27296)
			(xy 206.414622 -299.27296) (xy 206.418693 -299.217338) (xy 206.430819 -299.162901) (xy 206.450742 -299.11081)
			(xy 206.478038 -299.062175) (xy 206.512124 -299.018032) (xy 206.552273 -298.979323) (xy 206.597631 -298.946872)
			(xy 206.647231 -298.921371) (xy 206.700015 -298.903364) (xy 206.754858 -298.893234) (xy 206.810592 -298.891197)
			(xy 206.866029 -298.897297) (xy 206.919986 -298.911403) (xy 206.971315 -298.933215) (xy 207.018921 -298.962269)
			(xy 207.061789 -298.997944) (xy 207.099006 -299.039481) (xy 207.129779 -299.085994) (xy 207.153451 -299.136491)
			(xy 207.169519 -299.189898) (xy 207.177639 -299.245074) (xy 207.178148 -299.27296) (xy 207.177639 -299.300846)
			(xy 207.169519 -299.356022) (xy 207.153451 -299.409429) (xy 207.129779 -299.459926) (xy 207.099006 -299.506439)
			(xy 207.061789 -299.547976) (xy 207.018921 -299.583651) (xy 206.971315 -299.612705) (xy 206.919986 -299.634517)
			(xy 206.866029 -299.648623) (xy 206.810592 -299.654723) (xy 206.754858 -299.652686) (xy 206.700015 -299.642556)
			(xy 206.647231 -299.624549) (xy 206.597631 -299.599048) (xy 206.552273 -299.566597) (xy 206.512124 -299.527888)
			(xy 206.478038 -299.483745) (xy 206.450742 -299.43511) (xy 206.430819 -299.383019) (xy 206.418693 -299.328582)
			(xy 206.414622 -299.27296) (xy 199.326012 -299.27296) (xy 199.32192 -299.298138) (xy 199.306336 -299.344819)
			(xy 199.283465 -299.388396) (xy 199.2539 -299.42774) (xy 199.218407 -299.461832) (xy 199.177904 -299.489788)
			(xy 199.133442 -299.510886) (xy 199.086171 -299.524578) (xy 199.037316 -299.53051) (xy 198.988141 -299.528529)
			(xy 198.939922 -299.518685) (xy 198.893906 -299.501233) (xy 198.851285 -299.476626) (xy 198.813164 -299.445501)
			(xy 198.780529 -299.408664) (xy 198.754226 -299.367068) (xy 198.734935 -299.321792) (xy 198.723158 -299.274008)
			(xy 198.719198 -299.224954) (xy 198.38035 -299.224954) (xy 198.379855 -299.249561) (xy 198.37196 -299.298138)
			(xy 198.356376 -299.344819) (xy 198.333505 -299.388396) (xy 198.30394 -299.42774) (xy 198.268447 -299.461832)
			(xy 198.227944 -299.489788) (xy 198.183482 -299.510886) (xy 198.136211 -299.524578) (xy 198.087356 -299.53051)
			(xy 198.038181 -299.528529) (xy 197.989962 -299.518685) (xy 197.943946 -299.501233) (xy 197.901325 -299.476626)
			(xy 197.863204 -299.445501) (xy 197.830569 -299.408664) (xy 197.804266 -299.367068) (xy 197.784975 -299.321792)
			(xy 197.773198 -299.274008) (xy 197.769238 -299.224954) (xy 197.43039 -299.224954) (xy 197.429895 -299.249561)
			(xy 197.422 -299.298138) (xy 197.406416 -299.344819) (xy 197.383545 -299.388396) (xy 197.35398 -299.42774)
			(xy 197.318487 -299.461832) (xy 197.277984 -299.489788) (xy 197.233522 -299.510886) (xy 197.186251 -299.524578)
			(xy 197.137396 -299.53051) (xy 197.088221 -299.528529) (xy 197.040002 -299.518685) (xy 196.993986 -299.501233)
			(xy 196.951365 -299.476626) (xy 196.913244 -299.445501) (xy 196.880609 -299.408664) (xy 196.854306 -299.367068)
			(xy 196.835015 -299.321792) (xy 196.823238 -299.274008) (xy 196.819278 -299.224954) (xy 196.480176 -299.224954)
			(xy 196.479681 -299.249561) (xy 196.471786 -299.298138) (xy 196.456202 -299.344819) (xy 196.433331 -299.388396)
			(xy 196.403766 -299.42774) (xy 196.368273 -299.461832) (xy 196.32777 -299.489788) (xy 196.283308 -299.510886)
			(xy 196.236037 -299.524578) (xy 196.187182 -299.53051) (xy 196.138007 -299.528529) (xy 196.089788 -299.518685)
			(xy 196.043772 -299.501233) (xy 196.001151 -299.476626) (xy 195.96303 -299.445501) (xy 195.930395 -299.408664)
			(xy 195.904092 -299.367068) (xy 195.884801 -299.321792) (xy 195.873024 -299.274008) (xy 195.869064 -299.224954)
			(xy 195.530216 -299.224954) (xy 195.529721 -299.249561) (xy 195.521826 -299.298138) (xy 195.506242 -299.344819)
			(xy 195.483371 -299.388396) (xy 195.453806 -299.42774) (xy 195.418313 -299.461832) (xy 195.37781 -299.489788)
			(xy 195.333348 -299.510886) (xy 195.286077 -299.524578) (xy 195.237222 -299.53051) (xy 195.188047 -299.528529)
			(xy 195.139828 -299.518685) (xy 195.093812 -299.501233) (xy 195.051191 -299.476626) (xy 195.01307 -299.445501)
			(xy 194.980435 -299.408664) (xy 194.954132 -299.367068) (xy 194.934841 -299.321792) (xy 194.923064 -299.274008)
			(xy 194.919104 -299.224954) (xy 194.580256 -299.224954) (xy 194.579761 -299.249561) (xy 194.571866 -299.298138)
			(xy 194.556282 -299.344819) (xy 194.533411 -299.388396) (xy 194.503846 -299.42774) (xy 194.468353 -299.461832)
			(xy 194.42785 -299.489788) (xy 194.383388 -299.510886) (xy 194.336117 -299.524578) (xy 194.287262 -299.53051)
			(xy 194.238087 -299.528529) (xy 194.189868 -299.518685) (xy 194.143852 -299.501233) (xy 194.101231 -299.476626)
			(xy 194.06311 -299.445501) (xy 194.030475 -299.408664) (xy 194.004172 -299.367068) (xy 193.984881 -299.321792)
			(xy 193.973104 -299.274008) (xy 193.969144 -299.224954) (xy 193.630296 -299.224954) (xy 193.629801 -299.249561)
			(xy 193.621906 -299.298138) (xy 193.606322 -299.344819) (xy 193.583451 -299.388396) (xy 193.553886 -299.42774)
			(xy 193.518393 -299.461832) (xy 193.47789 -299.489788) (xy 193.433428 -299.510886) (xy 193.386157 -299.524578)
			(xy 193.337302 -299.53051) (xy 193.288127 -299.528529) (xy 193.239908 -299.518685) (xy 193.193892 -299.501233)
			(xy 193.151271 -299.476626) (xy 193.11315 -299.445501) (xy 193.080515 -299.408664) (xy 193.054212 -299.367068)
			(xy 193.034921 -299.321792) (xy 193.023144 -299.274008) (xy 193.019184 -299.224954) (xy 192.680336 -299.224954)
			(xy 192.679841 -299.249561) (xy 192.671946 -299.298138) (xy 192.656362 -299.344819) (xy 192.633491 -299.388396)
			(xy 192.603926 -299.42774) (xy 192.568433 -299.461832) (xy 192.52793 -299.489788) (xy 192.483468 -299.510886)
			(xy 192.436197 -299.524578) (xy 192.387342 -299.53051) (xy 192.338167 -299.528529) (xy 192.289948 -299.518685)
			(xy 192.243932 -299.501233) (xy 192.201311 -299.476626) (xy 192.16319 -299.445501) (xy 192.130555 -299.408664)
			(xy 192.104252 -299.367068) (xy 192.084961 -299.321792) (xy 192.073184 -299.274008) (xy 192.069224 -299.224954)
			(xy 189.830202 -299.224954) (xy 189.829707 -299.249561) (xy 189.821812 -299.298138) (xy 189.806228 -299.344819)
			(xy 189.783357 -299.388396) (xy 189.753792 -299.42774) (xy 189.718299 -299.461832) (xy 189.677796 -299.489788)
			(xy 189.633334 -299.510886) (xy 189.586063 -299.524578) (xy 189.537208 -299.53051) (xy 189.488033 -299.528529)
			(xy 189.439814 -299.518685) (xy 189.393798 -299.501233) (xy 189.351177 -299.476626) (xy 189.313056 -299.445501)
			(xy 189.280421 -299.408664) (xy 189.254118 -299.367068) (xy 189.234827 -299.321792) (xy 189.22305 -299.274008)
			(xy 189.21909 -299.224954) (xy 188.880242 -299.224954) (xy 188.879747 -299.249561) (xy 188.871852 -299.298138)
			(xy 188.856268 -299.344819) (xy 188.833397 -299.388396) (xy 188.803832 -299.42774) (xy 188.768339 -299.461832)
			(xy 188.727836 -299.489788) (xy 188.683374 -299.510886) (xy 188.636103 -299.524578) (xy 188.587248 -299.53051)
			(xy 188.538073 -299.528529) (xy 188.489854 -299.518685) (xy 188.443838 -299.501233) (xy 188.401217 -299.476626)
			(xy 188.363096 -299.445501) (xy 188.330461 -299.408664) (xy 188.304158 -299.367068) (xy 188.284867 -299.321792)
			(xy 188.27309 -299.274008) (xy 188.26913 -299.224954) (xy 187.930282 -299.224954) (xy 187.929787 -299.249561)
			(xy 187.921892 -299.298138) (xy 187.906308 -299.344819) (xy 187.883437 -299.388396) (xy 187.853872 -299.42774)
			(xy 187.818379 -299.461832) (xy 187.777876 -299.489788) (xy 187.733414 -299.510886) (xy 187.686143 -299.524578)
			(xy 187.637288 -299.53051) (xy 187.588113 -299.528529) (xy 187.539894 -299.518685) (xy 187.493878 -299.501233)
			(xy 187.451257 -299.476626) (xy 187.413136 -299.445501) (xy 187.380501 -299.408664) (xy 187.354198 -299.367068)
			(xy 187.334907 -299.321792) (xy 187.32313 -299.274008) (xy 187.31917 -299.224954) (xy 186.980322 -299.224954)
			(xy 186.979827 -299.249561) (xy 186.971932 -299.298138) (xy 186.956348 -299.344819) (xy 186.933477 -299.388396)
			(xy 186.903912 -299.42774) (xy 186.868419 -299.461832) (xy 186.827916 -299.489788) (xy 186.783454 -299.510886)
			(xy 186.736183 -299.524578) (xy 186.687328 -299.53051) (xy 186.638153 -299.528529) (xy 186.589934 -299.518685)
			(xy 186.543918 -299.501233) (xy 186.501297 -299.476626) (xy 186.463176 -299.445501) (xy 186.430541 -299.408664)
			(xy 186.404238 -299.367068) (xy 186.384947 -299.321792) (xy 186.37317 -299.274008) (xy 186.36921 -299.224954)
			(xy 186.055371 -299.224954) (xy 186.055371 -299.250995) (xy 186.047237 -299.302345) (xy 186.031169 -299.351791)
			(xy 186.007564 -299.398113) (xy 185.977003 -299.440173) (xy 185.940238 -299.476933) (xy 185.898174 -299.507489)
			(xy 185.851848 -299.531087) (xy 185.8024 -299.547148) (xy 185.751049 -299.555274) (xy 185.725054 -299.555662)
			(xy 185.7248 -299.555662) (xy 185.705898 -299.555373) (xy 185.668343 -299.55104) (xy 185.64987 -299.547026)
			(xy 185.63844 -299.544232) (xy 185.616088 -299.549312) (xy 185.54446 -299.606208) (xy 185.535752 -299.613788)
			(xy 185.525716 -299.634553) (xy 185.525156 -299.646086) (xy 185.525156 -299.753782) (xy 185.525713 -299.76445)
			(xy 204.14183 -299.76445) (xy 204.145901 -299.708828) (xy 204.158027 -299.654391) (xy 204.17795 -299.6023)
			(xy 204.205246 -299.553665) (xy 204.239332 -299.509522) (xy 204.279481 -299.470813) (xy 204.324839 -299.438362)
			(xy 204.374439 -299.412861) (xy 204.427223 -299.394854) (xy 204.482066 -299.384724) (xy 204.5378 -299.382687)
			(xy 204.593237 -299.388787) (xy 204.647194 -299.402893) (xy 204.698523 -299.424705) (xy 204.746129 -299.453759)
			(xy 204.788997 -299.489434) (xy 204.826214 -299.530971) (xy 204.856987 -299.577484) (xy 204.880659 -299.627981)
			(xy 204.896727 -299.681388) (xy 204.904847 -299.736564) (xy 204.905356 -299.76445) (xy 204.905078 -299.77969)
			(xy 208.738468 -299.77969) (xy 208.742539 -299.724068) (xy 208.754665 -299.669631) (xy 208.774588 -299.61754)
			(xy 208.801884 -299.568905) (xy 208.83597 -299.524762) (xy 208.876119 -299.486053) (xy 208.921477 -299.453602)
			(xy 208.971077 -299.428101) (xy 209.023861 -299.410094) (xy 209.078704 -299.399964) (xy 209.134438 -299.397927)
			(xy 209.189875 -299.404027) (xy 209.243832 -299.418133) (xy 209.295161 -299.439945) (xy 209.342767 -299.468999)
			(xy 209.385635 -299.504674) (xy 209.422852 -299.546211) (xy 209.453625 -299.592724) (xy 209.477297 -299.643221)
			(xy 209.493365 -299.696628) (xy 209.501485 -299.751804) (xy 209.501994 -299.77969) (xy 209.501485 -299.807576)
			(xy 209.493365 -299.862752) (xy 209.477297 -299.916159) (xy 209.453625 -299.966656) (xy 209.422852 -300.013169)
			(xy 209.385635 -300.054706) (xy 209.342767 -300.090381) (xy 209.295161 -300.119435) (xy 209.243832 -300.141247)
			(xy 209.189875 -300.155353) (xy 209.134438 -300.161453) (xy 209.078704 -300.159416) (xy 209.023861 -300.149286)
			(xy 208.971077 -300.131279) (xy 208.921477 -300.105778) (xy 208.876119 -300.073327) (xy 208.83597 -300.034618)
			(xy 208.801884 -299.990475) (xy 208.774588 -299.94184) (xy 208.754665 -299.889749) (xy 208.742539 -299.835312)
			(xy 208.738468 -299.77969) (xy 204.905078 -299.77969) (xy 204.904847 -299.792336) (xy 204.896727 -299.847512)
			(xy 204.880659 -299.900919) (xy 204.856987 -299.951416) (xy 204.826214 -299.997929) (xy 204.788997 -300.039466)
			(xy 204.746129 -300.075141) (xy 204.698523 -300.104195) (xy 204.647194 -300.126007) (xy 204.593237 -300.140113)
			(xy 204.5378 -300.146213) (xy 204.482066 -300.144176) (xy 204.427223 -300.134046) (xy 204.374439 -300.116039)
			(xy 204.324839 -300.090538) (xy 204.279481 -300.058087) (xy 204.239332 -300.019378) (xy 204.205246 -299.975235)
			(xy 204.17795 -299.9266) (xy 204.158027 -299.874509) (xy 204.145901 -299.820072) (xy 204.14183 -299.76445)
			(xy 185.525713 -299.76445) (xy 185.525741 -299.764979) (xy 185.535228 -299.785267) (xy 185.543444 -299.792898)
			(xy 185.543952 -299.793406) (xy 185.616088 -299.850556) (xy 185.63844 -299.855636) (xy 185.64987 -299.852842)
			(xy 185.668338 -299.848799) (xy 185.705897 -299.844475) (xy 185.7248 -299.844206) (xy 185.725054 -299.844206)
			(xy 185.751045 -299.844686) (xy 185.802386 -299.852811) (xy 185.851825 -299.868868) (xy 185.898143 -299.892463)
			(xy 185.940199 -299.923013) (xy 185.976957 -299.959766) (xy 186.007513 -300.001818) (xy 186.031114 -300.048132)
			(xy 186.047178 -300.097569) (xy 186.055311 -300.14891) (xy 186.055311 -300.174914) (xy 186.36921 -300.174914)
			(xy 186.37317 -300.12586) (xy 186.384947 -300.078076) (xy 186.404238 -300.0328) (xy 186.430541 -299.991204)
			(xy 186.463176 -299.954367) (xy 186.501297 -299.923242) (xy 186.543918 -299.898635) (xy 186.589934 -299.881183)
			(xy 186.638153 -299.871339) (xy 186.687328 -299.869358) (xy 186.736183 -299.87529) (xy 186.783454 -299.888982)
			(xy 186.827916 -299.91008) (xy 186.868419 -299.938036) (xy 186.903912 -299.972128) (xy 186.933477 -300.011472)
			(xy 186.956348 -300.055049) (xy 186.971932 -300.10173) (xy 186.979827 -300.150307) (xy 186.980322 -300.174914)
			(xy 187.31917 -300.174914) (xy 187.32313 -300.12586) (xy 187.334907 -300.078076) (xy 187.354198 -300.0328)
			(xy 187.380501 -299.991204) (xy 187.413136 -299.954367) (xy 187.451257 -299.923242) (xy 187.493878 -299.898635)
			(xy 187.539894 -299.881183) (xy 187.588113 -299.871339) (xy 187.637288 -299.869358) (xy 187.686143 -299.87529)
			(xy 187.733414 -299.888982) (xy 187.777876 -299.91008) (xy 187.818379 -299.938036) (xy 187.853872 -299.972128)
			(xy 187.883437 -300.011472) (xy 187.906308 -300.055049) (xy 187.921892 -300.10173) (xy 187.929787 -300.150307)
			(xy 187.930282 -300.174914) (xy 188.26913 -300.174914) (xy 188.27309 -300.12586) (xy 188.284867 -300.078076)
			(xy 188.304158 -300.0328) (xy 188.330461 -299.991204) (xy 188.363096 -299.954367) (xy 188.401217 -299.923242)
			(xy 188.443838 -299.898635) (xy 188.489854 -299.881183) (xy 188.538073 -299.871339) (xy 188.587248 -299.869358)
			(xy 188.636103 -299.87529) (xy 188.683374 -299.888982) (xy 188.727836 -299.91008) (xy 188.768339 -299.938036)
			(xy 188.803832 -299.972128) (xy 188.833397 -300.011472) (xy 188.856268 -300.055049) (xy 188.871852 -300.10173)
			(xy 188.879747 -300.150307) (xy 188.880242 -300.174914) (xy 189.21909 -300.174914) (xy 189.22305 -300.12586)
			(xy 189.234827 -300.078076) (xy 189.254118 -300.0328) (xy 189.280421 -299.991204) (xy 189.313056 -299.954367)
			(xy 189.351177 -299.923242) (xy 189.393798 -299.898635) (xy 189.439814 -299.881183) (xy 189.488033 -299.871339)
			(xy 189.537208 -299.869358) (xy 189.586063 -299.87529) (xy 189.633334 -299.888982) (xy 189.677796 -299.91008)
			(xy 189.718299 -299.938036) (xy 189.753792 -299.972128) (xy 189.783357 -300.011472) (xy 189.806228 -300.055049)
			(xy 189.821812 -300.10173) (xy 189.829707 -300.150307) (xy 189.830202 -300.174914) (xy 190.16905 -300.174914)
			(xy 190.17301 -300.12586) (xy 190.184787 -300.078076) (xy 190.204078 -300.0328) (xy 190.230381 -299.991204)
			(xy 190.263016 -299.954367) (xy 190.301137 -299.923242) (xy 190.343758 -299.898635) (xy 190.389774 -299.881183)
			(xy 190.437993 -299.871339) (xy 190.487168 -299.869358) (xy 190.536023 -299.87529) (xy 190.583294 -299.888982)
			(xy 190.627756 -299.91008) (xy 190.668259 -299.938036) (xy 190.703752 -299.972128) (xy 190.733317 -300.011472)
			(xy 190.756188 -300.055049) (xy 190.771772 -300.10173) (xy 190.779667 -300.150307) (xy 190.780162 -300.174914)
			(xy 191.119264 -300.174914) (xy 191.123224 -300.12586) (xy 191.135001 -300.078076) (xy 191.154292 -300.0328)
			(xy 191.180595 -299.991204) (xy 191.21323 -299.954367) (xy 191.251351 -299.923242) (xy 191.293972 -299.898635)
			(xy 191.339988 -299.881183) (xy 191.388207 -299.871339) (xy 191.437382 -299.869358) (xy 191.486237 -299.87529)
			(xy 191.533508 -299.888982) (xy 191.57797 -299.91008) (xy 191.618473 -299.938036) (xy 191.653966 -299.972128)
			(xy 191.683531 -300.011472) (xy 191.706402 -300.055049) (xy 191.721986 -300.10173) (xy 191.729881 -300.150307)
			(xy 191.730376 -300.174914) (xy 192.069224 -300.174914) (xy 192.073184 -300.12586) (xy 192.084961 -300.078076)
			(xy 192.104252 -300.0328) (xy 192.130555 -299.991204) (xy 192.16319 -299.954367) (xy 192.201311 -299.923242)
			(xy 192.243932 -299.898635) (xy 192.289948 -299.881183) (xy 192.338167 -299.871339) (xy 192.387342 -299.869358)
			(xy 192.436197 -299.87529) (xy 192.483468 -299.888982) (xy 192.52793 -299.91008) (xy 192.568433 -299.938036)
			(xy 192.603926 -299.972128) (xy 192.633491 -300.011472) (xy 192.656362 -300.055049) (xy 192.671946 -300.10173)
			(xy 192.679841 -300.150307) (xy 192.680336 -300.174914) (xy 193.019184 -300.174914) (xy 193.023144 -300.12586)
			(xy 193.034921 -300.078076) (xy 193.054212 -300.0328) (xy 193.080515 -299.991204) (xy 193.11315 -299.954367)
			(xy 193.151271 -299.923242) (xy 193.193892 -299.898635) (xy 193.239908 -299.881183) (xy 193.288127 -299.871339)
			(xy 193.337302 -299.869358) (xy 193.386157 -299.87529) (xy 193.433428 -299.888982) (xy 193.47789 -299.91008)
			(xy 193.518393 -299.938036) (xy 193.553886 -299.972128) (xy 193.583451 -300.011472) (xy 193.606322 -300.055049)
			(xy 193.621906 -300.10173) (xy 193.629801 -300.150307) (xy 193.630296 -300.174914) (xy 193.969144 -300.174914)
			(xy 193.973104 -300.12586) (xy 193.984881 -300.078076) (xy 194.004172 -300.0328) (xy 194.030475 -299.991204)
			(xy 194.06311 -299.954367) (xy 194.101231 -299.923242) (xy 194.143852 -299.898635) (xy 194.189868 -299.881183)
			(xy 194.238087 -299.871339) (xy 194.287262 -299.869358) (xy 194.336117 -299.87529) (xy 194.383388 -299.888982)
			(xy 194.42785 -299.91008) (xy 194.468353 -299.938036) (xy 194.503846 -299.972128) (xy 194.533411 -300.011472)
			(xy 194.556282 -300.055049) (xy 194.571866 -300.10173) (xy 194.579761 -300.150307) (xy 194.580256 -300.174914)
			(xy 194.919104 -300.174914) (xy 194.923064 -300.12586) (xy 194.934841 -300.078076) (xy 194.954132 -300.0328)
			(xy 194.980435 -299.991204) (xy 195.01307 -299.954367) (xy 195.051191 -299.923242) (xy 195.093812 -299.898635)
			(xy 195.139828 -299.881183) (xy 195.188047 -299.871339) (xy 195.237222 -299.869358) (xy 195.286077 -299.87529)
			(xy 195.333348 -299.888982) (xy 195.37781 -299.91008) (xy 195.418313 -299.938036) (xy 195.453806 -299.972128)
			(xy 195.483371 -300.011472) (xy 195.506242 -300.055049) (xy 195.521826 -300.10173) (xy 195.529721 -300.150307)
			(xy 195.530216 -300.174914) (xy 195.869064 -300.174914) (xy 195.873024 -300.12586) (xy 195.884801 -300.078076)
			(xy 195.904092 -300.0328) (xy 195.930395 -299.991204) (xy 195.96303 -299.954367) (xy 196.001151 -299.923242)
			(xy 196.043772 -299.898635) (xy 196.089788 -299.881183) (xy 196.138007 -299.871339) (xy 196.187182 -299.869358)
			(xy 196.236037 -299.87529) (xy 196.283308 -299.888982) (xy 196.32777 -299.91008) (xy 196.368273 -299.938036)
			(xy 196.403766 -299.972128) (xy 196.433331 -300.011472) (xy 196.456202 -300.055049) (xy 196.471786 -300.10173)
			(xy 196.479681 -300.150307) (xy 196.480176 -300.174914) (xy 196.819278 -300.174914) (xy 196.823238 -300.12586)
			(xy 196.835015 -300.078076) (xy 196.854306 -300.0328) (xy 196.880609 -299.991204) (xy 196.913244 -299.954367)
			(xy 196.951365 -299.923242) (xy 196.993986 -299.898635) (xy 197.040002 -299.881183) (xy 197.088221 -299.871339)
			(xy 197.137396 -299.869358) (xy 197.186251 -299.87529) (xy 197.233522 -299.888982) (xy 197.277984 -299.91008)
			(xy 197.318487 -299.938036) (xy 197.35398 -299.972128) (xy 197.383545 -300.011472) (xy 197.406416 -300.055049)
			(xy 197.422 -300.10173) (xy 197.429895 -300.150307) (xy 197.43039 -300.174914) (xy 197.769238 -300.174914)
			(xy 197.773198 -300.12586) (xy 197.784975 -300.078076) (xy 197.804266 -300.0328) (xy 197.830569 -299.991204)
			(xy 197.863204 -299.954367) (xy 197.901325 -299.923242) (xy 197.943946 -299.898635) (xy 197.989962 -299.881183)
			(xy 198.038181 -299.871339) (xy 198.087356 -299.869358) (xy 198.136211 -299.87529) (xy 198.183482 -299.888982)
			(xy 198.227944 -299.91008) (xy 198.268447 -299.938036) (xy 198.30394 -299.972128) (xy 198.333505 -300.011472)
			(xy 198.356376 -300.055049) (xy 198.37196 -300.10173) (xy 198.379855 -300.150307) (xy 198.38035 -300.174914)
			(xy 198.719198 -300.174914) (xy 198.723158 -300.12586) (xy 198.734935 -300.078076) (xy 198.754226 -300.0328)
			(xy 198.780529 -299.991204) (xy 198.813164 -299.954367) (xy 198.851285 -299.923242) (xy 198.893906 -299.898635)
			(xy 198.939922 -299.881183) (xy 198.988141 -299.871339) (xy 199.037316 -299.869358) (xy 199.086171 -299.87529)
			(xy 199.133442 -299.888982) (xy 199.177904 -299.91008) (xy 199.218407 -299.938036) (xy 199.2539 -299.972128)
			(xy 199.283465 -300.011472) (xy 199.306336 -300.055049) (xy 199.32192 -300.10173) (xy 199.329815 -300.150307)
			(xy 199.33031 -300.174914) (xy 199.329815 -300.199521) (xy 199.32192 -300.248098) (xy 199.306336 -300.294779)
			(xy 199.283465 -300.338356) (xy 199.2539 -300.3777) (xy 199.218407 -300.411792) (xy 199.177904 -300.439748)
			(xy 199.133442 -300.460846) (xy 199.086171 -300.474538) (xy 199.037316 -300.48047) (xy 198.988141 -300.478489)
			(xy 198.939922 -300.468645) (xy 198.893906 -300.451193) (xy 198.851285 -300.426586) (xy 198.813164 -300.395461)
			(xy 198.780529 -300.358624) (xy 198.754226 -300.317028) (xy 198.734935 -300.271752) (xy 198.723158 -300.223968)
			(xy 198.719198 -300.174914) (xy 198.38035 -300.174914) (xy 198.379855 -300.199521) (xy 198.37196 -300.248098)
			(xy 198.356376 -300.294779) (xy 198.333505 -300.338356) (xy 198.30394 -300.3777) (xy 198.268447 -300.411792)
			(xy 198.227944 -300.439748) (xy 198.183482 -300.460846) (xy 198.136211 -300.474538) (xy 198.087356 -300.48047)
			(xy 198.038181 -300.478489) (xy 197.989962 -300.468645) (xy 197.943946 -300.451193) (xy 197.901325 -300.426586)
			(xy 197.863204 -300.395461) (xy 197.830569 -300.358624) (xy 197.804266 -300.317028) (xy 197.784975 -300.271752)
			(xy 197.773198 -300.223968) (xy 197.769238 -300.174914) (xy 197.43039 -300.174914) (xy 197.429895 -300.199521)
			(xy 197.422 -300.248098) (xy 197.406416 -300.294779) (xy 197.383545 -300.338356) (xy 197.35398 -300.3777)
			(xy 197.318487 -300.411792) (xy 197.277984 -300.439748) (xy 197.233522 -300.460846) (xy 197.186251 -300.474538)
			(xy 197.137396 -300.48047) (xy 197.088221 -300.478489) (xy 197.040002 -300.468645) (xy 196.993986 -300.451193)
			(xy 196.951365 -300.426586) (xy 196.913244 -300.395461) (xy 196.880609 -300.358624) (xy 196.854306 -300.317028)
			(xy 196.835015 -300.271752) (xy 196.823238 -300.223968) (xy 196.819278 -300.174914) (xy 196.480176 -300.174914)
			(xy 196.479681 -300.199521) (xy 196.471786 -300.248098) (xy 196.456202 -300.294779) (xy 196.433331 -300.338356)
			(xy 196.403766 -300.3777) (xy 196.368273 -300.411792) (xy 196.32777 -300.439748) (xy 196.283308 -300.460846)
			(xy 196.236037 -300.474538) (xy 196.187182 -300.48047) (xy 196.138007 -300.478489) (xy 196.089788 -300.468645)
			(xy 196.043772 -300.451193) (xy 196.001151 -300.426586) (xy 195.96303 -300.395461) (xy 195.930395 -300.358624)
			(xy 195.904092 -300.317028) (xy 195.884801 -300.271752) (xy 195.873024 -300.223968) (xy 195.869064 -300.174914)
			(xy 195.530216 -300.174914) (xy 195.529721 -300.199521) (xy 195.521826 -300.248098) (xy 195.506242 -300.294779)
			(xy 195.483371 -300.338356) (xy 195.453806 -300.3777) (xy 195.418313 -300.411792) (xy 195.37781 -300.439748)
			(xy 195.333348 -300.460846) (xy 195.286077 -300.474538) (xy 195.237222 -300.48047) (xy 195.188047 -300.478489)
			(xy 195.139828 -300.468645) (xy 195.093812 -300.451193) (xy 195.051191 -300.426586) (xy 195.01307 -300.395461)
			(xy 194.980435 -300.358624) (xy 194.954132 -300.317028) (xy 194.934841 -300.271752) (xy 194.923064 -300.223968)
			(xy 194.919104 -300.174914) (xy 194.580256 -300.174914) (xy 194.579761 -300.199521) (xy 194.571866 -300.248098)
			(xy 194.556282 -300.294779) (xy 194.533411 -300.338356) (xy 194.503846 -300.3777) (xy 194.468353 -300.411792)
			(xy 194.42785 -300.439748) (xy 194.383388 -300.460846) (xy 194.336117 -300.474538) (xy 194.287262 -300.48047)
			(xy 194.238087 -300.478489) (xy 194.189868 -300.468645) (xy 194.143852 -300.451193) (xy 194.101231 -300.426586)
			(xy 194.06311 -300.395461) (xy 194.030475 -300.358624) (xy 194.004172 -300.317028) (xy 193.984881 -300.271752)
			(xy 193.973104 -300.223968) (xy 193.969144 -300.174914) (xy 193.630296 -300.174914) (xy 193.629801 -300.199521)
			(xy 193.621906 -300.248098) (xy 193.606322 -300.294779) (xy 193.583451 -300.338356) (xy 193.553886 -300.3777)
			(xy 193.518393 -300.411792) (xy 193.47789 -300.439748) (xy 193.433428 -300.460846) (xy 193.386157 -300.474538)
			(xy 193.337302 -300.48047) (xy 193.288127 -300.478489) (xy 193.239908 -300.468645) (xy 193.193892 -300.451193)
			(xy 193.151271 -300.426586) (xy 193.11315 -300.395461) (xy 193.080515 -300.358624) (xy 193.054212 -300.317028)
			(xy 193.034921 -300.271752) (xy 193.023144 -300.223968) (xy 193.019184 -300.174914) (xy 192.680336 -300.174914)
			(xy 192.679841 -300.199521) (xy 192.671946 -300.248098) (xy 192.656362 -300.294779) (xy 192.633491 -300.338356)
			(xy 192.603926 -300.3777) (xy 192.568433 -300.411792) (xy 192.52793 -300.439748) (xy 192.483468 -300.460846)
			(xy 192.436197 -300.474538) (xy 192.387342 -300.48047) (xy 192.338167 -300.478489) (xy 192.289948 -300.468645)
			(xy 192.243932 -300.451193) (xy 192.201311 -300.426586) (xy 192.16319 -300.395461) (xy 192.130555 -300.358624)
			(xy 192.104252 -300.317028) (xy 192.084961 -300.271752) (xy 192.073184 -300.223968) (xy 192.069224 -300.174914)
			(xy 191.730376 -300.174914) (xy 191.729881 -300.199521) (xy 191.721986 -300.248098) (xy 191.706402 -300.294779)
			(xy 191.683531 -300.338356) (xy 191.653966 -300.3777) (xy 191.618473 -300.411792) (xy 191.57797 -300.439748)
			(xy 191.533508 -300.460846) (xy 191.486237 -300.474538) (xy 191.437382 -300.48047) (xy 191.388207 -300.478489)
			(xy 191.339988 -300.468645) (xy 191.293972 -300.451193) (xy 191.251351 -300.426586) (xy 191.21323 -300.395461)
			(xy 191.180595 -300.358624) (xy 191.154292 -300.317028) (xy 191.135001 -300.271752) (xy 191.123224 -300.223968)
			(xy 191.119264 -300.174914) (xy 190.780162 -300.174914) (xy 190.779667 -300.199521) (xy 190.771772 -300.248098)
			(xy 190.756188 -300.294779) (xy 190.733317 -300.338356) (xy 190.703752 -300.3777) (xy 190.668259 -300.411792)
			(xy 190.627756 -300.439748) (xy 190.583294 -300.460846) (xy 190.536023 -300.474538) (xy 190.487168 -300.48047)
			(xy 190.437993 -300.478489) (xy 190.389774 -300.468645) (xy 190.343758 -300.451193) (xy 190.301137 -300.426586)
			(xy 190.263016 -300.395461) (xy 190.230381 -300.358624) (xy 190.204078 -300.317028) (xy 190.184787 -300.271752)
			(xy 190.17301 -300.223968) (xy 190.16905 -300.174914) (xy 189.830202 -300.174914) (xy 189.829707 -300.199521)
			(xy 189.821812 -300.248098) (xy 189.806228 -300.294779) (xy 189.783357 -300.338356) (xy 189.753792 -300.3777)
			(xy 189.718299 -300.411792) (xy 189.677796 -300.439748) (xy 189.633334 -300.460846) (xy 189.586063 -300.474538)
			(xy 189.537208 -300.48047) (xy 189.488033 -300.478489) (xy 189.439814 -300.468645) (xy 189.393798 -300.451193)
			(xy 189.351177 -300.426586) (xy 189.313056 -300.395461) (xy 189.280421 -300.358624) (xy 189.254118 -300.317028)
			(xy 189.234827 -300.271752) (xy 189.22305 -300.223968) (xy 189.21909 -300.174914) (xy 188.880242 -300.174914)
			(xy 188.879747 -300.199521) (xy 188.871852 -300.248098) (xy 188.856268 -300.294779) (xy 188.833397 -300.338356)
			(xy 188.803832 -300.3777) (xy 188.768339 -300.411792) (xy 188.727836 -300.439748) (xy 188.683374 -300.460846)
			(xy 188.636103 -300.474538) (xy 188.587248 -300.48047) (xy 188.538073 -300.478489) (xy 188.489854 -300.468645)
			(xy 188.443838 -300.451193) (xy 188.401217 -300.426586) (xy 188.363096 -300.395461) (xy 188.330461 -300.358624)
			(xy 188.304158 -300.317028) (xy 188.284867 -300.271752) (xy 188.27309 -300.223968) (xy 188.26913 -300.174914)
			(xy 187.930282 -300.174914) (xy 187.929787 -300.199521) (xy 187.921892 -300.248098) (xy 187.906308 -300.294779)
			(xy 187.883437 -300.338356) (xy 187.853872 -300.3777) (xy 187.818379 -300.411792) (xy 187.777876 -300.439748)
			(xy 187.733414 -300.460846) (xy 187.686143 -300.474538) (xy 187.637288 -300.48047) (xy 187.588113 -300.478489)
			(xy 187.539894 -300.468645) (xy 187.493878 -300.451193) (xy 187.451257 -300.426586) (xy 187.413136 -300.395461)
			(xy 187.380501 -300.358624) (xy 187.354198 -300.317028) (xy 187.334907 -300.271752) (xy 187.32313 -300.223968)
			(xy 187.31917 -300.174914) (xy 186.980322 -300.174914) (xy 186.979827 -300.199521) (xy 186.971932 -300.248098)
			(xy 186.956348 -300.294779) (xy 186.933477 -300.338356) (xy 186.903912 -300.3777) (xy 186.868419 -300.411792)
			(xy 186.827916 -300.439748) (xy 186.783454 -300.460846) (xy 186.736183 -300.474538) (xy 186.687328 -300.48047)
			(xy 186.638153 -300.478489) (xy 186.589934 -300.468645) (xy 186.543918 -300.451193) (xy 186.501297 -300.426586)
			(xy 186.463176 -300.395461) (xy 186.430541 -300.358624) (xy 186.404238 -300.317028) (xy 186.384947 -300.271752)
			(xy 186.37317 -300.223968) (xy 186.36921 -300.174914) (xy 186.055311 -300.174914) (xy 186.055311 -300.20089)
			(xy 186.047178 -300.252231) (xy 186.031114 -300.301668) (xy 186.007513 -300.347982) (xy 185.976957 -300.390034)
			(xy 185.940199 -300.426787) (xy 185.898143 -300.457337) (xy 185.851825 -300.480932) (xy 185.802386 -300.496989)
			(xy 185.751045 -300.505114) (xy 185.725054 -300.505622) (xy 185.7248 -300.505622) (xy 185.705898 -300.505333)
			(xy 185.668343 -300.500999) (xy 185.64987 -300.496986) (xy 185.63844 -300.494192) (xy 185.616088 -300.499272)
			(xy 185.54446 -300.556168) (xy 185.535746 -300.563746) (xy 185.525693 -300.58451) (xy 185.525156 -300.596046)
			(xy 185.525156 -300.703742) (xy 185.525733 -300.714943) (xy 185.53521 -300.735244) (xy 185.543444 -300.742858)
			(xy 185.543952 -300.743366) (xy 185.616088 -300.800516) (xy 185.63844 -300.805596) (xy 185.64987 -300.802802)
			(xy 185.668338 -300.798759) (xy 185.705897 -300.794436) (xy 185.7248 -300.794166) (xy 185.725054 -300.794166)
			(xy 185.751048 -300.794646) (xy 185.802396 -300.802772) (xy 185.85184 -300.818831) (xy 185.898164 -300.842429)
			(xy 185.940225 -300.872982) (xy 185.976988 -300.90974) (xy 186.007547 -300.951797) (xy 186.031151 -300.998117)
			(xy 186.047217 -301.047559) (xy 186.055351 -301.098906) (xy 186.055351 -301.124874) (xy 186.36921 -301.124874)
			(xy 186.37317 -301.07582) (xy 186.384947 -301.028036) (xy 186.404238 -300.98276) (xy 186.430541 -300.941164)
			(xy 186.463176 -300.904327) (xy 186.501297 -300.873202) (xy 186.543918 -300.848595) (xy 186.589934 -300.831143)
			(xy 186.638153 -300.821299) (xy 186.687328 -300.819318) (xy 186.736183 -300.82525) (xy 186.783454 -300.838942)
			(xy 186.827916 -300.86004) (xy 186.868419 -300.887996) (xy 186.903912 -300.922088) (xy 186.933477 -300.961432)
			(xy 186.956348 -301.005009) (xy 186.971932 -301.05169) (xy 186.979827 -301.100267) (xy 186.980322 -301.124874)
			(xy 187.31917 -301.124874) (xy 187.32313 -301.07582) (xy 187.334907 -301.028036) (xy 187.354198 -300.98276)
			(xy 187.380501 -300.941164) (xy 187.413136 -300.904327) (xy 187.451257 -300.873202) (xy 187.493878 -300.848595)
			(xy 187.539894 -300.831143) (xy 187.588113 -300.821299) (xy 187.637288 -300.819318) (xy 187.686143 -300.82525)
			(xy 187.733414 -300.838942) (xy 187.777876 -300.86004) (xy 187.818379 -300.887996) (xy 187.853872 -300.922088)
			(xy 187.883437 -300.961432) (xy 187.906308 -301.005009) (xy 187.921892 -301.05169) (xy 187.929787 -301.100267)
			(xy 187.930282 -301.124874) (xy 188.26913 -301.124874) (xy 188.27309 -301.07582) (xy 188.284867 -301.028036)
			(xy 188.304158 -300.98276) (xy 188.330461 -300.941164) (xy 188.363096 -300.904327) (xy 188.401217 -300.873202)
			(xy 188.443838 -300.848595) (xy 188.489854 -300.831143) (xy 188.538073 -300.821299) (xy 188.587248 -300.819318)
			(xy 188.636103 -300.82525) (xy 188.683374 -300.838942) (xy 188.727836 -300.86004) (xy 188.768339 -300.887996)
			(xy 188.803832 -300.922088) (xy 188.833397 -300.961432) (xy 188.856268 -301.005009) (xy 188.871852 -301.05169)
			(xy 188.879747 -301.100267) (xy 188.880242 -301.124874) (xy 189.21909 -301.124874) (xy 189.22305 -301.07582)
			(xy 189.234827 -301.028036) (xy 189.254118 -300.98276) (xy 189.280421 -300.941164) (xy 189.313056 -300.904327)
			(xy 189.351177 -300.873202) (xy 189.393798 -300.848595) (xy 189.439814 -300.831143) (xy 189.488033 -300.821299)
			(xy 189.537208 -300.819318) (xy 189.586063 -300.82525) (xy 189.633334 -300.838942) (xy 189.677796 -300.86004)
			(xy 189.718299 -300.887996) (xy 189.753792 -300.922088) (xy 189.783357 -300.961432) (xy 189.806228 -301.005009)
			(xy 189.821812 -301.05169) (xy 189.829707 -301.100267) (xy 189.830202 -301.124874) (xy 189.829707 -301.149481)
			(xy 189.821812 -301.198058) (xy 189.806228 -301.244739) (xy 189.783357 -301.288316) (xy 189.753792 -301.32766)
			(xy 189.718299 -301.361752) (xy 189.677796 -301.389708) (xy 189.633334 -301.410806) (xy 189.586063 -301.424498)
			(xy 189.537208 -301.43043) (xy 189.488033 -301.428449) (xy 189.439814 -301.418605) (xy 189.393798 -301.401153)
			(xy 189.351177 -301.376546) (xy 189.313056 -301.345421) (xy 189.280421 -301.308584) (xy 189.254118 -301.266988)
			(xy 189.234827 -301.221712) (xy 189.22305 -301.173928) (xy 189.21909 -301.124874) (xy 188.880242 -301.124874)
			(xy 188.879747 -301.149481) (xy 188.871852 -301.198058) (xy 188.856268 -301.244739) (xy 188.833397 -301.288316)
			(xy 188.803832 -301.32766) (xy 188.768339 -301.361752) (xy 188.727836 -301.389708) (xy 188.683374 -301.410806)
			(xy 188.636103 -301.424498) (xy 188.587248 -301.43043) (xy 188.538073 -301.428449) (xy 188.489854 -301.418605)
			(xy 188.443838 -301.401153) (xy 188.401217 -301.376546) (xy 188.363096 -301.345421) (xy 188.330461 -301.308584)
			(xy 188.304158 -301.266988) (xy 188.284867 -301.221712) (xy 188.27309 -301.173928) (xy 188.26913 -301.124874)
			(xy 187.930282 -301.124874) (xy 187.929787 -301.149481) (xy 187.921892 -301.198058) (xy 187.906308 -301.244739)
			(xy 187.883437 -301.288316) (xy 187.853872 -301.32766) (xy 187.818379 -301.361752) (xy 187.777876 -301.389708)
			(xy 187.733414 -301.410806) (xy 187.686143 -301.424498) (xy 187.637288 -301.43043) (xy 187.588113 -301.428449)
			(xy 187.539894 -301.418605) (xy 187.493878 -301.401153) (xy 187.451257 -301.376546) (xy 187.413136 -301.345421)
			(xy 187.380501 -301.308584) (xy 187.354198 -301.266988) (xy 187.334907 -301.221712) (xy 187.32313 -301.173928)
			(xy 187.31917 -301.124874) (xy 186.980322 -301.124874) (xy 186.979827 -301.149481) (xy 186.971932 -301.198058)
			(xy 186.956348 -301.244739) (xy 186.933477 -301.288316) (xy 186.903912 -301.32766) (xy 186.868419 -301.361752)
			(xy 186.827916 -301.389708) (xy 186.783454 -301.410806) (xy 186.736183 -301.424498) (xy 186.687328 -301.43043)
			(xy 186.638153 -301.428449) (xy 186.589934 -301.418605) (xy 186.543918 -301.401153) (xy 186.501297 -301.376546)
			(xy 186.463176 -301.345421) (xy 186.430541 -301.308584) (xy 186.404238 -301.266988) (xy 186.384947 -301.221712)
			(xy 186.37317 -301.173928) (xy 186.36921 -301.124874) (xy 186.055351 -301.124874) (xy 186.055351 -301.150894)
			(xy 186.047217 -301.202241) (xy 186.031151 -301.251683) (xy 186.007547 -301.298003) (xy 185.976988 -301.34006)
			(xy 185.940225 -301.376818) (xy 185.898164 -301.407371) (xy 185.85184 -301.430969) (xy 185.802396 -301.447028)
			(xy 185.751048 -301.455154) (xy 185.725054 -301.455582) (xy 185.7248 -301.455582) (xy 185.705898 -301.455293)
			(xy 185.668343 -301.45096) (xy 185.64987 -301.446946) (xy 185.63844 -301.444152) (xy 185.616088 -301.449232)
			(xy 185.54446 -301.506128) (xy 185.535739 -301.513703) (xy 185.52567 -301.534468) (xy 185.525156 -301.546006)
			(xy 185.525156 -301.653702) (xy 185.525745 -301.664897) (xy 185.535237 -301.685179) (xy 185.543444 -301.692818)
			(xy 185.543952 -301.693326) (xy 185.616088 -301.750476) (xy 185.63844 -301.755556) (xy 185.64987 -301.752762)
			(xy 185.668338 -301.748719) (xy 185.705897 -301.744394) (xy 185.7248 -301.744126) (xy 185.725054 -301.744126)
			(xy 185.751043 -301.744606) (xy 185.802382 -301.75273) (xy 185.851817 -301.768787) (xy 185.898132 -301.79238)
			(xy 185.940186 -301.822928) (xy 185.976942 -301.859679) (xy 186.007496 -301.901728) (xy 186.031096 -301.94804)
			(xy 186.047159 -301.997473) (xy 186.055291 -302.048811) (xy 186.055291 -302.074834) (xy 186.36921 -302.074834)
			(xy 186.37317 -302.02578) (xy 186.384947 -301.977996) (xy 186.404238 -301.93272) (xy 186.430541 -301.891124)
			(xy 186.463176 -301.854287) (xy 186.501297 -301.823162) (xy 186.543918 -301.798555) (xy 186.589934 -301.781103)
			(xy 186.638153 -301.771259) (xy 186.687328 -301.769278) (xy 186.736183 -301.77521) (xy 186.783454 -301.788902)
			(xy 186.827916 -301.81) (xy 186.868419 -301.837956) (xy 186.903912 -301.872048) (xy 186.933477 -301.911392)
			(xy 186.956348 -301.954969) (xy 186.971932 -302.00165) (xy 186.979827 -302.050227) (xy 186.980322 -302.074834)
			(xy 187.31917 -302.074834) (xy 187.32313 -302.02578) (xy 187.334907 -301.977996) (xy 187.354198 -301.93272)
			(xy 187.380501 -301.891124) (xy 187.413136 -301.854287) (xy 187.451257 -301.823162) (xy 187.493878 -301.798555)
			(xy 187.539894 -301.781103) (xy 187.588113 -301.771259) (xy 187.637288 -301.769278) (xy 187.686143 -301.77521)
			(xy 187.733414 -301.788902) (xy 187.777876 -301.81) (xy 187.818379 -301.837956) (xy 187.853872 -301.872048)
			(xy 187.883437 -301.911392) (xy 187.906308 -301.954969) (xy 187.921892 -302.00165) (xy 187.929787 -302.050227)
			(xy 187.930282 -302.074834) (xy 188.26913 -302.074834) (xy 188.27309 -302.02578) (xy 188.284867 -301.977996)
			(xy 188.304158 -301.93272) (xy 188.330461 -301.891124) (xy 188.363096 -301.854287) (xy 188.401217 -301.823162)
			(xy 188.443838 -301.798555) (xy 188.489854 -301.781103) (xy 188.538073 -301.771259) (xy 188.587248 -301.769278)
			(xy 188.636103 -301.77521) (xy 188.683374 -301.788902) (xy 188.727836 -301.81) (xy 188.768339 -301.837956)
			(xy 188.803832 -301.872048) (xy 188.833397 -301.911392) (xy 188.856268 -301.954969) (xy 188.871852 -302.00165)
			(xy 188.879747 -302.050227) (xy 188.880242 -302.074834) (xy 188.880076 -302.083066) (xy 189.219187 -302.083066)
			(xy 189.221877 -302.033498) (xy 189.232551 -301.985017) (xy 189.250928 -301.938902) (xy 189.276523 -301.896368)
			(xy 189.308663 -301.858535) (xy 189.3465 -301.8264) (xy 189.389038 -301.80081) (xy 189.435155 -301.782439)
			(xy 189.483637 -301.771771) (xy 189.533206 -301.769088) (xy 189.582557 -301.774459) (xy 189.630388 -301.787744)
			(xy 189.67544 -301.808592) (xy 189.716525 -301.836454) (xy 189.752561 -301.870596) (xy 189.782599 -301.910118)
			(xy 189.805847 -301.95398) (xy 189.821693 -302.001024) (xy 189.829719 -302.050013) (xy 189.83004 -302.06653)
			(xy 191.119415 -302.06653) (xy 191.124779 -302.017186) (xy 191.138056 -301.969361) (xy 191.158894 -301.924313)
			(xy 191.186745 -301.88323) (xy 191.220876 -301.847194) (xy 191.260387 -301.817154) (xy 191.304237 -301.793901)
			(xy 191.351272 -301.778049) (xy 191.400251 -301.770014) (xy 191.425068 -301.769526) (xy 191.439251 -301.769707)
			(xy 191.467491 -301.772376) (xy 191.481456 -301.77486) (xy 191.493902 -301.777146) (xy 191.517524 -301.76978)
			(xy 191.594994 -301.69231) (xy 191.60236 -301.668688) (xy 191.600074 -301.656242) (xy 191.597593 -301.642277)
			(xy 191.594924 -301.614037) (xy 191.59474 -301.599854) (xy 191.595096 -301.575857) (xy 191.602611 -301.528456)
			(xy 191.617449 -301.482813) (xy 191.639244 -301.440054) (xy 191.66746 -301.40123) (xy 191.701402 -301.367299)
			(xy 191.740234 -301.339095) (xy 191.783 -301.317313) (xy 191.828647 -301.302489) (xy 191.876051 -301.294989)
			(xy 191.900048 -301.294546) (xy 191.914231 -301.294731) (xy 191.942471 -301.297397) (xy 191.956436 -301.29988)
			(xy 191.968882 -301.302166) (xy 191.992504 -301.2948) (xy 192.069974 -301.21733) (xy 192.07734 -301.193708)
			(xy 192.075054 -301.181262) (xy 192.072577 -301.167296) (xy 192.069905 -301.139057) (xy 192.06972 -301.124874)
			(xy 192.070206 -301.100056) (xy 192.07824 -301.051075) (xy 192.094092 -301.004039) (xy 192.117345 -300.960187)
			(xy 192.147385 -300.920674) (xy 192.183422 -300.886542) (xy 192.224507 -300.858689) (xy 192.269556 -300.837849)
			(xy 192.317382 -300.824572) (xy 192.366727 -300.819207) (xy 192.41629 -300.821895) (xy 192.464765 -300.832566)
			(xy 192.510875 -300.850939) (xy 192.553406 -300.876529) (xy 192.591236 -300.908663) (xy 192.62337 -300.946493)
			(xy 192.64896 -300.989023) (xy 192.667333 -301.035133) (xy 192.678004 -301.083608) (xy 192.680243 -301.124874)
			(xy 193.019184 -301.124874) (xy 193.023144 -301.07582) (xy 193.034921 -301.028036) (xy 193.054212 -300.98276)
			(xy 193.080515 -300.941164) (xy 193.11315 -300.904327) (xy 193.151271 -300.873202) (xy 193.193892 -300.848595)
			(xy 193.239908 -300.831143) (xy 193.288127 -300.821299) (xy 193.337302 -300.819318) (xy 193.386157 -300.82525)
			(xy 193.433428 -300.838942) (xy 193.47789 -300.86004) (xy 193.518393 -300.887996) (xy 193.553886 -300.922088)
			(xy 193.583451 -300.961432) (xy 193.606322 -301.005009) (xy 193.621906 -301.05169) (xy 193.629801 -301.100267)
			(xy 193.630296 -301.124874) (xy 193.969144 -301.124874) (xy 193.973104 -301.07582) (xy 193.984881 -301.028036)
			(xy 194.004172 -300.98276) (xy 194.030475 -300.941164) (xy 194.06311 -300.904327) (xy 194.101231 -300.873202)
			(xy 194.143852 -300.848595) (xy 194.189868 -300.831143) (xy 194.238087 -300.821299) (xy 194.287262 -300.819318)
			(xy 194.336117 -300.82525) (xy 194.383388 -300.838942) (xy 194.42785 -300.86004) (xy 194.468353 -300.887996)
			(xy 194.503846 -300.922088) (xy 194.533411 -300.961432) (xy 194.556282 -301.005009) (xy 194.571866 -301.05169)
			(xy 194.579761 -301.100267) (xy 194.580256 -301.124874) (xy 194.919104 -301.124874) (xy 194.923064 -301.07582)
			(xy 194.934841 -301.028036) (xy 194.954132 -300.98276) (xy 194.980435 -300.941164) (xy 195.01307 -300.904327)
			(xy 195.051191 -300.873202) (xy 195.093812 -300.848595) (xy 195.139828 -300.831143) (xy 195.188047 -300.821299)
			(xy 195.237222 -300.819318) (xy 195.286077 -300.82525) (xy 195.333348 -300.838942) (xy 195.37781 -300.86004)
			(xy 195.418313 -300.887996) (xy 195.453806 -300.922088) (xy 195.483371 -300.961432) (xy 195.506242 -301.005009)
			(xy 195.521826 -301.05169) (xy 195.529721 -301.100267) (xy 195.530216 -301.124874) (xy 195.869064 -301.124874)
			(xy 195.873024 -301.07582) (xy 195.884801 -301.028036) (xy 195.904092 -300.98276) (xy 195.930395 -300.941164)
			(xy 195.96303 -300.904327) (xy 196.001151 -300.873202) (xy 196.043772 -300.848595) (xy 196.089788 -300.831143)
			(xy 196.138007 -300.821299) (xy 196.187182 -300.819318) (xy 196.236037 -300.82525) (xy 196.283308 -300.838942)
			(xy 196.32777 -300.86004) (xy 196.368273 -300.887996) (xy 196.403766 -300.922088) (xy 196.433331 -300.961432)
			(xy 196.456202 -301.005009) (xy 196.471786 -301.05169) (xy 196.479681 -301.100267) (xy 196.480176 -301.124874)
			(xy 196.819278 -301.124874) (xy 196.823238 -301.07582) (xy 196.835015 -301.028036) (xy 196.854306 -300.98276)
			(xy 196.880609 -300.941164) (xy 196.913244 -300.904327) (xy 196.951365 -300.873202) (xy 196.993986 -300.848595)
			(xy 197.040002 -300.831143) (xy 197.088221 -300.821299) (xy 197.137396 -300.819318) (xy 197.186251 -300.82525)
			(xy 197.233522 -300.838942) (xy 197.277984 -300.86004) (xy 197.318487 -300.887996) (xy 197.35398 -300.922088)
			(xy 197.383545 -300.961432) (xy 197.406416 -301.005009) (xy 197.422 -301.05169) (xy 197.429895 -301.100267)
			(xy 197.43039 -301.124874) (xy 197.769238 -301.124874) (xy 197.773198 -301.07582) (xy 197.784975 -301.028036)
			(xy 197.804266 -300.98276) (xy 197.830569 -300.941164) (xy 197.863204 -300.904327) (xy 197.901325 -300.873202)
			(xy 197.943946 -300.848595) (xy 197.989962 -300.831143) (xy 198.038181 -300.821299) (xy 198.087356 -300.819318)
			(xy 198.136211 -300.82525) (xy 198.183482 -300.838942) (xy 198.227944 -300.86004) (xy 198.268447 -300.887996)
			(xy 198.30394 -300.922088) (xy 198.333505 -300.961432) (xy 198.356376 -301.005009) (xy 198.37196 -301.05169)
			(xy 198.379855 -301.100267) (xy 198.38035 -301.124874) (xy 198.719198 -301.124874) (xy 198.723158 -301.07582)
			(xy 198.734935 -301.028036) (xy 198.754226 -300.98276) (xy 198.780529 -300.941164) (xy 198.813164 -300.904327)
			(xy 198.851285 -300.873202) (xy 198.893906 -300.848595) (xy 198.939922 -300.831143) (xy 198.988141 -300.821299)
			(xy 199.037316 -300.819318) (xy 199.086171 -300.82525) (xy 199.133442 -300.838942) (xy 199.177904 -300.86004)
			(xy 199.218407 -300.887996) (xy 199.2539 -300.922088) (xy 199.283465 -300.961432) (xy 199.306336 -301.005009)
			(xy 199.32192 -301.05169) (xy 199.329815 -301.100267) (xy 199.33031 -301.124874) (xy 199.329815 -301.149481)
			(xy 199.32192 -301.198058) (xy 199.306336 -301.244739) (xy 199.297259 -301.262034) (xy 201.475846 -301.262034)
			(xy 201.479917 -301.206412) (xy 201.492043 -301.151975) (xy 201.511966 -301.099884) (xy 201.539262 -301.051249)
			(xy 201.573348 -301.007106) (xy 201.613497 -300.968397) (xy 201.658855 -300.935946) (xy 201.708455 -300.910445)
			(xy 201.761239 -300.892438) (xy 201.816082 -300.882308) (xy 201.871816 -300.880271) (xy 201.927253 -300.886371)
			(xy 201.98121 -300.900477) (xy 202.032539 -300.922289) (xy 202.080145 -300.951343) (xy 202.123013 -300.987018)
			(xy 202.16023 -301.028555) (xy 202.169172 -301.04207) (xy 206.417162 -301.04207) (xy 206.421233 -300.986448)
			(xy 206.433359 -300.932011) (xy 206.453282 -300.87992) (xy 206.480578 -300.831285) (xy 206.514664 -300.787142)
			(xy 206.554813 -300.748433) (xy 206.600171 -300.715982) (xy 206.649771 -300.690481) (xy 206.702555 -300.672474)
			(xy 206.757398 -300.662344) (xy 206.813132 -300.660307) (xy 206.868569 -300.666407) (xy 206.922526 -300.680513)
			(xy 206.973855 -300.702325) (xy 207.021461 -300.731379) (xy 207.064329 -300.767054) (xy 207.101546 -300.808591)
			(xy 207.132319 -300.855104) (xy 207.155991 -300.905601) (xy 207.172059 -300.959008) (xy 207.180179 -301.014184)
			(xy 207.180688 -301.04207) (xy 207.180535 -301.050452) (xy 208.791046 -301.050452) (xy 208.795117 -300.99483)
			(xy 208.807243 -300.940393) (xy 208.827166 -300.888302) (xy 208.854462 -300.839667) (xy 208.888548 -300.795524)
			(xy 208.928697 -300.756815) (xy 208.974055 -300.724364) (xy 209.023655 -300.698863) (xy 209.076439 -300.680856)
			(xy 209.131282 -300.670726) (xy 209.187016 -300.668689) (xy 209.242453 -300.674789) (xy 209.29641 -300.688895)
			(xy 209.347739 -300.710707) (xy 209.395345 -300.739761) (xy 209.438213 -300.775436) (xy 209.47543 -300.816973)
			(xy 209.506203 -300.863486) (xy 209.529875 -300.913983) (xy 209.545943 -300.96739) (xy 209.554063 -301.022566)
			(xy 209.554572 -301.050452) (xy 209.554063 -301.078338) (xy 209.545943 -301.133514) (xy 209.529875 -301.186921)
			(xy 209.506203 -301.237418) (xy 209.47543 -301.283931) (xy 209.438213 -301.325468) (xy 209.395345 -301.361143)
			(xy 209.347739 -301.390197) (xy 209.29641 -301.412009) (xy 209.242453 -301.426115) (xy 209.187016 -301.432215)
			(xy 209.131282 -301.430178) (xy 209.076439 -301.420048) (xy 209.023655 -301.402041) (xy 208.974055 -301.37654)
			(xy 208.928697 -301.344089) (xy 208.888548 -301.30538) (xy 208.854462 -301.261237) (xy 208.827166 -301.212602)
			(xy 208.807243 -301.160511) (xy 208.795117 -301.106074) (xy 208.791046 -301.050452) (xy 207.180535 -301.050452)
			(xy 207.180179 -301.069956) (xy 207.172059 -301.125132) (xy 207.155991 -301.178539) (xy 207.132319 -301.229036)
			(xy 207.101546 -301.275549) (xy 207.064329 -301.317086) (xy 207.021461 -301.352761) (xy 206.973855 -301.381815)
			(xy 206.922526 -301.403627) (xy 206.868569 -301.417733) (xy 206.813132 -301.423833) (xy 206.757398 -301.421796)
			(xy 206.702555 -301.411666) (xy 206.649771 -301.393659) (xy 206.600171 -301.368158) (xy 206.554813 -301.335707)
			(xy 206.514664 -301.296998) (xy 206.480578 -301.252855) (xy 206.453282 -301.20422) (xy 206.433359 -301.152129)
			(xy 206.421233 -301.097692) (xy 206.417162 -301.04207) (xy 202.169172 -301.04207) (xy 202.191003 -301.075068)
			(xy 202.214675 -301.125565) (xy 202.230743 -301.178972) (xy 202.238863 -301.234148) (xy 202.239372 -301.262034)
			(xy 202.238863 -301.28992) (xy 202.230743 -301.345096) (xy 202.214675 -301.398503) (xy 202.191003 -301.449)
			(xy 202.16023 -301.495513) (xy 202.123013 -301.53705) (xy 202.080145 -301.572725) (xy 202.032539 -301.601779)
			(xy 201.98121 -301.623591) (xy 201.927253 -301.637697) (xy 201.871816 -301.643797) (xy 201.816082 -301.64176)
			(xy 201.761239 -301.63163) (xy 201.708455 -301.613623) (xy 201.658855 -301.588122) (xy 201.613497 -301.555671)
			(xy 201.573348 -301.516962) (xy 201.539262 -301.472819) (xy 201.511966 -301.424184) (xy 201.492043 -301.372093)
			(xy 201.479917 -301.317656) (xy 201.475846 -301.262034) (xy 199.297259 -301.262034) (xy 199.283465 -301.288316)
			(xy 199.2539 -301.32766) (xy 199.218407 -301.361752) (xy 199.177904 -301.389708) (xy 199.133442 -301.410806)
			(xy 199.086171 -301.424498) (xy 199.037316 -301.43043) (xy 198.988141 -301.428449) (xy 198.939922 -301.418605)
			(xy 198.893906 -301.401153) (xy 198.851285 -301.376546) (xy 198.813164 -301.345421) (xy 198.780529 -301.308584)
			(xy 198.754226 -301.266988) (xy 198.734935 -301.221712) (xy 198.723158 -301.173928) (xy 198.719198 -301.124874)
			(xy 198.38035 -301.124874) (xy 198.379855 -301.149481) (xy 198.37196 -301.198058) (xy 198.356376 -301.244739)
			(xy 198.333505 -301.288316) (xy 198.30394 -301.32766) (xy 198.268447 -301.361752) (xy 198.227944 -301.389708)
			(xy 198.183482 -301.410806) (xy 198.136211 -301.424498) (xy 198.087356 -301.43043) (xy 198.038181 -301.428449)
			(xy 197.989962 -301.418605) (xy 197.943946 -301.401153) (xy 197.901325 -301.376546) (xy 197.863204 -301.345421)
			(xy 197.830569 -301.308584) (xy 197.804266 -301.266988) (xy 197.784975 -301.221712) (xy 197.773198 -301.173928)
			(xy 197.769238 -301.124874) (xy 197.43039 -301.124874) (xy 197.429895 -301.149481) (xy 197.422 -301.198058)
			(xy 197.406416 -301.244739) (xy 197.383545 -301.288316) (xy 197.35398 -301.32766) (xy 197.318487 -301.361752)
			(xy 197.277984 -301.389708) (xy 197.233522 -301.410806) (xy 197.186251 -301.424498) (xy 197.137396 -301.43043)
			(xy 197.088221 -301.428449) (xy 197.040002 -301.418605) (xy 196.993986 -301.401153) (xy 196.951365 -301.376546)
			(xy 196.913244 -301.345421) (xy 196.880609 -301.308584) (xy 196.854306 -301.266988) (xy 196.835015 -301.221712)
			(xy 196.823238 -301.173928) (xy 196.819278 -301.124874) (xy 196.480176 -301.124874) (xy 196.479681 -301.149481)
			(xy 196.471786 -301.198058) (xy 196.456202 -301.244739) (xy 196.433331 -301.288316) (xy 196.403766 -301.32766)
			(xy 196.368273 -301.361752) (xy 196.32777 -301.389708) (xy 196.283308 -301.410806) (xy 196.236037 -301.424498)
			(xy 196.187182 -301.43043) (xy 196.138007 -301.428449) (xy 196.089788 -301.418605) (xy 196.043772 -301.401153)
			(xy 196.001151 -301.376546) (xy 195.96303 -301.345421) (xy 195.930395 -301.308584) (xy 195.904092 -301.266988)
			(xy 195.884801 -301.221712) (xy 195.873024 -301.173928) (xy 195.869064 -301.124874) (xy 195.530216 -301.124874)
			(xy 195.529721 -301.149481) (xy 195.521826 -301.198058) (xy 195.506242 -301.244739) (xy 195.483371 -301.288316)
			(xy 195.453806 -301.32766) (xy 195.418313 -301.361752) (xy 195.37781 -301.389708) (xy 195.333348 -301.410806)
			(xy 195.286077 -301.424498) (xy 195.237222 -301.43043) (xy 195.188047 -301.428449) (xy 195.139828 -301.418605)
			(xy 195.093812 -301.401153) (xy 195.051191 -301.376546) (xy 195.01307 -301.345421) (xy 194.980435 -301.308584)
			(xy 194.954132 -301.266988) (xy 194.934841 -301.221712) (xy 194.923064 -301.173928) (xy 194.919104 -301.124874)
			(xy 194.580256 -301.124874) (xy 194.579761 -301.149481) (xy 194.571866 -301.198058) (xy 194.556282 -301.244739)
			(xy 194.533411 -301.288316) (xy 194.503846 -301.32766) (xy 194.468353 -301.361752) (xy 194.42785 -301.389708)
			(xy 194.383388 -301.410806) (xy 194.336117 -301.424498) (xy 194.287262 -301.43043) (xy 194.238087 -301.428449)
			(xy 194.189868 -301.418605) (xy 194.143852 -301.401153) (xy 194.101231 -301.376546) (xy 194.06311 -301.345421)
			(xy 194.030475 -301.308584) (xy 194.004172 -301.266988) (xy 193.984881 -301.221712) (xy 193.973104 -301.173928)
			(xy 193.969144 -301.124874) (xy 193.630296 -301.124874) (xy 193.629801 -301.149481) (xy 193.621906 -301.198058)
			(xy 193.606322 -301.244739) (xy 193.583451 -301.288316) (xy 193.553886 -301.32766) (xy 193.518393 -301.361752)
			(xy 193.47789 -301.389708) (xy 193.433428 -301.410806) (xy 193.386157 -301.424498) (xy 193.337302 -301.43043)
			(xy 193.288127 -301.428449) (xy 193.239908 -301.418605) (xy 193.193892 -301.401153) (xy 193.151271 -301.376546)
			(xy 193.11315 -301.345421) (xy 193.080515 -301.308584) (xy 193.054212 -301.266988) (xy 193.034921 -301.221712)
			(xy 193.023144 -301.173928) (xy 193.019184 -301.124874) (xy 192.680243 -301.124874) (xy 192.680693 -301.133171)
			(xy 192.675328 -301.182516) (xy 192.662052 -301.230343) (xy 192.641212 -301.275392) (xy 192.61336 -301.316476)
			(xy 192.579227 -301.352513) (xy 192.539715 -301.382554) (xy 192.495863 -301.405807) (xy 192.448827 -301.42166)
			(xy 192.399846 -301.429694) (xy 192.375028 -301.430182) (xy 192.360845 -301.430002) (xy 192.332605 -301.427332)
			(xy 192.31864 -301.424848) (xy 192.306194 -301.422562) (xy 192.282572 -301.429928) (xy 192.205102 -301.507398)
			(xy 192.197736 -301.53102) (xy 192.200022 -301.543466) (xy 192.202504 -301.557431) (xy 192.205172 -301.585671)
			(xy 192.205356 -301.599854) (xy 192.204795 -301.623842) (xy 192.197297 -301.671227) (xy 192.182479 -301.716856)
			(xy 192.160706 -301.759606) (xy 192.132512 -301.798423) (xy 192.098594 -301.832351) (xy 192.059786 -301.860556)
			(xy 192.017043 -301.882343) (xy 191.971419 -301.897175) (xy 191.924035 -301.904688) (xy 191.900048 -301.905162)
			(xy 191.885865 -301.904979) (xy 191.857625 -301.902311) (xy 191.84366 -301.899828) (xy 191.831214 -301.897542)
			(xy 191.807592 -301.904908) (xy 191.730122 -301.982378) (xy 191.722756 -302.006) (xy 191.725042 -302.018446)
			(xy 191.72752 -302.032412) (xy 191.730191 -302.060651) (xy 191.730376 -302.074834) (xy 191.729886 -302.099651)
			(xy 191.721851 -302.14863) (xy 191.705998 -302.195664) (xy 191.682745 -302.239514) (xy 191.652705 -302.279025)
			(xy 191.616668 -302.313156) (xy 191.575585 -302.341007) (xy 191.530537 -302.361845) (xy 191.482712 -302.375121)
			(xy 191.433368 -302.380485) (xy 191.383807 -302.377796) (xy 191.335334 -302.367125) (xy 191.289226 -302.348753)
			(xy 191.246697 -302.323163) (xy 191.208868 -302.29103) (xy 191.176736 -302.253201) (xy 191.151147 -302.210672)
			(xy 191.132774 -302.164564) (xy 191.122103 -302.116091) (xy 191.119415 -302.06653) (xy 189.83004 -302.06653)
			(xy 189.830202 -302.074834) (xy 189.83003 -302.089017) (xy 189.827355 -302.117257) (xy 189.824868 -302.131222)
			(xy 189.822699 -302.145186) (xy 189.825283 -302.173317) (xy 189.835476 -302.199663) (xy 189.852496 -302.222208)
			(xy 189.875043 -302.239227) (xy 189.90139 -302.249418) (xy 189.92952 -302.252001) (xy 189.943486 -302.24984)
			(xy 189.957453 -302.24737) (xy 189.985692 -302.244694) (xy 189.999874 -302.244506) (xy 190.024697 -302.24495)
			(xy 190.07369 -302.252978) (xy 190.120739 -302.268826) (xy 190.164604 -302.292077) (xy 190.20413 -302.322119)
			(xy 190.238274 -302.358159) (xy 190.266138 -302.399249) (xy 190.286988 -302.444305) (xy 190.300273 -302.492141)
			(xy 190.305644 -302.541495) (xy 190.305194 -302.549814) (xy 192.544204 -302.549814) (xy 192.548164 -302.50076)
			(xy 192.559941 -302.452976) (xy 192.579232 -302.4077) (xy 192.605535 -302.366104) (xy 192.63817 -302.329267)
			(xy 192.676291 -302.298142) (xy 192.718912 -302.273535) (xy 192.764928 -302.256083) (xy 192.813147 -302.246239)
			(xy 192.862322 -302.244258) (xy 192.911177 -302.25019) (xy 192.958448 -302.263882) (xy 193.00291 -302.28498)
			(xy 193.043413 -302.312936) (xy 193.078906 -302.347028) (xy 193.108471 -302.386372) (xy 193.131342 -302.429949)
			(xy 193.146926 -302.47663) (xy 193.154821 -302.525207) (xy 193.155149 -302.541536) (xy 193.494295 -302.541536)
			(xy 193.499659 -302.492188) (xy 193.512935 -302.444359) (xy 193.533774 -302.399308) (xy 193.561628 -302.358221)
			(xy 193.595761 -302.322181) (xy 193.635274 -302.292138) (xy 193.679128 -302.268884) (xy 193.726166 -302.25303)
			(xy 193.775149 -302.244994) (xy 193.799968 -302.244506) (xy 193.814151 -302.244687) (xy 193.842391 -302.247356)
			(xy 193.856356 -302.24984) (xy 193.870331 -302.251931) (xy 193.898454 -302.249363) (xy 193.924796 -302.239185)
			(xy 193.94734 -302.222177) (xy 193.964359 -302.199642) (xy 193.974551 -302.173305) (xy 193.977134 -302.145183)
			(xy 193.974974 -302.131222) (xy 193.972491 -302.117257) (xy 193.969823 -302.089017) (xy 193.96964 -302.074834)
			(xy 193.970041 -302.050011) (xy 193.978068 -302.001017) (xy 193.993915 -301.953967) (xy 194.017164 -301.910101)
			(xy 194.047205 -301.870574) (xy 194.083244 -301.836428) (xy 194.124333 -301.808562) (xy 194.169388 -301.78771)
			(xy 194.217224 -301.774422) (xy 194.266579 -301.769048) (xy 194.316153 -301.77173) (xy 194.36464 -301.782396)
			(xy 194.410763 -301.800766) (xy 194.453307 -301.826356) (xy 194.49115 -301.858492) (xy 194.523296 -301.896326)
			(xy 194.548897 -301.938863) (xy 194.56728 -301.984981) (xy 194.577959 -302.033466) (xy 194.580208 -302.074834)
			(xy 195.869064 -302.074834) (xy 195.873024 -302.02578) (xy 195.884801 -301.977996) (xy 195.904092 -301.93272)
			(xy 195.930395 -301.891124) (xy 195.96303 -301.854287) (xy 196.001151 -301.823162) (xy 196.043772 -301.798555)
			(xy 196.089788 -301.781103) (xy 196.138007 -301.771259) (xy 196.187182 -301.769278) (xy 196.236037 -301.77521)
			(xy 196.283308 -301.788902) (xy 196.32777 -301.81) (xy 196.368273 -301.837956) (xy 196.403766 -301.872048)
			(xy 196.433331 -301.911392) (xy 196.456202 -301.954969) (xy 196.471786 -302.00165) (xy 196.479681 -302.050227)
			(xy 196.480176 -302.074834) (xy 197.769238 -302.074834) (xy 197.773198 -302.02578) (xy 197.784975 -301.977996)
			(xy 197.804266 -301.93272) (xy 197.830569 -301.891124) (xy 197.863204 -301.854287) (xy 197.901325 -301.823162)
			(xy 197.943946 -301.798555) (xy 197.989962 -301.781103) (xy 198.038181 -301.771259) (xy 198.087356 -301.769278)
			(xy 198.136211 -301.77521) (xy 198.183482 -301.788902) (xy 198.227944 -301.81) (xy 198.268447 -301.837956)
			(xy 198.30394 -301.872048) (xy 198.333505 -301.911392) (xy 198.356376 -301.954969) (xy 198.37196 -302.00165)
			(xy 198.379855 -302.050227) (xy 198.38035 -302.074834) (xy 198.719198 -302.074834) (xy 198.723158 -302.02578)
			(xy 198.734935 -301.977996) (xy 198.754226 -301.93272) (xy 198.780529 -301.891124) (xy 198.813164 -301.854287)
			(xy 198.851285 -301.823162) (xy 198.893906 -301.798555) (xy 198.939922 -301.781103) (xy 198.988141 -301.771259)
			(xy 199.037316 -301.769278) (xy 199.086171 -301.77521) (xy 199.133442 -301.788902) (xy 199.177904 -301.81)
			(xy 199.218407 -301.837956) (xy 199.22015 -301.83963) (xy 202.44765 -301.83963) (xy 202.451721 -301.784008)
			(xy 202.463847 -301.729571) (xy 202.48377 -301.67748) (xy 202.511066 -301.628845) (xy 202.545152 -301.584702)
			(xy 202.585301 -301.545993) (xy 202.630659 -301.513542) (xy 202.680259 -301.488041) (xy 202.733043 -301.470034)
			(xy 202.787886 -301.459904) (xy 202.84362 -301.457867) (xy 202.899057 -301.463967) (xy 202.953014 -301.478073)
			(xy 203.004343 -301.499885) (xy 203.051949 -301.528939) (xy 203.080393 -301.55261) (xy 204.219808 -301.55261)
			(xy 204.223879 -301.496988) (xy 204.236005 -301.442551) (xy 204.255928 -301.39046) (xy 204.283224 -301.341825)
			(xy 204.31731 -301.297682) (xy 204.357459 -301.258973) (xy 204.402817 -301.226522) (xy 204.452417 -301.201021)
			(xy 204.505201 -301.183014) (xy 204.560044 -301.172884) (xy 204.615778 -301.170847) (xy 204.671215 -301.176947)
			(xy 204.725172 -301.191053) (xy 204.776501 -301.212865) (xy 204.824107 -301.241919) (xy 204.866975 -301.277594)
			(xy 204.904192 -301.319131) (xy 204.934965 -301.365644) (xy 204.958637 -301.416141) (xy 204.974705 -301.469548)
			(xy 204.982825 -301.524724) (xy 204.983334 -301.55261) (xy 204.983162 -301.562008) (xy 205.203804 -301.562008)
			(xy 205.207875 -301.506386) (xy 205.220001 -301.451949) (xy 205.239924 -301.399858) (xy 205.26722 -301.351223)
			(xy 205.301306 -301.30708) (xy 205.341455 -301.268371) (xy 205.386813 -301.23592) (xy 205.436413 -301.210419)
			(xy 205.489197 -301.192412) (xy 205.54404 -301.182282) (xy 205.599774 -301.180245) (xy 205.655211 -301.186345)
			(xy 205.709168 -301.200451) (xy 205.760497 -301.222263) (xy 205.808103 -301.251317) (xy 205.850971 -301.286992)
			(xy 205.888188 -301.328529) (xy 205.918961 -301.375042) (xy 205.942633 -301.425539) (xy 205.958701 -301.478946)
			(xy 205.966821 -301.534122) (xy 205.96733 -301.562008) (xy 205.967061 -301.57674) (xy 207.613248 -301.57674)
			(xy 207.617319 -301.521118) (xy 207.629445 -301.466681) (xy 207.649368 -301.41459) (xy 207.676664 -301.365955)
			(xy 207.71075 -301.321812) (xy 207.750899 -301.283103) (xy 207.796257 -301.250652) (xy 207.845857 -301.225151)
			(xy 207.898641 -301.207144) (xy 207.953484 -301.197014) (xy 208.009218 -301.194977) (xy 208.064655 -301.201077)
			(xy 208.118612 -301.215183) (xy 208.169941 -301.236995) (xy 208.217547 -301.266049) (xy 208.260415 -301.301724)
			(xy 208.297632 -301.343261) (xy 208.328405 -301.389774) (xy 208.352077 -301.440271) (xy 208.368145 -301.493678)
			(xy 208.376265 -301.548854) (xy 208.376774 -301.57674) (xy 208.376265 -301.604626) (xy 208.368145 -301.659802)
			(xy 208.352077 -301.713209) (xy 208.328405 -301.763706) (xy 208.297632 -301.810219) (xy 208.260415 -301.851756)
			(xy 208.217547 -301.887431) (xy 208.169941 -301.916485) (xy 208.118612 -301.938297) (xy 208.064655 -301.952403)
			(xy 208.009218 -301.958503) (xy 207.953484 -301.956466) (xy 207.898641 -301.946336) (xy 207.845857 -301.928329)
			(xy 207.796257 -301.902828) (xy 207.750899 -301.870377) (xy 207.71075 -301.831668) (xy 207.676664 -301.787525)
			(xy 207.649368 -301.73889) (xy 207.629445 -301.686799) (xy 207.617319 -301.632362) (xy 207.613248 -301.57674)
			(xy 205.967061 -301.57674) (xy 205.966821 -301.589894) (xy 205.958701 -301.64507) (xy 205.942633 -301.698477)
			(xy 205.918961 -301.748974) (xy 205.888188 -301.795487) (xy 205.850971 -301.837024) (xy 205.808103 -301.872699)
			(xy 205.760497 -301.901753) (xy 205.709168 -301.923565) (xy 205.655211 -301.937671) (xy 205.599774 -301.943771)
			(xy 205.54404 -301.941734) (xy 205.489197 -301.931604) (xy 205.436413 -301.913597) (xy 205.386813 -301.888096)
			(xy 205.341455 -301.855645) (xy 205.301306 -301.816936) (xy 205.26722 -301.772793) (xy 205.239924 -301.724158)
			(xy 205.220001 -301.672067) (xy 205.207875 -301.61763) (xy 205.203804 -301.562008) (xy 204.983162 -301.562008)
			(xy 204.982825 -301.580496) (xy 204.974705 -301.635672) (xy 204.958637 -301.689079) (xy 204.934965 -301.739576)
			(xy 204.904192 -301.786089) (xy 204.866975 -301.827626) (xy 204.824107 -301.863301) (xy 204.776501 -301.892355)
			(xy 204.725172 -301.914167) (xy 204.671215 -301.928273) (xy 204.615778 -301.934373) (xy 204.560044 -301.932336)
			(xy 204.505201 -301.922206) (xy 204.452417 -301.904199) (xy 204.402817 -301.878698) (xy 204.357459 -301.846247)
			(xy 204.31731 -301.807538) (xy 204.283224 -301.763395) (xy 204.255928 -301.71476) (xy 204.236005 -301.662669)
			(xy 204.223879 -301.608232) (xy 204.219808 -301.55261) (xy 203.080393 -301.55261) (xy 203.094817 -301.564614)
			(xy 203.132034 -301.606151) (xy 203.162807 -301.652664) (xy 203.186479 -301.703161) (xy 203.202547 -301.756568)
			(xy 203.210667 -301.811744) (xy 203.211176 -301.83963) (xy 203.210667 -301.867516) (xy 203.202547 -301.922692)
			(xy 203.186479 -301.976099) (xy 203.162807 -302.026596) (xy 203.132034 -302.073109) (xy 203.094817 -302.114646)
			(xy 203.051949 -302.150321) (xy 203.004343 -302.179375) (xy 202.953014 -302.201187) (xy 202.899057 -302.215293)
			(xy 202.84362 -302.221393) (xy 202.787886 -302.219356) (xy 202.733043 -302.209226) (xy 202.680259 -302.191219)
			(xy 202.630659 -302.165718) (xy 202.585301 -302.133267) (xy 202.545152 -302.094558) (xy 202.511066 -302.050415)
			(xy 202.48377 -302.00178) (xy 202.463847 -301.949689) (xy 202.451721 -301.895252) (xy 202.44765 -301.83963)
			(xy 199.22015 -301.83963) (xy 199.2539 -301.872048) (xy 199.283465 -301.911392) (xy 199.306336 -301.954969)
			(xy 199.32192 -302.00165) (xy 199.329815 -302.050227) (xy 199.33031 -302.074834) (xy 199.329815 -302.099441)
			(xy 199.32192 -302.148018) (xy 199.306336 -302.194699) (xy 199.283465 -302.238276) (xy 199.2539 -302.27762)
			(xy 199.218407 -302.311712) (xy 199.177904 -302.339668) (xy 199.133442 -302.360766) (xy 199.086171 -302.374458)
			(xy 199.037316 -302.38039) (xy 198.988141 -302.378409) (xy 198.939922 -302.368565) (xy 198.893906 -302.351113)
			(xy 198.851285 -302.326506) (xy 198.813164 -302.295381) (xy 198.780529 -302.258544) (xy 198.754226 -302.216948)
			(xy 198.734935 -302.171672) (xy 198.723158 -302.123888) (xy 198.719198 -302.074834) (xy 198.38035 -302.074834)
			(xy 198.379855 -302.099441) (xy 198.37196 -302.148018) (xy 198.356376 -302.194699) (xy 198.333505 -302.238276)
			(xy 198.30394 -302.27762) (xy 198.268447 -302.311712) (xy 198.227944 -302.339668) (xy 198.183482 -302.360766)
			(xy 198.136211 -302.374458) (xy 198.087356 -302.38039) (xy 198.038181 -302.378409) (xy 197.989962 -302.368565)
			(xy 197.943946 -302.351113) (xy 197.901325 -302.326506) (xy 197.863204 -302.295381) (xy 197.830569 -302.258544)
			(xy 197.804266 -302.216948) (xy 197.784975 -302.171672) (xy 197.773198 -302.123888) (xy 197.769238 -302.074834)
			(xy 196.480176 -302.074834) (xy 196.479681 -302.099441) (xy 196.471786 -302.148018) (xy 196.456202 -302.194699)
			(xy 196.433331 -302.238276) (xy 196.403766 -302.27762) (xy 196.368273 -302.311712) (xy 196.32777 -302.339668)
			(xy 196.283308 -302.360766) (xy 196.236037 -302.374458) (xy 196.187182 -302.38039) (xy 196.138007 -302.378409)
			(xy 196.089788 -302.368565) (xy 196.043772 -302.351113) (xy 196.001151 -302.326506) (xy 195.96303 -302.295381)
			(xy 195.930395 -302.258544) (xy 195.904092 -302.216948) (xy 195.884801 -302.171672) (xy 195.873024 -302.123888)
			(xy 195.869064 -302.074834) (xy 194.580208 -302.074834) (xy 194.580654 -302.083039) (xy 194.575293 -302.132396)
			(xy 194.562018 -302.180235) (xy 194.541179 -302.225296) (xy 194.513324 -302.266392) (xy 194.479187 -302.30244)
			(xy 194.439668 -302.332491) (xy 194.395808 -302.355753) (xy 194.348763 -302.371613) (xy 194.299771 -302.379652)
			(xy 194.274948 -302.380142) (xy 194.260765 -302.379958) (xy 194.232525 -302.377291) (xy 194.21856 -302.374808)
			(xy 194.204603 -302.372573) (xy 194.176462 -302.375162) (xy 194.150108 -302.385363) (xy 194.127558 -302.402395)
			(xy 194.110537 -302.424954) (xy 194.10035 -302.451314) (xy 194.097776 -302.479456) (xy 194.099942 -302.493426)
			(xy 194.102418 -302.507392) (xy 194.10509 -302.535632) (xy 194.105276 -302.549814) (xy 194.104807 -302.574633)
			(xy 194.096775 -302.623617) (xy 194.080923 -302.670655) (xy 194.060431 -302.709305) (xy 200.909418 -302.709305)
			(xy 200.909418 -302.656007) (xy 200.917361 -302.603303) (xy 200.933071 -302.552373) (xy 200.956197 -302.504352)
			(xy 200.986221 -302.460315) (xy 201.022473 -302.421244) (xy 201.064144 -302.388013) (xy 201.110302 -302.361364)
			(xy 201.159916 -302.341892) (xy 201.211878 -302.330032) (xy 201.265028 -302.326049) (xy 201.318178 -302.330032)
			(xy 201.37014 -302.341892) (xy 201.419754 -302.361364) (xy 201.465912 -302.388013) (xy 201.507583 -302.421244)
			(xy 201.543835 -302.460315) (xy 201.573859 -302.504352) (xy 201.596985 -302.552373) (xy 201.612695 -302.603303)
			(xy 201.620638 -302.656007) (xy 201.621136 -302.682656) (xy 201.620638 -302.709305) (xy 201.612695 -302.762009)
			(xy 201.596985 -302.812939) (xy 201.573859 -302.86096) (xy 201.543835 -302.904997) (xy 201.507583 -302.944068)
			(xy 201.465912 -302.977299) (xy 201.419754 -303.003948) (xy 201.37014 -303.02342) (xy 201.318178 -303.03528)
			(xy 201.265028 -303.039264) (xy 201.211878 -303.03528) (xy 201.159916 -303.02342) (xy 201.110302 -303.003948)
			(xy 201.064144 -302.977299) (xy 201.022473 -302.944068) (xy 200.986221 -302.904997) (xy 200.956197 -302.86096)
			(xy 200.933071 -302.812939) (xy 200.917361 -302.762009) (xy 200.909418 -302.709305) (xy 194.060431 -302.709305)
			(xy 194.057671 -302.71451) (xy 194.027631 -302.754026) (xy 193.991593 -302.788161) (xy 193.950508 -302.816017)
			(xy 193.905458 -302.836859) (xy 193.857629 -302.850138) (xy 193.808282 -302.855505) (xy 193.758717 -302.852818)
			(xy 193.71024 -302.842148) (xy 193.664127 -302.823776) (xy 193.621594 -302.798185) (xy 193.583761 -302.766052)
			(xy 193.551625 -302.728221) (xy 193.526032 -302.685689) (xy 193.507658 -302.639577) (xy 193.496985 -302.591101)
			(xy 193.494295 -302.541536) (xy 193.155149 -302.541536) (xy 193.155316 -302.549814) (xy 193.154821 -302.574421)
			(xy 193.146926 -302.622998) (xy 193.131342 -302.669679) (xy 193.108471 -302.713256) (xy 193.078906 -302.7526)
			(xy 193.043413 -302.786692) (xy 193.00291 -302.814648) (xy 192.958448 -302.835746) (xy 192.911177 -302.849438)
			(xy 192.862322 -302.85537) (xy 192.813147 -302.853389) (xy 192.764928 -302.843545) (xy 192.718912 -302.826093)
			(xy 192.676291 -302.801486) (xy 192.63817 -302.770361) (xy 192.605535 -302.733524) (xy 192.579232 -302.691928)
			(xy 192.559941 -302.646652) (xy 192.548164 -302.598868) (xy 192.544204 -302.549814) (xy 190.305194 -302.549814)
			(xy 190.30296 -302.591069) (xy 190.292291 -302.639556) (xy 190.273918 -302.685677) (xy 190.248326 -302.728219)
			(xy 190.216188 -302.766059) (xy 190.178351 -302.798202) (xy 190.135813 -302.8238) (xy 190.089694 -302.842179)
			(xy 190.041209 -302.852855) (xy 189.991636 -302.855545) (xy 189.94228 -302.85018) (xy 189.894442 -302.836901)
			(xy 189.849383 -302.816058) (xy 189.80829 -302.788199) (xy 189.772245 -302.754059) (xy 189.742199 -302.714538)
			(xy 189.718942 -302.670676) (xy 189.703087 -302.623629) (xy 189.695053 -302.574637) (xy 189.694566 -302.549814)
			(xy 189.694745 -302.535631) (xy 189.697416 -302.507391) (xy 189.6999 -302.493426) (xy 189.702057 -302.479458)
			(xy 189.699484 -302.451325) (xy 189.689298 -302.424975) (xy 189.672279 -302.402426) (xy 189.649731 -302.385406)
			(xy 189.623381 -302.375218) (xy 189.595248 -302.372643) (xy 189.581282 -302.374808) (xy 189.567316 -302.377283)
			(xy 189.539076 -302.379956) (xy 189.524894 -302.380142) (xy 189.500073 -302.379616) (xy 189.451086 -302.371583)
			(xy 189.404043 -302.355731) (xy 189.360185 -302.332478) (xy 189.320666 -302.302434) (xy 189.286529 -302.266394)
			(xy 189.258672 -302.225305) (xy 189.23783 -302.18025) (xy 189.224552 -302.132417) (xy 189.219187 -302.083066)
			(xy 188.880076 -302.083066) (xy 188.879747 -302.099441) (xy 188.871852 -302.148018) (xy 188.856268 -302.194699)
			(xy 188.833397 -302.238276) (xy 188.803832 -302.27762) (xy 188.768339 -302.311712) (xy 188.727836 -302.339668)
			(xy 188.683374 -302.360766) (xy 188.636103 -302.374458) (xy 188.587248 -302.38039) (xy 188.538073 -302.378409)
			(xy 188.489854 -302.368565) (xy 188.443838 -302.351113) (xy 188.401217 -302.326506) (xy 188.363096 -302.295381)
			(xy 188.330461 -302.258544) (xy 188.304158 -302.216948) (xy 188.284867 -302.171672) (xy 188.27309 -302.123888)
			(xy 188.26913 -302.074834) (xy 187.930282 -302.074834) (xy 187.929787 -302.099441) (xy 187.921892 -302.148018)
			(xy 187.906308 -302.194699) (xy 187.883437 -302.238276) (xy 187.853872 -302.27762) (xy 187.818379 -302.311712)
			(xy 187.777876 -302.339668) (xy 187.733414 -302.360766) (xy 187.686143 -302.374458) (xy 187.637288 -302.38039)
			(xy 187.588113 -302.378409) (xy 187.539894 -302.368565) (xy 187.493878 -302.351113) (xy 187.451257 -302.326506)
			(xy 187.413136 -302.295381) (xy 187.380501 -302.258544) (xy 187.354198 -302.216948) (xy 187.334907 -302.171672)
			(xy 187.32313 -302.123888) (xy 187.31917 -302.074834) (xy 186.980322 -302.074834) (xy 186.979827 -302.099441)
			(xy 186.971932 -302.148018) (xy 186.956348 -302.194699) (xy 186.933477 -302.238276) (xy 186.903912 -302.27762)
			(xy 186.868419 -302.311712) (xy 186.827916 -302.339668) (xy 186.783454 -302.360766) (xy 186.736183 -302.374458)
			(xy 186.687328 -302.38039) (xy 186.638153 -302.378409) (xy 186.589934 -302.368565) (xy 186.543918 -302.351113)
			(xy 186.501297 -302.326506) (xy 186.463176 -302.295381) (xy 186.430541 -302.258544) (xy 186.404238 -302.216948)
			(xy 186.384947 -302.171672) (xy 186.37317 -302.123888) (xy 186.36921 -302.074834) (xy 186.055291 -302.074834)
			(xy 186.055291 -302.100789) (xy 186.047159 -302.152127) (xy 186.031096 -302.20156) (xy 186.007496 -302.247872)
			(xy 185.976942 -302.289921) (xy 185.940186 -302.326672) (xy 185.898132 -302.35722) (xy 185.851817 -302.380813)
			(xy 185.802382 -302.39687) (xy 185.751043 -302.404994) (xy 185.725054 -302.405542) (xy 185.7248 -302.405542)
			(xy 185.705898 -302.405253) (xy 185.668343 -302.40092) (xy 185.64987 -302.396906) (xy 185.63844 -302.394112)
			(xy 185.616088 -302.399192) (xy 185.54446 -302.456088) (xy 185.535749 -302.463667) (xy 185.525705 -302.484432)
			(xy 185.525156 -302.495966) (xy 185.525156 -302.603662) (xy 185.525737 -302.614861) (xy 185.535219 -302.635156)
			(xy 185.543444 -302.642778) (xy 185.543952 -302.643286) (xy 185.616088 -302.700436) (xy 185.63844 -302.705516)
			(xy 185.64987 -302.702722) (xy 185.668338 -302.698679) (xy 185.705897 -302.694355) (xy 185.7248 -302.694086)
			(xy 185.725054 -302.694086) (xy 185.751046 -302.694566) (xy 185.802391 -302.702691) (xy 185.851833 -302.71875)
			(xy 185.898153 -302.742346) (xy 185.940212 -302.772898) (xy 185.976973 -302.809653) (xy 186.00753 -302.851708)
			(xy 186.031133 -302.898025) (xy 186.047198 -302.947464) (xy 186.055331 -302.998808) (xy 186.055331 -303.024794)
			(xy 186.36921 -303.024794) (xy 186.37317 -302.97574) (xy 186.384947 -302.927956) (xy 186.404238 -302.88268)
			(xy 186.430541 -302.841084) (xy 186.463176 -302.804247) (xy 186.501297 -302.773122) (xy 186.543918 -302.748515)
			(xy 186.589934 -302.731063) (xy 186.638153 -302.721219) (xy 186.687328 -302.719238) (xy 186.736183 -302.72517)
			(xy 186.783454 -302.738862) (xy 186.827916 -302.75996) (xy 186.868419 -302.787916) (xy 186.903912 -302.822008)
			(xy 186.933477 -302.861352) (xy 186.956348 -302.904929) (xy 186.971932 -302.95161) (xy 186.979827 -303.000187)
			(xy 186.980322 -303.024794) (xy 187.31917 -303.024794) (xy 187.32313 -302.97574) (xy 187.334907 -302.927956)
			(xy 187.354198 -302.88268) (xy 187.380501 -302.841084) (xy 187.413136 -302.804247) (xy 187.451257 -302.773122)
			(xy 187.493878 -302.748515) (xy 187.539894 -302.731063) (xy 187.588113 -302.721219) (xy 187.637288 -302.719238)
			(xy 187.686143 -302.72517) (xy 187.733414 -302.738862) (xy 187.777876 -302.75996) (xy 187.818379 -302.787916)
			(xy 187.853872 -302.822008) (xy 187.883437 -302.861352) (xy 187.906308 -302.904929) (xy 187.921892 -302.95161)
			(xy 187.929787 -303.000187) (xy 187.930282 -303.024794) (xy 188.26913 -303.024794) (xy 188.27309 -302.97574)
			(xy 188.284867 -302.927956) (xy 188.304158 -302.88268) (xy 188.330461 -302.841084) (xy 188.363096 -302.804247)
			(xy 188.401217 -302.773122) (xy 188.443838 -302.748515) (xy 188.489854 -302.731063) (xy 188.538073 -302.721219)
			(xy 188.587248 -302.719238) (xy 188.636103 -302.72517) (xy 188.683374 -302.738862) (xy 188.727836 -302.75996)
			(xy 188.768339 -302.787916) (xy 188.803832 -302.822008) (xy 188.833397 -302.861352) (xy 188.856268 -302.904929)
			(xy 188.871852 -302.95161) (xy 188.879747 -303.000187) (xy 188.880242 -303.024794) (xy 188.879747 -303.049401)
			(xy 188.871852 -303.097978) (xy 188.856268 -303.144659) (xy 188.833397 -303.188236) (xy 188.803832 -303.22758)
			(xy 188.768339 -303.261672) (xy 188.727836 -303.289628) (xy 188.683374 -303.310726) (xy 188.636103 -303.324418)
			(xy 188.587248 -303.33035) (xy 188.538073 -303.328369) (xy 188.489854 -303.318525) (xy 188.443838 -303.301073)
			(xy 188.401217 -303.276466) (xy 188.363096 -303.245341) (xy 188.330461 -303.208504) (xy 188.304158 -303.166908)
			(xy 188.284867 -303.121632) (xy 188.27309 -303.073848) (xy 188.26913 -303.024794) (xy 187.930282 -303.024794)
			(xy 187.929787 -303.049401) (xy 187.921892 -303.097978) (xy 187.906308 -303.144659) (xy 187.883437 -303.188236)
			(xy 187.853872 -303.22758) (xy 187.818379 -303.261672) (xy 187.777876 -303.289628) (xy 187.733414 -303.310726)
			(xy 187.686143 -303.324418) (xy 187.637288 -303.33035) (xy 187.588113 -303.328369) (xy 187.539894 -303.318525)
			(xy 187.493878 -303.301073) (xy 187.451257 -303.276466) (xy 187.413136 -303.245341) (xy 187.380501 -303.208504)
			(xy 187.354198 -303.166908) (xy 187.334907 -303.121632) (xy 187.32313 -303.073848) (xy 187.31917 -303.024794)
			(xy 186.980322 -303.024794) (xy 186.979827 -303.049401) (xy 186.971932 -303.097978) (xy 186.956348 -303.144659)
			(xy 186.933477 -303.188236) (xy 186.903912 -303.22758) (xy 186.868419 -303.261672) (xy 186.827916 -303.289628)
			(xy 186.783454 -303.310726) (xy 186.736183 -303.324418) (xy 186.687328 -303.33035) (xy 186.638153 -303.328369)
			(xy 186.589934 -303.318525) (xy 186.543918 -303.301073) (xy 186.501297 -303.276466) (xy 186.463176 -303.245341)
			(xy 186.430541 -303.208504) (xy 186.404238 -303.166908) (xy 186.384947 -303.121632) (xy 186.37317 -303.073848)
			(xy 186.36921 -303.024794) (xy 186.055331 -303.024794) (xy 186.055331 -303.050792) (xy 186.047198 -303.102136)
			(xy 186.031133 -303.151575) (xy 186.00753 -303.197892) (xy 185.976973 -303.239947) (xy 185.940212 -303.276702)
			(xy 185.898153 -303.307254) (xy 185.851833 -303.33085) (xy 185.802391 -303.346909) (xy 185.751046 -303.355034)
			(xy 185.725054 -303.355502) (xy 185.7248 -303.355502) (xy 185.705898 -303.355213) (xy 185.668343 -303.350879)
			(xy 185.64987 -303.346866) (xy 185.63844 -303.344072) (xy 185.616088 -303.349152) (xy 185.54446 -303.406048)
			(xy 185.535743 -303.413624) (xy 185.525682 -303.434389) (xy 185.525156 -303.445926) (xy 185.525156 -303.553622)
			(xy 185.525749 -303.564815) (xy 185.535246 -303.585091) (xy 185.543444 -303.592738) (xy 185.543952 -303.593246)
			(xy 185.616088 -303.650396) (xy 185.63844 -303.655476) (xy 185.64987 -303.652682) (xy 185.668338 -303.648639)
			(xy 185.705897 -303.644316) (xy 185.7248 -303.644046) (xy 185.725054 -303.644046) (xy 185.751049 -303.644526)
			(xy 185.802401 -303.652652) (xy 185.851848 -303.668713) (xy 185.898174 -303.692311) (xy 185.940238 -303.722867)
			(xy 185.977003 -303.759627) (xy 186.007564 -303.801687) (xy 186.031169 -303.848009) (xy 186.047237 -303.897455)
			(xy 186.055371 -303.948805) (xy 186.055371 -303.974754) (xy 186.36921 -303.974754) (xy 186.37317 -303.9257)
			(xy 186.384947 -303.877916) (xy 186.404238 -303.83264) (xy 186.430541 -303.791044) (xy 186.463176 -303.754207)
			(xy 186.501297 -303.723082) (xy 186.543918 -303.698475) (xy 186.589934 -303.681023) (xy 186.638153 -303.671179)
			(xy 186.687328 -303.669198) (xy 186.736183 -303.67513) (xy 186.783454 -303.688822) (xy 186.827916 -303.70992)
			(xy 186.868419 -303.737876) (xy 186.903912 -303.771968) (xy 186.933477 -303.811312) (xy 186.956348 -303.854889)
			(xy 186.971932 -303.90157) (xy 186.979827 -303.950147) (xy 186.980322 -303.974754) (xy 187.31917 -303.974754)
			(xy 187.32313 -303.9257) (xy 187.334907 -303.877916) (xy 187.354198 -303.83264) (xy 187.380501 -303.791044)
			(xy 187.413136 -303.754207) (xy 187.451257 -303.723082) (xy 187.493878 -303.698475) (xy 187.539894 -303.681023)
			(xy 187.588113 -303.671179) (xy 187.637288 -303.669198) (xy 187.686143 -303.67513) (xy 187.733414 -303.688822)
			(xy 187.777876 -303.70992) (xy 187.818379 -303.737876) (xy 187.853872 -303.771968) (xy 187.883437 -303.811312)
			(xy 187.906308 -303.854889) (xy 187.921892 -303.90157) (xy 187.929787 -303.950147) (xy 187.930282 -303.974754)
			(xy 188.26913 -303.974754) (xy 188.27309 -303.9257) (xy 188.284867 -303.877916) (xy 188.304158 -303.83264)
			(xy 188.330461 -303.791044) (xy 188.363096 -303.754207) (xy 188.401217 -303.723082) (xy 188.443838 -303.698475)
			(xy 188.489854 -303.681023) (xy 188.538073 -303.671179) (xy 188.587248 -303.669198) (xy 188.636103 -303.67513)
			(xy 188.683374 -303.688822) (xy 188.727836 -303.70992) (xy 188.768339 -303.737876) (xy 188.803832 -303.771968)
			(xy 188.833397 -303.811312) (xy 188.856268 -303.854889) (xy 188.871852 -303.90157) (xy 188.879747 -303.950147)
			(xy 188.880242 -303.974754) (xy 188.879747 -303.999361) (xy 188.871852 -304.047938) (xy 188.856268 -304.094619)
			(xy 188.833397 -304.138196) (xy 188.803832 -304.17754) (xy 188.768339 -304.211632) (xy 188.727836 -304.239588)
			(xy 188.683374 -304.260686) (xy 188.636103 -304.274378) (xy 188.587248 -304.28031) (xy 188.538073 -304.278329)
			(xy 188.489854 -304.268485) (xy 188.443838 -304.251033) (xy 188.401217 -304.226426) (xy 188.363096 -304.195301)
			(xy 188.330461 -304.158464) (xy 188.304158 -304.116868) (xy 188.284867 -304.071592) (xy 188.27309 -304.023808)
			(xy 188.26913 -303.974754) (xy 187.930282 -303.974754) (xy 187.929787 -303.999361) (xy 187.921892 -304.047938)
			(xy 187.906308 -304.094619) (xy 187.883437 -304.138196) (xy 187.853872 -304.17754) (xy 187.818379 -304.211632)
			(xy 187.777876 -304.239588) (xy 187.733414 -304.260686) (xy 187.686143 -304.274378) (xy 187.637288 -304.28031)
			(xy 187.588113 -304.278329) (xy 187.539894 -304.268485) (xy 187.493878 -304.251033) (xy 187.451257 -304.226426)
			(xy 187.413136 -304.195301) (xy 187.380501 -304.158464) (xy 187.354198 -304.116868) (xy 187.334907 -304.071592)
			(xy 187.32313 -304.023808) (xy 187.31917 -303.974754) (xy 186.980322 -303.974754) (xy 186.979827 -303.999361)
			(xy 186.971932 -304.047938) (xy 186.956348 -304.094619) (xy 186.933477 -304.138196) (xy 186.903912 -304.17754)
			(xy 186.868419 -304.211632) (xy 186.827916 -304.239588) (xy 186.783454 -304.260686) (xy 186.736183 -304.274378)
			(xy 186.687328 -304.28031) (xy 186.638153 -304.278329) (xy 186.589934 -304.268485) (xy 186.543918 -304.251033)
			(xy 186.501297 -304.226426) (xy 186.463176 -304.195301) (xy 186.430541 -304.158464) (xy 186.404238 -304.116868)
			(xy 186.384947 -304.071592) (xy 186.37317 -304.023808) (xy 186.36921 -303.974754) (xy 186.055371 -303.974754)
			(xy 186.055371 -304.000795) (xy 186.047237 -304.052145) (xy 186.031169 -304.101591) (xy 186.007564 -304.147913)
			(xy 185.977003 -304.189973) (xy 185.940238 -304.226733) (xy 185.898174 -304.257289) (xy 185.851848 -304.280887)
			(xy 185.8024 -304.296948) (xy 185.751049 -304.305074) (xy 185.725054 -304.305462) (xy 185.698045 -304.30493)
			(xy 185.644746 -304.296156) (xy 185.593582 -304.278833) (xy 185.545915 -304.253422) (xy 185.503014 -304.220599)
			(xy 185.46602 -304.181238) (xy 185.435918 -304.136386) (xy 185.413509 -304.087237) (xy 185.399389 -304.035098)
			(xy 185.396124 -304.008282) (xy 185.3946 -303.99355) (xy 185.376312 -303.970436) (xy 185.314336 -303.948846)
			(xy 185.275728 -303.935384) (xy 185.266245 -303.932554) (xy 185.246502 -303.933593) (xy 185.237374 -303.937416)
			(xy 185.229246 -303.941226) (xy 185.092848 -304.077624) (xy 185.088784 -304.087784) (xy 185.08853 -304.088292)
			(xy 185.084974 -304.097182) (xy 185.07416 -304.121737) (xy 185.045775 -304.167264) (xy 185.010417 -304.207616)
			(xy 184.969013 -304.241735) (xy 184.922648 -304.268728) (xy 184.897776 -304.278792) (xy 184.887616 -304.282856)
			(xy 184.751472 -304.419) (xy 184.748932 -304.421794) (xy 184.745122 -304.426112) (xy 184.739658 -304.433096)
			(xy 184.733421 -304.449681) (xy 184.733189 -304.467398) (xy 184.735724 -304.475896) (xy 184.735978 -304.47615)
			(xy 184.756298 -304.533046) (xy 184.756298 -304.533554) (xy 184.766458 -304.562256) (xy 184.767474 -304.56505)
			(xy 184.77137 -304.573256) (xy 184.783853 -304.586437) (xy 184.800142 -304.594449) (xy 184.80913 -304.595784)
			(xy 184.835895 -304.599113) (xy 184.887915 -304.613341) (xy 184.936938 -304.635822) (xy 184.981663 -304.665959)
			(xy 185.020906 -304.702954) (xy 185.053625 -304.745826) (xy 185.078954 -304.793439) (xy 185.096222 -304.844531)
			(xy 185.104971 -304.897748) (xy 185.105548 -304.924714) (xy 185.41925 -304.924714) (xy 185.42321 -304.87566)
			(xy 185.434987 -304.827876) (xy 185.454278 -304.7826) (xy 185.480581 -304.741004) (xy 185.513216 -304.704167)
			(xy 185.551337 -304.673042) (xy 185.593958 -304.648435) (xy 185.639974 -304.630983) (xy 185.688193 -304.621139)
			(xy 185.737368 -304.619158) (xy 185.786223 -304.62509) (xy 185.833494 -304.638782) (xy 185.877956 -304.65988)
			(xy 185.918459 -304.687836) (xy 185.953952 -304.721928) (xy 185.983517 -304.761272) (xy 186.006388 -304.804849)
			(xy 186.021972 -304.85153) (xy 186.029867 -304.900107) (xy 186.030362 -304.924714) (xy 186.36921 -304.924714)
			(xy 186.37317 -304.87566) (xy 186.384947 -304.827876) (xy 186.404238 -304.7826) (xy 186.430541 -304.741004)
			(xy 186.463176 -304.704167) (xy 186.501297 -304.673042) (xy 186.543918 -304.648435) (xy 186.589934 -304.630983)
			(xy 186.638153 -304.621139) (xy 186.687328 -304.619158) (xy 186.736183 -304.62509) (xy 186.783454 -304.638782)
			(xy 186.827916 -304.65988) (xy 186.868419 -304.687836) (xy 186.903912 -304.721928) (xy 186.933477 -304.761272)
			(xy 186.956348 -304.804849) (xy 186.971932 -304.85153) (xy 186.979827 -304.900107) (xy 186.980322 -304.924714)
			(xy 187.31917 -304.924714) (xy 187.32313 -304.87566) (xy 187.334907 -304.827876) (xy 187.354198 -304.7826)
			(xy 187.380501 -304.741004) (xy 187.413136 -304.704167) (xy 187.451257 -304.673042) (xy 187.493878 -304.648435)
			(xy 187.539894 -304.630983) (xy 187.588113 -304.621139) (xy 187.637288 -304.619158) (xy 187.686143 -304.62509)
			(xy 187.733414 -304.638782) (xy 187.777876 -304.65988) (xy 187.818379 -304.687836) (xy 187.853872 -304.721928)
			(xy 187.883437 -304.761272) (xy 187.906308 -304.804849) (xy 187.921892 -304.85153) (xy 187.929787 -304.900107)
			(xy 187.930282 -304.924714) (xy 188.26913 -304.924714) (xy 188.27309 -304.87566) (xy 188.284867 -304.827876)
			(xy 188.304158 -304.7826) (xy 188.330461 -304.741004) (xy 188.363096 -304.704167) (xy 188.401217 -304.673042)
			(xy 188.443838 -304.648435) (xy 188.489854 -304.630983) (xy 188.538073 -304.621139) (xy 188.587248 -304.619158)
			(xy 188.636103 -304.62509) (xy 188.683374 -304.638782) (xy 188.727836 -304.65988) (xy 188.768339 -304.687836)
			(xy 188.803832 -304.721928) (xy 188.833397 -304.761272) (xy 188.856268 -304.804849) (xy 188.871852 -304.85153)
			(xy 188.879747 -304.900107) (xy 188.880242 -304.924714) (xy 188.879747 -304.949321) (xy 188.871852 -304.997898)
			(xy 188.856268 -305.044579) (xy 188.833397 -305.088156) (xy 188.803832 -305.1275) (xy 188.768339 -305.161592)
			(xy 188.727836 -305.189548) (xy 188.683374 -305.210646) (xy 188.636103 -305.224338) (xy 188.587248 -305.23027)
			(xy 188.538073 -305.228289) (xy 188.489854 -305.218445) (xy 188.443838 -305.200993) (xy 188.401217 -305.176386)
			(xy 188.363096 -305.145261) (xy 188.330461 -305.108424) (xy 188.304158 -305.066828) (xy 188.284867 -305.021552)
			(xy 188.27309 -304.973768) (xy 188.26913 -304.924714) (xy 187.930282 -304.924714) (xy 187.929787 -304.949321)
			(xy 187.921892 -304.997898) (xy 187.906308 -305.044579) (xy 187.883437 -305.088156) (xy 187.853872 -305.1275)
			(xy 187.818379 -305.161592) (xy 187.777876 -305.189548) (xy 187.733414 -305.210646) (xy 187.686143 -305.224338)
			(xy 187.637288 -305.23027) (xy 187.588113 -305.228289) (xy 187.539894 -305.218445) (xy 187.493878 -305.200993)
			(xy 187.451257 -305.176386) (xy 187.413136 -305.145261) (xy 187.380501 -305.108424) (xy 187.354198 -305.066828)
			(xy 187.334907 -305.021552) (xy 187.32313 -304.973768) (xy 187.31917 -304.924714) (xy 186.980322 -304.924714)
			(xy 186.979827 -304.949321) (xy 186.971932 -304.997898) (xy 186.956348 -305.044579) (xy 186.933477 -305.088156)
			(xy 186.903912 -305.1275) (xy 186.868419 -305.161592) (xy 186.827916 -305.189548) (xy 186.783454 -305.210646)
			(xy 186.736183 -305.224338) (xy 186.687328 -305.23027) (xy 186.638153 -305.228289) (xy 186.589934 -305.218445)
			(xy 186.543918 -305.200993) (xy 186.501297 -305.176386) (xy 186.463176 -305.145261) (xy 186.430541 -305.108424)
			(xy 186.404238 -305.066828) (xy 186.384947 -305.021552) (xy 186.37317 -304.973768) (xy 186.36921 -304.924714)
			(xy 186.030362 -304.924714) (xy 186.029867 -304.949321) (xy 186.021972 -304.997898) (xy 186.006388 -305.044579)
			(xy 185.983517 -305.088156) (xy 185.953952 -305.1275) (xy 185.918459 -305.161592) (xy 185.877956 -305.189548)
			(xy 185.833494 -305.210646) (xy 185.786223 -305.224338) (xy 185.737368 -305.23027) (xy 185.688193 -305.228289)
			(xy 185.639974 -305.218445) (xy 185.593958 -305.200993) (xy 185.551337 -305.176386) (xy 185.513216 -305.145261)
			(xy 185.480581 -305.108424) (xy 185.454278 -305.066828) (xy 185.434987 -305.021552) (xy 185.42321 -304.973768)
			(xy 185.41925 -304.924714) (xy 185.105548 -304.924714) (xy 185.105038 -304.950701) (xy 185.096908 -305.002036)
			(xy 185.080847 -305.051466) (xy 185.057251 -305.097776) (xy 185.026701 -305.139824) (xy 184.98995 -305.176575)
			(xy 184.947902 -305.207125) (xy 184.901592 -305.230721) (xy 184.852162 -305.246782) (xy 184.800827 -305.254912)
			(xy 184.748853 -305.254912) (xy 184.697518 -305.246782) (xy 184.648088 -305.230721) (xy 184.601778 -305.207125)
			(xy 184.55973 -305.176575) (xy 184.522979 -305.139824) (xy 184.492429 -305.097776) (xy 184.468833 -305.051466)
			(xy 184.452772 -305.002036) (xy 184.444642 -304.950701) (xy 184.444132 -304.924714) (xy 184.44458 -304.899919)
			(xy 184.451991 -304.850886) (xy 184.466635 -304.803508) (xy 184.488183 -304.758844) (xy 184.516154 -304.717896)
			(xy 184.549921 -304.681578) (xy 184.588728 -304.650705) (xy 184.609994 -304.637948) (xy 184.615836 -304.634646)
			(xy 184.625234 -304.625248) (xy 184.638188 -304.602896) (xy 184.642149 -304.595142) (xy 184.645148 -304.578002)
			(xy 184.64403 -304.569368) (xy 184.64276 -304.561748) (xy 184.640372 -304.550738) (xy 184.627633 -304.532191)
			(xy 184.6082 -304.520849) (xy 184.59704 -304.51933) (xy 184.592722 -304.519076) (xy 184.556146 -304.519076)
			(xy 184.546271 -304.519542) (xy 184.52798 -304.526992) (xy 184.520586 -304.533554) (xy 184.493916 -304.559716)
			(xy 184.493662 -304.55997) (xy 184.486316 -304.566778) (xy 184.467853 -304.574501) (xy 184.457848 -304.574956)
			(xy 166.62273 -304.574956) (xy 166.612767 -304.575442) (xy 166.59434 -304.583026) (xy 166.586916 -304.589688)
			(xy 166.156132 -305.020472) (xy 166.149293 -305.027873) (xy 166.14158 -305.046471) (xy 166.141146 -305.05654)
			(xy 166.141146 -305.874928) (xy 166.419288 -305.874928) (xy 166.423248 -305.825874) (xy 166.435025 -305.77809)
			(xy 166.454316 -305.732814) (xy 166.480619 -305.691218) (xy 166.513254 -305.654381) (xy 166.551375 -305.623256)
			(xy 166.593996 -305.598649) (xy 166.640012 -305.581197) (xy 166.688231 -305.571353) (xy 166.737406 -305.569372)
			(xy 166.786261 -305.575304) (xy 166.833532 -305.588996) (xy 166.877994 -305.610094) (xy 166.918497 -305.63805)
			(xy 166.95399 -305.672142) (xy 166.983555 -305.711486) (xy 167.006426 -305.755063) (xy 167.02201 -305.801744)
			(xy 167.029905 -305.850321) (xy 167.0304 -305.874928) (xy 167.369248 -305.874928) (xy 167.373208 -305.825874)
			(xy 167.384985 -305.77809) (xy 167.404276 -305.732814) (xy 167.430579 -305.691218) (xy 167.463214 -305.654381)
			(xy 167.501335 -305.623256) (xy 167.543956 -305.598649) (xy 167.589972 -305.581197) (xy 167.638191 -305.571353)
			(xy 167.687366 -305.569372) (xy 167.736221 -305.575304) (xy 167.783492 -305.588996) (xy 167.827954 -305.610094)
			(xy 167.868457 -305.63805) (xy 167.90395 -305.672142) (xy 167.933515 -305.711486) (xy 167.956386 -305.755063)
			(xy 167.97197 -305.801744) (xy 167.979865 -305.850321) (xy 167.98036 -305.874928) (xy 168.319208 -305.874928)
			(xy 168.323168 -305.825874) (xy 168.334945 -305.77809) (xy 168.354236 -305.732814) (xy 168.380539 -305.691218)
			(xy 168.413174 -305.654381) (xy 168.451295 -305.623256) (xy 168.493916 -305.598649) (xy 168.539932 -305.581197)
			(xy 168.588151 -305.571353) (xy 168.637326 -305.569372) (xy 168.686181 -305.575304) (xy 168.733452 -305.588996)
			(xy 168.777914 -305.610094) (xy 168.818417 -305.63805) (xy 168.85391 -305.672142) (xy 168.883475 -305.711486)
			(xy 168.906346 -305.755063) (xy 168.92193 -305.801744) (xy 168.929825 -305.850321) (xy 168.93032 -305.874928)
			(xy 169.269168 -305.874928) (xy 169.273128 -305.825874) (xy 169.284905 -305.77809) (xy 169.304196 -305.732814)
			(xy 169.330499 -305.691218) (xy 169.363134 -305.654381) (xy 169.401255 -305.623256) (xy 169.443876 -305.598649)
			(xy 169.489892 -305.581197) (xy 169.538111 -305.571353) (xy 169.587286 -305.569372) (xy 169.636141 -305.575304)
			(xy 169.683412 -305.588996) (xy 169.727874 -305.610094) (xy 169.768377 -305.63805) (xy 169.80387 -305.672142)
			(xy 169.833435 -305.711486) (xy 169.856306 -305.755063) (xy 169.87189 -305.801744) (xy 169.879785 -305.850321)
			(xy 169.88028 -305.874928) (xy 170.219128 -305.874928) (xy 170.223088 -305.825874) (xy 170.234865 -305.77809)
			(xy 170.254156 -305.732814) (xy 170.280459 -305.691218) (xy 170.313094 -305.654381) (xy 170.351215 -305.623256)
			(xy 170.393836 -305.598649) (xy 170.439852 -305.581197) (xy 170.488071 -305.571353) (xy 170.537246 -305.569372)
			(xy 170.586101 -305.575304) (xy 170.633372 -305.588996) (xy 170.677834 -305.610094) (xy 170.718337 -305.63805)
			(xy 170.75383 -305.672142) (xy 170.783395 -305.711486) (xy 170.806266 -305.755063) (xy 170.82185 -305.801744)
			(xy 170.829745 -305.850321) (xy 170.83024 -305.874928) (xy 171.169088 -305.874928) (xy 171.173048 -305.825874)
			(xy 171.184825 -305.77809) (xy 171.204116 -305.732814) (xy 171.230419 -305.691218) (xy 171.263054 -305.654381)
			(xy 171.301175 -305.623256) (xy 171.343796 -305.598649) (xy 171.389812 -305.581197) (xy 171.438031 -305.571353)
			(xy 171.487206 -305.569372) (xy 171.536061 -305.575304) (xy 171.583332 -305.588996) (xy 171.627794 -305.610094)
			(xy 171.668297 -305.63805) (xy 171.70379 -305.672142) (xy 171.733355 -305.711486) (xy 171.756226 -305.755063)
			(xy 171.77181 -305.801744) (xy 171.779705 -305.850321) (xy 171.7802 -305.874928) (xy 172.119048 -305.874928)
			(xy 172.123008 -305.825874) (xy 172.134785 -305.77809) (xy 172.154076 -305.732814) (xy 172.180379 -305.691218)
			(xy 172.213014 -305.654381) (xy 172.251135 -305.623256) (xy 172.293756 -305.598649) (xy 172.339772 -305.581197)
			(xy 172.387991 -305.571353) (xy 172.437166 -305.569372) (xy 172.486021 -305.575304) (xy 172.533292 -305.588996)
			(xy 172.577754 -305.610094) (xy 172.618257 -305.63805) (xy 172.65375 -305.672142) (xy 172.683315 -305.711486)
			(xy 172.706186 -305.755063) (xy 172.72177 -305.801744) (xy 172.729665 -305.850321) (xy 172.73016 -305.874928)
			(xy 173.069262 -305.874928) (xy 173.073222 -305.825874) (xy 173.084999 -305.77809) (xy 173.10429 -305.732814)
			(xy 173.130593 -305.691218) (xy 173.163228 -305.654381) (xy 173.201349 -305.623256) (xy 173.24397 -305.598649)
			(xy 173.289986 -305.581197) (xy 173.338205 -305.571353) (xy 173.38738 -305.569372) (xy 173.436235 -305.575304)
			(xy 173.483506 -305.588996) (xy 173.527968 -305.610094) (xy 173.568471 -305.63805) (xy 173.603964 -305.672142)
			(xy 173.633529 -305.711486) (xy 173.6564 -305.755063) (xy 173.671984 -305.801744) (xy 173.679879 -305.850321)
			(xy 173.680374 -305.874928) (xy 174.019222 -305.874928) (xy 174.023182 -305.825874) (xy 174.034959 -305.77809)
			(xy 174.05425 -305.732814) (xy 174.080553 -305.691218) (xy 174.113188 -305.654381) (xy 174.151309 -305.623256)
			(xy 174.19393 -305.598649) (xy 174.239946 -305.581197) (xy 174.288165 -305.571353) (xy 174.33734 -305.569372)
			(xy 174.386195 -305.575304) (xy 174.433466 -305.588996) (xy 174.477928 -305.610094) (xy 174.518431 -305.63805)
			(xy 174.553924 -305.672142) (xy 174.583489 -305.711486) (xy 174.60636 -305.755063) (xy 174.621944 -305.801744)
			(xy 174.629839 -305.850321) (xy 174.630334 -305.874928) (xy 175.919142 -305.874928) (xy 175.923102 -305.825874)
			(xy 175.934879 -305.77809) (xy 175.95417 -305.732814) (xy 175.980473 -305.691218) (xy 176.013108 -305.654381)
			(xy 176.051229 -305.623256) (xy 176.09385 -305.598649) (xy 176.139866 -305.581197) (xy 176.188085 -305.571353)
			(xy 176.23726 -305.569372) (xy 176.286115 -305.575304) (xy 176.333386 -305.588996) (xy 176.377848 -305.610094)
			(xy 176.418351 -305.63805) (xy 176.453844 -305.672142) (xy 176.483409 -305.711486) (xy 176.50628 -305.755063)
			(xy 176.521864 -305.801744) (xy 176.529759 -305.850321) (xy 176.530254 -305.874928) (xy 176.869102 -305.874928)
			(xy 176.873062 -305.825874) (xy 176.884839 -305.77809) (xy 176.90413 -305.732814) (xy 176.930433 -305.691218)
			(xy 176.963068 -305.654381) (xy 177.001189 -305.623256) (xy 177.04381 -305.598649) (xy 177.089826 -305.581197)
			(xy 177.138045 -305.571353) (xy 177.18722 -305.569372) (xy 177.236075 -305.575304) (xy 177.283346 -305.588996)
			(xy 177.327808 -305.610094) (xy 177.368311 -305.63805) (xy 177.403804 -305.672142) (xy 177.433369 -305.711486)
			(xy 177.45624 -305.755063) (xy 177.471824 -305.801744) (xy 177.479719 -305.850321) (xy 177.480214 -305.874928)
			(xy 177.819062 -305.874928) (xy 177.823022 -305.825874) (xy 177.834799 -305.77809) (xy 177.85409 -305.732814)
			(xy 177.880393 -305.691218) (xy 177.913028 -305.654381) (xy 177.951149 -305.623256) (xy 177.99377 -305.598649)
			(xy 178.039786 -305.581197) (xy 178.088005 -305.571353) (xy 178.13718 -305.569372) (xy 178.186035 -305.575304)
			(xy 178.233306 -305.588996) (xy 178.277768 -305.610094) (xy 178.318271 -305.63805) (xy 178.353764 -305.672142)
			(xy 178.383329 -305.711486) (xy 178.4062 -305.755063) (xy 178.421784 -305.801744) (xy 178.429679 -305.850321)
			(xy 178.430174 -305.874928) (xy 178.769276 -305.874928) (xy 178.773236 -305.825874) (xy 178.785013 -305.77809)
			(xy 178.804304 -305.732814) (xy 178.830607 -305.691218) (xy 178.863242 -305.654381) (xy 178.901363 -305.623256)
			(xy 178.943984 -305.598649) (xy 178.99 -305.581197) (xy 179.038219 -305.571353) (xy 179.087394 -305.569372)
			(xy 179.136249 -305.575304) (xy 179.18352 -305.588996) (xy 179.227982 -305.610094) (xy 179.268485 -305.63805)
			(xy 179.303978 -305.672142) (xy 179.333543 -305.711486) (xy 179.356414 -305.755063) (xy 179.371998 -305.801744)
			(xy 179.379893 -305.850321) (xy 179.380388 -305.874928) (xy 179.719236 -305.874928) (xy 179.723196 -305.825874)
			(xy 179.734973 -305.77809) (xy 179.754264 -305.732814) (xy 179.780567 -305.691218) (xy 179.813202 -305.654381)
			(xy 179.851323 -305.623256) (xy 179.893944 -305.598649) (xy 179.93996 -305.581197) (xy 179.988179 -305.571353)
			(xy 180.037354 -305.569372) (xy 180.086209 -305.575304) (xy 180.13348 -305.588996) (xy 180.177942 -305.610094)
			(xy 180.218445 -305.63805) (xy 180.253938 -305.672142) (xy 180.283503 -305.711486) (xy 180.306374 -305.755063)
			(xy 180.321958 -305.801744) (xy 180.329853 -305.850321) (xy 180.330348 -305.874928) (xy 180.669196 -305.874928)
			(xy 180.673156 -305.825874) (xy 180.684933 -305.77809) (xy 180.704224 -305.732814) (xy 180.730527 -305.691218)
			(xy 180.763162 -305.654381) (xy 180.801283 -305.623256) (xy 180.843904 -305.598649) (xy 180.88992 -305.581197)
			(xy 180.938139 -305.571353) (xy 180.987314 -305.569372) (xy 181.036169 -305.575304) (xy 181.08344 -305.588996)
			(xy 181.127902 -305.610094) (xy 181.168405 -305.63805) (xy 181.203898 -305.672142) (xy 181.233463 -305.711486)
			(xy 181.256334 -305.755063) (xy 181.271918 -305.801744) (xy 181.279813 -305.850321) (xy 181.280308 -305.874928)
			(xy 181.619156 -305.874928) (xy 181.623116 -305.825874) (xy 181.634893 -305.77809) (xy 181.654184 -305.732814)
			(xy 181.680487 -305.691218) (xy 181.713122 -305.654381) (xy 181.751243 -305.623256) (xy 181.793864 -305.598649)
			(xy 181.83988 -305.581197) (xy 181.888099 -305.571353) (xy 181.937274 -305.569372) (xy 181.986129 -305.575304)
			(xy 182.0334 -305.588996) (xy 182.077862 -305.610094) (xy 182.118365 -305.63805) (xy 182.153858 -305.672142)
			(xy 182.183423 -305.711486) (xy 182.206294 -305.755063) (xy 182.221878 -305.801744) (xy 182.229773 -305.850321)
			(xy 182.230268 -305.874928) (xy 182.569116 -305.874928) (xy 182.573076 -305.825874) (xy 182.584853 -305.77809)
			(xy 182.604144 -305.732814) (xy 182.630447 -305.691218) (xy 182.663082 -305.654381) (xy 182.701203 -305.623256)
			(xy 182.743824 -305.598649) (xy 182.78984 -305.581197) (xy 182.838059 -305.571353) (xy 182.887234 -305.569372)
			(xy 182.936089 -305.575304) (xy 182.98336 -305.588996) (xy 183.027822 -305.610094) (xy 183.068325 -305.63805)
			(xy 183.103818 -305.672142) (xy 183.133383 -305.711486) (xy 183.156254 -305.755063) (xy 183.171838 -305.801744)
			(xy 183.179733 -305.850321) (xy 183.180228 -305.874928) (xy 183.519076 -305.874928) (xy 183.523036 -305.825874)
			(xy 183.534813 -305.77809) (xy 183.554104 -305.732814) (xy 183.580407 -305.691218) (xy 183.613042 -305.654381)
			(xy 183.651163 -305.623256) (xy 183.693784 -305.598649) (xy 183.7398 -305.581197) (xy 183.788019 -305.571353)
			(xy 183.837194 -305.569372) (xy 183.886049 -305.575304) (xy 183.93332 -305.588996) (xy 183.977782 -305.610094)
			(xy 184.018285 -305.63805) (xy 184.053778 -305.672142) (xy 184.083343 -305.711486) (xy 184.106214 -305.755063)
			(xy 184.121798 -305.801744) (xy 184.129693 -305.850321) (xy 184.130188 -305.874928) (xy 184.469036 -305.874928)
			(xy 184.472996 -305.825874) (xy 184.484773 -305.77809) (xy 184.504064 -305.732814) (xy 184.530367 -305.691218)
			(xy 184.563002 -305.654381) (xy 184.601123 -305.623256) (xy 184.643744 -305.598649) (xy 184.68976 -305.581197)
			(xy 184.737979 -305.571353) (xy 184.787154 -305.569372) (xy 184.836009 -305.575304) (xy 184.88328 -305.588996)
			(xy 184.927742 -305.610094) (xy 184.968245 -305.63805) (xy 185.003738 -305.672142) (xy 185.033303 -305.711486)
			(xy 185.056174 -305.755063) (xy 185.071758 -305.801744) (xy 185.079653 -305.850321) (xy 185.080148 -305.874928)
			(xy 185.41925 -305.874928) (xy 185.42321 -305.825874) (xy 185.434987 -305.77809) (xy 185.454278 -305.732814)
			(xy 185.480581 -305.691218) (xy 185.513216 -305.654381) (xy 185.551337 -305.623256) (xy 185.593958 -305.598649)
			(xy 185.639974 -305.581197) (xy 185.688193 -305.571353) (xy 185.737368 -305.569372) (xy 185.786223 -305.575304)
			(xy 185.833494 -305.588996) (xy 185.877956 -305.610094) (xy 185.918459 -305.63805) (xy 185.953952 -305.672142)
			(xy 185.983517 -305.711486) (xy 186.006388 -305.755063) (xy 186.021972 -305.801744) (xy 186.029867 -305.850321)
			(xy 186.030362 -305.874928) (xy 186.36921 -305.874928) (xy 186.37317 -305.825874) (xy 186.384947 -305.77809)
			(xy 186.404238 -305.732814) (xy 186.430541 -305.691218) (xy 186.463176 -305.654381) (xy 186.501297 -305.623256)
			(xy 186.543918 -305.598649) (xy 186.589934 -305.581197) (xy 186.638153 -305.571353) (xy 186.687328 -305.569372)
			(xy 186.736183 -305.575304) (xy 186.783454 -305.588996) (xy 186.827916 -305.610094) (xy 186.868419 -305.63805)
			(xy 186.903912 -305.672142) (xy 186.933477 -305.711486) (xy 186.956348 -305.755063) (xy 186.971932 -305.801744)
			(xy 186.979827 -305.850321) (xy 186.980322 -305.874928) (xy 187.31917 -305.874928) (xy 187.32313 -305.825874)
			(xy 187.334907 -305.77809) (xy 187.354198 -305.732814) (xy 187.380501 -305.691218) (xy 187.413136 -305.654381)
			(xy 187.451257 -305.623256) (xy 187.493878 -305.598649) (xy 187.539894 -305.581197) (xy 187.588113 -305.571353)
			(xy 187.637288 -305.569372) (xy 187.686143 -305.575304) (xy 187.733414 -305.588996) (xy 187.777876 -305.610094)
			(xy 187.818379 -305.63805) (xy 187.853872 -305.672142) (xy 187.883437 -305.711486) (xy 187.906308 -305.755063)
			(xy 187.921892 -305.801744) (xy 187.929787 -305.850321) (xy 187.930282 -305.874928) (xy 188.26913 -305.874928)
			(xy 188.27309 -305.825874) (xy 188.284867 -305.77809) (xy 188.304158 -305.732814) (xy 188.330461 -305.691218)
			(xy 188.363096 -305.654381) (xy 188.401217 -305.623256) (xy 188.443838 -305.598649) (xy 188.489854 -305.581197)
			(xy 188.538073 -305.571353) (xy 188.587248 -305.569372) (xy 188.636103 -305.575304) (xy 188.683374 -305.588996)
			(xy 188.727836 -305.610094) (xy 188.768339 -305.63805) (xy 188.803832 -305.672142) (xy 188.833397 -305.711486)
			(xy 188.856268 -305.755063) (xy 188.871852 -305.801744) (xy 188.879747 -305.850321) (xy 188.880242 -305.874928)
			(xy 188.879747 -305.899535) (xy 188.871852 -305.948112) (xy 188.856268 -305.994793) (xy 188.833397 -306.03837)
			(xy 188.803832 -306.077714) (xy 188.768339 -306.111806) (xy 188.727836 -306.139762) (xy 188.683374 -306.16086)
			(xy 188.636103 -306.174552) (xy 188.587248 -306.180484) (xy 188.538073 -306.178503) (xy 188.489854 -306.168659)
			(xy 188.443838 -306.151207) (xy 188.401217 -306.1266) (xy 188.363096 -306.095475) (xy 188.330461 -306.058638)
			(xy 188.304158 -306.017042) (xy 188.284867 -305.971766) (xy 188.27309 -305.923982) (xy 188.26913 -305.874928)
			(xy 187.930282 -305.874928) (xy 187.929787 -305.899535) (xy 187.921892 -305.948112) (xy 187.906308 -305.994793)
			(xy 187.883437 -306.03837) (xy 187.853872 -306.077714) (xy 187.818379 -306.111806) (xy 187.777876 -306.139762)
			(xy 187.733414 -306.16086) (xy 187.686143 -306.174552) (xy 187.637288 -306.180484) (xy 187.588113 -306.178503)
			(xy 187.539894 -306.168659) (xy 187.493878 -306.151207) (xy 187.451257 -306.1266) (xy 187.413136 -306.095475)
			(xy 187.380501 -306.058638) (xy 187.354198 -306.017042) (xy 187.334907 -305.971766) (xy 187.32313 -305.923982)
			(xy 187.31917 -305.874928) (xy 186.980322 -305.874928) (xy 186.979827 -305.899535) (xy 186.971932 -305.948112)
			(xy 186.956348 -305.994793) (xy 186.933477 -306.03837) (xy 186.903912 -306.077714) (xy 186.868419 -306.111806)
			(xy 186.827916 -306.139762) (xy 186.783454 -306.16086) (xy 186.736183 -306.174552) (xy 186.687328 -306.180484)
			(xy 186.638153 -306.178503) (xy 186.589934 -306.168659) (xy 186.543918 -306.151207) (xy 186.501297 -306.1266)
			(xy 186.463176 -306.095475) (xy 186.430541 -306.058638) (xy 186.404238 -306.017042) (xy 186.384947 -305.971766)
			(xy 186.37317 -305.923982) (xy 186.36921 -305.874928) (xy 186.030362 -305.874928) (xy 186.029867 -305.899535)
			(xy 186.021972 -305.948112) (xy 186.006388 -305.994793) (xy 185.983517 -306.03837) (xy 185.953952 -306.077714)
			(xy 185.918459 -306.111806) (xy 185.877956 -306.139762) (xy 185.833494 -306.16086) (xy 185.786223 -306.174552)
			(xy 185.737368 -306.180484) (xy 185.688193 -306.178503) (xy 185.639974 -306.168659) (xy 185.593958 -306.151207)
			(xy 185.551337 -306.1266) (xy 185.513216 -306.095475) (xy 185.480581 -306.058638) (xy 185.454278 -306.017042)
			(xy 185.434987 -305.971766) (xy 185.42321 -305.923982) (xy 185.41925 -305.874928) (xy 185.080148 -305.874928)
			(xy 185.079653 -305.899535) (xy 185.071758 -305.948112) (xy 185.056174 -305.994793) (xy 185.033303 -306.03837)
			(xy 185.003738 -306.077714) (xy 184.968245 -306.111806) (xy 184.927742 -306.139762) (xy 184.88328 -306.16086)
			(xy 184.836009 -306.174552) (xy 184.787154 -306.180484) (xy 184.737979 -306.178503) (xy 184.68976 -306.168659)
			(xy 184.643744 -306.151207) (xy 184.601123 -306.1266) (xy 184.563002 -306.095475) (xy 184.530367 -306.058638)
			(xy 184.504064 -306.017042) (xy 184.484773 -305.971766) (xy 184.472996 -305.923982) (xy 184.469036 -305.874928)
			(xy 184.130188 -305.874928) (xy 184.129693 -305.899535) (xy 184.121798 -305.948112) (xy 184.106214 -305.994793)
			(xy 184.083343 -306.03837) (xy 184.053778 -306.077714) (xy 184.018285 -306.111806) (xy 183.977782 -306.139762)
			(xy 183.93332 -306.16086) (xy 183.886049 -306.174552) (xy 183.837194 -306.180484) (xy 183.788019 -306.178503)
			(xy 183.7398 -306.168659) (xy 183.693784 -306.151207) (xy 183.651163 -306.1266) (xy 183.613042 -306.095475)
			(xy 183.580407 -306.058638) (xy 183.554104 -306.017042) (xy 183.534813 -305.971766) (xy 183.523036 -305.923982)
			(xy 183.519076 -305.874928) (xy 183.180228 -305.874928) (xy 183.179733 -305.899535) (xy 183.171838 -305.948112)
			(xy 183.156254 -305.994793) (xy 183.133383 -306.03837) (xy 183.103818 -306.077714) (xy 183.068325 -306.111806)
			(xy 183.027822 -306.139762) (xy 182.98336 -306.16086) (xy 182.936089 -306.174552) (xy 182.887234 -306.180484)
			(xy 182.838059 -306.178503) (xy 182.78984 -306.168659) (xy 182.743824 -306.151207) (xy 182.701203 -306.1266)
			(xy 182.663082 -306.095475) (xy 182.630447 -306.058638) (xy 182.604144 -306.017042) (xy 182.584853 -305.971766)
			(xy 182.573076 -305.923982) (xy 182.569116 -305.874928) (xy 182.230268 -305.874928) (xy 182.229773 -305.899535)
			(xy 182.221878 -305.948112) (xy 182.206294 -305.994793) (xy 182.183423 -306.03837) (xy 182.153858 -306.077714)
			(xy 182.118365 -306.111806) (xy 182.077862 -306.139762) (xy 182.0334 -306.16086) (xy 181.986129 -306.174552)
			(xy 181.937274 -306.180484) (xy 181.888099 -306.178503) (xy 181.83988 -306.168659) (xy 181.793864 -306.151207)
			(xy 181.751243 -306.1266) (xy 181.713122 -306.095475) (xy 181.680487 -306.058638) (xy 181.654184 -306.017042)
			(xy 181.634893 -305.971766) (xy 181.623116 -305.923982) (xy 181.619156 -305.874928) (xy 181.280308 -305.874928)
			(xy 181.279813 -305.899535) (xy 181.271918 -305.948112) (xy 181.256334 -305.994793) (xy 181.233463 -306.03837)
			(xy 181.203898 -306.077714) (xy 181.168405 -306.111806) (xy 181.127902 -306.139762) (xy 181.08344 -306.16086)
			(xy 181.036169 -306.174552) (xy 180.987314 -306.180484) (xy 180.938139 -306.178503) (xy 180.88992 -306.168659)
			(xy 180.843904 -306.151207) (xy 180.801283 -306.1266) (xy 180.763162 -306.095475) (xy 180.730527 -306.058638)
			(xy 180.704224 -306.017042) (xy 180.684933 -305.971766) (xy 180.673156 -305.923982) (xy 180.669196 -305.874928)
			(xy 180.330348 -305.874928) (xy 180.329853 -305.899535) (xy 180.321958 -305.948112) (xy 180.306374 -305.994793)
			(xy 180.283503 -306.03837) (xy 180.253938 -306.077714) (xy 180.218445 -306.111806) (xy 180.177942 -306.139762)
			(xy 180.13348 -306.16086) (xy 180.086209 -306.174552) (xy 180.037354 -306.180484) (xy 179.988179 -306.178503)
			(xy 179.93996 -306.168659) (xy 179.893944 -306.151207) (xy 179.851323 -306.1266) (xy 179.813202 -306.095475)
			(xy 179.780567 -306.058638) (xy 179.754264 -306.017042) (xy 179.734973 -305.971766) (xy 179.723196 -305.923982)
			(xy 179.719236 -305.874928) (xy 179.380388 -305.874928) (xy 179.379893 -305.899535) (xy 179.371998 -305.948112)
			(xy 179.356414 -305.994793) (xy 179.333543 -306.03837) (xy 179.303978 -306.077714) (xy 179.268485 -306.111806)
			(xy 179.227982 -306.139762) (xy 179.18352 -306.16086) (xy 179.136249 -306.174552) (xy 179.087394 -306.180484)
			(xy 179.038219 -306.178503) (xy 178.99 -306.168659) (xy 178.943984 -306.151207) (xy 178.901363 -306.1266)
			(xy 178.863242 -306.095475) (xy 178.830607 -306.058638) (xy 178.804304 -306.017042) (xy 178.785013 -305.971766)
			(xy 178.773236 -305.923982) (xy 178.769276 -305.874928) (xy 178.430174 -305.874928) (xy 178.429679 -305.899535)
			(xy 178.421784 -305.948112) (xy 178.4062 -305.994793) (xy 178.383329 -306.03837) (xy 178.353764 -306.077714)
			(xy 178.318271 -306.111806) (xy 178.277768 -306.139762) (xy 178.233306 -306.16086) (xy 178.186035 -306.174552)
			(xy 178.13718 -306.180484) (xy 178.088005 -306.178503) (xy 178.039786 -306.168659) (xy 177.99377 -306.151207)
			(xy 177.951149 -306.1266) (xy 177.913028 -306.095475) (xy 177.880393 -306.058638) (xy 177.85409 -306.017042)
			(xy 177.834799 -305.971766) (xy 177.823022 -305.923982) (xy 177.819062 -305.874928) (xy 177.480214 -305.874928)
			(xy 177.479719 -305.899535) (xy 177.471824 -305.948112) (xy 177.45624 -305.994793) (xy 177.433369 -306.03837)
			(xy 177.403804 -306.077714) (xy 177.368311 -306.111806) (xy 177.327808 -306.139762) (xy 177.283346 -306.16086)
			(xy 177.236075 -306.174552) (xy 177.18722 -306.180484) (xy 177.138045 -306.178503) (xy 177.089826 -306.168659)
			(xy 177.04381 -306.151207) (xy 177.001189 -306.1266) (xy 176.963068 -306.095475) (xy 176.930433 -306.058638)
			(xy 176.90413 -306.017042) (xy 176.884839 -305.971766) (xy 176.873062 -305.923982) (xy 176.869102 -305.874928)
			(xy 176.530254 -305.874928) (xy 176.529759 -305.899535) (xy 176.521864 -305.948112) (xy 176.50628 -305.994793)
			(xy 176.483409 -306.03837) (xy 176.453844 -306.077714) (xy 176.418351 -306.111806) (xy 176.377848 -306.139762)
			(xy 176.333386 -306.16086) (xy 176.286115 -306.174552) (xy 176.23726 -306.180484) (xy 176.188085 -306.178503)
			(xy 176.139866 -306.168659) (xy 176.09385 -306.151207) (xy 176.051229 -306.1266) (xy 176.013108 -306.095475)
			(xy 175.980473 -306.058638) (xy 175.95417 -306.017042) (xy 175.934879 -305.971766) (xy 175.923102 -305.923982)
			(xy 175.919142 -305.874928) (xy 174.630334 -305.874928) (xy 174.629839 -305.899535) (xy 174.621944 -305.948112)
			(xy 174.60636 -305.994793) (xy 174.583489 -306.03837) (xy 174.553924 -306.077714) (xy 174.518431 -306.111806)
			(xy 174.477928 -306.139762) (xy 174.433466 -306.16086) (xy 174.386195 -306.174552) (xy 174.33734 -306.180484)
			(xy 174.288165 -306.178503) (xy 174.239946 -306.168659) (xy 174.19393 -306.151207) (xy 174.151309 -306.1266)
			(xy 174.113188 -306.095475) (xy 174.080553 -306.058638) (xy 174.05425 -306.017042) (xy 174.034959 -305.971766)
			(xy 174.023182 -305.923982) (xy 174.019222 -305.874928) (xy 173.680374 -305.874928) (xy 173.679879 -305.899535)
			(xy 173.671984 -305.948112) (xy 173.6564 -305.994793) (xy 173.633529 -306.03837) (xy 173.603964 -306.077714)
			(xy 173.568471 -306.111806) (xy 173.527968 -306.139762) (xy 173.483506 -306.16086) (xy 173.436235 -306.174552)
			(xy 173.38738 -306.180484) (xy 173.338205 -306.178503) (xy 173.289986 -306.168659) (xy 173.24397 -306.151207)
			(xy 173.201349 -306.1266) (xy 173.163228 -306.095475) (xy 173.130593 -306.058638) (xy 173.10429 -306.017042)
			(xy 173.084999 -305.971766) (xy 173.073222 -305.923982) (xy 173.069262 -305.874928) (xy 172.73016 -305.874928)
			(xy 172.729665 -305.899535) (xy 172.72177 -305.948112) (xy 172.706186 -305.994793) (xy 172.683315 -306.03837)
			(xy 172.65375 -306.077714) (xy 172.618257 -306.111806) (xy 172.577754 -306.139762) (xy 172.533292 -306.16086)
			(xy 172.486021 -306.174552) (xy 172.437166 -306.180484) (xy 172.387991 -306.178503) (xy 172.339772 -306.168659)
			(xy 172.293756 -306.151207) (xy 172.251135 -306.1266) (xy 172.213014 -306.095475) (xy 172.180379 -306.058638)
			(xy 172.154076 -306.017042) (xy 172.134785 -305.971766) (xy 172.123008 -305.923982) (xy 172.119048 -305.874928)
			(xy 171.7802 -305.874928) (xy 171.779705 -305.899535) (xy 171.77181 -305.948112) (xy 171.756226 -305.994793)
			(xy 171.733355 -306.03837) (xy 171.70379 -306.077714) (xy 171.668297 -306.111806) (xy 171.627794 -306.139762)
			(xy 171.583332 -306.16086) (xy 171.536061 -306.174552) (xy 171.487206 -306.180484) (xy 171.438031 -306.178503)
			(xy 171.389812 -306.168659) (xy 171.343796 -306.151207) (xy 171.301175 -306.1266) (xy 171.263054 -306.095475)
			(xy 171.230419 -306.058638) (xy 171.204116 -306.017042) (xy 171.184825 -305.971766) (xy 171.173048 -305.923982)
			(xy 171.169088 -305.874928) (xy 170.83024 -305.874928) (xy 170.829745 -305.899535) (xy 170.82185 -305.948112)
			(xy 170.806266 -305.994793) (xy 170.783395 -306.03837) (xy 170.75383 -306.077714) (xy 170.718337 -306.111806)
			(xy 170.677834 -306.139762) (xy 170.633372 -306.16086) (xy 170.586101 -306.174552) (xy 170.537246 -306.180484)
			(xy 170.488071 -306.178503) (xy 170.439852 -306.168659) (xy 170.393836 -306.151207) (xy 170.351215 -306.1266)
			(xy 170.313094 -306.095475) (xy 170.280459 -306.058638) (xy 170.254156 -306.017042) (xy 170.234865 -305.971766)
			(xy 170.223088 -305.923982) (xy 170.219128 -305.874928) (xy 169.88028 -305.874928) (xy 169.879785 -305.899535)
			(xy 169.87189 -305.948112) (xy 169.856306 -305.994793) (xy 169.833435 -306.03837) (xy 169.80387 -306.077714)
			(xy 169.768377 -306.111806) (xy 169.727874 -306.139762) (xy 169.683412 -306.16086) (xy 169.636141 -306.174552)
			(xy 169.587286 -306.180484) (xy 169.538111 -306.178503) (xy 169.489892 -306.168659) (xy 169.443876 -306.151207)
			(xy 169.401255 -306.1266) (xy 169.363134 -306.095475) (xy 169.330499 -306.058638) (xy 169.304196 -306.017042)
			(xy 169.284905 -305.971766) (xy 169.273128 -305.923982) (xy 169.269168 -305.874928) (xy 168.93032 -305.874928)
			(xy 168.929825 -305.899535) (xy 168.92193 -305.948112) (xy 168.906346 -305.994793) (xy 168.883475 -306.03837)
			(xy 168.85391 -306.077714) (xy 168.818417 -306.111806) (xy 168.777914 -306.139762) (xy 168.733452 -306.16086)
			(xy 168.686181 -306.174552) (xy 168.637326 -306.180484) (xy 168.588151 -306.178503) (xy 168.539932 -306.168659)
			(xy 168.493916 -306.151207) (xy 168.451295 -306.1266) (xy 168.413174 -306.095475) (xy 168.380539 -306.058638)
			(xy 168.354236 -306.017042) (xy 168.334945 -305.971766) (xy 168.323168 -305.923982) (xy 168.319208 -305.874928)
			(xy 167.98036 -305.874928) (xy 167.979865 -305.899535) (xy 167.97197 -305.948112) (xy 167.956386 -305.994793)
			(xy 167.933515 -306.03837) (xy 167.90395 -306.077714) (xy 167.868457 -306.111806) (xy 167.827954 -306.139762)
			(xy 167.783492 -306.16086) (xy 167.736221 -306.174552) (xy 167.687366 -306.180484) (xy 167.638191 -306.178503)
			(xy 167.589972 -306.168659) (xy 167.543956 -306.151207) (xy 167.501335 -306.1266) (xy 167.463214 -306.095475)
			(xy 167.430579 -306.058638) (xy 167.404276 -306.017042) (xy 167.384985 -305.971766) (xy 167.373208 -305.923982)
			(xy 167.369248 -305.874928) (xy 167.0304 -305.874928) (xy 167.029905 -305.899535) (xy 167.02201 -305.948112)
			(xy 167.006426 -305.994793) (xy 166.983555 -306.03837) (xy 166.95399 -306.077714) (xy 166.918497 -306.111806)
			(xy 166.877994 -306.139762) (xy 166.833532 -306.16086) (xy 166.786261 -306.174552) (xy 166.737406 -306.180484)
			(xy 166.688231 -306.178503) (xy 166.640012 -306.168659) (xy 166.593996 -306.151207) (xy 166.551375 -306.1266)
			(xy 166.513254 -306.095475) (xy 166.480619 -306.058638) (xy 166.454316 -306.017042) (xy 166.435025 -305.971766)
			(xy 166.423248 -305.923982) (xy 166.419288 -305.874928) (xy 166.141146 -305.874928) (xy 166.141146 -306.824888)
			(xy 166.419288 -306.824888) (xy 166.423248 -306.775834) (xy 166.435025 -306.72805) (xy 166.454316 -306.682774)
			(xy 166.480619 -306.641178) (xy 166.513254 -306.604341) (xy 166.551375 -306.573216) (xy 166.593996 -306.548609)
			(xy 166.640012 -306.531157) (xy 166.688231 -306.521313) (xy 166.737406 -306.519332) (xy 166.786261 -306.525264)
			(xy 166.833532 -306.538956) (xy 166.877994 -306.560054) (xy 166.918497 -306.58801) (xy 166.95399 -306.622102)
			(xy 166.983555 -306.661446) (xy 167.006426 -306.705023) (xy 167.02201 -306.751704) (xy 167.029905 -306.800281)
			(xy 167.0304 -306.824888) (xy 167.369248 -306.824888) (xy 167.373208 -306.775834) (xy 167.384985 -306.72805)
			(xy 167.404276 -306.682774) (xy 167.430579 -306.641178) (xy 167.463214 -306.604341) (xy 167.501335 -306.573216)
			(xy 167.543956 -306.548609) (xy 167.589972 -306.531157) (xy 167.638191 -306.521313) (xy 167.687366 -306.519332)
			(xy 167.736221 -306.525264) (xy 167.783492 -306.538956) (xy 167.827954 -306.560054) (xy 167.868457 -306.58801)
			(xy 167.90395 -306.622102) (xy 167.933515 -306.661446) (xy 167.956386 -306.705023) (xy 167.97197 -306.751704)
			(xy 167.979865 -306.800281) (xy 167.98036 -306.824888) (xy 168.319208 -306.824888) (xy 168.323168 -306.775834)
			(xy 168.334945 -306.72805) (xy 168.354236 -306.682774) (xy 168.380539 -306.641178) (xy 168.413174 -306.604341)
			(xy 168.451295 -306.573216) (xy 168.493916 -306.548609) (xy 168.539932 -306.531157) (xy 168.588151 -306.521313)
			(xy 168.637326 -306.519332) (xy 168.686181 -306.525264) (xy 168.733452 -306.538956) (xy 168.777914 -306.560054)
			(xy 168.818417 -306.58801) (xy 168.85391 -306.622102) (xy 168.883475 -306.661446) (xy 168.906346 -306.705023)
			(xy 168.92193 -306.751704) (xy 168.929825 -306.800281) (xy 168.93032 -306.824888) (xy 169.269168 -306.824888)
			(xy 169.273128 -306.775834) (xy 169.284905 -306.72805) (xy 169.304196 -306.682774) (xy 169.330499 -306.641178)
			(xy 169.363134 -306.604341) (xy 169.401255 -306.573216) (xy 169.443876 -306.548609) (xy 169.489892 -306.531157)
			(xy 169.538111 -306.521313) (xy 169.587286 -306.519332) (xy 169.636141 -306.525264) (xy 169.683412 -306.538956)
			(xy 169.727874 -306.560054) (xy 169.768377 -306.58801) (xy 169.80387 -306.622102) (xy 169.833435 -306.661446)
			(xy 169.856306 -306.705023) (xy 169.87189 -306.751704) (xy 169.879785 -306.800281) (xy 169.88028 -306.824888)
			(xy 170.219128 -306.824888) (xy 170.223088 -306.775834) (xy 170.234865 -306.72805) (xy 170.254156 -306.682774)
			(xy 170.280459 -306.641178) (xy 170.313094 -306.604341) (xy 170.351215 -306.573216) (xy 170.393836 -306.548609)
			(xy 170.439852 -306.531157) (xy 170.488071 -306.521313) (xy 170.537246 -306.519332) (xy 170.586101 -306.525264)
			(xy 170.633372 -306.538956) (xy 170.677834 -306.560054) (xy 170.718337 -306.58801) (xy 170.75383 -306.622102)
			(xy 170.783395 -306.661446) (xy 170.806266 -306.705023) (xy 170.82185 -306.751704) (xy 170.829745 -306.800281)
			(xy 170.83024 -306.824888) (xy 171.169088 -306.824888) (xy 171.173048 -306.775834) (xy 171.184825 -306.72805)
			(xy 171.204116 -306.682774) (xy 171.230419 -306.641178) (xy 171.263054 -306.604341) (xy 171.301175 -306.573216)
			(xy 171.343796 -306.548609) (xy 171.389812 -306.531157) (xy 171.438031 -306.521313) (xy 171.487206 -306.519332)
			(xy 171.536061 -306.525264) (xy 171.583332 -306.538956) (xy 171.627794 -306.560054) (xy 171.668297 -306.58801)
			(xy 171.70379 -306.622102) (xy 171.733355 -306.661446) (xy 171.756226 -306.705023) (xy 171.77181 -306.751704)
			(xy 171.779705 -306.800281) (xy 171.7802 -306.824888) (xy 172.119048 -306.824888) (xy 172.123008 -306.775834)
			(xy 172.134785 -306.72805) (xy 172.154076 -306.682774) (xy 172.180379 -306.641178) (xy 172.213014 -306.604341)
			(xy 172.251135 -306.573216) (xy 172.293756 -306.548609) (xy 172.339772 -306.531157) (xy 172.387991 -306.521313)
			(xy 172.437166 -306.519332) (xy 172.486021 -306.525264) (xy 172.533292 -306.538956) (xy 172.577754 -306.560054)
			(xy 172.618257 -306.58801) (xy 172.65375 -306.622102) (xy 172.683315 -306.661446) (xy 172.706186 -306.705023)
			(xy 172.72177 -306.751704) (xy 172.729665 -306.800281) (xy 172.73016 -306.824888) (xy 173.069262 -306.824888)
			(xy 173.073222 -306.775834) (xy 173.084999 -306.72805) (xy 173.10429 -306.682774) (xy 173.130593 -306.641178)
			(xy 173.163228 -306.604341) (xy 173.201349 -306.573216) (xy 173.24397 -306.548609) (xy 173.289986 -306.531157)
			(xy 173.338205 -306.521313) (xy 173.38738 -306.519332) (xy 173.436235 -306.525264) (xy 173.483506 -306.538956)
			(xy 173.527968 -306.560054) (xy 173.568471 -306.58801) (xy 173.603964 -306.622102) (xy 173.633529 -306.661446)
			(xy 173.6564 -306.705023) (xy 173.671984 -306.751704) (xy 173.679879 -306.800281) (xy 173.680374 -306.824888)
			(xy 174.019222 -306.824888) (xy 174.023182 -306.775834) (xy 174.034959 -306.72805) (xy 174.05425 -306.682774)
			(xy 174.080553 -306.641178) (xy 174.113188 -306.604341) (xy 174.151309 -306.573216) (xy 174.19393 -306.548609)
			(xy 174.239946 -306.531157) (xy 174.288165 -306.521313) (xy 174.33734 -306.519332) (xy 174.386195 -306.525264)
			(xy 174.433466 -306.538956) (xy 174.477928 -306.560054) (xy 174.518431 -306.58801) (xy 174.553924 -306.622102)
			(xy 174.583489 -306.661446) (xy 174.60636 -306.705023) (xy 174.621944 -306.751704) (xy 174.629839 -306.800281)
			(xy 174.630334 -306.824888) (xy 175.919142 -306.824888) (xy 175.923102 -306.775834) (xy 175.934879 -306.72805)
			(xy 175.95417 -306.682774) (xy 175.980473 -306.641178) (xy 176.013108 -306.604341) (xy 176.051229 -306.573216)
			(xy 176.09385 -306.548609) (xy 176.139866 -306.531157) (xy 176.188085 -306.521313) (xy 176.23726 -306.519332)
			(xy 176.286115 -306.525264) (xy 176.333386 -306.538956) (xy 176.377848 -306.560054) (xy 176.418351 -306.58801)
			(xy 176.453844 -306.622102) (xy 176.483409 -306.661446) (xy 176.50628 -306.705023) (xy 176.521864 -306.751704)
			(xy 176.529759 -306.800281) (xy 176.530254 -306.824888) (xy 176.869102 -306.824888) (xy 176.873062 -306.775834)
			(xy 176.884839 -306.72805) (xy 176.90413 -306.682774) (xy 176.930433 -306.641178) (xy 176.963068 -306.604341)
			(xy 177.001189 -306.573216) (xy 177.04381 -306.548609) (xy 177.089826 -306.531157) (xy 177.138045 -306.521313)
			(xy 177.18722 -306.519332) (xy 177.236075 -306.525264) (xy 177.283346 -306.538956) (xy 177.327808 -306.560054)
			(xy 177.368311 -306.58801) (xy 177.403804 -306.622102) (xy 177.433369 -306.661446) (xy 177.45624 -306.705023)
			(xy 177.471824 -306.751704) (xy 177.479719 -306.800281) (xy 177.480214 -306.824888) (xy 177.819062 -306.824888)
			(xy 177.823022 -306.775834) (xy 177.834799 -306.72805) (xy 177.85409 -306.682774) (xy 177.880393 -306.641178)
			(xy 177.913028 -306.604341) (xy 177.951149 -306.573216) (xy 177.99377 -306.548609) (xy 178.039786 -306.531157)
			(xy 178.088005 -306.521313) (xy 178.13718 -306.519332) (xy 178.186035 -306.525264) (xy 178.233306 -306.538956)
			(xy 178.277768 -306.560054) (xy 178.318271 -306.58801) (xy 178.353764 -306.622102) (xy 178.383329 -306.661446)
			(xy 178.4062 -306.705023) (xy 178.421784 -306.751704) (xy 178.429679 -306.800281) (xy 178.430174 -306.824888)
			(xy 178.769276 -306.824888) (xy 178.773236 -306.775834) (xy 178.785013 -306.72805) (xy 178.804304 -306.682774)
			(xy 178.830607 -306.641178) (xy 178.863242 -306.604341) (xy 178.901363 -306.573216) (xy 178.943984 -306.548609)
			(xy 178.99 -306.531157) (xy 179.038219 -306.521313) (xy 179.087394 -306.519332) (xy 179.136249 -306.525264)
			(xy 179.18352 -306.538956) (xy 179.227982 -306.560054) (xy 179.268485 -306.58801) (xy 179.303978 -306.622102)
			(xy 179.333543 -306.661446) (xy 179.356414 -306.705023) (xy 179.371998 -306.751704) (xy 179.379893 -306.800281)
			(xy 179.380388 -306.824888) (xy 179.719236 -306.824888) (xy 179.723196 -306.775834) (xy 179.734973 -306.72805)
			(xy 179.754264 -306.682774) (xy 179.780567 -306.641178) (xy 179.813202 -306.604341) (xy 179.851323 -306.573216)
			(xy 179.893944 -306.548609) (xy 179.93996 -306.531157) (xy 179.988179 -306.521313) (xy 180.037354 -306.519332)
			(xy 180.086209 -306.525264) (xy 180.13348 -306.538956) (xy 180.177942 -306.560054) (xy 180.218445 -306.58801)
			(xy 180.253938 -306.622102) (xy 180.283503 -306.661446) (xy 180.306374 -306.705023) (xy 180.321958 -306.751704)
			(xy 180.329853 -306.800281) (xy 180.330348 -306.824888) (xy 180.669196 -306.824888) (xy 180.673156 -306.775834)
			(xy 180.684933 -306.72805) (xy 180.704224 -306.682774) (xy 180.730527 -306.641178) (xy 180.763162 -306.604341)
			(xy 180.801283 -306.573216) (xy 180.843904 -306.548609) (xy 180.88992 -306.531157) (xy 180.938139 -306.521313)
			(xy 180.987314 -306.519332) (xy 181.036169 -306.525264) (xy 181.08344 -306.538956) (xy 181.127902 -306.560054)
			(xy 181.168405 -306.58801) (xy 181.203898 -306.622102) (xy 181.233463 -306.661446) (xy 181.256334 -306.705023)
			(xy 181.271918 -306.751704) (xy 181.279813 -306.800281) (xy 181.280308 -306.824888) (xy 181.619156 -306.824888)
			(xy 181.623116 -306.775834) (xy 181.634893 -306.72805) (xy 181.654184 -306.682774) (xy 181.680487 -306.641178)
			(xy 181.713122 -306.604341) (xy 181.751243 -306.573216) (xy 181.793864 -306.548609) (xy 181.83988 -306.531157)
			(xy 181.888099 -306.521313) (xy 181.937274 -306.519332) (xy 181.986129 -306.525264) (xy 182.0334 -306.538956)
			(xy 182.077862 -306.560054) (xy 182.118365 -306.58801) (xy 182.153858 -306.622102) (xy 182.183423 -306.661446)
			(xy 182.206294 -306.705023) (xy 182.221878 -306.751704) (xy 182.229773 -306.800281) (xy 182.230268 -306.824888)
			(xy 182.569116 -306.824888) (xy 182.573076 -306.775834) (xy 182.584853 -306.72805) (xy 182.604144 -306.682774)
			(xy 182.630447 -306.641178) (xy 182.663082 -306.604341) (xy 182.701203 -306.573216) (xy 182.743824 -306.548609)
			(xy 182.78984 -306.531157) (xy 182.838059 -306.521313) (xy 182.887234 -306.519332) (xy 182.936089 -306.525264)
			(xy 182.98336 -306.538956) (xy 183.027822 -306.560054) (xy 183.068325 -306.58801) (xy 183.103818 -306.622102)
			(xy 183.133383 -306.661446) (xy 183.156254 -306.705023) (xy 183.171838 -306.751704) (xy 183.179733 -306.800281)
			(xy 183.180228 -306.824888) (xy 183.519076 -306.824888) (xy 183.523036 -306.775834) (xy 183.534813 -306.72805)
			(xy 183.554104 -306.682774) (xy 183.580407 -306.641178) (xy 183.613042 -306.604341) (xy 183.651163 -306.573216)
			(xy 183.693784 -306.548609) (xy 183.7398 -306.531157) (xy 183.788019 -306.521313) (xy 183.837194 -306.519332)
			(xy 183.886049 -306.525264) (xy 183.93332 -306.538956) (xy 183.977782 -306.560054) (xy 184.018285 -306.58801)
			(xy 184.053778 -306.622102) (xy 184.083343 -306.661446) (xy 184.106214 -306.705023) (xy 184.121798 -306.751704)
			(xy 184.129693 -306.800281) (xy 184.130188 -306.824888) (xy 184.469036 -306.824888) (xy 184.472996 -306.775834)
			(xy 184.484773 -306.72805) (xy 184.504064 -306.682774) (xy 184.530367 -306.641178) (xy 184.563002 -306.604341)
			(xy 184.601123 -306.573216) (xy 184.643744 -306.548609) (xy 184.68976 -306.531157) (xy 184.737979 -306.521313)
			(xy 184.787154 -306.519332) (xy 184.836009 -306.525264) (xy 184.88328 -306.538956) (xy 184.927742 -306.560054)
			(xy 184.968245 -306.58801) (xy 185.003738 -306.622102) (xy 185.033303 -306.661446) (xy 185.056174 -306.705023)
			(xy 185.071758 -306.751704) (xy 185.079653 -306.800281) (xy 185.080148 -306.824888) (xy 185.41925 -306.824888)
			(xy 185.42321 -306.775834) (xy 185.434987 -306.72805) (xy 185.454278 -306.682774) (xy 185.480581 -306.641178)
			(xy 185.513216 -306.604341) (xy 185.551337 -306.573216) (xy 185.593958 -306.548609) (xy 185.639974 -306.531157)
			(xy 185.688193 -306.521313) (xy 185.737368 -306.519332) (xy 185.786223 -306.525264) (xy 185.833494 -306.538956)
			(xy 185.877956 -306.560054) (xy 185.918459 -306.58801) (xy 185.953952 -306.622102) (xy 185.983517 -306.661446)
			(xy 186.006388 -306.705023) (xy 186.021972 -306.751704) (xy 186.029867 -306.800281) (xy 186.030362 -306.824888)
			(xy 186.36921 -306.824888) (xy 186.37317 -306.775834) (xy 186.384947 -306.72805) (xy 186.404238 -306.682774)
			(xy 186.430541 -306.641178) (xy 186.463176 -306.604341) (xy 186.501297 -306.573216) (xy 186.543918 -306.548609)
			(xy 186.589934 -306.531157) (xy 186.638153 -306.521313) (xy 186.687328 -306.519332) (xy 186.736183 -306.525264)
			(xy 186.783454 -306.538956) (xy 186.827916 -306.560054) (xy 186.868419 -306.58801) (xy 186.903912 -306.622102)
			(xy 186.933477 -306.661446) (xy 186.956348 -306.705023) (xy 186.971932 -306.751704) (xy 186.979827 -306.800281)
			(xy 186.980322 -306.824888) (xy 187.31917 -306.824888) (xy 187.32313 -306.775834) (xy 187.334907 -306.72805)
			(xy 187.354198 -306.682774) (xy 187.380501 -306.641178) (xy 187.413136 -306.604341) (xy 187.451257 -306.573216)
			(xy 187.493878 -306.548609) (xy 187.539894 -306.531157) (xy 187.588113 -306.521313) (xy 187.637288 -306.519332)
			(xy 187.686143 -306.525264) (xy 187.733414 -306.538956) (xy 187.777876 -306.560054) (xy 187.818379 -306.58801)
			(xy 187.853872 -306.622102) (xy 187.883437 -306.661446) (xy 187.906308 -306.705023) (xy 187.921892 -306.751704)
			(xy 187.929787 -306.800281) (xy 187.930282 -306.824888) (xy 188.26913 -306.824888) (xy 188.27309 -306.775834)
			(xy 188.284867 -306.72805) (xy 188.304158 -306.682774) (xy 188.330461 -306.641178) (xy 188.363096 -306.604341)
			(xy 188.401217 -306.573216) (xy 188.443838 -306.548609) (xy 188.489854 -306.531157) (xy 188.538073 -306.521313)
			(xy 188.587248 -306.519332) (xy 188.636103 -306.525264) (xy 188.683374 -306.538956) (xy 188.727836 -306.560054)
			(xy 188.768339 -306.58801) (xy 188.803832 -306.622102) (xy 188.833397 -306.661446) (xy 188.856268 -306.705023)
			(xy 188.871852 -306.751704) (xy 188.879747 -306.800281) (xy 188.880242 -306.824888) (xy 188.879747 -306.849495)
			(xy 188.871852 -306.898072) (xy 188.856268 -306.944753) (xy 188.833397 -306.98833) (xy 188.803832 -307.027674)
			(xy 188.768339 -307.061766) (xy 188.727836 -307.089722) (xy 188.683374 -307.11082) (xy 188.636103 -307.124512)
			(xy 188.587248 -307.130444) (xy 188.538073 -307.128463) (xy 188.489854 -307.118619) (xy 188.443838 -307.101167)
			(xy 188.401217 -307.07656) (xy 188.363096 -307.045435) (xy 188.330461 -307.008598) (xy 188.304158 -306.967002)
			(xy 188.284867 -306.921726) (xy 188.27309 -306.873942) (xy 188.26913 -306.824888) (xy 187.930282 -306.824888)
			(xy 187.929787 -306.849495) (xy 187.921892 -306.898072) (xy 187.906308 -306.944753) (xy 187.883437 -306.98833)
			(xy 187.853872 -307.027674) (xy 187.818379 -307.061766) (xy 187.777876 -307.089722) (xy 187.733414 -307.11082)
			(xy 187.686143 -307.124512) (xy 187.637288 -307.130444) (xy 187.588113 -307.128463) (xy 187.539894 -307.118619)
			(xy 187.493878 -307.101167) (xy 187.451257 -307.07656) (xy 187.413136 -307.045435) (xy 187.380501 -307.008598)
			(xy 187.354198 -306.967002) (xy 187.334907 -306.921726) (xy 187.32313 -306.873942) (xy 187.31917 -306.824888)
			(xy 186.980322 -306.824888) (xy 186.979827 -306.849495) (xy 186.971932 -306.898072) (xy 186.956348 -306.944753)
			(xy 186.933477 -306.98833) (xy 186.903912 -307.027674) (xy 186.868419 -307.061766) (xy 186.827916 -307.089722)
			(xy 186.783454 -307.11082) (xy 186.736183 -307.124512) (xy 186.687328 -307.130444) (xy 186.638153 -307.128463)
			(xy 186.589934 -307.118619) (xy 186.543918 -307.101167) (xy 186.501297 -307.07656) (xy 186.463176 -307.045435)
			(xy 186.430541 -307.008598) (xy 186.404238 -306.967002) (xy 186.384947 -306.921726) (xy 186.37317 -306.873942)
			(xy 186.36921 -306.824888) (xy 186.030362 -306.824888) (xy 186.029867 -306.849495) (xy 186.021972 -306.898072)
			(xy 186.006388 -306.944753) (xy 185.983517 -306.98833) (xy 185.953952 -307.027674) (xy 185.918459 -307.061766)
			(xy 185.877956 -307.089722) (xy 185.833494 -307.11082) (xy 185.786223 -307.124512) (xy 185.737368 -307.130444)
			(xy 185.688193 -307.128463) (xy 185.639974 -307.118619) (xy 185.593958 -307.101167) (xy 185.551337 -307.07656)
			(xy 185.513216 -307.045435) (xy 185.480581 -307.008598) (xy 185.454278 -306.967002) (xy 185.434987 -306.921726)
			(xy 185.42321 -306.873942) (xy 185.41925 -306.824888) (xy 185.080148 -306.824888) (xy 185.079653 -306.849495)
			(xy 185.071758 -306.898072) (xy 185.056174 -306.944753) (xy 185.033303 -306.98833) (xy 185.003738 -307.027674)
			(xy 184.968245 -307.061766) (xy 184.927742 -307.089722) (xy 184.88328 -307.11082) (xy 184.836009 -307.124512)
			(xy 184.787154 -307.130444) (xy 184.737979 -307.128463) (xy 184.68976 -307.118619) (xy 184.643744 -307.101167)
			(xy 184.601123 -307.07656) (xy 184.563002 -307.045435) (xy 184.530367 -307.008598) (xy 184.504064 -306.967002)
			(xy 184.484773 -306.921726) (xy 184.472996 -306.873942) (xy 184.469036 -306.824888) (xy 184.130188 -306.824888)
			(xy 184.129693 -306.849495) (xy 184.121798 -306.898072) (xy 184.106214 -306.944753) (xy 184.083343 -306.98833)
			(xy 184.053778 -307.027674) (xy 184.018285 -307.061766) (xy 183.977782 -307.089722) (xy 183.93332 -307.11082)
			(xy 183.886049 -307.124512) (xy 183.837194 -307.130444) (xy 183.788019 -307.128463) (xy 183.7398 -307.118619)
			(xy 183.693784 -307.101167) (xy 183.651163 -307.07656) (xy 183.613042 -307.045435) (xy 183.580407 -307.008598)
			(xy 183.554104 -306.967002) (xy 183.534813 -306.921726) (xy 183.523036 -306.873942) (xy 183.519076 -306.824888)
			(xy 183.180228 -306.824888) (xy 183.179733 -306.849495) (xy 183.171838 -306.898072) (xy 183.156254 -306.944753)
			(xy 183.133383 -306.98833) (xy 183.103818 -307.027674) (xy 183.068325 -307.061766) (xy 183.027822 -307.089722)
			(xy 182.98336 -307.11082) (xy 182.936089 -307.124512) (xy 182.887234 -307.130444) (xy 182.838059 -307.128463)
			(xy 182.78984 -307.118619) (xy 182.743824 -307.101167) (xy 182.701203 -307.07656) (xy 182.663082 -307.045435)
			(xy 182.630447 -307.008598) (xy 182.604144 -306.967002) (xy 182.584853 -306.921726) (xy 182.573076 -306.873942)
			(xy 182.569116 -306.824888) (xy 182.230268 -306.824888) (xy 182.229773 -306.849495) (xy 182.221878 -306.898072)
			(xy 182.206294 -306.944753) (xy 182.183423 -306.98833) (xy 182.153858 -307.027674) (xy 182.118365 -307.061766)
			(xy 182.077862 -307.089722) (xy 182.0334 -307.11082) (xy 181.986129 -307.124512) (xy 181.937274 -307.130444)
			(xy 181.888099 -307.128463) (xy 181.83988 -307.118619) (xy 181.793864 -307.101167) (xy 181.751243 -307.07656)
			(xy 181.713122 -307.045435) (xy 181.680487 -307.008598) (xy 181.654184 -306.967002) (xy 181.634893 -306.921726)
			(xy 181.623116 -306.873942) (xy 181.619156 -306.824888) (xy 181.280308 -306.824888) (xy 181.279813 -306.849495)
			(xy 181.271918 -306.898072) (xy 181.256334 -306.944753) (xy 181.233463 -306.98833) (xy 181.203898 -307.027674)
			(xy 181.168405 -307.061766) (xy 181.127902 -307.089722) (xy 181.08344 -307.11082) (xy 181.036169 -307.124512)
			(xy 180.987314 -307.130444) (xy 180.938139 -307.128463) (xy 180.88992 -307.118619) (xy 180.843904 -307.101167)
			(xy 180.801283 -307.07656) (xy 180.763162 -307.045435) (xy 180.730527 -307.008598) (xy 180.704224 -306.967002)
			(xy 180.684933 -306.921726) (xy 180.673156 -306.873942) (xy 180.669196 -306.824888) (xy 180.330348 -306.824888)
			(xy 180.329853 -306.849495) (xy 180.321958 -306.898072) (xy 180.306374 -306.944753) (xy 180.283503 -306.98833)
			(xy 180.253938 -307.027674) (xy 180.218445 -307.061766) (xy 180.177942 -307.089722) (xy 180.13348 -307.11082)
			(xy 180.086209 -307.124512) (xy 180.037354 -307.130444) (xy 179.988179 -307.128463) (xy 179.93996 -307.118619)
			(xy 179.893944 -307.101167) (xy 179.851323 -307.07656) (xy 179.813202 -307.045435) (xy 179.780567 -307.008598)
			(xy 179.754264 -306.967002) (xy 179.734973 -306.921726) (xy 179.723196 -306.873942) (xy 179.719236 -306.824888)
			(xy 179.380388 -306.824888) (xy 179.379893 -306.849495) (xy 179.371998 -306.898072) (xy 179.356414 -306.944753)
			(xy 179.333543 -306.98833) (xy 179.303978 -307.027674) (xy 179.268485 -307.061766) (xy 179.227982 -307.089722)
			(xy 179.18352 -307.11082) (xy 179.136249 -307.124512) (xy 179.087394 -307.130444) (xy 179.038219 -307.128463)
			(xy 178.99 -307.118619) (xy 178.943984 -307.101167) (xy 178.901363 -307.07656) (xy 178.863242 -307.045435)
			(xy 178.830607 -307.008598) (xy 178.804304 -306.967002) (xy 178.785013 -306.921726) (xy 178.773236 -306.873942)
			(xy 178.769276 -306.824888) (xy 178.430174 -306.824888) (xy 178.429679 -306.849495) (xy 178.421784 -306.898072)
			(xy 178.4062 -306.944753) (xy 178.383329 -306.98833) (xy 178.353764 -307.027674) (xy 178.318271 -307.061766)
			(xy 178.277768 -307.089722) (xy 178.233306 -307.11082) (xy 178.186035 -307.124512) (xy 178.13718 -307.130444)
			(xy 178.088005 -307.128463) (xy 178.039786 -307.118619) (xy 177.99377 -307.101167) (xy 177.951149 -307.07656)
			(xy 177.913028 -307.045435) (xy 177.880393 -307.008598) (xy 177.85409 -306.967002) (xy 177.834799 -306.921726)
			(xy 177.823022 -306.873942) (xy 177.819062 -306.824888) (xy 177.480214 -306.824888) (xy 177.479719 -306.849495)
			(xy 177.471824 -306.898072) (xy 177.45624 -306.944753) (xy 177.433369 -306.98833) (xy 177.403804 -307.027674)
			(xy 177.368311 -307.061766) (xy 177.327808 -307.089722) (xy 177.283346 -307.11082) (xy 177.236075 -307.124512)
			(xy 177.18722 -307.130444) (xy 177.138045 -307.128463) (xy 177.089826 -307.118619) (xy 177.04381 -307.101167)
			(xy 177.001189 -307.07656) (xy 176.963068 -307.045435) (xy 176.930433 -307.008598) (xy 176.90413 -306.967002)
			(xy 176.884839 -306.921726) (xy 176.873062 -306.873942) (xy 176.869102 -306.824888) (xy 176.530254 -306.824888)
			(xy 176.529759 -306.849495) (xy 176.521864 -306.898072) (xy 176.50628 -306.944753) (xy 176.483409 -306.98833)
			(xy 176.453844 -307.027674) (xy 176.418351 -307.061766) (xy 176.377848 -307.089722) (xy 176.333386 -307.11082)
			(xy 176.286115 -307.124512) (xy 176.23726 -307.130444) (xy 176.188085 -307.128463) (xy 176.139866 -307.118619)
			(xy 176.09385 -307.101167) (xy 176.051229 -307.07656) (xy 176.013108 -307.045435) (xy 175.980473 -307.008598)
			(xy 175.95417 -306.967002) (xy 175.934879 -306.921726) (xy 175.923102 -306.873942) (xy 175.919142 -306.824888)
			(xy 174.630334 -306.824888) (xy 174.629839 -306.849495) (xy 174.621944 -306.898072) (xy 174.60636 -306.944753)
			(xy 174.583489 -306.98833) (xy 174.553924 -307.027674) (xy 174.518431 -307.061766) (xy 174.477928 -307.089722)
			(xy 174.433466 -307.11082) (xy 174.386195 -307.124512) (xy 174.33734 -307.130444) (xy 174.288165 -307.128463)
			(xy 174.239946 -307.118619) (xy 174.19393 -307.101167) (xy 174.151309 -307.07656) (xy 174.113188 -307.045435)
			(xy 174.080553 -307.008598) (xy 174.05425 -306.967002) (xy 174.034959 -306.921726) (xy 174.023182 -306.873942)
			(xy 174.019222 -306.824888) (xy 173.680374 -306.824888) (xy 173.679879 -306.849495) (xy 173.671984 -306.898072)
			(xy 173.6564 -306.944753) (xy 173.633529 -306.98833) (xy 173.603964 -307.027674) (xy 173.568471 -307.061766)
			(xy 173.527968 -307.089722) (xy 173.483506 -307.11082) (xy 173.436235 -307.124512) (xy 173.38738 -307.130444)
			(xy 173.338205 -307.128463) (xy 173.289986 -307.118619) (xy 173.24397 -307.101167) (xy 173.201349 -307.07656)
			(xy 173.163228 -307.045435) (xy 173.130593 -307.008598) (xy 173.10429 -306.967002) (xy 173.084999 -306.921726)
			(xy 173.073222 -306.873942) (xy 173.069262 -306.824888) (xy 172.73016 -306.824888) (xy 172.729665 -306.849495)
			(xy 172.72177 -306.898072) (xy 172.706186 -306.944753) (xy 172.683315 -306.98833) (xy 172.65375 -307.027674)
			(xy 172.618257 -307.061766) (xy 172.577754 -307.089722) (xy 172.533292 -307.11082) (xy 172.486021 -307.124512)
			(xy 172.437166 -307.130444) (xy 172.387991 -307.128463) (xy 172.339772 -307.118619) (xy 172.293756 -307.101167)
			(xy 172.251135 -307.07656) (xy 172.213014 -307.045435) (xy 172.180379 -307.008598) (xy 172.154076 -306.967002)
			(xy 172.134785 -306.921726) (xy 172.123008 -306.873942) (xy 172.119048 -306.824888) (xy 171.7802 -306.824888)
			(xy 171.779705 -306.849495) (xy 171.77181 -306.898072) (xy 171.756226 -306.944753) (xy 171.733355 -306.98833)
			(xy 171.70379 -307.027674) (xy 171.668297 -307.061766) (xy 171.627794 -307.089722) (xy 171.583332 -307.11082)
			(xy 171.536061 -307.124512) (xy 171.487206 -307.130444) (xy 171.438031 -307.128463) (xy 171.389812 -307.118619)
			(xy 171.343796 -307.101167) (xy 171.301175 -307.07656) (xy 171.263054 -307.045435) (xy 171.230419 -307.008598)
			(xy 171.204116 -306.967002) (xy 171.184825 -306.921726) (xy 171.173048 -306.873942) (xy 171.169088 -306.824888)
			(xy 170.83024 -306.824888) (xy 170.829745 -306.849495) (xy 170.82185 -306.898072) (xy 170.806266 -306.944753)
			(xy 170.783395 -306.98833) (xy 170.75383 -307.027674) (xy 170.718337 -307.061766) (xy 170.677834 -307.089722)
			(xy 170.633372 -307.11082) (xy 170.586101 -307.124512) (xy 170.537246 -307.130444) (xy 170.488071 -307.128463)
			(xy 170.439852 -307.118619) (xy 170.393836 -307.101167) (xy 170.351215 -307.07656) (xy 170.313094 -307.045435)
			(xy 170.280459 -307.008598) (xy 170.254156 -306.967002) (xy 170.234865 -306.921726) (xy 170.223088 -306.873942)
			(xy 170.219128 -306.824888) (xy 169.88028 -306.824888) (xy 169.879785 -306.849495) (xy 169.87189 -306.898072)
			(xy 169.856306 -306.944753) (xy 169.833435 -306.98833) (xy 169.80387 -307.027674) (xy 169.768377 -307.061766)
			(xy 169.727874 -307.089722) (xy 169.683412 -307.11082) (xy 169.636141 -307.124512) (xy 169.587286 -307.130444)
			(xy 169.538111 -307.128463) (xy 169.489892 -307.118619) (xy 169.443876 -307.101167) (xy 169.401255 -307.07656)
			(xy 169.363134 -307.045435) (xy 169.330499 -307.008598) (xy 169.304196 -306.967002) (xy 169.284905 -306.921726)
			(xy 169.273128 -306.873942) (xy 169.269168 -306.824888) (xy 168.93032 -306.824888) (xy 168.929825 -306.849495)
			(xy 168.92193 -306.898072) (xy 168.906346 -306.944753) (xy 168.883475 -306.98833) (xy 168.85391 -307.027674)
			(xy 168.818417 -307.061766) (xy 168.777914 -307.089722) (xy 168.733452 -307.11082) (xy 168.686181 -307.124512)
			(xy 168.637326 -307.130444) (xy 168.588151 -307.128463) (xy 168.539932 -307.118619) (xy 168.493916 -307.101167)
			(xy 168.451295 -307.07656) (xy 168.413174 -307.045435) (xy 168.380539 -307.008598) (xy 168.354236 -306.967002)
			(xy 168.334945 -306.921726) (xy 168.323168 -306.873942) (xy 168.319208 -306.824888) (xy 167.98036 -306.824888)
			(xy 167.979865 -306.849495) (xy 167.97197 -306.898072) (xy 167.956386 -306.944753) (xy 167.933515 -306.98833)
			(xy 167.90395 -307.027674) (xy 167.868457 -307.061766) (xy 167.827954 -307.089722) (xy 167.783492 -307.11082)
			(xy 167.736221 -307.124512) (xy 167.687366 -307.130444) (xy 167.638191 -307.128463) (xy 167.589972 -307.118619)
			(xy 167.543956 -307.101167) (xy 167.501335 -307.07656) (xy 167.463214 -307.045435) (xy 167.430579 -307.008598)
			(xy 167.404276 -306.967002) (xy 167.384985 -306.921726) (xy 167.373208 -306.873942) (xy 167.369248 -306.824888)
			(xy 167.0304 -306.824888) (xy 167.029905 -306.849495) (xy 167.02201 -306.898072) (xy 167.006426 -306.944753)
			(xy 166.983555 -306.98833) (xy 166.95399 -307.027674) (xy 166.918497 -307.061766) (xy 166.877994 -307.089722)
			(xy 166.833532 -307.11082) (xy 166.786261 -307.124512) (xy 166.737406 -307.130444) (xy 166.688231 -307.128463)
			(xy 166.640012 -307.118619) (xy 166.593996 -307.101167) (xy 166.551375 -307.07656) (xy 166.513254 -307.045435)
			(xy 166.480619 -307.008598) (xy 166.454316 -306.967002) (xy 166.435025 -306.921726) (xy 166.423248 -306.873942)
			(xy 166.419288 -306.824888) (xy 166.141146 -306.824888) (xy 166.141146 -307.774848) (xy 166.419288 -307.774848)
			(xy 166.423248 -307.725794) (xy 166.435025 -307.67801) (xy 166.454316 -307.632734) (xy 166.480619 -307.591138)
			(xy 166.513254 -307.554301) (xy 166.551375 -307.523176) (xy 166.593996 -307.498569) (xy 166.640012 -307.481117)
			(xy 166.688231 -307.471273) (xy 166.737406 -307.469292) (xy 166.786261 -307.475224) (xy 166.833532 -307.488916)
			(xy 166.877994 -307.510014) (xy 166.918497 -307.53797) (xy 166.95399 -307.572062) (xy 166.983555 -307.611406)
			(xy 167.006426 -307.654983) (xy 167.02201 -307.701664) (xy 167.029905 -307.750241) (xy 167.0304 -307.774848)
			(xy 167.369248 -307.774848) (xy 167.373208 -307.725794) (xy 167.384985 -307.67801) (xy 167.404276 -307.632734)
			(xy 167.430579 -307.591138) (xy 167.463214 -307.554301) (xy 167.501335 -307.523176) (xy 167.543956 -307.498569)
			(xy 167.589972 -307.481117) (xy 167.638191 -307.471273) (xy 167.687366 -307.469292) (xy 167.736221 -307.475224)
			(xy 167.783492 -307.488916) (xy 167.827954 -307.510014) (xy 167.868457 -307.53797) (xy 167.90395 -307.572062)
			(xy 167.933515 -307.611406) (xy 167.956386 -307.654983) (xy 167.97197 -307.701664) (xy 167.979865 -307.750241)
			(xy 167.98036 -307.774848) (xy 168.319208 -307.774848) (xy 168.323168 -307.725794) (xy 168.334945 -307.67801)
			(xy 168.354236 -307.632734) (xy 168.380539 -307.591138) (xy 168.413174 -307.554301) (xy 168.451295 -307.523176)
			(xy 168.493916 -307.498569) (xy 168.539932 -307.481117) (xy 168.588151 -307.471273) (xy 168.637326 -307.469292)
			(xy 168.686181 -307.475224) (xy 168.733452 -307.488916) (xy 168.777914 -307.510014) (xy 168.818417 -307.53797)
			(xy 168.85391 -307.572062) (xy 168.883475 -307.611406) (xy 168.906346 -307.654983) (xy 168.92193 -307.701664)
			(xy 168.929825 -307.750241) (xy 168.93032 -307.774848) (xy 169.269168 -307.774848) (xy 169.273128 -307.725794)
			(xy 169.284905 -307.67801) (xy 169.304196 -307.632734) (xy 169.330499 -307.591138) (xy 169.363134 -307.554301)
			(xy 169.401255 -307.523176) (xy 169.443876 -307.498569) (xy 169.489892 -307.481117) (xy 169.538111 -307.471273)
			(xy 169.587286 -307.469292) (xy 169.636141 -307.475224) (xy 169.683412 -307.488916) (xy 169.727874 -307.510014)
			(xy 169.768377 -307.53797) (xy 169.80387 -307.572062) (xy 169.833435 -307.611406) (xy 169.856306 -307.654983)
			(xy 169.87189 -307.701664) (xy 169.879785 -307.750241) (xy 169.88028 -307.774848) (xy 170.219128 -307.774848)
			(xy 170.223088 -307.725794) (xy 170.234865 -307.67801) (xy 170.254156 -307.632734) (xy 170.280459 -307.591138)
			(xy 170.313094 -307.554301) (xy 170.351215 -307.523176) (xy 170.393836 -307.498569) (xy 170.439852 -307.481117)
			(xy 170.488071 -307.471273) (xy 170.537246 -307.469292) (xy 170.586101 -307.475224) (xy 170.633372 -307.488916)
			(xy 170.677834 -307.510014) (xy 170.718337 -307.53797) (xy 170.75383 -307.572062) (xy 170.783395 -307.611406)
			(xy 170.806266 -307.654983) (xy 170.82185 -307.701664) (xy 170.829745 -307.750241) (xy 170.83024 -307.774848)
			(xy 171.169088 -307.774848) (xy 171.173048 -307.725794) (xy 171.184825 -307.67801) (xy 171.204116 -307.632734)
			(xy 171.230419 -307.591138) (xy 171.263054 -307.554301) (xy 171.301175 -307.523176) (xy 171.343796 -307.498569)
			(xy 171.389812 -307.481117) (xy 171.438031 -307.471273) (xy 171.487206 -307.469292) (xy 171.536061 -307.475224)
			(xy 171.583332 -307.488916) (xy 171.627794 -307.510014) (xy 171.668297 -307.53797) (xy 171.70379 -307.572062)
			(xy 171.733355 -307.611406) (xy 171.756226 -307.654983) (xy 171.77181 -307.701664) (xy 171.779705 -307.750241)
			(xy 171.7802 -307.774848) (xy 172.119302 -307.774848) (xy 172.123262 -307.725794) (xy 172.135039 -307.67801)
			(xy 172.15433 -307.632734) (xy 172.180633 -307.591138) (xy 172.213268 -307.554301) (xy 172.251389 -307.523176)
			(xy 172.29401 -307.498569) (xy 172.340026 -307.481117) (xy 172.388245 -307.471273) (xy 172.43742 -307.469292)
			(xy 172.486275 -307.475224) (xy 172.533546 -307.488916) (xy 172.578008 -307.510014) (xy 172.618511 -307.53797)
			(xy 172.654004 -307.572062) (xy 172.683569 -307.611406) (xy 172.70644 -307.654983) (xy 172.722024 -307.701664)
			(xy 172.729919 -307.750241) (xy 172.730414 -307.774848) (xy 173.069262 -307.774848) (xy 173.073222 -307.725794)
			(xy 173.084999 -307.67801) (xy 173.10429 -307.632734) (xy 173.130593 -307.591138) (xy 173.163228 -307.554301)
			(xy 173.201349 -307.523176) (xy 173.24397 -307.498569) (xy 173.289986 -307.481117) (xy 173.338205 -307.471273)
			(xy 173.38738 -307.469292) (xy 173.436235 -307.475224) (xy 173.483506 -307.488916) (xy 173.527968 -307.510014)
			(xy 173.568471 -307.53797) (xy 173.603964 -307.572062) (xy 173.633529 -307.611406) (xy 173.6564 -307.654983)
			(xy 173.671984 -307.701664) (xy 173.679879 -307.750241) (xy 173.680374 -307.774848) (xy 174.019222 -307.774848)
			(xy 174.023182 -307.725794) (xy 174.034959 -307.67801) (xy 174.05425 -307.632734) (xy 174.080553 -307.591138)
			(xy 174.113188 -307.554301) (xy 174.151309 -307.523176) (xy 174.19393 -307.498569) (xy 174.239946 -307.481117)
			(xy 174.288165 -307.471273) (xy 174.33734 -307.469292) (xy 174.386195 -307.475224) (xy 174.433466 -307.488916)
			(xy 174.477928 -307.510014) (xy 174.518431 -307.53797) (xy 174.553924 -307.572062) (xy 174.583489 -307.611406)
			(xy 174.60636 -307.654983) (xy 174.621944 -307.701664) (xy 174.629839 -307.750241) (xy 174.630334 -307.774848)
			(xy 175.919142 -307.774848) (xy 175.923102 -307.725794) (xy 175.934879 -307.67801) (xy 175.95417 -307.632734)
			(xy 175.980473 -307.591138) (xy 176.013108 -307.554301) (xy 176.051229 -307.523176) (xy 176.09385 -307.498569)
			(xy 176.139866 -307.481117) (xy 176.188085 -307.471273) (xy 176.23726 -307.469292) (xy 176.286115 -307.475224)
			(xy 176.333386 -307.488916) (xy 176.377848 -307.510014) (xy 176.418351 -307.53797) (xy 176.453844 -307.572062)
			(xy 176.483409 -307.611406) (xy 176.50628 -307.654983) (xy 176.521864 -307.701664) (xy 176.529759 -307.750241)
			(xy 176.530254 -307.774848) (xy 176.869102 -307.774848) (xy 176.873062 -307.725794) (xy 176.884839 -307.67801)
			(xy 176.90413 -307.632734) (xy 176.930433 -307.591138) (xy 176.963068 -307.554301) (xy 177.001189 -307.523176)
			(xy 177.04381 -307.498569) (xy 177.089826 -307.481117) (xy 177.138045 -307.471273) (xy 177.18722 -307.469292)
			(xy 177.236075 -307.475224) (xy 177.283346 -307.488916) (xy 177.327808 -307.510014) (xy 177.368311 -307.53797)
			(xy 177.403804 -307.572062) (xy 177.433369 -307.611406) (xy 177.45624 -307.654983) (xy 177.471824 -307.701664)
			(xy 177.479719 -307.750241) (xy 177.480214 -307.774848) (xy 177.819062 -307.774848) (xy 177.823022 -307.725794)
			(xy 177.834799 -307.67801) (xy 177.85409 -307.632734) (xy 177.880393 -307.591138) (xy 177.913028 -307.554301)
			(xy 177.951149 -307.523176) (xy 177.99377 -307.498569) (xy 178.039786 -307.481117) (xy 178.088005 -307.471273)
			(xy 178.13718 -307.469292) (xy 178.186035 -307.475224) (xy 178.233306 -307.488916) (xy 178.277768 -307.510014)
			(xy 178.318271 -307.53797) (xy 178.353764 -307.572062) (xy 178.383329 -307.611406) (xy 178.4062 -307.654983)
			(xy 178.421784 -307.701664) (xy 178.429679 -307.750241) (xy 178.430169 -307.774594) (xy 178.769022 -307.774594)
			(xy 178.772982 -307.72554) (xy 178.784759 -307.677756) (xy 178.80405 -307.63248) (xy 178.830353 -307.590884)
			(xy 178.862988 -307.554047) (xy 178.901109 -307.522922) (xy 178.94373 -307.498315) (xy 178.989746 -307.480863)
			(xy 179.037965 -307.471019) (xy 179.08714 -307.469038) (xy 179.135995 -307.47497) (xy 179.183266 -307.488662)
			(xy 179.227728 -307.50976) (xy 179.268231 -307.537716) (xy 179.303724 -307.571808) (xy 179.333289 -307.611152)
			(xy 179.35616 -307.654729) (xy 179.371744 -307.70141) (xy 179.379639 -307.749987) (xy 179.380134 -307.774594)
			(xy 179.719236 -307.774594) (xy 179.723196 -307.72554) (xy 179.734973 -307.677756) (xy 179.754264 -307.63248)
			(xy 179.780567 -307.590884) (xy 179.813202 -307.554047) (xy 179.851323 -307.522922) (xy 179.893944 -307.498315)
			(xy 179.93996 -307.480863) (xy 179.988179 -307.471019) (xy 180.037354 -307.469038) (xy 180.086209 -307.47497)
			(xy 180.13348 -307.488662) (xy 180.177942 -307.50976) (xy 180.218445 -307.537716) (xy 180.253938 -307.571808)
			(xy 180.283503 -307.611152) (xy 180.306374 -307.654729) (xy 180.321958 -307.70141) (xy 180.329853 -307.749987)
			(xy 180.330348 -307.774594) (xy 180.330343 -307.774848) (xy 180.669196 -307.774848) (xy 180.673156 -307.725794)
			(xy 180.684933 -307.67801) (xy 180.704224 -307.632734) (xy 180.730527 -307.591138) (xy 180.763162 -307.554301)
			(xy 180.801283 -307.523176) (xy 180.843904 -307.498569) (xy 180.88992 -307.481117) (xy 180.938139 -307.471273)
			(xy 180.987314 -307.469292) (xy 181.036169 -307.475224) (xy 181.08344 -307.488916) (xy 181.127902 -307.510014)
			(xy 181.168405 -307.53797) (xy 181.203898 -307.572062) (xy 181.233463 -307.611406) (xy 181.256334 -307.654983)
			(xy 181.271918 -307.701664) (xy 181.279813 -307.750241) (xy 181.280308 -307.774848) (xy 181.619156 -307.774848)
			(xy 181.623116 -307.725794) (xy 181.634893 -307.67801) (xy 181.654184 -307.632734) (xy 181.680487 -307.591138)
			(xy 181.713122 -307.554301) (xy 181.751243 -307.523176) (xy 181.793864 -307.498569) (xy 181.83988 -307.481117)
			(xy 181.888099 -307.471273) (xy 181.937274 -307.469292) (xy 181.986129 -307.475224) (xy 182.0334 -307.488916)
			(xy 182.077862 -307.510014) (xy 182.118365 -307.53797) (xy 182.153858 -307.572062) (xy 182.183423 -307.611406)
			(xy 182.206294 -307.654983) (xy 182.221878 -307.701664) (xy 182.229773 -307.750241) (xy 182.230268 -307.774848)
			(xy 182.569116 -307.774848) (xy 182.573076 -307.725794) (xy 182.584853 -307.67801) (xy 182.604144 -307.632734)
			(xy 182.630447 -307.591138) (xy 182.663082 -307.554301) (xy 182.701203 -307.523176) (xy 182.743824 -307.498569)
			(xy 182.78984 -307.481117) (xy 182.838059 -307.471273) (xy 182.887234 -307.469292) (xy 182.936089 -307.475224)
			(xy 182.98336 -307.488916) (xy 183.027822 -307.510014) (xy 183.068325 -307.53797) (xy 183.103818 -307.572062)
			(xy 183.133383 -307.611406) (xy 183.156254 -307.654983) (xy 183.171838 -307.701664) (xy 183.179733 -307.750241)
			(xy 183.180228 -307.774848) (xy 183.519076 -307.774848) (xy 183.523036 -307.725794) (xy 183.534813 -307.67801)
			(xy 183.554104 -307.632734) (xy 183.580407 -307.591138) (xy 183.613042 -307.554301) (xy 183.651163 -307.523176)
			(xy 183.693784 -307.498569) (xy 183.7398 -307.481117) (xy 183.788019 -307.471273) (xy 183.837194 -307.469292)
			(xy 183.886049 -307.475224) (xy 183.93332 -307.488916) (xy 183.977782 -307.510014) (xy 184.018285 -307.53797)
			(xy 184.053778 -307.572062) (xy 184.083343 -307.611406) (xy 184.106214 -307.654983) (xy 184.121798 -307.701664)
			(xy 184.129693 -307.750241) (xy 184.130188 -307.774848) (xy 184.469036 -307.774848) (xy 184.472996 -307.725794)
			(xy 184.484773 -307.67801) (xy 184.504064 -307.632734) (xy 184.530367 -307.591138) (xy 184.563002 -307.554301)
			(xy 184.601123 -307.523176) (xy 184.643744 -307.498569) (xy 184.68976 -307.481117) (xy 184.737979 -307.471273)
			(xy 184.787154 -307.469292) (xy 184.836009 -307.475224) (xy 184.88328 -307.488916) (xy 184.927742 -307.510014)
			(xy 184.968245 -307.53797) (xy 185.003738 -307.572062) (xy 185.033303 -307.611406) (xy 185.056174 -307.654983)
			(xy 185.071758 -307.701664) (xy 185.079653 -307.750241) (xy 185.080148 -307.774848) (xy 185.41925 -307.774848)
			(xy 185.42321 -307.725794) (xy 185.434987 -307.67801) (xy 185.454278 -307.632734) (xy 185.480581 -307.591138)
			(xy 185.513216 -307.554301) (xy 185.551337 -307.523176) (xy 185.593958 -307.498569) (xy 185.639974 -307.481117)
			(xy 185.688193 -307.471273) (xy 185.737368 -307.469292) (xy 185.786223 -307.475224) (xy 185.833494 -307.488916)
			(xy 185.877956 -307.510014) (xy 185.918459 -307.53797) (xy 185.953952 -307.572062) (xy 185.983517 -307.611406)
			(xy 186.006388 -307.654983) (xy 186.021972 -307.701664) (xy 186.029867 -307.750241) (xy 186.030362 -307.774848)
			(xy 186.36921 -307.774848) (xy 186.37317 -307.725794) (xy 186.384947 -307.67801) (xy 186.404238 -307.632734)
			(xy 186.430541 -307.591138) (xy 186.463176 -307.554301) (xy 186.501297 -307.523176) (xy 186.543918 -307.498569)
			(xy 186.589934 -307.481117) (xy 186.638153 -307.471273) (xy 186.687328 -307.469292) (xy 186.736183 -307.475224)
			(xy 186.783454 -307.488916) (xy 186.827916 -307.510014) (xy 186.868419 -307.53797) (xy 186.903912 -307.572062)
			(xy 186.933477 -307.611406) (xy 186.956348 -307.654983) (xy 186.971932 -307.701664) (xy 186.979827 -307.750241)
			(xy 186.980322 -307.774848) (xy 187.31917 -307.774848) (xy 187.32313 -307.725794) (xy 187.334907 -307.67801)
			(xy 187.354198 -307.632734) (xy 187.380501 -307.591138) (xy 187.413136 -307.554301) (xy 187.451257 -307.523176)
			(xy 187.493878 -307.498569) (xy 187.539894 -307.481117) (xy 187.588113 -307.471273) (xy 187.637288 -307.469292)
			(xy 187.686143 -307.475224) (xy 187.733414 -307.488916) (xy 187.777876 -307.510014) (xy 187.818379 -307.53797)
			(xy 187.853872 -307.572062) (xy 187.883437 -307.611406) (xy 187.906308 -307.654983) (xy 187.921892 -307.701664)
			(xy 187.929787 -307.750241) (xy 187.930282 -307.774848) (xy 188.26913 -307.774848) (xy 188.27309 -307.725794)
			(xy 188.284867 -307.67801) (xy 188.304158 -307.632734) (xy 188.330461 -307.591138) (xy 188.363096 -307.554301)
			(xy 188.401217 -307.523176) (xy 188.443838 -307.498569) (xy 188.489854 -307.481117) (xy 188.538073 -307.471273)
			(xy 188.587248 -307.469292) (xy 188.636103 -307.475224) (xy 188.683374 -307.488916) (xy 188.727836 -307.510014)
			(xy 188.768339 -307.53797) (xy 188.803832 -307.572062) (xy 188.833397 -307.611406) (xy 188.856268 -307.654983)
			(xy 188.871852 -307.701664) (xy 188.879747 -307.750241) (xy 188.880242 -307.774848) (xy 188.879747 -307.799455)
			(xy 188.871852 -307.848032) (xy 188.856268 -307.894713) (xy 188.833397 -307.93829) (xy 188.803832 -307.977634)
			(xy 188.768339 -308.011726) (xy 188.727836 -308.039682) (xy 188.683374 -308.06078) (xy 188.636103 -308.074472)
			(xy 188.587248 -308.080404) (xy 188.538073 -308.078423) (xy 188.489854 -308.068579) (xy 188.443838 -308.051127)
			(xy 188.401217 -308.02652) (xy 188.363096 -307.995395) (xy 188.330461 -307.958558) (xy 188.304158 -307.916962)
			(xy 188.284867 -307.871686) (xy 188.27309 -307.823902) (xy 188.26913 -307.774848) (xy 187.930282 -307.774848)
			(xy 187.929787 -307.799455) (xy 187.921892 -307.848032) (xy 187.906308 -307.894713) (xy 187.883437 -307.93829)
			(xy 187.853872 -307.977634) (xy 187.818379 -308.011726) (xy 187.777876 -308.039682) (xy 187.733414 -308.06078)
			(xy 187.686143 -308.074472) (xy 187.637288 -308.080404) (xy 187.588113 -308.078423) (xy 187.539894 -308.068579)
			(xy 187.493878 -308.051127) (xy 187.451257 -308.02652) (xy 187.413136 -307.995395) (xy 187.380501 -307.958558)
			(xy 187.354198 -307.916962) (xy 187.334907 -307.871686) (xy 187.32313 -307.823902) (xy 187.31917 -307.774848)
			(xy 186.980322 -307.774848) (xy 186.979827 -307.799455) (xy 186.971932 -307.848032) (xy 186.956348 -307.894713)
			(xy 186.933477 -307.93829) (xy 186.903912 -307.977634) (xy 186.868419 -308.011726) (xy 186.827916 -308.039682)
			(xy 186.783454 -308.06078) (xy 186.736183 -308.074472) (xy 186.687328 -308.080404) (xy 186.638153 -308.078423)
			(xy 186.589934 -308.068579) (xy 186.543918 -308.051127) (xy 186.501297 -308.02652) (xy 186.463176 -307.995395)
			(xy 186.430541 -307.958558) (xy 186.404238 -307.916962) (xy 186.384947 -307.871686) (xy 186.37317 -307.823902)
			(xy 186.36921 -307.774848) (xy 186.030362 -307.774848) (xy 186.029867 -307.799455) (xy 186.021972 -307.848032)
			(xy 186.006388 -307.894713) (xy 185.983517 -307.93829) (xy 185.953952 -307.977634) (xy 185.918459 -308.011726)
			(xy 185.877956 -308.039682) (xy 185.833494 -308.06078) (xy 185.786223 -308.074472) (xy 185.737368 -308.080404)
			(xy 185.688193 -308.078423) (xy 185.639974 -308.068579) (xy 185.593958 -308.051127) (xy 185.551337 -308.02652)
			(xy 185.513216 -307.995395) (xy 185.480581 -307.958558) (xy 185.454278 -307.916962) (xy 185.434987 -307.871686)
			(xy 185.42321 -307.823902) (xy 185.41925 -307.774848) (xy 185.080148 -307.774848) (xy 185.079653 -307.799455)
			(xy 185.071758 -307.848032) (xy 185.056174 -307.894713) (xy 185.033303 -307.93829) (xy 185.003738 -307.977634)
			(xy 184.968245 -308.011726) (xy 184.927742 -308.039682) (xy 184.88328 -308.06078) (xy 184.836009 -308.074472)
			(xy 184.787154 -308.080404) (xy 184.737979 -308.078423) (xy 184.68976 -308.068579) (xy 184.643744 -308.051127)
			(xy 184.601123 -308.02652) (xy 184.563002 -307.995395) (xy 184.530367 -307.958558) (xy 184.504064 -307.916962)
			(xy 184.484773 -307.871686) (xy 184.472996 -307.823902) (xy 184.469036 -307.774848) (xy 184.130188 -307.774848)
			(xy 184.129693 -307.799455) (xy 184.121798 -307.848032) (xy 184.106214 -307.894713) (xy 184.083343 -307.93829)
			(xy 184.053778 -307.977634) (xy 184.018285 -308.011726) (xy 183.977782 -308.039682) (xy 183.93332 -308.06078)
			(xy 183.886049 -308.074472) (xy 183.837194 -308.080404) (xy 183.788019 -308.078423) (xy 183.7398 -308.068579)
			(xy 183.693784 -308.051127) (xy 183.651163 -308.02652) (xy 183.613042 -307.995395) (xy 183.580407 -307.958558)
			(xy 183.554104 -307.916962) (xy 183.534813 -307.871686) (xy 183.523036 -307.823902) (xy 183.519076 -307.774848)
			(xy 183.180228 -307.774848) (xy 183.179733 -307.799455) (xy 183.171838 -307.848032) (xy 183.156254 -307.894713)
			(xy 183.133383 -307.93829) (xy 183.103818 -307.977634) (xy 183.068325 -308.011726) (xy 183.027822 -308.039682)
			(xy 182.98336 -308.06078) (xy 182.936089 -308.074472) (xy 182.887234 -308.080404) (xy 182.838059 -308.078423)
			(xy 182.78984 -308.068579) (xy 182.743824 -308.051127) (xy 182.701203 -308.02652) (xy 182.663082 -307.995395)
			(xy 182.630447 -307.958558) (xy 182.604144 -307.916962) (xy 182.584853 -307.871686) (xy 182.573076 -307.823902)
			(xy 182.569116 -307.774848) (xy 182.230268 -307.774848) (xy 182.229773 -307.799455) (xy 182.221878 -307.848032)
			(xy 182.206294 -307.894713) (xy 182.183423 -307.93829) (xy 182.153858 -307.977634) (xy 182.118365 -308.011726)
			(xy 182.077862 -308.039682) (xy 182.0334 -308.06078) (xy 181.986129 -308.074472) (xy 181.937274 -308.080404)
			(xy 181.888099 -308.078423) (xy 181.83988 -308.068579) (xy 181.793864 -308.051127) (xy 181.751243 -308.02652)
			(xy 181.713122 -307.995395) (xy 181.680487 -307.958558) (xy 181.654184 -307.916962) (xy 181.634893 -307.871686)
			(xy 181.623116 -307.823902) (xy 181.619156 -307.774848) (xy 181.280308 -307.774848) (xy 181.279813 -307.799455)
			(xy 181.271918 -307.848032) (xy 181.256334 -307.894713) (xy 181.233463 -307.93829) (xy 181.203898 -307.977634)
			(xy 181.168405 -308.011726) (xy 181.127902 -308.039682) (xy 181.08344 -308.06078) (xy 181.036169 -308.074472)
			(xy 180.987314 -308.080404) (xy 180.938139 -308.078423) (xy 180.88992 -308.068579) (xy 180.843904 -308.051127)
			(xy 180.801283 -308.02652) (xy 180.763162 -307.995395) (xy 180.730527 -307.958558) (xy 180.704224 -307.916962)
			(xy 180.684933 -307.871686) (xy 180.673156 -307.823902) (xy 180.669196 -307.774848) (xy 180.330343 -307.774848)
			(xy 180.329853 -307.799201) (xy 180.321958 -307.847778) (xy 180.306374 -307.894459) (xy 180.283503 -307.938036)
			(xy 180.253938 -307.97738) (xy 180.218445 -308.011472) (xy 180.177942 -308.039428) (xy 180.13348 -308.060526)
			(xy 180.086209 -308.074218) (xy 180.037354 -308.08015) (xy 179.988179 -308.078169) (xy 179.93996 -308.068325)
			(xy 179.893944 -308.050873) (xy 179.851323 -308.026266) (xy 179.813202 -307.995141) (xy 179.780567 -307.958304)
			(xy 179.754264 -307.916708) (xy 179.734973 -307.871432) (xy 179.723196 -307.823648) (xy 179.719236 -307.774594)
			(xy 179.380134 -307.774594) (xy 179.379639 -307.799201) (xy 179.371744 -307.847778) (xy 179.35616 -307.894459)
			(xy 179.333289 -307.938036) (xy 179.303724 -307.97738) (xy 179.268231 -308.011472) (xy 179.227728 -308.039428)
			(xy 179.183266 -308.060526) (xy 179.135995 -308.074218) (xy 179.08714 -308.08015) (xy 179.037965 -308.078169)
			(xy 178.989746 -308.068325) (xy 178.94373 -308.050873) (xy 178.901109 -308.026266) (xy 178.862988 -307.995141)
			(xy 178.830353 -307.958304) (xy 178.80405 -307.916708) (xy 178.784759 -307.871432) (xy 178.772982 -307.823648)
			(xy 178.769022 -307.774594) (xy 178.430169 -307.774594) (xy 178.430174 -307.774848) (xy 178.429679 -307.799455)
			(xy 178.421784 -307.848032) (xy 178.4062 -307.894713) (xy 178.383329 -307.93829) (xy 178.353764 -307.977634)
			(xy 178.318271 -308.011726) (xy 178.277768 -308.039682) (xy 178.233306 -308.06078) (xy 178.186035 -308.074472)
			(xy 178.13718 -308.080404) (xy 178.088005 -308.078423) (xy 178.039786 -308.068579) (xy 177.99377 -308.051127)
			(xy 177.951149 -308.02652) (xy 177.913028 -307.995395) (xy 177.880393 -307.958558) (xy 177.85409 -307.916962)
			(xy 177.834799 -307.871686) (xy 177.823022 -307.823902) (xy 177.819062 -307.774848) (xy 177.480214 -307.774848)
			(xy 177.479719 -307.799455) (xy 177.471824 -307.848032) (xy 177.45624 -307.894713) (xy 177.433369 -307.93829)
			(xy 177.403804 -307.977634) (xy 177.368311 -308.011726) (xy 177.327808 -308.039682) (xy 177.283346 -308.06078)
			(xy 177.236075 -308.074472) (xy 177.18722 -308.080404) (xy 177.138045 -308.078423) (xy 177.089826 -308.068579)
			(xy 177.04381 -308.051127) (xy 177.001189 -308.02652) (xy 176.963068 -307.995395) (xy 176.930433 -307.958558)
			(xy 176.90413 -307.916962) (xy 176.884839 -307.871686) (xy 176.873062 -307.823902) (xy 176.869102 -307.774848)
			(xy 176.530254 -307.774848) (xy 176.529759 -307.799455) (xy 176.521864 -307.848032) (xy 176.50628 -307.894713)
			(xy 176.483409 -307.93829) (xy 176.453844 -307.977634) (xy 176.418351 -308.011726) (xy 176.377848 -308.039682)
			(xy 176.333386 -308.06078) (xy 176.286115 -308.074472) (xy 176.23726 -308.080404) (xy 176.188085 -308.078423)
			(xy 176.139866 -308.068579) (xy 176.09385 -308.051127) (xy 176.051229 -308.02652) (xy 176.013108 -307.995395)
			(xy 175.980473 -307.958558) (xy 175.95417 -307.916962) (xy 175.934879 -307.871686) (xy 175.923102 -307.823902)
			(xy 175.919142 -307.774848) (xy 174.630334 -307.774848) (xy 174.629839 -307.799455) (xy 174.621944 -307.848032)
			(xy 174.60636 -307.894713) (xy 174.583489 -307.93829) (xy 174.553924 -307.977634) (xy 174.518431 -308.011726)
			(xy 174.477928 -308.039682) (xy 174.433466 -308.06078) (xy 174.386195 -308.074472) (xy 174.33734 -308.080404)
			(xy 174.288165 -308.078423) (xy 174.239946 -308.068579) (xy 174.19393 -308.051127) (xy 174.151309 -308.02652)
			(xy 174.113188 -307.995395) (xy 174.080553 -307.958558) (xy 174.05425 -307.916962) (xy 174.034959 -307.871686)
			(xy 174.023182 -307.823902) (xy 174.019222 -307.774848) (xy 173.680374 -307.774848) (xy 173.679879 -307.799455)
			(xy 173.671984 -307.848032) (xy 173.6564 -307.894713) (xy 173.633529 -307.93829) (xy 173.603964 -307.977634)
			(xy 173.568471 -308.011726) (xy 173.527968 -308.039682) (xy 173.483506 -308.06078) (xy 173.436235 -308.074472)
			(xy 173.38738 -308.080404) (xy 173.338205 -308.078423) (xy 173.289986 -308.068579) (xy 173.24397 -308.051127)
			(xy 173.201349 -308.02652) (xy 173.163228 -307.995395) (xy 173.130593 -307.958558) (xy 173.10429 -307.916962)
			(xy 173.084999 -307.871686) (xy 173.073222 -307.823902) (xy 173.069262 -307.774848) (xy 172.730414 -307.774848)
			(xy 172.729919 -307.799455) (xy 172.722024 -307.848032) (xy 172.70644 -307.894713) (xy 172.683569 -307.93829)
			(xy 172.654004 -307.977634) (xy 172.618511 -308.011726) (xy 172.578008 -308.039682) (xy 172.533546 -308.06078)
			(xy 172.486275 -308.074472) (xy 172.43742 -308.080404) (xy 172.388245 -308.078423) (xy 172.340026 -308.068579)
			(xy 172.29401 -308.051127) (xy 172.251389 -308.02652) (xy 172.213268 -307.995395) (xy 172.180633 -307.958558)
			(xy 172.15433 -307.916962) (xy 172.135039 -307.871686) (xy 172.123262 -307.823902) (xy 172.119302 -307.774848)
			(xy 171.7802 -307.774848) (xy 171.779705 -307.799455) (xy 171.77181 -307.848032) (xy 171.756226 -307.894713)
			(xy 171.733355 -307.93829) (xy 171.70379 -307.977634) (xy 171.668297 -308.011726) (xy 171.627794 -308.039682)
			(xy 171.583332 -308.06078) (xy 171.536061 -308.074472) (xy 171.487206 -308.080404) (xy 171.438031 -308.078423)
			(xy 171.389812 -308.068579) (xy 171.343796 -308.051127) (xy 171.301175 -308.02652) (xy 171.263054 -307.995395)
			(xy 171.230419 -307.958558) (xy 171.204116 -307.916962) (xy 171.184825 -307.871686) (xy 171.173048 -307.823902)
			(xy 171.169088 -307.774848) (xy 170.83024 -307.774848) (xy 170.829745 -307.799455) (xy 170.82185 -307.848032)
			(xy 170.806266 -307.894713) (xy 170.783395 -307.93829) (xy 170.75383 -307.977634) (xy 170.718337 -308.011726)
			(xy 170.677834 -308.039682) (xy 170.633372 -308.06078) (xy 170.586101 -308.074472) (xy 170.537246 -308.080404)
			(xy 170.488071 -308.078423) (xy 170.439852 -308.068579) (xy 170.393836 -308.051127) (xy 170.351215 -308.02652)
			(xy 170.313094 -307.995395) (xy 170.280459 -307.958558) (xy 170.254156 -307.916962) (xy 170.234865 -307.871686)
			(xy 170.223088 -307.823902) (xy 170.219128 -307.774848) (xy 169.88028 -307.774848) (xy 169.879785 -307.799455)
			(xy 169.87189 -307.848032) (xy 169.856306 -307.894713) (xy 169.833435 -307.93829) (xy 169.80387 -307.977634)
			(xy 169.768377 -308.011726) (xy 169.727874 -308.039682) (xy 169.683412 -308.06078) (xy 169.636141 -308.074472)
			(xy 169.587286 -308.080404) (xy 169.538111 -308.078423) (xy 169.489892 -308.068579) (xy 169.443876 -308.051127)
			(xy 169.401255 -308.02652) (xy 169.363134 -307.995395) (xy 169.330499 -307.958558) (xy 169.304196 -307.916962)
			(xy 169.284905 -307.871686) (xy 169.273128 -307.823902) (xy 169.269168 -307.774848) (xy 168.93032 -307.774848)
			(xy 168.929825 -307.799455) (xy 168.92193 -307.848032) (xy 168.906346 -307.894713) (xy 168.883475 -307.93829)
			(xy 168.85391 -307.977634) (xy 168.818417 -308.011726) (xy 168.777914 -308.039682) (xy 168.733452 -308.06078)
			(xy 168.686181 -308.074472) (xy 168.637326 -308.080404) (xy 168.588151 -308.078423) (xy 168.539932 -308.068579)
			(xy 168.493916 -308.051127) (xy 168.451295 -308.02652) (xy 168.413174 -307.995395) (xy 168.380539 -307.958558)
			(xy 168.354236 -307.916962) (xy 168.334945 -307.871686) (xy 168.323168 -307.823902) (xy 168.319208 -307.774848)
			(xy 167.98036 -307.774848) (xy 167.979865 -307.799455) (xy 167.97197 -307.848032) (xy 167.956386 -307.894713)
			(xy 167.933515 -307.93829) (xy 167.90395 -307.977634) (xy 167.868457 -308.011726) (xy 167.827954 -308.039682)
			(xy 167.783492 -308.06078) (xy 167.736221 -308.074472) (xy 167.687366 -308.080404) (xy 167.638191 -308.078423)
			(xy 167.589972 -308.068579) (xy 167.543956 -308.051127) (xy 167.501335 -308.02652) (xy 167.463214 -307.995395)
			(xy 167.430579 -307.958558) (xy 167.404276 -307.916962) (xy 167.384985 -307.871686) (xy 167.373208 -307.823902)
			(xy 167.369248 -307.774848) (xy 167.0304 -307.774848) (xy 167.029905 -307.799455) (xy 167.02201 -307.848032)
			(xy 167.006426 -307.894713) (xy 166.983555 -307.93829) (xy 166.95399 -307.977634) (xy 166.918497 -308.011726)
			(xy 166.877994 -308.039682) (xy 166.833532 -308.06078) (xy 166.786261 -308.074472) (xy 166.737406 -308.080404)
			(xy 166.688231 -308.078423) (xy 166.640012 -308.068579) (xy 166.593996 -308.051127) (xy 166.551375 -308.02652)
			(xy 166.513254 -307.995395) (xy 166.480619 -307.958558) (xy 166.454316 -307.916962) (xy 166.435025 -307.871686)
			(xy 166.423248 -307.823902) (xy 166.419288 -307.774848) (xy 166.141146 -307.774848) (xy 166.141146 -308.724808)
			(xy 166.419288 -308.724808) (xy 166.423248 -308.675754) (xy 166.435025 -308.62797) (xy 166.454316 -308.582694)
			(xy 166.480619 -308.541098) (xy 166.513254 -308.504261) (xy 166.551375 -308.473136) (xy 166.593996 -308.448529)
			(xy 166.640012 -308.431077) (xy 166.688231 -308.421233) (xy 166.737406 -308.419252) (xy 166.786261 -308.425184)
			(xy 166.833532 -308.438876) (xy 166.877994 -308.459974) (xy 166.918497 -308.48793) (xy 166.95399 -308.522022)
			(xy 166.983555 -308.561366) (xy 167.006426 -308.604943) (xy 167.02201 -308.651624) (xy 167.029905 -308.700201)
			(xy 167.0304 -308.724808) (xy 167.369248 -308.724808) (xy 167.373208 -308.675754) (xy 167.384985 -308.62797)
			(xy 167.404276 -308.582694) (xy 167.430579 -308.541098) (xy 167.463214 -308.504261) (xy 167.501335 -308.473136)
			(xy 167.543956 -308.448529) (xy 167.589972 -308.431077) (xy 167.638191 -308.421233) (xy 167.687366 -308.419252)
			(xy 167.736221 -308.425184) (xy 167.783492 -308.438876) (xy 167.827954 -308.459974) (xy 167.868457 -308.48793)
			(xy 167.90395 -308.522022) (xy 167.933515 -308.561366) (xy 167.956386 -308.604943) (xy 167.97197 -308.651624)
			(xy 167.979865 -308.700201) (xy 167.98036 -308.724808) (xy 168.319208 -308.724808) (xy 168.323168 -308.675754)
			(xy 168.334945 -308.62797) (xy 168.354236 -308.582694) (xy 168.380539 -308.541098) (xy 168.413174 -308.504261)
			(xy 168.451295 -308.473136) (xy 168.493916 -308.448529) (xy 168.539932 -308.431077) (xy 168.588151 -308.421233)
			(xy 168.637326 -308.419252) (xy 168.686181 -308.425184) (xy 168.733452 -308.438876) (xy 168.777914 -308.459974)
			(xy 168.818417 -308.48793) (xy 168.85391 -308.522022) (xy 168.883475 -308.561366) (xy 168.906346 -308.604943)
			(xy 168.92193 -308.651624) (xy 168.929825 -308.700201) (xy 168.93032 -308.724808) (xy 169.269168 -308.724808)
			(xy 169.273128 -308.675754) (xy 169.284905 -308.62797) (xy 169.304196 -308.582694) (xy 169.330499 -308.541098)
			(xy 169.363134 -308.504261) (xy 169.401255 -308.473136) (xy 169.443876 -308.448529) (xy 169.489892 -308.431077)
			(xy 169.538111 -308.421233) (xy 169.587286 -308.419252) (xy 169.636141 -308.425184) (xy 169.683412 -308.438876)
			(xy 169.727874 -308.459974) (xy 169.768377 -308.48793) (xy 169.80387 -308.522022) (xy 169.833435 -308.561366)
			(xy 169.856306 -308.604943) (xy 169.87189 -308.651624) (xy 169.879785 -308.700201) (xy 169.88028 -308.724808)
			(xy 170.219128 -308.724808) (xy 170.223088 -308.675754) (xy 170.234865 -308.62797) (xy 170.254156 -308.582694)
			(xy 170.280459 -308.541098) (xy 170.313094 -308.504261) (xy 170.351215 -308.473136) (xy 170.393836 -308.448529)
			(xy 170.439852 -308.431077) (xy 170.488071 -308.421233) (xy 170.537246 -308.419252) (xy 170.586101 -308.425184)
			(xy 170.633372 -308.438876) (xy 170.677834 -308.459974) (xy 170.718337 -308.48793) (xy 170.75383 -308.522022)
			(xy 170.783395 -308.561366) (xy 170.806266 -308.604943) (xy 170.82185 -308.651624) (xy 170.829745 -308.700201)
			(xy 170.83024 -308.724808) (xy 171.169088 -308.724808) (xy 171.173048 -308.675754) (xy 171.184825 -308.62797)
			(xy 171.204116 -308.582694) (xy 171.230419 -308.541098) (xy 171.263054 -308.504261) (xy 171.301175 -308.473136)
			(xy 171.343796 -308.448529) (xy 171.389812 -308.431077) (xy 171.438031 -308.421233) (xy 171.487206 -308.419252)
			(xy 171.536061 -308.425184) (xy 171.583332 -308.438876) (xy 171.627794 -308.459974) (xy 171.668297 -308.48793)
			(xy 171.70379 -308.522022) (xy 171.733355 -308.561366) (xy 171.756226 -308.604943) (xy 171.77181 -308.651624)
			(xy 171.779705 -308.700201) (xy 171.7802 -308.724808) (xy 172.119302 -308.724808) (xy 172.123262 -308.675754)
			(xy 172.135039 -308.62797) (xy 172.15433 -308.582694) (xy 172.180633 -308.541098) (xy 172.213268 -308.504261)
			(xy 172.251389 -308.473136) (xy 172.29401 -308.448529) (xy 172.340026 -308.431077) (xy 172.388245 -308.421233)
			(xy 172.43742 -308.419252) (xy 172.486275 -308.425184) (xy 172.533546 -308.438876) (xy 172.578008 -308.459974)
			(xy 172.618511 -308.48793) (xy 172.654004 -308.522022) (xy 172.683569 -308.561366) (xy 172.70644 -308.604943)
			(xy 172.722024 -308.651624) (xy 172.729919 -308.700201) (xy 172.730414 -308.724808) (xy 174.019222 -308.724808)
			(xy 174.023182 -308.675754) (xy 174.034959 -308.62797) (xy 174.05425 -308.582694) (xy 174.080553 -308.541098)
			(xy 174.113188 -308.504261) (xy 174.151309 -308.473136) (xy 174.19393 -308.448529) (xy 174.239946 -308.431077)
			(xy 174.288165 -308.421233) (xy 174.33734 -308.419252) (xy 174.386195 -308.425184) (xy 174.433466 -308.438876)
			(xy 174.477928 -308.459974) (xy 174.518431 -308.48793) (xy 174.553924 -308.522022) (xy 174.583489 -308.561366)
			(xy 174.60636 -308.604943) (xy 174.621944 -308.651624) (xy 174.629839 -308.700201) (xy 174.630334 -308.724808)
			(xy 174.629839 -308.749415) (xy 174.621944 -308.797992) (xy 174.60636 -308.844673) (xy 174.583489 -308.88825)
			(xy 174.553924 -308.927594) (xy 174.518431 -308.961686) (xy 174.477928 -308.989642) (xy 174.433466 -309.01074)
			(xy 174.386195 -309.024432) (xy 174.33734 -309.030364) (xy 174.288165 -309.028383) (xy 174.239946 -309.018539)
			(xy 174.19393 -309.001087) (xy 174.151309 -308.97648) (xy 174.113188 -308.945355) (xy 174.080553 -308.908518)
			(xy 174.05425 -308.866922) (xy 174.034959 -308.821646) (xy 174.023182 -308.773862) (xy 174.019222 -308.724808)
			(xy 172.730414 -308.724808) (xy 172.729919 -308.749415) (xy 172.722024 -308.797992) (xy 172.70644 -308.844673)
			(xy 172.683569 -308.88825) (xy 172.654004 -308.927594) (xy 172.618511 -308.961686) (xy 172.578008 -308.989642)
			(xy 172.533546 -309.01074) (xy 172.486275 -309.024432) (xy 172.43742 -309.030364) (xy 172.388245 -309.028383)
			(xy 172.340026 -309.018539) (xy 172.29401 -309.001087) (xy 172.251389 -308.97648) (xy 172.213268 -308.945355)
			(xy 172.180633 -308.908518) (xy 172.15433 -308.866922) (xy 172.135039 -308.821646) (xy 172.123262 -308.773862)
			(xy 172.119302 -308.724808) (xy 171.7802 -308.724808) (xy 171.779705 -308.749415) (xy 171.77181 -308.797992)
			(xy 171.756226 -308.844673) (xy 171.733355 -308.88825) (xy 171.70379 -308.927594) (xy 171.668297 -308.961686)
			(xy 171.627794 -308.989642) (xy 171.583332 -309.01074) (xy 171.536061 -309.024432) (xy 171.487206 -309.030364)
			(xy 171.438031 -309.028383) (xy 171.389812 -309.018539) (xy 171.343796 -309.001087) (xy 171.301175 -308.97648)
			(xy 171.263054 -308.945355) (xy 171.230419 -308.908518) (xy 171.204116 -308.866922) (xy 171.184825 -308.821646)
			(xy 171.173048 -308.773862) (xy 171.169088 -308.724808) (xy 170.83024 -308.724808) (xy 170.829745 -308.749415)
			(xy 170.82185 -308.797992) (xy 170.806266 -308.844673) (xy 170.783395 -308.88825) (xy 170.75383 -308.927594)
			(xy 170.718337 -308.961686) (xy 170.677834 -308.989642) (xy 170.633372 -309.01074) (xy 170.586101 -309.024432)
			(xy 170.537246 -309.030364) (xy 170.488071 -309.028383) (xy 170.439852 -309.018539) (xy 170.393836 -309.001087)
			(xy 170.351215 -308.97648) (xy 170.313094 -308.945355) (xy 170.280459 -308.908518) (xy 170.254156 -308.866922)
			(xy 170.234865 -308.821646) (xy 170.223088 -308.773862) (xy 170.219128 -308.724808) (xy 169.88028 -308.724808)
			(xy 169.879785 -308.749415) (xy 169.87189 -308.797992) (xy 169.856306 -308.844673) (xy 169.833435 -308.88825)
			(xy 169.80387 -308.927594) (xy 169.768377 -308.961686) (xy 169.727874 -308.989642) (xy 169.683412 -309.01074)
			(xy 169.636141 -309.024432) (xy 169.587286 -309.030364) (xy 169.538111 -309.028383) (xy 169.489892 -309.018539)
			(xy 169.443876 -309.001087) (xy 169.401255 -308.97648) (xy 169.363134 -308.945355) (xy 169.330499 -308.908518)
			(xy 169.304196 -308.866922) (xy 169.284905 -308.821646) (xy 169.273128 -308.773862) (xy 169.269168 -308.724808)
			(xy 168.93032 -308.724808) (xy 168.929825 -308.749415) (xy 168.92193 -308.797992) (xy 168.906346 -308.844673)
			(xy 168.883475 -308.88825) (xy 168.85391 -308.927594) (xy 168.818417 -308.961686) (xy 168.777914 -308.989642)
			(xy 168.733452 -309.01074) (xy 168.686181 -309.024432) (xy 168.637326 -309.030364) (xy 168.588151 -309.028383)
			(xy 168.539932 -309.018539) (xy 168.493916 -309.001087) (xy 168.451295 -308.97648) (xy 168.413174 -308.945355)
			(xy 168.380539 -308.908518) (xy 168.354236 -308.866922) (xy 168.334945 -308.821646) (xy 168.323168 -308.773862)
			(xy 168.319208 -308.724808) (xy 167.98036 -308.724808) (xy 167.979865 -308.749415) (xy 167.97197 -308.797992)
			(xy 167.956386 -308.844673) (xy 167.933515 -308.88825) (xy 167.90395 -308.927594) (xy 167.868457 -308.961686)
			(xy 167.827954 -308.989642) (xy 167.783492 -309.01074) (xy 167.736221 -309.024432) (xy 167.687366 -309.030364)
			(xy 167.638191 -309.028383) (xy 167.589972 -309.018539) (xy 167.543956 -309.001087) (xy 167.501335 -308.97648)
			(xy 167.463214 -308.945355) (xy 167.430579 -308.908518) (xy 167.404276 -308.866922) (xy 167.384985 -308.821646)
			(xy 167.373208 -308.773862) (xy 167.369248 -308.724808) (xy 167.0304 -308.724808) (xy 167.029905 -308.749415)
			(xy 167.02201 -308.797992) (xy 167.006426 -308.844673) (xy 166.983555 -308.88825) (xy 166.95399 -308.927594)
			(xy 166.918497 -308.961686) (xy 166.877994 -308.989642) (xy 166.833532 -309.01074) (xy 166.786261 -309.024432)
			(xy 166.737406 -309.030364) (xy 166.688231 -309.028383) (xy 166.640012 -309.018539) (xy 166.593996 -309.001087)
			(xy 166.551375 -308.97648) (xy 166.513254 -308.945355) (xy 166.480619 -308.908518) (xy 166.454316 -308.866922)
			(xy 166.435025 -308.821646) (xy 166.423248 -308.773862) (xy 166.419288 -308.724808) (xy 166.141146 -308.724808)
			(xy 166.141146 -309.22468) (xy 166.141616 -309.234553) (xy 166.149069 -309.252841) (xy 166.155624 -309.26024)
			(xy 166.155878 -309.260494) (xy 166.353744 -309.45836) (xy 166.361176 -309.465155) (xy 166.379789 -309.472802)
			(xy 166.399912 -309.472742) (xy 166.40937 -309.469282) (xy 166.420292 -309.46471) (xy 166.424853 -309.462908)
			(xy 166.434442 -309.460856) (xy 166.439342 -309.460646) (xy 166.450518 -309.460646) (xy 166.460586 -309.460218)
			(xy 166.47918 -309.452493) (xy 166.486586 -309.44566) (xy 166.487348 -309.444898) (xy 166.487602 -309.444644)
			(xy 166.506426 -309.425973) (xy 166.548922 -309.394275) (xy 166.59593 -309.369762) (xy 166.646247 -309.353062)
			(xy 166.698584 -309.344603) (xy 166.725092 -309.34406) (xy 166.750064 -309.344522) (xy 166.799439 -309.352041)
			(xy 166.847124 -309.366893) (xy 166.892035 -309.388743) (xy 166.933153 -309.417093) (xy 166.969544 -309.4513)
			(xy 167.000382 -309.490586) (xy 167.024967 -309.534061) (xy 167.042739 -309.580736) (xy 167.053296 -309.629552)
			(xy 167.055292 -309.654448) (xy 167.056054 -309.667656) (xy 167.089074 -309.719472) (xy 167.089836 -309.720488)
			(xy 167.095932 -309.729632) (xy 167.107108 -309.739284) (xy 167.113966 -309.742078) (xy 167.134236 -309.751173)
			(xy 167.174003 -309.770992) (xy 167.193468 -309.781702) (xy 167.20566 -309.788306) (xy 167.232838 -309.787798)
			(xy 167.288972 -309.753508) (xy 167.320468 -309.734204) (xy 167.327922 -309.729182) (xy 167.339017 -309.715056)
			(xy 167.344586 -309.697979) (xy 167.344598 -309.688992) (xy 167.344598 -309.688738) (xy 167.344344 -309.675276)
			(xy 167.344344 -309.674514) (xy 167.344875 -309.64854) (xy 167.353041 -309.597237) (xy 167.369126 -309.547842)
			(xy 167.392736 -309.501569) (xy 167.42329 -309.459556) (xy 167.460037 -309.422836) (xy 167.502072 -309.392312)
			(xy 167.548362 -309.368735) (xy 167.597769 -309.352685) (xy 167.649078 -309.344556) (xy 167.675052 -309.34406)
			(xy 167.701045 -309.34454) (xy 167.752391 -309.352665) (xy 167.801834 -309.368722) (xy 167.848156 -309.392317)
			(xy 167.890217 -309.422868) (xy 167.92698 -309.459622) (xy 167.957541 -309.501676) (xy 167.981147 -309.547992)
			(xy 167.997217 -309.597431) (xy 168.005354 -309.648775) (xy 168.00576 -309.674768) (xy 168.005506 -309.688738)
			(xy 168.005506 -309.688992) (xy 168.005591 -309.697903) (xy 168.011101 -309.714836) (xy 168.022056 -309.728874)
			(xy 168.029382 -309.73395) (xy 168.08704 -309.769764) (xy 168.087548 -309.769764) (xy 168.104312 -309.780432)
			(xy 168.110288 -309.783941) (xy 168.123554 -309.787934) (xy 168.130474 -309.788306) (xy 168.144444 -309.78856)
			(xy 168.156382 -309.78221) (xy 168.15689 -309.781702) (xy 168.182612 -309.767606) (xy 168.235481 -309.742188)
			(xy 168.262554 -309.730902) (xy 168.271715 -309.726708) (xy 168.286023 -309.712543) (xy 168.293813 -309.693977)
			(xy 168.294304 -309.683912) (xy 168.294304 -309.674768) (xy 168.294816 -309.648783) (xy 168.302951 -309.597453)
			(xy 168.319015 -309.548027) (xy 168.342612 -309.501723) (xy 168.373163 -309.45968) (xy 168.409914 -309.422934)
			(xy 168.451961 -309.392389) (xy 168.498268 -309.368798) (xy 168.547696 -309.35274) (xy 168.599027 -309.344612)
			(xy 168.625012 -309.34406) (xy 168.649983 -309.344524) (xy 168.699356 -309.352045) (xy 168.747038 -309.366899)
			(xy 168.791947 -309.38875) (xy 168.833062 -309.4171) (xy 168.869451 -309.451307) (xy 168.900287 -309.490593)
			(xy 168.924869 -309.534066) (xy 168.94264 -309.58074) (xy 168.953196 -309.629554) (xy 168.955212 -309.654448)
			(xy 168.955974 -309.667656) (xy 168.988994 -309.719472) (xy 168.989756 -309.720488) (xy 168.995852 -309.729632)
			(xy 169.007028 -309.739284) (xy 169.013886 -309.742078) (xy 169.034156 -309.751173) (xy 169.073923 -309.770993)
			(xy 169.093388 -309.781702) (xy 169.10558 -309.788306) (xy 169.132758 -309.787798) (xy 169.188892 -309.753508)
			(xy 169.220388 -309.734204) (xy 169.227839 -309.72918) (xy 169.238931 -309.715054) (xy 169.244497 -309.697978)
			(xy 169.244518 -309.688992) (xy 169.244518 -309.688738) (xy 169.244264 -309.675276) (xy 169.244264 -309.674514)
			(xy 169.244795 -309.648541) (xy 169.252961 -309.597239) (xy 169.269047 -309.547845) (xy 169.292657 -309.501573)
			(xy 169.323211 -309.459562) (xy 169.359958 -309.422844) (xy 169.401994 -309.392322) (xy 169.448284 -309.368748)
			(xy 169.49769 -309.3527) (xy 169.548998 -309.344574) (xy 169.574972 -309.34406) (xy 169.600962 -309.344567)
			(xy 169.652301 -309.352694) (xy 169.701738 -309.368752) (xy 169.748053 -309.392346) (xy 169.790108 -309.422895)
			(xy 169.826866 -309.459646) (xy 169.857422 -309.501695) (xy 169.881025 -309.548007) (xy 169.897092 -309.59744)
			(xy 169.905228 -309.648779) (xy 169.90568 -309.674768) (xy 169.905426 -309.688738) (xy 169.905426 -309.688992)
			(xy 169.905511 -309.697903) (xy 169.911022 -309.714834) (xy 169.92198 -309.728868) (xy 169.929302 -309.73395)
			(xy 169.98696 -309.769764) (xy 169.987468 -309.769764) (xy 170.004232 -309.780432) (xy 170.010209 -309.783939)
			(xy 170.023474 -309.787926) (xy 170.030394 -309.788306) (xy 170.044364 -309.78856) (xy 170.056302 -309.78221)
			(xy 170.05681 -309.781702) (xy 170.082532 -309.767606) (xy 170.135401 -309.742189) (xy 170.162474 -309.730902)
			(xy 170.171633 -309.726706) (xy 170.185934 -309.712539) (xy 170.193721 -309.693975) (xy 170.194224 -309.683912)
			(xy 170.194224 -309.674768) (xy 170.194736 -309.648783) (xy 170.202871 -309.597455) (xy 170.218935 -309.54803)
			(xy 170.242533 -309.501728) (xy 170.273084 -309.459687) (xy 170.309835 -309.422942) (xy 170.351882 -309.392399)
			(xy 170.39819 -309.36881) (xy 170.447617 -309.352756) (xy 170.498947 -309.344631) (xy 170.524932 -309.34406)
			(xy 170.549902 -309.344525) (xy 170.599273 -309.352048) (xy 170.646952 -309.366905) (xy 170.691858 -309.388756)
			(xy 170.732971 -309.417107) (xy 170.769358 -309.451314) (xy 170.800191 -309.490599) (xy 170.824772 -309.534072)
			(xy 170.842541 -309.580744) (xy 170.853097 -309.629556) (xy 170.855132 -309.654448) (xy 170.855894 -309.667656)
			(xy 170.888914 -309.719472) (xy 170.889676 -309.720488) (xy 170.895772 -309.729632) (xy 170.906948 -309.739284)
			(xy 170.913806 -309.742078) (xy 170.934075 -309.751173) (xy 170.973842 -309.770994) (xy 170.993308 -309.781702)
			(xy 171.0055 -309.788306) (xy 171.032678 -309.787798) (xy 171.088812 -309.753508) (xy 171.120308 -309.734204)
			(xy 171.127757 -309.729179) (xy 171.138844 -309.715052) (xy 171.144408 -309.697978) (xy 171.144438 -309.688992)
			(xy 171.144438 -309.688738) (xy 171.144184 -309.675276) (xy 171.144184 -309.674514) (xy 171.144715 -309.648541)
			(xy 171.152881 -309.597241) (xy 171.168967 -309.547848) (xy 171.192578 -309.501578) (xy 171.223133 -309.459568)
			(xy 171.25988 -309.422852) (xy 171.301915 -309.392332) (xy 171.348205 -309.36876) (xy 171.397612 -309.352716)
			(xy 171.448919 -309.344593) (xy 171.474892 -309.34406) (xy 171.500881 -309.344569) (xy 171.552218 -309.352698)
			(xy 171.601652 -309.368758) (xy 171.647964 -309.392353) (xy 171.690016 -309.422902) (xy 171.726772 -309.459653)
			(xy 171.757326 -309.501701) (xy 171.780927 -309.548011) (xy 171.796992 -309.597443) (xy 171.805128 -309.64878)
			(xy 171.8056 -309.674768) (xy 171.805346 -309.688738) (xy 171.805346 -309.688992) (xy 171.80543 -309.697905)
			(xy 171.810936 -309.714843) (xy 171.821884 -309.72889) (xy 171.829222 -309.73395) (xy 171.88688 -309.769764)
			(xy 171.887388 -309.769764) (xy 171.904152 -309.780432) (xy 171.91013 -309.783936) (xy 171.923395 -309.787918)
			(xy 171.930314 -309.788306) (xy 171.944284 -309.78856) (xy 171.956222 -309.78221) (xy 171.95673 -309.781702)
			(xy 171.982453 -309.767607) (xy 172.035322 -309.742191) (xy 172.062394 -309.730902) (xy 172.071564 -309.726715)
			(xy 172.085888 -309.712553) (xy 172.093688 -309.693982) (xy 172.094144 -309.683912) (xy 172.094144 -309.674768)
			(xy 172.094656 -309.648781) (xy 172.10279 -309.597448) (xy 172.118853 -309.548018) (xy 172.14245 -309.50171)
			(xy 172.173 -309.459662) (xy 172.20975 -309.42291) (xy 172.251796 -309.392358) (xy 172.298104 -309.368759)
			(xy 172.347532 -309.352694) (xy 172.398865 -309.344557) (xy 172.424852 -309.34406) (xy 172.450571 -309.344553)
			(xy 172.501388 -309.352524) (xy 172.550358 -309.368267) (xy 172.596301 -309.391401) (xy 172.638108 -309.421369)
			(xy 172.674772 -309.457448) (xy 172.705407 -309.498769) (xy 172.729277 -309.544334) (xy 172.745804 -309.593045)
			(xy 172.754591 -309.643727) (xy 172.75556 -309.669434) (xy 172.755814 -309.68442) (xy 172.77842 -309.718202)
			(xy 172.784008 -309.72506) (xy 172.788072 -309.72887) (xy 172.794676 -309.734458) (xy 172.802042 -309.737506)
			(xy 172.809916 -309.740554) (xy 172.81017 -309.740808) (xy 172.818806 -309.744618) (xy 172.837885 -309.753172)
			(xy 172.875364 -309.77172) (xy 172.893736 -309.781702) (xy 172.905928 -309.788306) (xy 172.932852 -309.787798)
			(xy 172.982636 -309.757572) (xy 172.983144 -309.757572) (xy 173.020482 -309.734458) (xy 173.02794 -309.729437)
			(xy 173.039048 -309.715313) (xy 173.044633 -309.698235) (xy 173.044612 -309.689246) (xy 173.044358 -309.675276)
			(xy 173.044358 -309.674514) (xy 173.044889 -309.648541) (xy 173.053055 -309.597239) (xy 173.069141 -309.547844)
			(xy 173.092751 -309.501572) (xy 173.123305 -309.45956) (xy 173.160052 -309.422841) (xy 173.202087 -309.392319)
			(xy 173.248377 -309.368744) (xy 173.297784 -309.352696) (xy 173.349092 -309.344569) (xy 173.375066 -309.34406)
			(xy 173.401058 -309.344541) (xy 173.452402 -309.352667) (xy 173.501844 -309.368726) (xy 173.548164 -309.392322)
			(xy 173.590223 -309.422873) (xy 173.626984 -309.459627) (xy 173.657544 -309.50168) (xy 173.681149 -309.547995)
			(xy 173.697217 -309.597433) (xy 173.705354 -309.648776) (xy 173.705774 -309.674768) (xy 173.70552 -309.68569)
			(xy 173.70552 -309.69077) (xy 173.706278 -309.703432) (xy 173.718414 -309.725671) (xy 173.728634 -309.733188)
			(xy 173.729142 -309.733696) (xy 173.781212 -309.765954) (xy 173.803564 -309.77967) (xy 173.812043 -309.784333)
			(xy 173.831102 -309.787604) (xy 173.840648 -309.78602) (xy 173.853856 -309.783226) (xy 173.86046 -309.77967)
			(xy 173.891075 -309.763214) (xy 173.954256 -309.73423) (xy 173.986698 -309.721758) (xy 173.996172 -309.717696)
			(xy 174.011071 -309.703477) (xy 174.019203 -309.684556) (xy 174.019718 -309.67426) (xy 174.020229 -309.650297)
			(xy 174.027802 -309.602972) (xy 174.042678 -309.557412) (xy 174.06449 -309.514736) (xy 174.092703 -309.475993)
			(xy 174.126624 -309.442135) (xy 174.16542 -309.413994) (xy 174.208136 -309.392261) (xy 174.253723 -309.377469)
			(xy 174.301062 -309.369984) (xy 174.325026 -309.36946) (xy 174.350897 -309.370006) (xy 174.401899 -309.378728)
			(xy 174.450702 -309.395919) (xy 174.49591 -309.421088) (xy 174.536232 -309.453513) (xy 174.570514 -309.492269)
			(xy 174.597775 -309.536247) (xy 174.617237 -309.58419) (xy 174.628343 -309.634726) (xy 174.63008 -309.660544)
			(xy 174.630334 -309.66791) (xy 174.634906 -309.681118) (xy 174.658782 -309.715408) (xy 174.670212 -309.724552)
			(xy 174.677578 -309.727346) (xy 174.721686 -309.74529) (xy 174.806458 -309.788675) (xy 174.886539 -309.840207)
			(xy 174.924212 -309.869332) (xy 174.93361 -309.875174) (xy 174.956229 -309.886744) (xy 174.997599 -309.91623)
			(xy 175.033517 -309.952157) (xy 175.062993 -309.993533) (xy 175.07458 -310.016144) (xy 175.080422 -310.025542)
			(xy 175.111509 -310.065733) (xy 175.165985 -310.151508) (xy 175.189134 -310.196738) (xy 175.193232 -310.20423)
			(xy 175.205438 -310.216157) (xy 175.21301 -310.220106) (xy 175.233237 -310.22978) (xy 175.272876 -310.250744)
			(xy 175.292258 -310.262016) (xy 175.304704 -310.269128)
		)
		(stroke
			(width 0)
			(type solid)
		)
		(fill yes)
		(layer "In7.Cu")
		(net "P1V25_SERDES_VDDPLL_PEX1")
	)
	(gr_poly
		(pts
			(xy 407.532332 -310.268874) (xy 407.620978 -310.214518) (xy 407.628527 -310.209407) (xy 407.639715 -310.195028)
			(xy 407.645214 -310.177659) (xy 407.645108 -310.168544) (xy 407.645108 -310.16829) (xy 407.6446 -310.149748)
			(xy 407.645043 -310.125753) (xy 407.652543 -310.078352) (xy 407.667368 -310.032708) (xy 407.689151 -309.989946)
			(xy 407.717356 -309.951118) (xy 407.751288 -309.917182) (xy 407.790112 -309.888972) (xy 407.832871 -309.867183)
			(xy 407.878513 -309.852353) (xy 407.925913 -309.844846) (xy 407.949908 -309.84444) (xy 407.963963 -309.844649)
			(xy 407.991947 -309.847322) (xy 408.005788 -309.849774) (xy 408.006296 -309.849774) (xy 408.018525 -309.851262)
			(xy 408.042005 -309.843945) (xy 408.051254 -309.835804) (xy 408.110944 -309.776114) (xy 408.11913 -309.766818)
			(xy 408.126439 -309.743193) (xy 408.124914 -309.730902) (xy 408.122437 -309.717) (xy 408.119764 -309.688887)
			(xy 408.11958 -309.674768) (xy 408.120053 -309.650778) (xy 408.127563 -309.60339) (xy 408.142393 -309.557759)
			(xy 408.164178 -309.51501) (xy 408.192382 -309.476195) (xy 408.22631 -309.442269) (xy 408.265127 -309.414068)
			(xy 408.307878 -309.392285) (xy 408.353509 -309.377458) (xy 408.400898 -309.369951) (xy 408.424888 -309.36946)
			(xy 408.439006 -309.369662) (xy 408.467117 -309.372337) (xy 408.481022 -309.374794) (xy 408.493324 -309.37648)
			(xy 408.517017 -309.369146) (xy 408.526234 -309.360824) (xy 408.585924 -309.301134) (xy 408.594077 -309.291895)
			(xy 408.601388 -309.268405) (xy 408.599894 -309.256176) (xy 408.599894 -309.255668) (xy 408.597442 -309.241891)
			(xy 408.594774 -309.214034) (xy 408.59456 -309.200042) (xy 408.59456 -309.199534) (xy 408.594778 -309.185543)
			(xy 408.597452 -309.157686) (xy 408.599894 -309.143908) (xy 408.599894 -309.1434) (xy 408.601404 -309.131163)
			(xy 408.594121 -309.107649) (xy 408.585924 -309.098442) (xy 408.526234 -309.038752) (xy 408.516994 -309.030602)
			(xy 408.493505 -309.023294) (xy 408.481276 -309.024782) (xy 408.481022 -309.024782) (xy 408.46712 -309.02726)
			(xy 408.439008 -309.029935) (xy 408.424888 -309.030116) (xy 408.400067 -309.029629) (xy 408.351078 -309.021596)
			(xy 408.304034 -309.005743) (xy 408.260175 -308.982488) (xy 408.220656 -308.952444) (xy 408.186518 -308.916402)
			(xy 408.158661 -308.875313) (xy 408.137818 -308.830257) (xy 408.124538 -308.782423) (xy 408.119173 -308.733071)
			(xy 408.121862 -308.683501) (xy 408.132536 -308.635019) (xy 408.150912 -308.588903) (xy 408.176507 -308.546367)
			(xy 408.208646 -308.508532) (xy 408.246483 -308.476395) (xy 408.289021 -308.450803) (xy 408.335139 -308.43243)
			(xy 408.383621 -308.421759) (xy 408.433191 -308.419073) (xy 408.482543 -308.424442) (xy 408.530376 -308.437725)
			(xy 408.57543 -308.45857) (xy 408.616518 -308.48643) (xy 408.652558 -308.520571) (xy 408.682599 -308.560092)
			(xy 408.705851 -308.603953) (xy 408.721701 -308.650997) (xy 408.729731 -308.699987) (xy 408.730196 -308.724808)
			(xy 408.729987 -308.738863) (xy 408.727313 -308.766847) (xy 408.724862 -308.780688) (xy 408.724862 -308.781196)
			(xy 408.723374 -308.793424) (xy 408.730695 -308.816902) (xy 408.738832 -308.826154) (xy 408.798522 -308.885844)
			(xy 408.807764 -308.893983) (xy 408.831249 -308.901266) (xy 408.84348 -308.899814) (xy 408.843734 -308.899814)
			(xy 408.857573 -308.897348) (xy 408.885558 -308.89468) (xy 408.899614 -308.89448) (xy 408.900122 -308.89448)
			(xy 408.914114 -308.894696) (xy 408.941971 -308.897366) (xy 408.955748 -308.899814) (xy 408.956256 -308.899814)
			(xy 408.968489 -308.901311) (xy 408.991986 -308.894012) (xy 409.001214 -308.885844) (xy 409.060904 -308.826154)
			(xy 409.069043 -308.816913) (xy 409.076321 -308.793428) (xy 409.074874 -308.781196) (xy 409.074874 -308.780688)
			(xy 409.072407 -308.766849) (xy 409.069736 -308.738864) (xy 409.06954 -308.724808) (xy 409.070062 -308.699553)
			(xy 409.078375 -308.649731) (xy 409.094776 -308.601957) (xy 409.118817 -308.557534) (xy 409.149841 -308.517674)
			(xy 409.187003 -308.483464) (xy 409.229289 -308.455838) (xy 409.275545 -308.435548) (xy 409.32451 -308.423148)
			(xy 409.374848 -308.418977) (xy 409.425186 -308.423148) (xy 409.474151 -308.435548) (xy 409.520407 -308.455838)
			(xy 409.562693 -308.483464) (xy 409.599855 -308.517674) (xy 409.630879 -308.557534) (xy 409.65492 -308.601957)
			(xy 409.671321 -308.649731) (xy 409.679634 -308.699553) (xy 409.680156 -308.724808) (xy 409.679947 -308.738863)
			(xy 409.677274 -308.766847) (xy 409.674822 -308.780688) (xy 409.674822 -308.781196) (xy 409.673334 -308.793425)
			(xy 409.680651 -308.816905) (xy 409.688792 -308.826154) (xy 409.748482 -308.885844) (xy 409.757723 -308.893991)
			(xy 409.78121 -308.901292) (xy 409.79344 -308.899814) (xy 409.793694 -308.899814) (xy 409.807533 -308.897347)
			(xy 409.835518 -308.894674) (xy 409.849574 -308.89448) (xy 409.850082 -308.89448) (xy 409.864074 -308.894694)
			(xy 409.891931 -308.89736) (xy 409.905708 -308.899814) (xy 409.906216 -308.899814) (xy 409.918452 -308.901321)
			(xy 409.941962 -308.894035) (xy 409.951174 -308.885844) (xy 410.010864 -308.826154) (xy 410.018995 -308.81691)
			(xy 410.026264 -308.793428) (xy 410.024834 -308.781196) (xy 410.024834 -308.780688) (xy 410.022367 -308.766849)
			(xy 410.019697 -308.738864) (xy 410.0195 -308.724808) (xy 410.019985 -308.699988) (xy 410.028015 -308.651001)
			(xy 410.043864 -308.603959) (xy 410.067115 -308.5601) (xy 410.097155 -308.520581) (xy 410.133193 -308.486442)
			(xy 410.174279 -308.458584) (xy 410.219331 -308.437739) (xy 410.267161 -308.424458) (xy 410.31651 -308.419089)
			(xy 410.366078 -308.421776) (xy 410.414558 -308.432445) (xy 410.460674 -308.450818) (xy 410.503209 -308.476409)
			(xy 410.541044 -308.508545) (xy 410.573181 -308.546378) (xy 410.598775 -308.588912) (xy 410.61715 -308.635026)
			(xy 410.627822 -308.683506) (xy 410.630049 -308.724554) (xy 410.968964 -308.724554) (xy 410.972924 -308.6755)
			(xy 410.984701 -308.627716) (xy 411.003992 -308.58244) (xy 411.030295 -308.540844) (xy 411.06293 -308.504007)
			(xy 411.101051 -308.472882) (xy 411.143672 -308.448275) (xy 411.189688 -308.430823) (xy 411.237907 -308.420979)
			(xy 411.287082 -308.418998) (xy 411.335937 -308.42493) (xy 411.383208 -308.438622) (xy 411.42767 -308.45972)
			(xy 411.468173 -308.487676) (xy 411.503666 -308.521768) (xy 411.533231 -308.561112) (xy 411.556102 -308.604689)
			(xy 411.571686 -308.65137) (xy 411.579581 -308.699947) (xy 411.580076 -308.724554) (xy 411.580071 -308.724808)
			(xy 411.919178 -308.724808) (xy 411.923138 -308.675754) (xy 411.934915 -308.62797) (xy 411.954206 -308.582694)
			(xy 411.980509 -308.541098) (xy 412.013144 -308.504261) (xy 412.051265 -308.473136) (xy 412.093886 -308.448529)
			(xy 412.139902 -308.431077) (xy 412.188121 -308.421233) (xy 412.237296 -308.419252) (xy 412.286151 -308.425184)
			(xy 412.333422 -308.438876) (xy 412.377884 -308.459974) (xy 412.418387 -308.48793) (xy 412.45388 -308.522022)
			(xy 412.483445 -308.561366) (xy 412.506316 -308.604943) (xy 412.5219 -308.651624) (xy 412.529795 -308.700201)
			(xy 412.53029 -308.724808) (xy 412.869138 -308.724808) (xy 412.873098 -308.675754) (xy 412.884875 -308.62797)
			(xy 412.904166 -308.582694) (xy 412.930469 -308.541098) (xy 412.963104 -308.504261) (xy 413.001225 -308.473136)
			(xy 413.043846 -308.448529) (xy 413.089862 -308.431077) (xy 413.138081 -308.421233) (xy 413.187256 -308.419252)
			(xy 413.236111 -308.425184) (xy 413.283382 -308.438876) (xy 413.327844 -308.459974) (xy 413.368347 -308.48793)
			(xy 413.40384 -308.522022) (xy 413.433405 -308.561366) (xy 413.456276 -308.604943) (xy 413.47186 -308.651624)
			(xy 413.479755 -308.700201) (xy 413.48025 -308.724808) (xy 413.819098 -308.724808) (xy 413.823058 -308.675754)
			(xy 413.834835 -308.62797) (xy 413.854126 -308.582694) (xy 413.880429 -308.541098) (xy 413.913064 -308.504261)
			(xy 413.951185 -308.473136) (xy 413.993806 -308.448529) (xy 414.039822 -308.431077) (xy 414.088041 -308.421233)
			(xy 414.137216 -308.419252) (xy 414.186071 -308.425184) (xy 414.233342 -308.438876) (xy 414.277804 -308.459974)
			(xy 414.318307 -308.48793) (xy 414.3538 -308.522022) (xy 414.383365 -308.561366) (xy 414.406236 -308.604943)
			(xy 414.42182 -308.651624) (xy 414.429715 -308.700201) (xy 414.43021 -308.724808) (xy 414.769058 -308.724808)
			(xy 414.773018 -308.675754) (xy 414.784795 -308.62797) (xy 414.804086 -308.582694) (xy 414.830389 -308.541098)
			(xy 414.863024 -308.504261) (xy 414.901145 -308.473136) (xy 414.943766 -308.448529) (xy 414.989782 -308.431077)
			(xy 415.038001 -308.421233) (xy 415.087176 -308.419252) (xy 415.136031 -308.425184) (xy 415.183302 -308.438876)
			(xy 415.227764 -308.459974) (xy 415.268267 -308.48793) (xy 415.30376 -308.522022) (xy 415.333325 -308.561366)
			(xy 415.356196 -308.604943) (xy 415.37178 -308.651624) (xy 415.379675 -308.700201) (xy 415.38017 -308.724808)
			(xy 415.719018 -308.724808) (xy 415.722978 -308.675754) (xy 415.734755 -308.62797) (xy 415.754046 -308.582694)
			(xy 415.780349 -308.541098) (xy 415.812984 -308.504261) (xy 415.851105 -308.473136) (xy 415.893726 -308.448529)
			(xy 415.939742 -308.431077) (xy 415.987961 -308.421233) (xy 416.037136 -308.419252) (xy 416.085991 -308.425184)
			(xy 416.133262 -308.438876) (xy 416.177724 -308.459974) (xy 416.218227 -308.48793) (xy 416.25372 -308.522022)
			(xy 416.283285 -308.561366) (xy 416.306156 -308.604943) (xy 416.32174 -308.651624) (xy 416.329635 -308.700201)
			(xy 416.33013 -308.724808) (xy 416.669232 -308.724808) (xy 416.673192 -308.675754) (xy 416.684969 -308.62797)
			(xy 416.70426 -308.582694) (xy 416.730563 -308.541098) (xy 416.763198 -308.504261) (xy 416.801319 -308.473136)
			(xy 416.84394 -308.448529) (xy 416.889956 -308.431077) (xy 416.938175 -308.421233) (xy 416.98735 -308.419252)
			(xy 417.036205 -308.425184) (xy 417.083476 -308.438876) (xy 417.127938 -308.459974) (xy 417.168441 -308.48793)
			(xy 417.203934 -308.522022) (xy 417.233499 -308.561366) (xy 417.25637 -308.604943) (xy 417.271954 -308.651624)
			(xy 417.279849 -308.700201) (xy 417.280344 -308.724808) (xy 417.619192 -308.724808) (xy 417.623152 -308.675754)
			(xy 417.634929 -308.62797) (xy 417.65422 -308.582694) (xy 417.680523 -308.541098) (xy 417.713158 -308.504261)
			(xy 417.751279 -308.473136) (xy 417.7939 -308.448529) (xy 417.839916 -308.431077) (xy 417.888135 -308.421233)
			(xy 417.93731 -308.419252) (xy 417.986165 -308.425184) (xy 418.033436 -308.438876) (xy 418.077898 -308.459974)
			(xy 418.118401 -308.48793) (xy 418.153894 -308.522022) (xy 418.183459 -308.561366) (xy 418.20633 -308.604943)
			(xy 418.221914 -308.651624) (xy 418.229809 -308.700201) (xy 418.230304 -308.724808) (xy 418.569152 -308.724808)
			(xy 418.573112 -308.675754) (xy 418.584889 -308.62797) (xy 418.60418 -308.582694) (xy 418.630483 -308.541098)
			(xy 418.663118 -308.504261) (xy 418.701239 -308.473136) (xy 418.74386 -308.448529) (xy 418.789876 -308.431077)
			(xy 418.838095 -308.421233) (xy 418.88727 -308.419252) (xy 418.936125 -308.425184) (xy 418.983396 -308.438876)
			(xy 419.027858 -308.459974) (xy 419.068361 -308.48793) (xy 419.103854 -308.522022) (xy 419.133419 -308.561366)
			(xy 419.15629 -308.604943) (xy 419.171874 -308.651624) (xy 419.179769 -308.700201) (xy 419.180264 -308.724808)
			(xy 419.519112 -308.724808) (xy 419.523072 -308.675754) (xy 419.534849 -308.62797) (xy 419.55414 -308.582694)
			(xy 419.580443 -308.541098) (xy 419.613078 -308.504261) (xy 419.651199 -308.473136) (xy 419.69382 -308.448529)
			(xy 419.739836 -308.431077) (xy 419.788055 -308.421233) (xy 419.83723 -308.419252) (xy 419.886085 -308.425184)
			(xy 419.933356 -308.438876) (xy 419.977818 -308.459974) (xy 420.018321 -308.48793) (xy 420.053814 -308.522022)
			(xy 420.083379 -308.561366) (xy 420.10625 -308.604943) (xy 420.121834 -308.651624) (xy 420.129729 -308.700201)
			(xy 420.130224 -308.724808) (xy 420.469072 -308.724808) (xy 420.473032 -308.675754) (xy 420.484809 -308.62797)
			(xy 420.5041 -308.582694) (xy 420.530403 -308.541098) (xy 420.563038 -308.504261) (xy 420.601159 -308.473136)
			(xy 420.64378 -308.448529) (xy 420.689796 -308.431077) (xy 420.738015 -308.421233) (xy 420.78719 -308.419252)
			(xy 420.836045 -308.425184) (xy 420.883316 -308.438876) (xy 420.927778 -308.459974) (xy 420.968281 -308.48793)
			(xy 421.003774 -308.522022) (xy 421.033339 -308.561366) (xy 421.05621 -308.604943) (xy 421.071794 -308.651624)
			(xy 421.079689 -308.700201) (xy 421.080184 -308.724808) (xy 421.079689 -308.749415) (xy 421.071794 -308.797992)
			(xy 421.05621 -308.844673) (xy 421.033339 -308.88825) (xy 421.003774 -308.927594) (xy 420.968281 -308.961686)
			(xy 420.927778 -308.989642) (xy 420.883316 -309.01074) (xy 420.836045 -309.024432) (xy 420.78719 -309.030364)
			(xy 420.738015 -309.028383) (xy 420.689796 -309.018539) (xy 420.64378 -309.001087) (xy 420.601159 -308.97648)
			(xy 420.563038 -308.945355) (xy 420.530403 -308.908518) (xy 420.5041 -308.866922) (xy 420.484809 -308.821646)
			(xy 420.473032 -308.773862) (xy 420.469072 -308.724808) (xy 420.130224 -308.724808) (xy 420.129729 -308.749415)
			(xy 420.121834 -308.797992) (xy 420.10625 -308.844673) (xy 420.083379 -308.88825) (xy 420.053814 -308.927594)
			(xy 420.018321 -308.961686) (xy 419.977818 -308.989642) (xy 419.933356 -309.01074) (xy 419.886085 -309.024432)
			(xy 419.83723 -309.030364) (xy 419.788055 -309.028383) (xy 419.739836 -309.018539) (xy 419.69382 -309.001087)
			(xy 419.651199 -308.97648) (xy 419.613078 -308.945355) (xy 419.580443 -308.908518) (xy 419.55414 -308.866922)
			(xy 419.534849 -308.821646) (xy 419.523072 -308.773862) (xy 419.519112 -308.724808) (xy 419.180264 -308.724808)
			(xy 419.179769 -308.749415) (xy 419.171874 -308.797992) (xy 419.15629 -308.844673) (xy 419.133419 -308.88825)
			(xy 419.103854 -308.927594) (xy 419.068361 -308.961686) (xy 419.027858 -308.989642) (xy 418.983396 -309.01074)
			(xy 418.936125 -309.024432) (xy 418.88727 -309.030364) (xy 418.838095 -309.028383) (xy 418.789876 -309.018539)
			(xy 418.74386 -309.001087) (xy 418.701239 -308.97648) (xy 418.663118 -308.945355) (xy 418.630483 -308.908518)
			(xy 418.60418 -308.866922) (xy 418.584889 -308.821646) (xy 418.573112 -308.773862) (xy 418.569152 -308.724808)
			(xy 418.230304 -308.724808) (xy 418.229809 -308.749415) (xy 418.221914 -308.797992) (xy 418.20633 -308.844673)
			(xy 418.183459 -308.88825) (xy 418.153894 -308.927594) (xy 418.118401 -308.961686) (xy 418.077898 -308.989642)
			(xy 418.033436 -309.01074) (xy 417.986165 -309.024432) (xy 417.93731 -309.030364) (xy 417.888135 -309.028383)
			(xy 417.839916 -309.018539) (xy 417.7939 -309.001087) (xy 417.751279 -308.97648) (xy 417.713158 -308.945355)
			(xy 417.680523 -308.908518) (xy 417.65422 -308.866922) (xy 417.634929 -308.821646) (xy 417.623152 -308.773862)
			(xy 417.619192 -308.724808) (xy 417.280344 -308.724808) (xy 417.279849 -308.749415) (xy 417.271954 -308.797992)
			(xy 417.25637 -308.844673) (xy 417.233499 -308.88825) (xy 417.203934 -308.927594) (xy 417.168441 -308.961686)
			(xy 417.127938 -308.989642) (xy 417.083476 -309.01074) (xy 417.036205 -309.024432) (xy 416.98735 -309.030364)
			(xy 416.938175 -309.028383) (xy 416.889956 -309.018539) (xy 416.84394 -309.001087) (xy 416.801319 -308.97648)
			(xy 416.763198 -308.945355) (xy 416.730563 -308.908518) (xy 416.70426 -308.866922) (xy 416.684969 -308.821646)
			(xy 416.673192 -308.773862) (xy 416.669232 -308.724808) (xy 416.33013 -308.724808) (xy 416.329635 -308.749415)
			(xy 416.32174 -308.797992) (xy 416.306156 -308.844673) (xy 416.283285 -308.88825) (xy 416.25372 -308.927594)
			(xy 416.218227 -308.961686) (xy 416.177724 -308.989642) (xy 416.133262 -309.01074) (xy 416.085991 -309.024432)
			(xy 416.037136 -309.030364) (xy 415.987961 -309.028383) (xy 415.939742 -309.018539) (xy 415.893726 -309.001087)
			(xy 415.851105 -308.97648) (xy 415.812984 -308.945355) (xy 415.780349 -308.908518) (xy 415.754046 -308.866922)
			(xy 415.734755 -308.821646) (xy 415.722978 -308.773862) (xy 415.719018 -308.724808) (xy 415.38017 -308.724808)
			(xy 415.379675 -308.749415) (xy 415.37178 -308.797992) (xy 415.356196 -308.844673) (xy 415.333325 -308.88825)
			(xy 415.30376 -308.927594) (xy 415.268267 -308.961686) (xy 415.227764 -308.989642) (xy 415.183302 -309.01074)
			(xy 415.136031 -309.024432) (xy 415.087176 -309.030364) (xy 415.038001 -309.028383) (xy 414.989782 -309.018539)
			(xy 414.943766 -309.001087) (xy 414.901145 -308.97648) (xy 414.863024 -308.945355) (xy 414.830389 -308.908518)
			(xy 414.804086 -308.866922) (xy 414.784795 -308.821646) (xy 414.773018 -308.773862) (xy 414.769058 -308.724808)
			(xy 414.43021 -308.724808) (xy 414.429715 -308.749415) (xy 414.42182 -308.797992) (xy 414.406236 -308.844673)
			(xy 414.383365 -308.88825) (xy 414.3538 -308.927594) (xy 414.318307 -308.961686) (xy 414.277804 -308.989642)
			(xy 414.233342 -309.01074) (xy 414.186071 -309.024432) (xy 414.137216 -309.030364) (xy 414.088041 -309.028383)
			(xy 414.039822 -309.018539) (xy 413.993806 -309.001087) (xy 413.951185 -308.97648) (xy 413.913064 -308.945355)
			(xy 413.880429 -308.908518) (xy 413.854126 -308.866922) (xy 413.834835 -308.821646) (xy 413.823058 -308.773862)
			(xy 413.819098 -308.724808) (xy 413.48025 -308.724808) (xy 413.479755 -308.749415) (xy 413.47186 -308.797992)
			(xy 413.456276 -308.844673) (xy 413.433405 -308.88825) (xy 413.40384 -308.927594) (xy 413.368347 -308.961686)
			(xy 413.327844 -308.989642) (xy 413.283382 -309.01074) (xy 413.236111 -309.024432) (xy 413.187256 -309.030364)
			(xy 413.138081 -309.028383) (xy 413.089862 -309.018539) (xy 413.043846 -309.001087) (xy 413.001225 -308.97648)
			(xy 412.963104 -308.945355) (xy 412.930469 -308.908518) (xy 412.904166 -308.866922) (xy 412.884875 -308.821646)
			(xy 412.873098 -308.773862) (xy 412.869138 -308.724808) (xy 412.53029 -308.724808) (xy 412.529795 -308.749415)
			(xy 412.5219 -308.797992) (xy 412.506316 -308.844673) (xy 412.483445 -308.88825) (xy 412.45388 -308.927594)
			(xy 412.418387 -308.961686) (xy 412.377884 -308.989642) (xy 412.333422 -309.01074) (xy 412.286151 -309.024432)
			(xy 412.237296 -309.030364) (xy 412.188121 -309.028383) (xy 412.139902 -309.018539) (xy 412.093886 -309.001087)
			(xy 412.051265 -308.97648) (xy 412.013144 -308.945355) (xy 411.980509 -308.908518) (xy 411.954206 -308.866922)
			(xy 411.934915 -308.821646) (xy 411.923138 -308.773862) (xy 411.919178 -308.724808) (xy 411.580071 -308.724808)
			(xy 411.579581 -308.749161) (xy 411.571686 -308.797738) (xy 411.556102 -308.844419) (xy 411.533231 -308.887996)
			(xy 411.503666 -308.92734) (xy 411.468173 -308.961432) (xy 411.42767 -308.989388) (xy 411.383208 -309.010486)
			(xy 411.335937 -309.024178) (xy 411.287082 -309.03011) (xy 411.237907 -309.028129) (xy 411.189688 -309.018285)
			(xy 411.143672 -309.000833) (xy 411.101051 -308.976226) (xy 411.06293 -308.945101) (xy 411.030295 -308.908264)
			(xy 411.003992 -308.866668) (xy 410.984701 -308.821392) (xy 410.972924 -308.773608) (xy 410.968964 -308.724554)
			(xy 410.630049 -308.724554) (xy 410.630511 -308.733073) (xy 410.625145 -308.782423) (xy 410.611866 -308.830254)
			(xy 410.591024 -308.875307) (xy 410.563168 -308.916395) (xy 410.529031 -308.952435) (xy 410.489513 -308.982477)
			(xy 410.445656 -309.00573) (xy 410.398614 -309.021581) (xy 410.349628 -309.029613) (xy 410.324808 -309.030116)
			(xy 410.310753 -309.029908) (xy 410.282769 -309.027236) (xy 410.268928 -309.024782) (xy 410.26842 -309.024782)
			(xy 410.256189 -309.02329) (xy 410.2327 -309.030597) (xy 410.223462 -309.038752) (xy 410.163772 -309.098442)
			(xy 410.155635 -309.107684) (xy 410.148359 -309.131168) (xy 410.149802 -309.1434) (xy 410.149802 -309.143908)
			(xy 410.152255 -309.157685) (xy 410.154926 -309.185542) (xy 410.155136 -309.199534) (xy 410.155136 -309.200042)
			(xy 410.15492 -309.214033) (xy 410.152248 -309.24189) (xy 410.149802 -309.255668) (xy 410.149802 -309.256176)
			(xy 410.14831 -309.268407) (xy 410.155617 -309.291896) (xy 410.163772 -309.301134) (xy 410.223462 -309.360824)
			(xy 410.23276 -309.369005) (xy 410.256383 -309.376312) (xy 410.268674 -309.374794) (xy 410.282576 -309.372316)
			(xy 410.310688 -309.369641) (xy 410.324808 -309.36946) (xy 410.348736 -309.369926) (xy 410.396007 -309.377394)
			(xy 410.441533 -309.392144) (xy 410.484201 -309.413817) (xy 410.522966 -309.441881) (xy 410.556877 -309.475649)
			(xy 410.585105 -309.514294) (xy 410.606958 -309.55687) (xy 410.621902 -309.602333) (xy 410.62957 -309.649572)
			(xy 410.630116 -309.673498) (xy 410.630116 -309.675276) (xy 410.629354 -309.698898) (xy 410.6291 -309.700676)
			(xy 410.6291 -309.703978) (xy 410.629396 -309.712565) (xy 410.635003 -309.728795) (xy 410.645662 -309.742258)
			(xy 410.652722 -309.747158) (xy 410.727144 -309.793894) (xy 410.736624 -309.799293) (xy 410.758207 -309.802338)
			(xy 410.7688 -309.799736) (xy 410.780484 -309.796434) (xy 410.786072 -309.793132) (xy 410.818873 -309.774311)
			(xy 410.886897 -309.741255) (xy 410.921962 -309.727092) (xy 410.929074 -309.724298) (xy 410.940504 -309.715408)
			(xy 410.964634 -309.681118) (xy 410.96946 -309.66791) (xy 410.969714 -309.66029) (xy 410.971478 -309.634484)
			(xy 410.982592 -309.583972) (xy 411.00206 -309.536055) (xy 411.029326 -309.492105) (xy 411.063609 -309.453379)
			(xy 411.103928 -309.420985) (xy 411.14913 -309.395849) (xy 411.197922 -309.378692) (xy 411.248907 -309.370003)
			(xy 411.274768 -309.36946) (xy 411.300637 -309.370009) (xy 411.351633 -309.378737) (xy 411.40043 -309.395932)
			(xy 411.445632 -309.421102) (xy 411.485948 -309.453528) (xy 411.520224 -309.492283) (xy 411.547481 -309.536259)
			(xy 411.56694 -309.584198) (xy 411.578044 -309.63473) (xy 411.579822 -309.660544) (xy 411.580076 -309.668164)
			(xy 411.584902 -309.681626) (xy 411.608524 -309.7149) (xy 411.620208 -309.724044) (xy 411.627066 -309.726838)
			(xy 411.661726 -309.740862) (xy 411.728987 -309.773534) (xy 411.761432 -309.792116) (xy 411.767274 -309.795672)
			(xy 411.783276 -309.79999) (xy 411.793501 -309.802124) (xy 411.814109 -309.79886) (xy 411.823154 -309.79364)
			(xy 411.86608 -309.766716) (xy 411.891988 -309.750206) (xy 411.894528 -309.748682) (xy 411.90799 -309.741316)
			(xy 411.922214 -309.714392) (xy 411.920436 -309.697882) (xy 411.919674 -309.676292) (xy 411.919674 -309.673752)
			(xy 411.920275 -309.648552) (xy 411.928719 -309.59886) (xy 411.945211 -309.55123) (xy 411.969301 -309.506956)
			(xy 412.000337 -309.467239) (xy 412.037474 -309.43316) (xy 412.079704 -309.405643) (xy 412.125881 -309.385437)
			(xy 412.174749 -309.373089) (xy 412.224982 -309.368935) (xy 412.275215 -309.373089) (xy 412.324083 -309.385437)
			(xy 412.37026 -309.405643) (xy 412.41249 -309.43316) (xy 412.449627 -309.467239) (xy 412.480663 -309.506956)
			(xy 412.504753 -309.55123) (xy 412.521245 -309.59886) (xy 412.529689 -309.648552) (xy 412.53029 -309.673752)
			(xy 412.53029 -309.675022) (xy 412.529274 -309.700168) (xy 412.529274 -309.700422) (xy 412.528258 -309.715662)
			(xy 412.542482 -309.74157) (xy 412.555436 -309.748682) (xy 412.557976 -309.750206) (xy 412.602426 -309.7784)
			(xy 412.602934 -309.7784) (xy 412.628334 -309.794148) (xy 412.637367 -309.799223) (xy 412.657823 -309.802388)
			(xy 412.667958 -309.800244) (xy 412.68015 -309.796942) (xy 412.6865 -309.793132) (xy 412.722623 -309.772469)
			(xy 412.797786 -309.736732) (xy 412.836614 -309.721758) (xy 412.846086 -309.717694) (xy 412.86098 -309.703474)
			(xy 412.869109 -309.684554) (xy 412.869634 -309.67426) (xy 412.870195 -309.649032) (xy 412.878574 -309.599275)
			(xy 412.895021 -309.551574) (xy 412.919086 -309.507225) (xy 412.950116 -309.467437) (xy 412.987266 -309.433292)
			(xy 413.029524 -309.405721) (xy 413.07574 -309.385473) (xy 413.124657 -309.373099) (xy 413.174942 -309.368937)
			(xy 413.225227 -309.373099) (xy 413.274144 -309.385473) (xy 413.32036 -309.405721) (xy 413.362618 -309.433292)
			(xy 413.399768 -309.467437) (xy 413.430798 -309.507225) (xy 413.454863 -309.551574) (xy 413.47131 -309.599275)
			(xy 413.479689 -309.649032) (xy 413.48025 -309.67426) (xy 413.480727 -309.684563) (xy 413.488848 -309.703502)
			(xy 413.503788 -309.717694) (xy 413.51327 -309.721758) (xy 413.543826 -309.733437) (xy 413.603442 -309.760383)
			(xy 413.632396 -309.775606) (xy 413.63265 -309.77586) (xy 413.638492 -309.778908) (xy 413.65043 -309.781956)
			(xy 413.678878 -309.781956) (xy 413.685919 -309.781737) (xy 413.699459 -309.777876) (xy 413.705548 -309.774336)
			(xy 413.770318 -309.734204) (xy 413.777479 -309.729372) (xy 413.788313 -309.715929) (xy 413.794076 -309.699655)
			(xy 413.794448 -309.691024) (xy 413.794448 -309.684674) (xy 413.794194 -309.675022) (xy 413.794194 -309.674514)
			(xy 413.794725 -309.648542) (xy 413.802891 -309.597242) (xy 413.818977 -309.54785) (xy 413.842588 -309.50158)
			(xy 413.873143 -309.459571) (xy 413.90989 -309.422856) (xy 413.951926 -309.392338) (xy 413.998216 -309.368767)
			(xy 414.047622 -309.352724) (xy 414.098929 -309.344602) (xy 414.124902 -309.34406) (xy 414.15089 -309.34457)
			(xy 414.202226 -309.3527) (xy 414.251658 -309.368761) (xy 414.29797 -309.392356) (xy 414.340021 -309.422906)
			(xy 414.376775 -309.459657) (xy 414.407328 -309.501704) (xy 414.430927 -309.548014) (xy 414.446993 -309.597445)
			(xy 414.455128 -309.64878) (xy 414.45561 -309.674768) (xy 414.455356 -309.684674) (xy 414.455356 -309.691024)
			(xy 414.455689 -309.699666) (xy 414.461433 -309.715966) (xy 414.472287 -309.729414) (xy 414.479486 -309.734204)
			(xy 414.553146 -309.77967) (xy 414.553908 -309.780178) (xy 414.563085 -309.785058) (xy 414.583681 -309.787688)
			(xy 414.593786 -309.785258) (xy 414.60039 -309.78348) (xy 414.609788 -309.77967) (xy 414.612582 -309.778146)
			(xy 414.636932 -309.765152) (xy 414.686874 -309.741643) (xy 414.712404 -309.731156) (xy 414.721578 -309.726971)
			(xy 414.735915 -309.712811) (xy 414.743732 -309.694239) (xy 414.744154 -309.684166) (xy 414.744154 -309.674768)
			(xy 414.744664 -309.648781) (xy 414.752794 -309.597446) (xy 414.768855 -309.548016) (xy 414.792451 -309.501706)
			(xy 414.823001 -309.459658) (xy 414.859752 -309.422907) (xy 414.9018 -309.392357) (xy 414.94811 -309.368761)
			(xy 414.99754 -309.3527) (xy 415.048875 -309.34457) (xy 415.100849 -309.34457) (xy 415.152184 -309.3527)
			(xy 415.201614 -309.368761) (xy 415.247924 -309.392357) (xy 415.289972 -309.422907) (xy 415.326723 -309.459658)
			(xy 415.357273 -309.501706) (xy 415.380869 -309.548016) (xy 415.39693 -309.597446) (xy 415.40506 -309.648781)
			(xy 415.40557 -309.674768) (xy 415.40557 -309.682642) (xy 415.405062 -309.694326) (xy 415.414968 -309.715916)
			(xy 415.430208 -309.728108) (xy 415.437574 -309.731156) (xy 415.437828 -309.731156) (xy 415.46497 -309.742428)
			(xy 415.517966 -309.767846) (xy 415.543746 -309.781956) (xy 415.554668 -309.786528) (xy 415.566098 -309.789576)
			(xy 415.59226 -309.78475) (xy 415.596673 -309.783824) (xy 415.605107 -309.780634) (xy 415.609024 -309.7784)
			(xy 415.61639 -309.773828) (xy 415.622232 -309.76697) (xy 415.622486 -309.766716) (xy 415.625049 -309.763737)
			(xy 415.63092 -309.758513) (xy 415.63417 -309.756302) (xy 415.670238 -309.73395) (xy 415.671508 -309.733188)
			(xy 415.671762 -309.732934) (xy 415.681827 -309.725418) (xy 415.693693 -309.703312) (xy 415.694368 -309.69077)
			(xy 415.694368 -309.68442) (xy 415.694114 -309.675022) (xy 415.694114 -309.674514) (xy 415.694645 -309.648542)
			(xy 415.702811 -309.597244) (xy 415.718898 -309.547853) (xy 415.742509 -309.501584) (xy 415.773064 -309.459577)
			(xy 415.809812 -309.422864) (xy 415.851847 -309.392348) (xy 415.898138 -309.36878) (xy 415.947543 -309.352739)
			(xy 415.99885 -309.344621) (xy 416.024822 -309.34406) (xy 416.050809 -309.344571) (xy 416.102143 -309.352704)
			(xy 416.151572 -309.368767) (xy 416.197881 -309.392363) (xy 416.239929 -309.422913) (xy 416.276681 -309.459663)
			(xy 416.307231 -309.50171) (xy 416.330829 -309.548018) (xy 416.346893 -309.597448) (xy 416.355028 -309.648781)
			(xy 416.35553 -309.674768) (xy 416.355276 -309.684674) (xy 416.355276 -309.691024) (xy 416.35561 -309.699665)
			(xy 416.361355 -309.715963) (xy 416.372211 -309.729409) (xy 416.379406 -309.734204) (xy 416.453066 -309.77967)
			(xy 416.453828 -309.780178) (xy 416.463005 -309.785054) (xy 416.483599 -309.787676) (xy 416.493706 -309.785258)
			(xy 416.50031 -309.78348) (xy 416.510724 -309.779416) (xy 416.513518 -309.777892) (xy 416.534341 -309.766699)
			(xy 416.576905 -309.746116) (xy 416.598608 -309.736744) (xy 416.604196 -309.732172) (xy 416.620706 -309.71871)
			(xy 416.625024 -309.71236) (xy 416.639756 -309.690516) (xy 416.644074 -309.676546) (xy 416.644328 -309.66918)
			(xy 416.645245 -309.643478) (xy 416.654053 -309.592809) (xy 416.670598 -309.544115) (xy 416.694481 -309.498568)
			(xy 416.725127 -309.457268) (xy 416.761797 -309.42121) (xy 416.803606 -309.391262) (xy 416.849547 -309.368147)
			(xy 416.898512 -309.352423) (xy 416.949322 -309.344467) (xy 416.975036 -309.34406) (xy 417.000244 -309.344537)
			(xy 417.050074 -309.352196) (xy 417.098163 -309.367331) (xy 417.143398 -309.389591) (xy 417.184729 -309.418461)
			(xy 417.221198 -309.45327) (xy 417.25196 -309.493212) (xy 417.276302 -309.537362) (xy 417.293659 -309.584695)
			(xy 417.30363 -309.634114) (xy 417.305236 -309.659274) (xy 417.30549 -309.663084) (xy 417.307522 -309.674006)
			(xy 417.30803 -309.677562) (xy 417.312094 -309.689754) (xy 417.314634 -309.696358) (xy 417.31819 -309.702454)
			(xy 417.322762 -309.709312) (xy 417.328858 -309.718202) (xy 417.349432 -309.735982) (xy 417.356544 -309.73903)
			(xy 417.378786 -309.7488) (xy 417.422368 -309.770272) (xy 417.443666 -309.781956) (xy 417.455858 -309.78856)
			(xy 417.483036 -309.788052) (xy 417.53282 -309.757572) (xy 417.55949 -309.741316) (xy 417.565052 -309.737591)
			(xy 417.574191 -309.727817) (xy 417.577524 -309.722012) (xy 417.588192 -309.7022) (xy 417.591014 -309.696571)
			(xy 417.594091 -309.684364) (xy 417.594288 -309.67807) (xy 417.594288 -309.674514) (xy 417.594819 -309.648541)
			(xy 417.602985 -309.597241) (xy 417.619071 -309.547849) (xy 417.642682 -309.501579) (xy 417.673237 -309.459569)
			(xy 417.709984 -309.422853) (xy 417.752019 -309.392334) (xy 417.79831 -309.368763) (xy 417.847716 -309.352719)
			(xy 417.899023 -309.344597) (xy 417.924996 -309.34406) (xy 417.950984 -309.344569) (xy 418.002321 -309.352699)
			(xy 418.051754 -309.368759) (xy 418.098067 -309.392354) (xy 418.140118 -309.422904) (xy 418.176873 -309.459655)
			(xy 418.207427 -309.501703) (xy 418.231027 -309.548012) (xy 418.247092 -309.597444) (xy 418.255228 -309.64878)
			(xy 418.255704 -309.674768) (xy 418.25545 -309.684674) (xy 418.25545 -309.691024) (xy 418.255783 -309.699666)
			(xy 418.261526 -309.715966) (xy 418.27238 -309.729416) (xy 418.27958 -309.734204) (xy 418.35324 -309.77967)
			(xy 418.354002 -309.780178) (xy 418.363179 -309.785059) (xy 418.383775 -309.787691) (xy 418.39388 -309.785258)
			(xy 418.400484 -309.78348) (xy 418.409882 -309.77967) (xy 418.412676 -309.778146) (xy 418.437026 -309.765152)
			(xy 418.486968 -309.741643) (xy 418.512498 -309.731156) (xy 418.521673 -309.726971) (xy 418.536011 -309.712812)
			(xy 418.54383 -309.694239) (xy 418.544248 -309.684166) (xy 418.544248 -309.674768) (xy 418.544758 -309.648781)
			(xy 418.552888 -309.597446) (xy 418.568949 -309.548016) (xy 418.592545 -309.501706) (xy 418.623095 -309.459658)
			(xy 418.659846 -309.422907) (xy 418.701894 -309.392357) (xy 418.748204 -309.368761) (xy 418.797634 -309.3527)
			(xy 418.848969 -309.34457) (xy 418.900943 -309.34457) (xy 418.952278 -309.3527) (xy 419.001708 -309.368761)
			(xy 419.048018 -309.392357) (xy 419.090066 -309.422907) (xy 419.126817 -309.459658) (xy 419.157367 -309.501706)
			(xy 419.180963 -309.548016) (xy 419.197024 -309.597446) (xy 419.205154 -309.648781) (xy 419.205664 -309.674768)
			(xy 419.205664 -309.682642) (xy 419.205156 -309.694326) (xy 419.215062 -309.715916) (xy 419.230302 -309.728108)
			(xy 419.237668 -309.731156) (xy 419.237922 -309.731156) (xy 419.265064 -309.742428) (xy 419.31806 -309.767845)
			(xy 419.34384 -309.781956) (xy 419.354762 -309.786528) (xy 419.366192 -309.789576) (xy 419.392354 -309.78475)
			(xy 419.396768 -309.783825) (xy 419.405202 -309.780636) (xy 419.409118 -309.7784) (xy 419.416484 -309.773828)
			(xy 419.422326 -309.76697) (xy 419.42258 -309.766716) (xy 419.425143 -309.763737) (xy 419.431014 -309.758512)
			(xy 419.434264 -309.756302) (xy 419.470332 -309.73395) (xy 419.471602 -309.733188) (xy 419.471856 -309.732934)
			(xy 419.481922 -309.725419) (xy 419.49379 -309.703312) (xy 419.494462 -309.69077) (xy 419.494462 -309.68442)
			(xy 419.494208 -309.675022) (xy 419.494208 -309.674514) (xy 419.494739 -309.648542) (xy 419.502905 -309.597243)
			(xy 419.518992 -309.547852) (xy 419.542603 -309.501583) (xy 419.573158 -309.459575) (xy 419.609905 -309.422861)
			(xy 419.651941 -309.392345) (xy 419.698231 -309.368776) (xy 419.747637 -309.352734) (xy 419.798944 -309.344615)
			(xy 419.824916 -309.34406) (xy 419.850903 -309.344571) (xy 419.902238 -309.352703) (xy 419.951668 -309.368765)
			(xy 419.997978 -309.392361) (xy 420.040026 -309.422911) (xy 420.076779 -309.459661) (xy 420.10733 -309.501709)
			(xy 420.130929 -309.548017) (xy 420.146993 -309.597447) (xy 420.155128 -309.648781) (xy 420.155624 -309.674768)
			(xy 420.15537 -309.684674) (xy 420.15537 -309.691024) (xy 420.155704 -309.699665) (xy 420.161448 -309.715964)
			(xy 420.172304 -309.72941) (xy 420.1795 -309.734204) (xy 420.25316 -309.77967) (xy 420.253922 -309.780178)
			(xy 420.263099 -309.785055) (xy 420.283693 -309.787679) (xy 420.2938 -309.785258) (xy 420.300404 -309.78348)
			(xy 420.309802 -309.77967) (xy 420.312596 -309.778146) (xy 420.336946 -309.765153) (xy 420.386888 -309.741644)
			(xy 420.412418 -309.731156) (xy 420.42159 -309.726969) (xy 420.435923 -309.712808) (xy 420.443738 -309.694238)
			(xy 420.444168 -309.684166) (xy 420.444168 -309.674768) (xy 420.444678 -309.648781) (xy 420.452808 -309.597446)
			(xy 420.468869 -309.548016) (xy 420.492465 -309.501706) (xy 420.523015 -309.459658) (xy 420.559766 -309.422907)
			(xy 420.601814 -309.392357) (xy 420.648124 -309.368761) (xy 420.697554 -309.3527) (xy 420.748889 -309.34457)
			(xy 420.800863 -309.34457) (xy 420.852198 -309.3527) (xy 420.901628 -309.368761) (xy 420.947938 -309.392357)
			(xy 420.989986 -309.422907) (xy 421.026737 -309.459658) (xy 421.057287 -309.501706) (xy 421.080883 -309.548016)
			(xy 421.096944 -309.597446) (xy 421.105074 -309.648781) (xy 421.105584 -309.674768) (xy 421.105584 -309.682642)
			(xy 421.105076 -309.694072) (xy 421.114982 -309.715662) (xy 421.130222 -309.728108) (xy 421.137588 -309.731156)
			(xy 421.16937 -309.744456) (xy 421.231151 -309.774966) (xy 421.261032 -309.792116) (xy 421.267128 -309.795672)
			(xy 421.282876 -309.799736) (xy 421.293015 -309.801857) (xy 421.313471 -309.798716) (xy 421.3225 -309.79364)
			(xy 421.36695 -309.765954) (xy 421.395144 -309.748174) (xy 421.404092 -309.74196) (xy 421.41608 -309.723795)
			(xy 421.418258 -309.713122) (xy 421.420036 -309.7022) (xy 421.419782 -309.692802) (xy 421.419782 -309.69204)
			(xy 421.419274 -309.675276) (xy 421.419274 -309.674514) (xy 421.419765 -309.650531) (xy 421.427305 -309.603161)
			(xy 421.442155 -309.557551) (xy 421.463951 -309.514823) (xy 421.492155 -309.476025) (xy 421.526077 -309.442111)
			(xy 421.564881 -309.413915) (xy 421.607614 -309.392129) (xy 421.653227 -309.377289) (xy 421.700599 -309.36976)
			(xy 421.724582 -309.369206) (xy 421.72509 -309.369206) (xy 421.748204 -309.370222) (xy 421.75938 -309.370984)
			(xy 421.780208 -309.363364) (xy 421.79367 -309.349902) (xy 421.800782 -309.341012) (xy 421.843962 -309.272432)
			(xy 421.849142 -309.263086) (xy 421.852172 -309.241957) (xy 421.849804 -309.231538) (xy 421.84574 -309.217314)
			(xy 421.842438 -309.211726) (xy 421.826078 -309.183164) (xy 421.796841 -309.124185) (xy 421.784018 -309.09387)
			(xy 421.78097 -309.086758) (xy 421.770048 -309.07355) (xy 421.762405 -309.065379) (xy 421.742109 -309.05603)
			(xy 421.730932 -309.055516) (xy 421.724836 -309.055516) (xy 421.698844 -309.055036) (xy 421.6475 -309.046909)
			(xy 421.59806 -309.030849) (xy 421.55174 -309.007253) (xy 421.509683 -308.9767) (xy 421.472923 -308.939945)
			(xy 421.442366 -308.897891) (xy 421.418765 -308.851574) (xy 421.4027 -308.802135) (xy 421.394567 -308.750792)
			(xy 421.394567 -308.698808) (xy 421.4027 -308.647465) (xy 421.418765 -308.598026) (xy 421.442366 -308.551709)
			(xy 421.472923 -308.509655) (xy 421.509683 -308.4729) (xy 421.55174 -308.442347) (xy 421.59806 -308.418751)
			(xy 421.6475 -308.402691) (xy 421.698844 -308.394564) (xy 421.724836 -308.3941) (xy 421.73271 -308.3941)
			(xy 421.748458 -308.394608) (xy 421.775128 -308.377336) (xy 421.781224 -308.36235) (xy 421.792488 -308.335081)
			(xy 421.817907 -308.281831) (xy 421.832024 -308.255924) (xy 421.838882 -308.243732) (xy 421.83812 -308.216554)
			(xy 421.816784 -308.18201) (xy 421.78859 -308.136798) (xy 421.781478 -308.127654) (xy 421.774112 -308.120288)
			(xy 421.770343 -308.116675) (xy 421.761638 -308.110915) (xy 421.75684 -308.108858) (xy 421.74668 -308.104794)
			(xy 421.736012 -308.105302) (xy 421.724836 -308.105556) (xy 421.698846 -308.105049) (xy 421.647504 -308.096923)
			(xy 421.598066 -308.080866) (xy 421.551748 -308.057273) (xy 421.509691 -308.026725) (xy 421.47293 -307.989973)
			(xy 421.442371 -307.947924) (xy 421.418766 -307.901612) (xy 421.402696 -307.852178) (xy 421.394557 -307.800838)
			(xy 421.394128 -307.774848) (xy 421.394633 -307.748872) (xy 421.40275 -307.697558) (xy 421.418792 -307.648145)
			(xy 421.442363 -307.601849) (xy 421.472885 -307.559808) (xy 421.509606 -307.523058) (xy 421.551622 -307.492503)
			(xy 421.597899 -307.468894) (xy 421.647299 -307.452812) (xy 421.698606 -307.444654) (xy 421.724582 -307.44414)
			(xy 421.72509 -307.44414) (xy 421.734742 -307.444394) (xy 421.741092 -307.444394) (xy 421.749726 -307.444049)
			(xy 421.766005 -307.438287) (xy 421.779427 -307.427421) (xy 421.784272 -307.420264) (xy 421.828976 -307.347874)
			(xy 421.833294 -307.338984) (xy 421.834564 -307.335174) (xy 421.837781 -307.325242) (xy 421.836848 -307.304407)
			(xy 421.832786 -307.294788) (xy 421.832532 -307.29428) (xy 421.825928 -307.282088) (xy 421.814473 -307.260531)
			(xy 421.793508 -307.216441) (xy 421.784018 -307.19395) (xy 421.78097 -307.186584) (xy 421.769794 -307.17363)
			(xy 421.762204 -307.165493) (xy 421.742046 -307.156132) (xy 421.730932 -307.155596) (xy 421.724836 -307.155596)
			(xy 421.698846 -307.155116) (xy 421.647505 -307.146989) (xy 421.598067 -307.130931) (xy 421.551751 -307.107336)
			(xy 421.509696 -307.076785) (xy 421.472938 -307.040032) (xy 421.442383 -306.99798) (xy 421.418783 -306.951666)
			(xy 421.402719 -306.90223) (xy 421.394587 -306.85089) (xy 421.394587 -306.79891) (xy 421.402719 -306.74757)
			(xy 421.418783 -306.698134) (xy 421.442383 -306.65182) (xy 421.472938 -306.609768) (xy 421.509696 -306.573015)
			(xy 421.551751 -306.542464) (xy 421.598067 -306.518869) (xy 421.647505 -306.502811) (xy 421.698846 -306.494684)
			(xy 421.724836 -306.49418) (xy 421.73271 -306.49418) (xy 421.748458 -306.494688) (xy 421.775128 -306.477416)
			(xy 421.781224 -306.46243) (xy 421.792489 -306.435161) (xy 421.817909 -306.381912) (xy 421.832024 -306.356004)
			(xy 421.838882 -306.343812) (xy 421.83812 -306.316634) (xy 421.816784 -306.28209) (xy 421.78859 -306.236878)
			(xy 421.781478 -306.227734) (xy 421.774112 -306.220368) (xy 421.770342 -306.216757) (xy 421.761637 -306.210999)
			(xy 421.75684 -306.208938) (xy 421.74668 -306.204874) (xy 421.736012 -306.205382) (xy 421.724836 -306.205636)
			(xy 421.698844 -306.205156) (xy 421.6475 -306.197029) (xy 421.598058 -306.18097) (xy 421.551738 -306.157375)
			(xy 421.509679 -306.126824) (xy 421.472918 -306.090069) (xy 421.442359 -306.048016) (xy 421.418754 -306.001701)
			(xy 421.402686 -305.952263) (xy 421.394549 -305.90092) (xy 421.394128 -305.874928) (xy 421.394634 -305.848953)
			(xy 421.402754 -305.797642) (xy 421.418797 -305.748231) (xy 421.44237 -305.701938) (xy 421.472892 -305.6599)
			(xy 421.509613 -305.623152) (xy 421.551628 -305.592599) (xy 421.597904 -305.568992) (xy 421.647302 -305.552911)
			(xy 421.698607 -305.544754) (xy 421.724582 -305.54422) (xy 421.72509 -305.54422) (xy 421.734742 -305.544474)
			(xy 421.741092 -305.544474) (xy 421.749699 -305.54413) (xy 421.765945 -305.538434) (xy 421.779411 -305.527708)
			(xy 421.784272 -305.520598) (xy 421.80764 -305.483006) (xy 421.80764 -305.482498) (xy 421.83812 -305.43246)
			(xy 421.838628 -305.405282) (xy 421.83177 -305.39309) (xy 421.81018 -305.351942) (xy 421.804338 -305.340258)
			(xy 421.804338 -305.340004) (xy 421.793924 -305.317906) (xy 421.78097 -305.287426) (xy 421.775382 -305.272948)
			(xy 421.749474 -305.255422) (xy 421.724836 -305.255422) (xy 421.698844 -305.254942) (xy 421.647499 -305.246814)
			(xy 421.598057 -305.230755) (xy 421.551737 -305.207158) (xy 421.509679 -305.176605) (xy 421.472918 -305.139848)
			(xy 421.442361 -305.097794) (xy 421.418759 -305.051476) (xy 421.402694 -305.002036) (xy 421.394561 -304.950692)
			(xy 421.394561 -304.898708) (xy 421.402694 -304.847364) (xy 421.418759 -304.797924) (xy 421.442361 -304.751606)
			(xy 421.472918 -304.709551) (xy 421.509679 -304.672795) (xy 421.551737 -304.642242) (xy 421.598057 -304.618645)
			(xy 421.647499 -304.602586) (xy 421.698844 -304.594458) (xy 421.724836 -304.594006) (xy 421.73271 -304.594006)
			(xy 421.743124 -304.59426) (xy 421.763444 -304.586132) (xy 421.777414 -304.571146) (xy 421.78097 -304.56251)
			(xy 421.788336 -304.545238) (xy 421.788336 -304.544984) (xy 421.798145 -304.52248) (xy 421.819746 -304.47839)
			(xy 421.831516 -304.456846) (xy 421.832024 -304.45583) (xy 421.83304 -304.453798) (xy 421.836572 -304.445893)
			(xy 421.838682 -304.42872) (xy 421.834999 -304.411813) (xy 421.830754 -304.404268) (xy 421.785542 -304.331624)
			(xy 421.781478 -304.32756) (xy 421.774112 -304.320194) (xy 421.770343 -304.316581) (xy 421.761639 -304.31082)
			(xy 421.75684 -304.308764) (xy 421.74668 -304.3047) (xy 421.736012 -304.305208) (xy 421.724836 -304.305462)
			(xy 421.698853 -304.304955) (xy 421.647525 -304.296831) (xy 421.5981 -304.280778) (xy 421.551794 -304.257191)
			(xy 421.509749 -304.22665) (xy 421.472999 -304.189908) (xy 421.442449 -304.14787) (xy 421.418851 -304.10157)
			(xy 421.402786 -304.052149) (xy 421.394651 -304.000823) (xy 421.394645 -303.948856) (xy 421.402768 -303.897528)
			(xy 421.418821 -303.848103) (xy 421.442407 -303.801797) (xy 421.472948 -303.759751) (xy 421.509689 -303.723001)
			(xy 421.551727 -303.69245) (xy 421.598027 -303.668852) (xy 421.647448 -303.652787) (xy 421.698774 -303.644651)
			(xy 421.750741 -303.644645) (xy 421.802069 -303.652767) (xy 421.851494 -303.668819) (xy 421.8978 -303.692406)
			(xy 421.939846 -303.722945) (xy 421.976597 -303.759686) (xy 422.007148 -303.801724) (xy 422.030747 -303.848024)
			(xy 422.046812 -303.897445) (xy 422.054949 -303.948771) (xy 422.055544 -303.974754) (xy 422.05529 -303.98466)
			(xy 422.05529 -303.99101) (xy 422.055622 -303.999652) (xy 422.061364 -304.015952) (xy 422.072222 -304.029399)
			(xy 422.07942 -304.03419) (xy 422.153842 -304.07991) (xy 422.157144 -304.081942) (xy 422.160446 -304.083466)
			(xy 422.161716 -304.083974) (xy 422.167046 -304.086096) (xy 422.178332 -304.088141) (xy 422.184068 -304.088038)
			(xy 422.196768 -304.08753) (xy 422.207182 -304.081688) (xy 422.246552 -304.061114) (xy 422.254072 -304.056964)
			(xy 422.266015 -304.044634) (xy 422.26992 -304.036984) (xy 422.287428 -304.000771) (xy 422.327611 -303.931084)
			(xy 422.350184 -303.897792) (xy 422.352393 -303.89436) (xy 422.355837 -303.88696) (xy 422.357042 -303.88306)
			(xy 422.365197 -303.856795) (xy 422.388982 -303.807211) (xy 422.42063 -303.762237) (xy 422.459272 -303.723108)
			(xy 422.503848 -303.6909) (xy 422.553131 -303.666498) (xy 422.579292 -303.658016) (xy 422.585896 -303.65573)
			(xy 422.596056 -303.650904) (xy 422.599866 -303.648364) (xy 422.630895 -303.627528) (xy 422.695616 -303.590135)
			(xy 422.763019 -303.557824) (xy 422.797732 -303.54397) (xy 422.797986 -303.54397) (xy 422.804688 -303.54105)
			(xy 422.816172 -303.532013) (xy 422.820592 -303.52619) (xy 422.840404 -303.498504) (xy 422.844976 -303.48555)
			(xy 422.845484 -303.478438) (xy 422.847775 -303.453063) (xy 422.859724 -303.403538) (xy 422.879726 -303.356683)
			(xy 422.907226 -303.313797) (xy 422.941462 -303.27607) (xy 422.981485 -303.244548) (xy 423.026184 -303.220105)
			(xy 423.07432 -303.203418) (xy 423.124557 -303.194952) (xy 423.15003 -303.194466) (xy 423.175337 -303.194965)
			(xy 423.225258 -303.203316) (xy 423.273118 -303.219785) (xy 423.317607 -303.243921) (xy 423.357507 -303.275062)
			(xy 423.391726 -303.312357) (xy 423.419326 -303.354783) (xy 423.439552 -303.401181) (xy 423.446194 -303.425606)
			(xy 423.447972 -303.433226) (xy 423.455846 -303.445926) (xy 423.48912 -303.47539) (xy 423.503852 -303.48174)
			(xy 423.511726 -303.482502) (xy 423.562272 -303.488852) (xy 423.578274 -303.491646) (xy 423.614596 -303.498504)
			(xy 423.619761 -303.499451) (xy 423.630259 -303.499451) (xy 423.635424 -303.498504) (xy 423.671746 -303.491646)
			(xy 423.687748 -303.488852) (xy 423.738294 -303.482502) (xy 423.746168 -303.48174) (xy 423.7609 -303.47539)
			(xy 423.794174 -303.445926) (xy 423.802048 -303.433226) (xy 423.803826 -303.425606) (xy 423.810458 -303.401178)
			(xy 423.830685 -303.354781) (xy 423.858287 -303.312354) (xy 423.892507 -303.27506) (xy 423.932409 -303.24392)
			(xy 423.9769 -303.219787) (xy 424.024761 -303.20332) (xy 424.074683 -303.194972) (xy 424.09999 -303.194466)
			(xy 424.114045 -303.194674) (xy 424.142029 -303.197346) (xy 424.15587 -303.1998) (xy 424.156378 -303.1998)
			(xy 424.168609 -303.201292) (xy 424.192097 -303.193984) (xy 424.201336 -303.18583) (xy 424.261026 -303.12614)
			(xy 424.26918 -303.116901) (xy 424.276493 -303.093411) (xy 424.274996 -303.081182) (xy 424.274996 -303.080674)
			(xy 424.27253 -303.066835) (xy 424.269861 -303.03885) (xy 424.269662 -303.024794) (xy 424.270148 -302.99997)
			(xy 424.278182 -302.950977) (xy 424.294035 -302.903929) (xy 424.317292 -302.860066) (xy 424.347338 -302.820543)
			(xy 424.383383 -302.786401) (xy 424.424477 -302.758541) (xy 424.469536 -302.737697) (xy 424.517375 -302.724416)
			(xy 424.566731 -302.719051) (xy 424.616306 -302.721741) (xy 424.664792 -302.732416) (xy 424.710912 -302.750795)
			(xy 424.753452 -302.776393) (xy 424.791289 -302.808536) (xy 424.823428 -302.846378) (xy 424.849021 -302.88892)
			(xy 424.867395 -302.935043) (xy 424.878064 -302.98353) (xy 424.880298 -303.024794) (xy 425.219126 -303.024794)
			(xy 425.223086 -302.97574) (xy 425.234863 -302.927956) (xy 425.254154 -302.88268) (xy 425.280457 -302.841084)
			(xy 425.313092 -302.804247) (xy 425.351213 -302.773122) (xy 425.393834 -302.748515) (xy 425.43985 -302.731063)
			(xy 425.488069 -302.721219) (xy 425.537244 -302.719238) (xy 425.586099 -302.72517) (xy 425.63337 -302.738862)
			(xy 425.677832 -302.75996) (xy 425.718335 -302.787916) (xy 425.753828 -302.822008) (xy 425.783393 -302.861352)
			(xy 425.806264 -302.904929) (xy 425.821848 -302.95161) (xy 425.829743 -303.000187) (xy 425.830238 -303.024794)
			(xy 425.829743 -303.049401) (xy 425.821848 -303.097978) (xy 425.806264 -303.144659) (xy 425.783393 -303.188236)
			(xy 425.753828 -303.22758) (xy 425.718335 -303.261672) (xy 425.677832 -303.289628) (xy 425.63337 -303.310726)
			(xy 425.586099 -303.324418) (xy 425.537244 -303.33035) (xy 425.488069 -303.328369) (xy 425.43985 -303.318525)
			(xy 425.393834 -303.301073) (xy 425.351213 -303.276466) (xy 425.313092 -303.245341) (xy 425.280457 -303.208504)
			(xy 425.254154 -303.166908) (xy 425.234863 -303.121632) (xy 425.223086 -303.073848) (xy 425.219126 -303.024794)
			(xy 424.880298 -303.024794) (xy 424.880748 -303.033105) (xy 424.875377 -303.082461) (xy 424.862091 -303.130297)
			(xy 424.841241 -303.175355) (xy 424.813376 -303.216445) (xy 424.779231 -303.252486) (xy 424.739704 -303.282528)
			(xy 424.695838 -303.305779) (xy 424.648788 -303.321627) (xy 424.599794 -303.329654) (xy 424.57497 -303.330102)
			(xy 424.560915 -303.329892) (xy 424.532932 -303.327217) (xy 424.51909 -303.324768) (xy 424.518582 -303.324768)
			(xy 424.506348 -303.323262) (xy 424.482844 -303.330558) (xy 424.473624 -303.338738) (xy 424.413934 -303.398428)
			(xy 424.405799 -303.407672) (xy 424.398522 -303.431155) (xy 424.399964 -303.443386) (xy 424.399964 -303.443894)
			(xy 424.403266 -303.465484) (xy 424.403266 -303.465738) (xy 424.40352 -303.468532) (xy 424.404536 -303.478438)
			(xy 424.405552 -303.492662) (xy 424.429428 -303.52619) (xy 424.433875 -303.531987) (xy 424.44535 -303.54102)
			(xy 424.452034 -303.54397) (xy 424.452288 -303.54397) (xy 424.466874 -303.549721) (xy 424.495708 -303.562043)
			(xy 424.509946 -303.568608) (xy 424.546192 -303.58588) (xy 424.616003 -303.625557) (xy 424.649392 -303.647856)
			(xy 424.655742 -303.651666) (xy 424.66641 -303.657) (xy 424.670474 -303.658016) (xy 424.696352 -303.666433)
			(xy 424.74515 -303.690509) (xy 424.789362 -303.722231) (xy 424.8278 -303.760746) (xy 424.859433 -303.805022)
			(xy 424.871896 -303.829212) (xy 424.876406 -303.837587) (xy 424.890389 -303.850463) (xy 424.908111 -303.857336)
			(xy 424.917616 -303.85766) (xy 425.182284 -303.85766) (xy 425.191773 -303.857264) (xy 425.209454 -303.850368)
			(xy 425.223443 -303.837543) (xy 425.228004 -303.829212) (xy 425.240062 -303.805775) (xy 425.270472 -303.762729)
			(xy 425.307325 -303.725051) (xy 425.349688 -303.693696) (xy 425.396488 -303.669457) (xy 425.446541 -303.652949)
			(xy 425.498578 -303.644589) (xy 425.551282 -303.644589) (xy 425.603319 -303.652949) (xy 425.653372 -303.669457)
			(xy 425.700172 -303.693696) (xy 425.742535 -303.725051) (xy 425.779388 -303.762729) (xy 425.809798 -303.805775)
			(xy 425.821856 -303.829212) (xy 425.826369 -303.83758) (xy 425.840355 -303.85044) (xy 425.858074 -303.857292)
			(xy 425.867576 -303.85766) (xy 426.132244 -303.85766) (xy 426.141737 -303.85727) (xy 426.159429 -303.850384)
			(xy 426.17343 -303.83756) (xy 426.177964 -303.829212) (xy 426.190022 -303.805773) (xy 426.220432 -303.762721)
			(xy 426.257284 -303.725036) (xy 426.299645 -303.693672) (xy 426.346444 -303.669422) (xy 426.396497 -303.6529)
			(xy 426.448536 -303.644524) (xy 426.47489 -303.644046) (xy 426.488417 -303.644227) (xy 426.515374 -303.646517)
			(xy 426.528738 -303.648618) (xy 426.540676 -303.65065) (xy 426.563282 -303.643792) (xy 426.631354 -303.579022)
			(xy 426.639441 -303.570534) (xy 426.647536 -303.54856) (xy 426.646848 -303.536858) (xy 426.646848 -303.535842)
			(xy 426.645815 -303.526924) (xy 426.644673 -303.509005) (xy 426.644562 -303.500028) (xy 426.644562 -303.49952)
			(xy 426.64478 -303.485529) (xy 426.647455 -303.457673) (xy 426.649896 -303.443894) (xy 426.649896 -303.443386)
			(xy 426.651403 -303.43115) (xy 426.644115 -303.40764) (xy 426.635926 -303.398428) (xy 426.576236 -303.338738)
			(xy 426.566995 -303.33059) (xy 426.543507 -303.323283) (xy 426.531278 -303.324768) (xy 426.531024 -303.324768)
			(xy 426.517122 -303.327246) (xy 426.48901 -303.329921) (xy 426.47489 -303.330102) (xy 426.45007 -303.329615)
			(xy 426.401084 -303.321583) (xy 426.354043 -303.305731) (xy 426.310186 -303.282478) (xy 426.270668 -303.252436)
			(xy 426.236532 -303.216397) (xy 426.208675 -303.17531) (xy 426.187833 -303.130257) (xy 426.174553 -303.082426)
			(xy 426.169187 -303.033077) (xy 426.171875 -302.983509) (xy 426.182547 -302.93503) (xy 426.200921 -302.888916)
			(xy 426.226514 -302.846381) (xy 426.25865 -302.808548) (xy 426.296485 -302.776411) (xy 426.339019 -302.750819)
			(xy 426.385134 -302.732446) (xy 426.433613 -302.721775) (xy 426.483181 -302.719087) (xy 426.53253 -302.724454)
			(xy 426.580361 -302.737734) (xy 426.625413 -302.758577) (xy 426.6665 -302.786434) (xy 426.702539 -302.820571)
			(xy 426.73258 -302.860089) (xy 426.755833 -302.903946) (xy 426.771684 -302.950988) (xy 426.779716 -302.999974)
			(xy 426.780198 -303.024794) (xy 426.77999 -303.038849) (xy 426.777317 -303.066833) (xy 426.774864 -303.080674)
			(xy 426.774864 -303.081182) (xy 426.773373 -303.093411) (xy 426.780689 -303.116893) (xy 426.788834 -303.12614)
			(xy 426.848524 -303.18583) (xy 426.857766 -303.19397) (xy 426.881251 -303.201254) (xy 426.893482 -303.1998)
			(xy 426.893736 -303.1998) (xy 426.907575 -303.197335) (xy 426.93556 -303.194666) (xy 426.949616 -303.194466)
			(xy 426.950124 -303.194466) (xy 426.964116 -303.194682) (xy 426.991973 -303.197352) (xy 427.00575 -303.1998)
			(xy 427.006258 -303.1998) (xy 427.01849 -303.201297) (xy 427.041985 -303.193995) (xy 427.051216 -303.18583)
			(xy 427.110906 -303.12614) (xy 427.119062 -303.116902) (xy 427.126379 -303.093411) (xy 427.124876 -303.081182)
			(xy 427.124876 -303.080674) (xy 427.12241 -303.066835) (xy 427.11974 -303.03885) (xy 427.119542 -303.024794)
			(xy 427.120028 -302.999978) (xy 427.128058 -302.951) (xy 427.143906 -302.903967) (xy 427.167154 -302.860117)
			(xy 427.19719 -302.820605) (xy 427.233222 -302.786473) (xy 427.274301 -302.75862) (xy 427.319345 -302.737779)
			(xy 427.367167 -302.724499) (xy 427.416507 -302.719131) (xy 427.466066 -302.721816) (xy 427.514538 -302.732483)
			(xy 427.560646 -302.750851) (xy 427.603175 -302.776436) (xy 427.641004 -302.808565) (xy 427.673138 -302.84639)
			(xy 427.698729 -302.888915) (xy 427.717104 -302.93502) (xy 427.727778 -302.98349) (xy 427.730022 -303.024794)
			(xy 428.069006 -303.024794) (xy 428.072966 -302.97574) (xy 428.084743 -302.927956) (xy 428.104034 -302.88268)
			(xy 428.130337 -302.841084) (xy 428.162972 -302.804247) (xy 428.201093 -302.773122) (xy 428.243714 -302.748515)
			(xy 428.28973 -302.731063) (xy 428.337949 -302.721219) (xy 428.387124 -302.719238) (xy 428.435979 -302.72517)
			(xy 428.48325 -302.738862) (xy 428.527712 -302.75996) (xy 428.568215 -302.787916) (xy 428.603708 -302.822008)
			(xy 428.633273 -302.861352) (xy 428.656144 -302.904929) (xy 428.671728 -302.95161) (xy 428.679623 -303.000187)
			(xy 428.680118 -303.024794) (xy 429.01922 -303.024794) (xy 429.02318 -302.97574) (xy 429.034957 -302.927956)
			(xy 429.054248 -302.88268) (xy 429.080551 -302.841084) (xy 429.113186 -302.804247) (xy 429.151307 -302.773122)
			(xy 429.193928 -302.748515) (xy 429.239944 -302.731063) (xy 429.288163 -302.721219) (xy 429.337338 -302.719238)
			(xy 429.386193 -302.72517) (xy 429.433464 -302.738862) (xy 429.477926 -302.75996) (xy 429.518429 -302.787916)
			(xy 429.553922 -302.822008) (xy 429.583487 -302.861352) (xy 429.606358 -302.904929) (xy 429.621942 -302.95161)
			(xy 429.629837 -303.000187) (xy 429.630332 -303.024794) (xy 429.96918 -303.024794) (xy 429.97314 -302.97574)
			(xy 429.984917 -302.927956) (xy 430.004208 -302.88268) (xy 430.030511 -302.841084) (xy 430.063146 -302.804247)
			(xy 430.101267 -302.773122) (xy 430.143888 -302.748515) (xy 430.189904 -302.731063) (xy 430.238123 -302.721219)
			(xy 430.287298 -302.719238) (xy 430.336153 -302.72517) (xy 430.383424 -302.738862) (xy 430.427886 -302.75996)
			(xy 430.468389 -302.787916) (xy 430.503882 -302.822008) (xy 430.533447 -302.861352) (xy 430.556318 -302.904929)
			(xy 430.571902 -302.95161) (xy 430.579797 -303.000187) (xy 430.580292 -303.024794) (xy 430.9039 -303.024794)
			(xy 430.90786 -302.97574) (xy 430.919637 -302.927956) (xy 430.938928 -302.88268) (xy 430.965231 -302.841084)
			(xy 430.997866 -302.804247) (xy 431.035987 -302.773122) (xy 431.078608 -302.748515) (xy 431.124624 -302.731063)
			(xy 431.172843 -302.721219) (xy 431.222018 -302.719238) (xy 431.270873 -302.72517) (xy 431.318144 -302.738862)
			(xy 431.362606 -302.75996) (xy 431.403109 -302.787916) (xy 431.438602 -302.822008) (xy 431.468167 -302.861352)
			(xy 431.491038 -302.904929) (xy 431.506622 -302.95161) (xy 431.514517 -303.000187) (xy 431.515012 -303.024794)
			(xy 431.514517 -303.049401) (xy 431.506622 -303.097978) (xy 431.491038 -303.144659) (xy 431.468167 -303.188236)
			(xy 431.438602 -303.22758) (xy 431.403109 -303.261672) (xy 431.362606 -303.289628) (xy 431.318144 -303.310726)
			(xy 431.270873 -303.324418) (xy 431.222018 -303.33035) (xy 431.172843 -303.328369) (xy 431.124624 -303.318525)
			(xy 431.078608 -303.301073) (xy 431.035987 -303.276466) (xy 430.997866 -303.245341) (xy 430.965231 -303.208504)
			(xy 430.938928 -303.166908) (xy 430.919637 -303.121632) (xy 430.90786 -303.073848) (xy 430.9039 -303.024794)
			(xy 430.580292 -303.024794) (xy 430.579797 -303.049401) (xy 430.571902 -303.097978) (xy 430.556318 -303.144659)
			(xy 430.533447 -303.188236) (xy 430.503882 -303.22758) (xy 430.468389 -303.261672) (xy 430.427886 -303.289628)
			(xy 430.383424 -303.310726) (xy 430.336153 -303.324418) (xy 430.287298 -303.33035) (xy 430.238123 -303.328369)
			(xy 430.189904 -303.318525) (xy 430.143888 -303.301073) (xy 430.101267 -303.276466) (xy 430.063146 -303.245341)
			(xy 430.030511 -303.208504) (xy 430.004208 -303.166908) (xy 429.984917 -303.121632) (xy 429.97314 -303.073848)
			(xy 429.96918 -303.024794) (xy 429.630332 -303.024794) (xy 429.629837 -303.049401) (xy 429.621942 -303.097978)
			(xy 429.606358 -303.144659) (xy 429.583487 -303.188236) (xy 429.553922 -303.22758) (xy 429.518429 -303.261672)
			(xy 429.477926 -303.289628) (xy 429.433464 -303.310726) (xy 429.386193 -303.324418) (xy 429.337338 -303.33035)
			(xy 429.288163 -303.328369) (xy 429.239944 -303.318525) (xy 429.193928 -303.301073) (xy 429.151307 -303.276466)
			(xy 429.113186 -303.245341) (xy 429.080551 -303.208504) (xy 429.054248 -303.166908) (xy 429.034957 -303.121632)
			(xy 429.02318 -303.073848) (xy 429.01922 -303.024794) (xy 428.680118 -303.024794) (xy 428.679623 -303.049401)
			(xy 428.671728 -303.097978) (xy 428.656144 -303.144659) (xy 428.633273 -303.188236) (xy 428.603708 -303.22758)
			(xy 428.568215 -303.261672) (xy 428.527712 -303.289628) (xy 428.48325 -303.310726) (xy 428.435979 -303.324418)
			(xy 428.387124 -303.33035) (xy 428.337949 -303.328369) (xy 428.28973 -303.318525) (xy 428.243714 -303.301073)
			(xy 428.201093 -303.276466) (xy 428.162972 -303.245341) (xy 428.130337 -303.208504) (xy 428.104034 -303.166908)
			(xy 428.084743 -303.121632) (xy 428.072966 -303.073848) (xy 428.069006 -303.024794) (xy 427.730022 -303.024794)
			(xy 427.73047 -303.033049) (xy 427.725109 -303.08239) (xy 427.711836 -303.130214) (xy 427.691002 -303.175261)
			(xy 427.663155 -303.216344) (xy 427.629028 -303.252381) (xy 427.58952 -303.282422) (xy 427.545674 -303.305677)
			(xy 427.498642 -303.321531) (xy 427.449666 -303.329568) (xy 427.42485 -303.330102) (xy 427.410795 -303.329896)
			(xy 427.38281 -303.327227) (xy 427.36897 -303.324768) (xy 427.368462 -303.324768) (xy 427.356229 -303.323267)
			(xy 427.332733 -303.330569) (xy 427.323504 -303.338738) (xy 427.263814 -303.398428) (xy 427.255669 -303.407668)
			(xy 427.24838 -303.431155) (xy 427.249844 -303.443386) (xy 427.249844 -303.443894) (xy 427.252298 -303.457671)
			(xy 427.254969 -303.485528) (xy 427.255178 -303.49952) (xy 427.255178 -303.500028) (xy 427.255068 -303.509005)
			(xy 427.253925 -303.526924) (xy 427.252892 -303.535842) (xy 427.252892 -303.536858) (xy 427.252242 -303.548558)
			(xy 427.260312 -303.57053) (xy 427.268386 -303.579022) (xy 427.336458 -303.643792) (xy 427.359064 -303.65065)
			(xy 427.371002 -303.648618) (xy 427.384365 -303.646507) (xy 427.411323 -303.644218) (xy 427.42485 -303.644046)
			(xy 427.451206 -303.644554) (xy 427.503251 -303.652909) (xy 427.553312 -303.669416) (xy 427.60012 -303.693655)
			(xy 427.642489 -303.725014) (xy 427.679346 -303.762697) (xy 427.709758 -303.805751) (xy 427.721776 -303.829212)
			(xy 427.726285 -303.837589) (xy 427.740267 -303.850471) (xy 427.757989 -303.857351) (xy 427.767496 -303.85766)
			(xy 428.032164 -303.85766) (xy 428.041655 -303.857267) (xy 428.059342 -303.850376) (xy 428.073336 -303.837552)
			(xy 428.077884 -303.829212) (xy 428.089942 -303.805775) (xy 428.120352 -303.762729) (xy 428.157205 -303.725051)
			(xy 428.199568 -303.693696) (xy 428.246368 -303.669457) (xy 428.296421 -303.652949) (xy 428.348458 -303.644589)
			(xy 428.401162 -303.644589) (xy 428.453199 -303.652949) (xy 428.503252 -303.669457) (xy 428.550052 -303.693696)
			(xy 428.592415 -303.725051) (xy 428.629268 -303.762729) (xy 428.659678 -303.805775) (xy 428.671736 -303.829212)
			(xy 428.676248 -303.837582) (xy 428.690233 -303.850447) (xy 428.707953 -303.857307) (xy 428.717456 -303.85766)
			(xy 428.982378 -303.85766) (xy 428.991867 -303.857265) (xy 429.00955 -303.850371) (xy 429.023541 -303.837545)
			(xy 429.028098 -303.829212) (xy 429.040156 -303.805775) (xy 429.070566 -303.762729) (xy 429.107419 -303.725051)
			(xy 429.149782 -303.693696) (xy 429.196582 -303.669457) (xy 429.246635 -303.652949) (xy 429.298672 -303.644589)
			(xy 429.351376 -303.644589) (xy 429.403413 -303.652949) (xy 429.453466 -303.669457) (xy 429.500266 -303.693696)
			(xy 429.542629 -303.725051) (xy 429.579482 -303.762729) (xy 429.609892 -303.805775) (xy 429.62195 -303.829212)
			(xy 429.626463 -303.837581) (xy 429.640448 -303.850442) (xy 429.658168 -303.857297) (xy 429.66767 -303.85766)
			(xy 429.932084 -303.85766) (xy 429.939266 -303.857417) (xy 429.953065 -303.853425) (xy 429.959262 -303.849786)
			(xy 429.959516 -303.849532) (xy 429.965141 -303.84572) (xy 429.974286 -303.835679) (xy 429.97755 -303.82972)
			(xy 429.977804 -303.829212) (xy 429.978058 -303.828958) (xy 429.990119 -303.805521) (xy 430.020532 -303.762475)
			(xy 430.057385 -303.724796) (xy 430.099747 -303.693436) (xy 430.146545 -303.66919) (xy 430.196595 -303.65267)
			(xy 430.248631 -303.644295) (xy 430.274984 -303.643792) (xy 431.230278 -303.643792) (xy 431.256569 -303.644721)
			(xy 431.308371 -303.653881) (xy 431.358069 -303.671131) (xy 431.404407 -303.696033) (xy 431.446215 -303.727961)
			(xy 431.46472 -303.746662) (xy 431.470816 -303.753266) (xy 431.487072 -303.761394) (xy 431.492398 -303.763852)
			(xy 431.503814 -303.766538) (xy 431.509678 -303.766728) (xy 431.579528 -303.766728) (xy 431.590037 -303.766196)
			(xy 431.609307 -303.757794) (xy 431.616866 -303.750472) (xy 431.635786 -303.730791) (xy 431.678892 -303.697296)
			(xy 431.726915 -303.67134) (xy 431.778551 -303.653627) (xy 431.832396 -303.644639) (xy 431.85969 -303.644046)
			(xy 431.859944 -303.644046) (xy 431.884569 -303.644497) (xy 431.933275 -303.6518) (xy 431.980356 -303.666254)
			(xy 432.024771 -303.687537) (xy 432.065533 -303.715178) (xy 432.10174 -303.748564) (xy 432.1175 -303.76749)
			(xy 432.124784 -303.775719) (xy 432.144397 -303.785584) (xy 432.155346 -303.78654) (xy 433.226464 -303.78654)
			(xy 433.266072 -303.786971) (xy 433.345032 -303.793325) (xy 433.384198 -303.79924) (xy 433.395374 -303.801018)
			(xy 433.406804 -303.797716) (xy 433.412424 -303.795946) (xy 433.422691 -303.790168) (xy 433.427124 -303.786286)
			(xy 433.485544 -303.732438) (xy 433.493498 -303.724291) (xy 433.501945 -303.703182) (xy 433.5018 -303.691798)
			(xy 433.5018 -303.691036) (xy 433.500784 -303.662588) (xy 433.501271 -303.635337) (xy 433.509028 -303.58139)
			(xy 433.524385 -303.529096) (xy 433.547026 -303.47952) (xy 433.576493 -303.433671) (xy 433.612184 -303.392481)
			(xy 433.653374 -303.35679) (xy 433.699224 -303.327324) (xy 433.7488 -303.304683) (xy 433.801094 -303.289328)
			(xy 433.855041 -303.28157) (xy 433.882292 -303.28108) (xy 433.910743 -303.281612) (xy 433.967013 -303.290075)
			(xy 434.021402 -303.306799) (xy 434.072705 -303.331414) (xy 434.119784 -303.363374) (xy 434.161596 -303.40197)
			(xy 434.197214 -303.446346) (xy 434.225847 -303.49552) (xy 434.246861 -303.5484) (xy 434.253894 -303.575974)
			(xy 434.256434 -303.586388) (xy 434.277516 -303.614582) (xy 434.283866 -303.620932) (xy 434.29047 -303.625504)
			(xy 434.361844 -303.663096) (xy 434.384196 -303.664112) (xy 434.394864 -303.65954) (xy 434.407224 -303.654451)
			(xy 434.432521 -303.645808) (xy 434.44541 -303.642268) (xy 434.45811 -303.638966) (xy 434.476906 -303.621186)
			(xy 434.511196 -303.515014) (xy 434.50637 -303.489614) (xy 434.497988 -303.479454) (xy 434.481678 -303.458901)
			(xy 434.454255 -303.414168) (xy 434.433222 -303.366099) (xy 434.418976 -303.315601) (xy 434.411786 -303.263627)
			(xy 434.411374 -303.237392) (xy 434.41186 -303.210141) (xy 434.419618 -303.156193) (xy 434.434973 -303.103898)
			(xy 434.457615 -303.054321) (xy 434.487081 -303.00847) (xy 434.522772 -302.967279) (xy 434.563962 -302.931587)
			(xy 434.609812 -302.902119) (xy 434.659389 -302.879477) (xy 434.711683 -302.86412) (xy 434.765631 -302.856361)
			(xy 434.792882 -302.855884) (xy 434.819832 -302.856354) (xy 434.873196 -302.86395) (xy 434.924959 -302.878979)
			(xy 434.974092 -302.901143) (xy 435.019618 -302.93) (xy 435.060631 -302.964975) (xy 435.096314 -303.005374)
			(xy 435.110439 -303.026826) (xy 436.919622 -303.026826) (xy 436.923693 -302.971204) (xy 436.935819 -302.916767)
			(xy 436.955742 -302.864676) (xy 436.983038 -302.816041) (xy 437.017124 -302.771898) (xy 437.057273 -302.733189)
			(xy 437.102631 -302.700738) (xy 437.152231 -302.675237) (xy 437.205015 -302.65723) (xy 437.259858 -302.6471)
			(xy 437.315592 -302.645063) (xy 437.371029 -302.651163) (xy 437.424986 -302.665269) (xy 437.476315 -302.687081)
			(xy 437.523921 -302.716135) (xy 437.566789 -302.75181) (xy 437.604006 -302.793347) (xy 437.634779 -302.83986)
			(xy 437.658451 -302.890357) (xy 437.674519 -302.943764) (xy 437.682639 -302.99894) (xy 437.683148 -303.026826)
			(xy 437.935622 -303.026826) (xy 437.939693 -302.971204) (xy 437.951819 -302.916767) (xy 437.971742 -302.864676)
			(xy 437.999038 -302.816041) (xy 438.033124 -302.771898) (xy 438.073273 -302.733189) (xy 438.118631 -302.700738)
			(xy 438.168231 -302.675237) (xy 438.221015 -302.65723) (xy 438.275858 -302.6471) (xy 438.331592 -302.645063)
			(xy 438.387029 -302.651163) (xy 438.440986 -302.665269) (xy 438.492315 -302.687081) (xy 438.539921 -302.716135)
			(xy 438.582789 -302.75181) (xy 438.620006 -302.793347) (xy 438.650779 -302.83986) (xy 438.674451 -302.890357)
			(xy 438.690519 -302.943764) (xy 438.698639 -302.99894) (xy 438.699148 -303.026826) (xy 438.951622 -303.026826)
			(xy 438.955693 -302.971204) (xy 438.967819 -302.916767) (xy 438.987742 -302.864676) (xy 439.015038 -302.816041)
			(xy 439.049124 -302.771898) (xy 439.089273 -302.733189) (xy 439.134631 -302.700738) (xy 439.184231 -302.675237)
			(xy 439.237015 -302.65723) (xy 439.291858 -302.6471) (xy 439.347592 -302.645063) (xy 439.403029 -302.651163)
			(xy 439.456986 -302.665269) (xy 439.508315 -302.687081) (xy 439.555921 -302.716135) (xy 439.598789 -302.75181)
			(xy 439.636006 -302.793347) (xy 439.666779 -302.83986) (xy 439.690451 -302.890357) (xy 439.706519 -302.943764)
			(xy 439.714639 -302.99894) (xy 439.715148 -303.026826) (xy 439.967622 -303.026826) (xy 439.971693 -302.971204)
			(xy 439.983819 -302.916767) (xy 440.003742 -302.864676) (xy 440.031038 -302.816041) (xy 440.065124 -302.771898)
			(xy 440.105273 -302.733189) (xy 440.150631 -302.700738) (xy 440.200231 -302.675237) (xy 440.253015 -302.65723)
			(xy 440.307858 -302.6471) (xy 440.363592 -302.645063) (xy 440.419029 -302.651163) (xy 440.472986 -302.665269)
			(xy 440.524315 -302.687081) (xy 440.571921 -302.716135) (xy 440.614789 -302.75181) (xy 440.652006 -302.793347)
			(xy 440.682779 -302.83986) (xy 440.706451 -302.890357) (xy 440.722519 -302.943764) (xy 440.730639 -302.99894)
			(xy 440.731148 -303.026826) (xy 440.983622 -303.026826) (xy 440.987693 -302.971204) (xy 440.999819 -302.916767)
			(xy 441.019742 -302.864676) (xy 441.047038 -302.816041) (xy 441.081124 -302.771898) (xy 441.121273 -302.733189)
			(xy 441.166631 -302.700738) (xy 441.216231 -302.675237) (xy 441.269015 -302.65723) (xy 441.323858 -302.6471)
			(xy 441.379592 -302.645063) (xy 441.435029 -302.651163) (xy 441.488986 -302.665269) (xy 441.540315 -302.687081)
			(xy 441.587921 -302.716135) (xy 441.630789 -302.75181) (xy 441.668006 -302.793347) (xy 441.698779 -302.83986)
			(xy 441.722451 -302.890357) (xy 441.738519 -302.943764) (xy 441.746639 -302.99894) (xy 441.747148 -303.026826)
			(xy 441.746639 -303.054712) (xy 441.738519 -303.109888) (xy 441.722451 -303.163295) (xy 441.698779 -303.213792)
			(xy 441.668006 -303.260305) (xy 441.630789 -303.301842) (xy 441.587921 -303.337517) (xy 441.540315 -303.366571)
			(xy 441.488986 -303.388383) (xy 441.435029 -303.402489) (xy 441.379592 -303.408589) (xy 441.323858 -303.406552)
			(xy 441.269015 -303.396422) (xy 441.216231 -303.378415) (xy 441.166631 -303.352914) (xy 441.121273 -303.320463)
			(xy 441.081124 -303.281754) (xy 441.047038 -303.237611) (xy 441.019742 -303.188976) (xy 440.999819 -303.136885)
			(xy 440.987693 -303.082448) (xy 440.983622 -303.026826) (xy 440.731148 -303.026826) (xy 440.730639 -303.054712)
			(xy 440.722519 -303.109888) (xy 440.706451 -303.163295) (xy 440.682779 -303.213792) (xy 440.652006 -303.260305)
			(xy 440.614789 -303.301842) (xy 440.571921 -303.337517) (xy 440.524315 -303.366571) (xy 440.472986 -303.388383)
			(xy 440.419029 -303.402489) (xy 440.363592 -303.408589) (xy 440.307858 -303.406552) (xy 440.253015 -303.396422)
			(xy 440.200231 -303.378415) (xy 440.150631 -303.352914) (xy 440.105273 -303.320463) (xy 440.065124 -303.281754)
			(xy 440.031038 -303.237611) (xy 440.003742 -303.188976) (xy 439.983819 -303.136885) (xy 439.971693 -303.082448)
			(xy 439.967622 -303.026826) (xy 439.715148 -303.026826) (xy 439.714639 -303.054712) (xy 439.706519 -303.109888)
			(xy 439.690451 -303.163295) (xy 439.666779 -303.213792) (xy 439.636006 -303.260305) (xy 439.598789 -303.301842)
			(xy 439.555921 -303.337517) (xy 439.508315 -303.366571) (xy 439.456986 -303.388383) (xy 439.403029 -303.402489)
			(xy 439.347592 -303.408589) (xy 439.291858 -303.406552) (xy 439.237015 -303.396422) (xy 439.184231 -303.378415)
			(xy 439.134631 -303.352914) (xy 439.089273 -303.320463) (xy 439.049124 -303.281754) (xy 439.015038 -303.237611)
			(xy 438.987742 -303.188976) (xy 438.967819 -303.136885) (xy 438.955693 -303.082448) (xy 438.951622 -303.026826)
			(xy 438.699148 -303.026826) (xy 438.698639 -303.054712) (xy 438.690519 -303.109888) (xy 438.674451 -303.163295)
			(xy 438.650779 -303.213792) (xy 438.620006 -303.260305) (xy 438.582789 -303.301842) (xy 438.539921 -303.337517)
			(xy 438.492315 -303.366571) (xy 438.440986 -303.388383) (xy 438.387029 -303.402489) (xy 438.331592 -303.408589)
			(xy 438.275858 -303.406552) (xy 438.221015 -303.396422) (xy 438.168231 -303.378415) (xy 438.118631 -303.352914)
			(xy 438.073273 -303.320463) (xy 438.033124 -303.281754) (xy 437.999038 -303.237611) (xy 437.971742 -303.188976)
			(xy 437.951819 -303.136885) (xy 437.939693 -303.082448) (xy 437.935622 -303.026826) (xy 437.683148 -303.026826)
			(xy 437.682639 -303.054712) (xy 437.674519 -303.109888) (xy 437.658451 -303.163295) (xy 437.634779 -303.213792)
			(xy 437.604006 -303.260305) (xy 437.566789 -303.301842) (xy 437.523921 -303.337517) (xy 437.476315 -303.366571)
			(xy 437.424986 -303.388383) (xy 437.371029 -303.402489) (xy 437.315592 -303.408589) (xy 437.259858 -303.406552)
			(xy 437.205015 -303.396422) (xy 437.152231 -303.378415) (xy 437.102631 -303.352914) (xy 437.057273 -303.320463)
			(xy 437.017124 -303.281754) (xy 436.983038 -303.237611) (xy 436.955742 -303.188976) (xy 436.935819 -303.136885)
			(xy 436.923693 -303.082448) (xy 436.919622 -303.026826) (xy 435.110439 -303.026826) (xy 435.125957 -303.050392)
			(xy 435.148971 -303.099133) (xy 435.164897 -303.150627) (xy 435.173419 -303.20385) (xy 435.17439 -303.230788)
			(xy 435.17439 -303.237392) (xy 435.1739 -303.265023) (xy 435.165928 -303.319707) (xy 435.150148 -303.372669)
			(xy 435.126893 -303.4228) (xy 435.11216 -303.44618) (xy 435.11216 -303.446434) (xy 435.10667 -303.455736)
			(xy 435.103374 -303.47706) (xy 435.10581 -303.487582) (xy 435.125876 -303.560988) (xy 435.129246 -303.571357)
			(xy 435.143199 -303.588081) (xy 435.1528 -303.593246) (xy 435.176573 -303.605333) (xy 435.220786 -303.635156)
			(xy 435.260418 -303.670842) (xy 435.294696 -303.711699) (xy 435.322952 -303.756929) (xy 435.344636 -303.805653)
			(xy 435.359327 -303.856921) (xy 435.366737 -303.909734) (xy 435.367176 -303.9364) (xy 435.366713 -303.962934)
			(xy 435.359347 -304.01549) (xy 435.344771 -304.066517) (xy 435.323267 -304.115034) (xy 435.295249 -304.160104)
			(xy 435.261257 -304.200857) (xy 435.221947 -304.236509) (xy 435.178077 -304.266371) (xy 435.130493 -304.289867)
			(xy 435.080113 -304.306544) (xy 435.027908 -304.316082) (xy 435.001416 -304.317654) (xy 434.98389 -304.318416)
			(xy 434.957728 -304.34026) (xy 434.950362 -304.373534) (xy 434.949113 -304.380048) (xy 434.94963 -304.393297)
			(xy 434.951378 -304.399696) (xy 434.955281 -304.410316) (xy 434.970577 -304.426945) (xy 434.980842 -304.4317)
			(xy 434.991256 -304.435764) (xy 435.000654 -304.439574) (xy 436.29072 -304.439574) (xy 436.294399 -304.439476)
			(xy 436.301667 -304.438326) (xy 436.305198 -304.437288) (xy 436.324248 -304.4317) (xy 436.333138 -304.426112)
			(xy 436.342028 -304.421032) (xy 436.34533 -304.419508) (xy 436.34787 -304.417984) (xy 436.355744 -304.413666)
			(xy 436.364634 -304.409348) (xy 436.364888 -304.409094) (xy 436.368698 -304.407316) (xy 436.373778 -304.40503)
			(xy 436.384163 -304.400414) (xy 436.405385 -304.392279) (xy 436.416196 -304.388774) (xy 436.444115 -304.380519)
			(xy 436.501643 -304.37159) (xy 436.53075 -304.370994) (xy 436.555151 -304.371412) (xy 436.603546 -304.377701)
			(xy 436.650742 -304.390118) (xy 436.673498 -304.398934) (xy 436.68666 -304.404376) (xy 436.712212 -304.416966)
			(xy 436.724552 -304.42408) (xy 436.730902 -304.42789) (xy 436.736744 -304.431446) (xy 436.763668 -304.439574)
			(xy 448.23761 -304.439574) (xy 448.247679 -304.439148) (xy 448.266278 -304.431429) (xy 448.273678 -304.424588)
			(xy 448.732148 -303.966118) (xy 448.739548 -303.959277) (xy 448.758147 -303.951557) (xy 448.768216 -303.951132)
			(xy 465.200746 -303.951132) (xy 465.210813 -303.950701) (xy 465.229409 -303.942979) (xy 465.236814 -303.936146)
			(xy 465.881974 -303.290986) (xy 465.882482 -303.290478) (xy 465.889066 -303.283097) (xy 465.896523 -303.264799)
			(xy 465.89696 -303.254918) (xy 465.89696 -254.788162) (xy 465.896529 -254.778096) (xy 465.8888 -254.759505)
			(xy 465.881974 -254.752094) (xy 465.359496 -254.229616) (xy 465.352384 -254.22225) (xy 465.333588 -254.21463)
			(xy 460.228188 -254.21463) (xy 460.21498 -254.212852) (xy 460.211678 -254.211836) (xy 460.207868 -254.210312)
			(xy 460.203458 -254.208755) (xy 460.194256 -254.207099) (xy 460.18958 -254.20701) (xy 458.753972 -254.20701)
			(xy 458.747368 -254.206794) (xy 458.734622 -254.203325) (xy 458.728826 -254.200152) (xy 458.727556 -254.199644)
			(xy 458.723238 -254.197358) (xy 458.717912 -254.194897) (xy 458.706496 -254.192206) (xy 458.700632 -254.192024)
			(xy 412.453328 -254.192024) (xy 412.434532 -254.199644) (xy 412.42742 -254.20701) (xy 409.859988 -256.774442)
			(xy 409.854609 -256.780193) (xy 409.847367 -256.794164) (xy 409.845764 -256.801874) (xy 409.478311 -258.92633)
			(xy 448.944998 -258.92633) (xy 448.949069 -258.870708) (xy 448.961195 -258.816271) (xy 448.981118 -258.76418)
			(xy 449.008414 -258.715545) (xy 449.0425 -258.671402) (xy 449.082649 -258.632693) (xy 449.128007 -258.600242)
			(xy 449.177607 -258.574741) (xy 449.230391 -258.556734) (xy 449.285234 -258.546604) (xy 449.340968 -258.544567)
			(xy 449.396405 -258.550667) (xy 449.450362 -258.564773) (xy 449.501691 -258.586585) (xy 449.549297 -258.615639)
			(xy 449.592165 -258.651314) (xy 449.629382 -258.692851) (xy 449.660155 -258.739364) (xy 449.683827 -258.789861)
			(xy 449.699895 -258.843268) (xy 449.706213 -258.886198) (xy 450.433184 -258.886198) (xy 450.437255 -258.830576)
			(xy 450.449381 -258.776139) (xy 450.469304 -258.724048) (xy 450.4966 -258.675413) (xy 450.530686 -258.63127)
			(xy 450.570835 -258.592561) (xy 450.616193 -258.56011) (xy 450.665793 -258.534609) (xy 450.718577 -258.516602)
			(xy 450.77342 -258.506472) (xy 450.829154 -258.504435) (xy 450.884591 -258.510535) (xy 450.938548 -258.524641)
			(xy 450.989877 -258.546453) (xy 451.037483 -258.575507) (xy 451.080351 -258.611182) (xy 451.117568 -258.652719)
			(xy 451.148341 -258.699232) (xy 451.172013 -258.749729) (xy 451.188081 -258.803136) (xy 451.196201 -258.858312)
			(xy 451.19671 -258.886198) (xy 451.196201 -258.914084) (xy 451.191446 -258.946396) (xy 451.94169 -258.946396)
			(xy 451.945761 -258.890774) (xy 451.957887 -258.836337) (xy 451.97781 -258.784246) (xy 452.005106 -258.735611)
			(xy 452.039192 -258.691468) (xy 452.079341 -258.652759) (xy 452.124699 -258.620308) (xy 452.174299 -258.594807)
			(xy 452.227083 -258.5768) (xy 452.281926 -258.56667) (xy 452.33766 -258.564633) (xy 452.393097 -258.570733)
			(xy 452.447054 -258.584839) (xy 452.498383 -258.606651) (xy 452.545989 -258.635705) (xy 452.588857 -258.67138)
			(xy 452.626074 -258.712917) (xy 452.656847 -258.75943) (xy 452.680519 -258.809927) (xy 452.696587 -258.863334)
			(xy 452.699952 -258.886198) (xy 453.449942 -258.886198) (xy 453.454013 -258.830576) (xy 453.466139 -258.776139)
			(xy 453.486062 -258.724048) (xy 453.513358 -258.675413) (xy 453.547444 -258.63127) (xy 453.587593 -258.592561)
			(xy 453.632951 -258.56011) (xy 453.682551 -258.534609) (xy 453.735335 -258.516602) (xy 453.790178 -258.506472)
			(xy 453.845912 -258.504435) (xy 453.901349 -258.510535) (xy 453.955306 -258.524641) (xy 454.006635 -258.546453)
			(xy 454.054241 -258.575507) (xy 454.097109 -258.611182) (xy 454.134326 -258.652719) (xy 454.165099 -258.699232)
			(xy 454.188771 -258.749729) (xy 454.19353 -258.765548) (xy 455.159362 -258.765548) (xy 455.163433 -258.709926)
			(xy 455.175559 -258.655489) (xy 455.195482 -258.603398) (xy 455.222778 -258.554763) (xy 455.256864 -258.51062)
			(xy 455.297013 -258.471911) (xy 455.342371 -258.43946) (xy 455.391971 -258.413959) (xy 455.444755 -258.395952)
			(xy 455.499598 -258.385822) (xy 455.555332 -258.383785) (xy 455.610769 -258.389885) (xy 455.664726 -258.403991)
			(xy 455.716055 -258.425803) (xy 455.763661 -258.454857) (xy 455.806529 -258.490532) (xy 455.843746 -258.532069)
			(xy 455.874519 -258.578582) (xy 455.898191 -258.629079) (xy 455.914259 -258.682486) (xy 455.922379 -258.737662)
			(xy 455.922888 -258.765548) (xy 455.922379 -258.793434) (xy 455.917624 -258.825746) (xy 456.728066 -258.825746)
			(xy 456.732137 -258.770124) (xy 456.744263 -258.715687) (xy 456.764186 -258.663596) (xy 456.791482 -258.614961)
			(xy 456.825568 -258.570818) (xy 456.865717 -258.532109) (xy 456.911075 -258.499658) (xy 456.960675 -258.474157)
			(xy 457.013459 -258.45615) (xy 457.068302 -258.44602) (xy 457.124036 -258.443983) (xy 457.179473 -258.450083)
			(xy 457.23343 -258.464189) (xy 457.284759 -258.486001) (xy 457.332365 -258.515055) (xy 457.375233 -258.55073)
			(xy 457.41245 -258.592267) (xy 457.443223 -258.63878) (xy 457.466895 -258.689277) (xy 457.482963 -258.742684)
			(xy 457.491083 -258.79786) (xy 457.491592 -258.825746) (xy 457.491226 -258.845812) (xy 458.135734 -258.845812)
			(xy 458.139805 -258.79019) (xy 458.151931 -258.735753) (xy 458.171854 -258.683662) (xy 458.19915 -258.635027)
			(xy 458.233236 -258.590884) (xy 458.273385 -258.552175) (xy 458.318743 -258.519724) (xy 458.368343 -258.494223)
			(xy 458.421127 -258.476216) (xy 458.47597 -258.466086) (xy 458.531704 -258.464049) (xy 458.587141 -258.470149)
			(xy 458.641098 -258.484255) (xy 458.692427 -258.506067) (xy 458.740033 -258.535121) (xy 458.782901 -258.570796)
			(xy 458.820118 -258.612333) (xy 458.850891 -258.658846) (xy 458.874563 -258.709343) (xy 458.890631 -258.76275)
			(xy 458.898751 -258.817926) (xy 458.89926 -258.845812) (xy 458.898751 -258.873698) (xy 458.890631 -258.928874)
			(xy 458.874563 -258.982281) (xy 458.850891 -259.032778) (xy 458.820118 -259.079291) (xy 458.782901 -259.120828)
			(xy 458.740033 -259.156503) (xy 458.692427 -259.185557) (xy 458.641098 -259.207369) (xy 458.587141 -259.221475)
			(xy 458.531704 -259.227575) (xy 458.47597 -259.225538) (xy 458.421127 -259.215408) (xy 458.368343 -259.197401)
			(xy 458.318743 -259.1719) (xy 458.273385 -259.139449) (xy 458.233236 -259.10074) (xy 458.19915 -259.056597)
			(xy 458.171854 -259.007962) (xy 458.151931 -258.955871) (xy 458.139805 -258.901434) (xy 458.135734 -258.845812)
			(xy 457.491226 -258.845812) (xy 457.491083 -258.853632) (xy 457.482963 -258.908808) (xy 457.466895 -258.962215)
			(xy 457.443223 -259.012712) (xy 457.41245 -259.059225) (xy 457.375233 -259.100762) (xy 457.332365 -259.136437)
			(xy 457.284759 -259.165491) (xy 457.23343 -259.187303) (xy 457.179473 -259.201409) (xy 457.124036 -259.207509)
			(xy 457.068302 -259.205472) (xy 457.013459 -259.195342) (xy 456.960675 -259.177335) (xy 456.911075 -259.151834)
			(xy 456.865717 -259.119383) (xy 456.825568 -259.080674) (xy 456.791482 -259.036531) (xy 456.764186 -258.987896)
			(xy 456.744263 -258.935805) (xy 456.732137 -258.881368) (xy 456.728066 -258.825746) (xy 455.917624 -258.825746)
			(xy 455.914259 -258.84861) (xy 455.898191 -258.902017) (xy 455.874519 -258.952514) (xy 455.843746 -258.999027)
			(xy 455.806529 -259.040564) (xy 455.763661 -259.076239) (xy 455.716055 -259.105293) (xy 455.664726 -259.127105)
			(xy 455.610769 -259.141211) (xy 455.555332 -259.147311) (xy 455.499598 -259.145274) (xy 455.444755 -259.135144)
			(xy 455.391971 -259.117137) (xy 455.342371 -259.091636) (xy 455.297013 -259.059185) (xy 455.256864 -259.020476)
			(xy 455.222778 -258.976333) (xy 455.195482 -258.927698) (xy 455.175559 -258.875607) (xy 455.163433 -258.82117)
			(xy 455.159362 -258.765548) (xy 454.19353 -258.765548) (xy 454.204839 -258.803136) (xy 454.212959 -258.858312)
			(xy 454.213468 -258.886198) (xy 454.212959 -258.914084) (xy 454.204839 -258.96926) (xy 454.188771 -259.022667)
			(xy 454.165099 -259.073164) (xy 454.134326 -259.119677) (xy 454.097109 -259.161214) (xy 454.054241 -259.196889)
			(xy 454.006635 -259.225943) (xy 453.955306 -259.247755) (xy 453.901349 -259.261861) (xy 453.845912 -259.267961)
			(xy 453.790178 -259.265924) (xy 453.735335 -259.255794) (xy 453.682551 -259.237787) (xy 453.632951 -259.212286)
			(xy 453.587593 -259.179835) (xy 453.547444 -259.141126) (xy 453.513358 -259.096983) (xy 453.486062 -259.048348)
			(xy 453.466139 -258.996257) (xy 453.454013 -258.94182) (xy 453.449942 -258.886198) (xy 452.699952 -258.886198)
			(xy 452.704707 -258.91851) (xy 452.705216 -258.946396) (xy 452.704707 -258.974282) (xy 452.696587 -259.029458)
			(xy 452.680519 -259.082865) (xy 452.656847 -259.133362) (xy 452.626074 -259.179875) (xy 452.588857 -259.221412)
			(xy 452.545989 -259.257087) (xy 452.498383 -259.286141) (xy 452.447054 -259.307953) (xy 452.393097 -259.322059)
			(xy 452.33766 -259.328159) (xy 452.281926 -259.326122) (xy 452.227083 -259.315992) (xy 452.174299 -259.297985)
			(xy 452.124699 -259.272484) (xy 452.079341 -259.240033) (xy 452.039192 -259.201324) (xy 452.005106 -259.157181)
			(xy 451.97781 -259.108546) (xy 451.957887 -259.056455) (xy 451.945761 -259.002018) (xy 451.94169 -258.946396)
			(xy 451.191446 -258.946396) (xy 451.188081 -258.96926) (xy 451.172013 -259.022667) (xy 451.148341 -259.073164)
			(xy 451.117568 -259.119677) (xy 451.080351 -259.161214) (xy 451.037483 -259.196889) (xy 450.989877 -259.225943)
			(xy 450.938548 -259.247755) (xy 450.884591 -259.261861) (xy 450.829154 -259.267961) (xy 450.77342 -259.265924)
			(xy 450.718577 -259.255794) (xy 450.665793 -259.237787) (xy 450.616193 -259.212286) (xy 450.570835 -259.179835)
			(xy 450.530686 -259.141126) (xy 450.4966 -259.096983) (xy 450.469304 -259.048348) (xy 450.449381 -258.996257)
			(xy 450.437255 -258.94182) (xy 450.433184 -258.886198) (xy 449.706213 -258.886198) (xy 449.708015 -258.898444)
			(xy 449.708524 -258.92633) (xy 449.708015 -258.954216) (xy 449.699895 -259.009392) (xy 449.683827 -259.062799)
			(xy 449.660155 -259.113296) (xy 449.629382 -259.159809) (xy 449.592165 -259.201346) (xy 449.549297 -259.237021)
			(xy 449.501691 -259.266075) (xy 449.450362 -259.287887) (xy 449.396405 -259.301993) (xy 449.340968 -259.308093)
			(xy 449.285234 -259.306056) (xy 449.230391 -259.295926) (xy 449.177607 -259.277919) (xy 449.128007 -259.252418)
			(xy 449.082649 -259.219967) (xy 449.0425 -259.181258) (xy 449.008414 -259.137115) (xy 448.981118 -259.08848)
			(xy 448.961195 -259.036389) (xy 448.949069 -258.981952) (xy 448.944998 -258.92633) (xy 409.478311 -258.92633)
			(xy 409.366327 -259.573776) (xy 446.548508 -259.573776) (xy 446.552579 -259.518154) (xy 446.564705 -259.463717)
			(xy 446.584628 -259.411626) (xy 446.611924 -259.362991) (xy 446.64601 -259.318848) (xy 446.686159 -259.280139)
			(xy 446.731517 -259.247688) (xy 446.781117 -259.222187) (xy 446.833901 -259.20418) (xy 446.888744 -259.19405)
			(xy 446.944478 -259.192013) (xy 446.999915 -259.198113) (xy 447.053872 -259.212219) (xy 447.105201 -259.234031)
			(xy 447.152807 -259.263085) (xy 447.195675 -259.29876) (xy 447.232892 -259.340297) (xy 447.242842 -259.355336)
			(xy 459.730854 -259.355336) (xy 459.734925 -259.299714) (xy 459.747051 -259.245277) (xy 459.766974 -259.193186)
			(xy 459.79427 -259.144551) (xy 459.828356 -259.100408) (xy 459.868505 -259.061699) (xy 459.913863 -259.029248)
			(xy 459.963463 -259.003747) (xy 460.016247 -258.98574) (xy 460.07109 -258.97561) (xy 460.126824 -258.973573)
			(xy 460.182261 -258.979673) (xy 460.236218 -258.993779) (xy 460.287547 -259.015591) (xy 460.335153 -259.044645)
			(xy 460.378021 -259.08032) (xy 460.415238 -259.121857) (xy 460.446011 -259.16837) (xy 460.469683 -259.218867)
			(xy 460.485751 -259.272274) (xy 460.493871 -259.32745) (xy 460.49438 -259.355336) (xy 460.493871 -259.383222)
			(xy 460.485751 -259.438398) (xy 460.469683 -259.491805) (xy 460.446011 -259.542302) (xy 460.415238 -259.588815)
			(xy 460.378021 -259.630352) (xy 460.335153 -259.666027) (xy 460.287547 -259.695081) (xy 460.236218 -259.716893)
			(xy 460.182261 -259.730999) (xy 460.126824 -259.737099) (xy 460.07109 -259.735062) (xy 460.016247 -259.724932)
			(xy 459.963463 -259.706925) (xy 459.913863 -259.681424) (xy 459.868505 -259.648973) (xy 459.828356 -259.610264)
			(xy 459.79427 -259.566121) (xy 459.766974 -259.517486) (xy 459.747051 -259.465395) (xy 459.734925 -259.410958)
			(xy 459.730854 -259.355336) (xy 447.242842 -259.355336) (xy 447.263665 -259.38681) (xy 447.287337 -259.437307)
			(xy 447.303405 -259.490714) (xy 447.311525 -259.54589) (xy 447.312034 -259.573776) (xy 447.311525 -259.601662)
			(xy 447.303405 -259.656838) (xy 447.287337 -259.710245) (xy 447.263665 -259.760742) (xy 447.232892 -259.807255)
			(xy 447.195675 -259.848792) (xy 447.152807 -259.884467) (xy 447.105201 -259.913521) (xy 447.053872 -259.935333)
			(xy 446.999915 -259.949439) (xy 446.944478 -259.955539) (xy 446.888744 -259.953502) (xy 446.833901 -259.943372)
			(xy 446.781117 -259.925365) (xy 446.731517 -259.899864) (xy 446.686159 -259.867413) (xy 446.64601 -259.828704)
			(xy 446.611924 -259.784561) (xy 446.584628 -259.735926) (xy 446.564705 -259.683835) (xy 446.552579 -259.629398)
			(xy 446.548508 -259.573776) (xy 409.366327 -259.573776) (xy 409.289445 -260.018276) (xy 448.904358 -260.018276)
			(xy 448.908429 -259.962654) (xy 448.920555 -259.908217) (xy 448.940478 -259.856126) (xy 448.967774 -259.807491)
			(xy 449.00186 -259.763348) (xy 449.042009 -259.724639) (xy 449.087367 -259.692188) (xy 449.136967 -259.666687)
			(xy 449.189751 -259.64868) (xy 449.244594 -259.63855) (xy 449.300328 -259.636513) (xy 449.355765 -259.642613)
			(xy 449.409722 -259.656719) (xy 449.461051 -259.678531) (xy 449.508657 -259.707585) (xy 449.551525 -259.74326)
			(xy 449.588742 -259.784797) (xy 449.619515 -259.83131) (xy 449.643187 -259.881807) (xy 449.659255 -259.935214)
			(xy 449.667375 -259.99039) (xy 449.667884 -260.018276) (xy 450.428358 -260.018276) (xy 450.432429 -259.962654)
			(xy 450.444555 -259.908217) (xy 450.464478 -259.856126) (xy 450.491774 -259.807491) (xy 450.52586 -259.763348)
			(xy 450.566009 -259.724639) (xy 450.611367 -259.692188) (xy 450.660967 -259.666687) (xy 450.713751 -259.64868)
			(xy 450.768594 -259.63855) (xy 450.824328 -259.636513) (xy 450.879765 -259.642613) (xy 450.933722 -259.656719)
			(xy 450.985051 -259.678531) (xy 451.032657 -259.707585) (xy 451.075525 -259.74326) (xy 451.112742 -259.784797)
			(xy 451.143515 -259.83131) (xy 451.167187 -259.881807) (xy 451.183255 -259.935214) (xy 451.185685 -259.951728)
			(xy 451.492364 -259.951728) (xy 451.496435 -259.896106) (xy 451.508561 -259.841669) (xy 451.528484 -259.789578)
			(xy 451.55578 -259.740943) (xy 451.589866 -259.6968) (xy 451.630015 -259.658091) (xy 451.675373 -259.62564)
			(xy 451.724973 -259.600139) (xy 451.777757 -259.582132) (xy 451.8326 -259.572002) (xy 451.888334 -259.569965)
			(xy 451.943771 -259.576065) (xy 451.997728 -259.590171) (xy 452.049057 -259.611983) (xy 452.096663 -259.641037)
			(xy 452.139531 -259.676712) (xy 452.176748 -259.718249) (xy 452.207521 -259.764762) (xy 452.231193 -259.815259)
			(xy 452.247261 -259.868666) (xy 452.255381 -259.923842) (xy 452.25589 -259.951728) (xy 452.255381 -259.979614)
			(xy 452.249691 -260.018276) (xy 452.714358 -260.018276) (xy 452.718429 -259.962654) (xy 452.730555 -259.908217)
			(xy 452.750478 -259.856126) (xy 452.777774 -259.807491) (xy 452.81186 -259.763348) (xy 452.852009 -259.724639)
			(xy 452.897367 -259.692188) (xy 452.946967 -259.666687) (xy 452.999751 -259.64868) (xy 453.054594 -259.63855)
			(xy 453.110328 -259.636513) (xy 453.165765 -259.642613) (xy 453.219722 -259.656719) (xy 453.271051 -259.678531)
			(xy 453.318657 -259.707585) (xy 453.361525 -259.74326) (xy 453.398742 -259.784797) (xy 453.429515 -259.83131)
			(xy 453.453187 -259.881807) (xy 453.469255 -259.935214) (xy 453.477375 -259.99039) (xy 453.477884 -260.018276)
			(xy 454.238358 -260.018276) (xy 454.242429 -259.962654) (xy 454.254555 -259.908217) (xy 454.274478 -259.856126)
			(xy 454.301774 -259.807491) (xy 454.33586 -259.763348) (xy 454.376009 -259.724639) (xy 454.421367 -259.692188)
			(xy 454.470967 -259.666687) (xy 454.523751 -259.64868) (xy 454.578594 -259.63855) (xy 454.634328 -259.636513)
			(xy 454.689765 -259.642613) (xy 454.743722 -259.656719) (xy 454.795051 -259.678531) (xy 454.842657 -259.707585)
			(xy 454.885525 -259.74326) (xy 454.922742 -259.784797) (xy 454.953515 -259.83131) (xy 454.977187 -259.881807)
			(xy 454.993255 -259.935214) (xy 455.001375 -259.99039) (xy 455.001884 -260.018276) (xy 455.762358 -260.018276)
			(xy 455.766429 -259.962654) (xy 455.778555 -259.908217) (xy 455.798478 -259.856126) (xy 455.825774 -259.807491)
			(xy 455.85986 -259.763348) (xy 455.900009 -259.724639) (xy 455.945367 -259.692188) (xy 455.994967 -259.666687)
			(xy 456.047751 -259.64868) (xy 456.102594 -259.63855) (xy 456.158328 -259.636513) (xy 456.213765 -259.642613)
			(xy 456.267722 -259.656719) (xy 456.319051 -259.678531) (xy 456.366657 -259.707585) (xy 456.409525 -259.74326)
			(xy 456.446742 -259.784797) (xy 456.477515 -259.83131) (xy 456.501187 -259.881807) (xy 456.517255 -259.935214)
			(xy 456.525375 -259.99039) (xy 456.525884 -260.018276) (xy 457.286358 -260.018276) (xy 457.290429 -259.962654)
			(xy 457.302555 -259.908217) (xy 457.322478 -259.856126) (xy 457.349774 -259.807491) (xy 457.38386 -259.763348)
			(xy 457.424009 -259.724639) (xy 457.469367 -259.692188) (xy 457.518967 -259.666687) (xy 457.571751 -259.64868)
			(xy 457.626594 -259.63855) (xy 457.682328 -259.636513) (xy 457.737765 -259.642613) (xy 457.791722 -259.656719)
			(xy 457.843051 -259.678531) (xy 457.890657 -259.707585) (xy 457.933525 -259.74326) (xy 457.970742 -259.784797)
			(xy 458.001515 -259.83131) (xy 458.025187 -259.881807) (xy 458.041255 -259.935214) (xy 458.049375 -259.99039)
			(xy 458.049884 -260.018276) (xy 458.810358 -260.018276) (xy 458.814429 -259.962654) (xy 458.826555 -259.908217)
			(xy 458.846478 -259.856126) (xy 458.873774 -259.807491) (xy 458.90786 -259.763348) (xy 458.948009 -259.724639)
			(xy 458.993367 -259.692188) (xy 459.042967 -259.666687) (xy 459.095751 -259.64868) (xy 459.150594 -259.63855)
			(xy 459.206328 -259.636513) (xy 459.261765 -259.642613) (xy 459.315722 -259.656719) (xy 459.367051 -259.678531)
			(xy 459.414657 -259.707585) (xy 459.457525 -259.74326) (xy 459.494742 -259.784797) (xy 459.525515 -259.83131)
			(xy 459.549187 -259.881807) (xy 459.565255 -259.935214) (xy 459.573375 -259.99039) (xy 459.573884 -260.018276)
			(xy 459.573375 -260.046162) (xy 459.565255 -260.101338) (xy 459.549187 -260.154745) (xy 459.525515 -260.205242)
			(xy 459.494742 -260.251755) (xy 459.457525 -260.293292) (xy 459.414657 -260.328967) (xy 459.367051 -260.358021)
			(xy 459.315722 -260.379833) (xy 459.261765 -260.393939) (xy 459.206328 -260.400039) (xy 459.150594 -260.398002)
			(xy 459.095751 -260.387872) (xy 459.042967 -260.369865) (xy 458.993367 -260.344364) (xy 458.948009 -260.311913)
			(xy 458.90786 -260.273204) (xy 458.873774 -260.229061) (xy 458.846478 -260.180426) (xy 458.826555 -260.128335)
			(xy 458.814429 -260.073898) (xy 458.810358 -260.018276) (xy 458.049884 -260.018276) (xy 458.049375 -260.046162)
			(xy 458.041255 -260.101338) (xy 458.025187 -260.154745) (xy 458.001515 -260.205242) (xy 457.970742 -260.251755)
			(xy 457.933525 -260.293292) (xy 457.890657 -260.328967) (xy 457.843051 -260.358021) (xy 457.791722 -260.379833)
			(xy 457.737765 -260.393939) (xy 457.682328 -260.400039) (xy 457.626594 -260.398002) (xy 457.571751 -260.387872)
			(xy 457.518967 -260.369865) (xy 457.469367 -260.344364) (xy 457.424009 -260.311913) (xy 457.38386 -260.273204)
			(xy 457.349774 -260.229061) (xy 457.322478 -260.180426) (xy 457.302555 -260.128335) (xy 457.290429 -260.073898)
			(xy 457.286358 -260.018276) (xy 456.525884 -260.018276) (xy 456.525375 -260.046162) (xy 456.517255 -260.101338)
			(xy 456.501187 -260.154745) (xy 456.477515 -260.205242) (xy 456.446742 -260.251755) (xy 456.409525 -260.293292)
			(xy 456.366657 -260.328967) (xy 456.319051 -260.358021) (xy 456.267722 -260.379833) (xy 456.213765 -260.393939)
			(xy 456.158328 -260.400039) (xy 456.102594 -260.398002) (xy 456.047751 -260.387872) (xy 455.994967 -260.369865)
			(xy 455.945367 -260.344364) (xy 455.900009 -260.311913) (xy 455.85986 -260.273204) (xy 455.825774 -260.229061)
			(xy 455.798478 -260.180426) (xy 455.778555 -260.128335) (xy 455.766429 -260.073898) (xy 455.762358 -260.018276)
			(xy 455.001884 -260.018276) (xy 455.001375 -260.046162) (xy 454.993255 -260.101338) (xy 454.977187 -260.154745)
			(xy 454.953515 -260.205242) (xy 454.922742 -260.251755) (xy 454.885525 -260.293292) (xy 454.842657 -260.328967)
			(xy 454.795051 -260.358021) (xy 454.743722 -260.379833) (xy 454.689765 -260.393939) (xy 454.634328 -260.400039)
			(xy 454.578594 -260.398002) (xy 454.523751 -260.387872) (xy 454.470967 -260.369865) (xy 454.421367 -260.344364)
			(xy 454.376009 -260.311913) (xy 454.33586 -260.273204) (xy 454.301774 -260.229061) (xy 454.274478 -260.180426)
			(xy 454.254555 -260.128335) (xy 454.242429 -260.073898) (xy 454.238358 -260.018276) (xy 453.477884 -260.018276)
			(xy 453.477375 -260.046162) (xy 453.469255 -260.101338) (xy 453.453187 -260.154745) (xy 453.429515 -260.205242)
			(xy 453.398742 -260.251755) (xy 453.361525 -260.293292) (xy 453.318657 -260.328967) (xy 453.271051 -260.358021)
			(xy 453.219722 -260.379833) (xy 453.165765 -260.393939) (xy 453.110328 -260.400039) (xy 453.054594 -260.398002)
			(xy 452.999751 -260.387872) (xy 452.946967 -260.369865) (xy 452.897367 -260.344364) (xy 452.852009 -260.311913)
			(xy 452.81186 -260.273204) (xy 452.777774 -260.229061) (xy 452.750478 -260.180426) (xy 452.730555 -260.128335)
			(xy 452.718429 -260.073898) (xy 452.714358 -260.018276) (xy 452.249691 -260.018276) (xy 452.247261 -260.03479)
			(xy 452.231193 -260.088197) (xy 452.207521 -260.138694) (xy 452.176748 -260.185207) (xy 452.139531 -260.226744)
			(xy 452.096663 -260.262419) (xy 452.049057 -260.291473) (xy 451.997728 -260.313285) (xy 451.943771 -260.327391)
			(xy 451.888334 -260.333491) (xy 451.8326 -260.331454) (xy 451.777757 -260.321324) (xy 451.724973 -260.303317)
			(xy 451.675373 -260.277816) (xy 451.630015 -260.245365) (xy 451.589866 -260.206656) (xy 451.55578 -260.162513)
			(xy 451.528484 -260.113878) (xy 451.508561 -260.061787) (xy 451.496435 -260.00735) (xy 451.492364 -259.951728)
			(xy 451.185685 -259.951728) (xy 451.191375 -259.99039) (xy 451.191884 -260.018276) (xy 451.191375 -260.046162)
			(xy 451.183255 -260.101338) (xy 451.167187 -260.154745) (xy 451.143515 -260.205242) (xy 451.112742 -260.251755)
			(xy 451.075525 -260.293292) (xy 451.032657 -260.328967) (xy 450.985051 -260.358021) (xy 450.933722 -260.379833)
			(xy 450.879765 -260.393939) (xy 450.824328 -260.400039) (xy 450.768594 -260.398002) (xy 450.713751 -260.387872)
			(xy 450.660967 -260.369865) (xy 450.611367 -260.344364) (xy 450.566009 -260.311913) (xy 450.52586 -260.273204)
			(xy 450.491774 -260.229061) (xy 450.464478 -260.180426) (xy 450.444555 -260.128335) (xy 450.432429 -260.073898)
			(xy 450.428358 -260.018276) (xy 449.667884 -260.018276) (xy 449.667375 -260.046162) (xy 449.659255 -260.101338)
			(xy 449.643187 -260.154745) (xy 449.619515 -260.205242) (xy 449.588742 -260.251755) (xy 449.551525 -260.293292)
			(xy 449.508657 -260.328967) (xy 449.461051 -260.358021) (xy 449.409722 -260.379833) (xy 449.355765 -260.393939)
			(xy 449.300328 -260.400039) (xy 449.244594 -260.398002) (xy 449.189751 -260.387872) (xy 449.136967 -260.369865)
			(xy 449.087367 -260.344364) (xy 449.042009 -260.311913) (xy 449.00186 -260.273204) (xy 448.967774 -260.229061)
			(xy 448.940478 -260.180426) (xy 448.920555 -260.128335) (xy 448.908429 -260.073898) (xy 448.904358 -260.018276)
			(xy 409.289445 -260.018276) (xy 409.128593 -260.948251) (xy 448.90537 -260.948251) (xy 448.90537 -260.893749)
			(xy 448.913126 -260.839803) (xy 448.92848 -260.787509) (xy 448.95112 -260.737932) (xy 448.980585 -260.692082)
			(xy 449.016274 -260.650891) (xy 449.057462 -260.615199) (xy 449.103311 -260.585731) (xy 449.152886 -260.563088)
			(xy 449.205179 -260.547731) (xy 449.259125 -260.539971) (xy 449.286376 -260.539484) (xy 449.313443 -260.539965)
			(xy 449.367035 -260.547614) (xy 449.419007 -260.562762) (xy 449.468316 -260.585105) (xy 449.513971 -260.614194)
			(xy 449.555056 -260.649444) (xy 449.590745 -260.690148) (xy 449.620323 -260.735488) (xy 449.643193 -260.784555)
			(xy 449.658898 -260.836361) (xy 449.667122 -260.889867) (xy 449.667884 -260.916928) (xy 449.668059 -260.920992)
			(xy 450.428358 -260.920992) (xy 450.432429 -260.86537) (xy 450.444555 -260.810933) (xy 450.464478 -260.758842)
			(xy 450.491774 -260.710207) (xy 450.52586 -260.666064) (xy 450.566009 -260.627355) (xy 450.611367 -260.594904)
			(xy 450.660967 -260.569403) (xy 450.713751 -260.551396) (xy 450.768594 -260.541266) (xy 450.824328 -260.539229)
			(xy 450.879765 -260.545329) (xy 450.933722 -260.559435) (xy 450.985051 -260.581247) (xy 451.032657 -260.610301)
			(xy 451.075525 -260.645976) (xy 451.112742 -260.687513) (xy 451.143515 -260.734026) (xy 451.167187 -260.784523)
			(xy 451.183255 -260.83793) (xy 451.191375 -260.893106) (xy 451.191884 -260.920992) (xy 451.952358 -260.920992)
			(xy 451.956429 -260.86537) (xy 451.968555 -260.810933) (xy 451.988478 -260.758842) (xy 452.015774 -260.710207)
			(xy 452.04986 -260.666064) (xy 452.090009 -260.627355) (xy 452.135367 -260.594904) (xy 452.184967 -260.569403)
			(xy 452.237751 -260.551396) (xy 452.292594 -260.541266) (xy 452.348328 -260.539229) (xy 452.403765 -260.545329)
			(xy 452.457722 -260.559435) (xy 452.509051 -260.581247) (xy 452.556657 -260.610301) (xy 452.599525 -260.645976)
			(xy 452.636742 -260.687513) (xy 452.667515 -260.734026) (xy 452.691187 -260.784523) (xy 452.707255 -260.83793)
			(xy 452.715375 -260.893106) (xy 452.715884 -260.920992) (xy 453.476358 -260.920992) (xy 453.480429 -260.86537)
			(xy 453.492555 -260.810933) (xy 453.512478 -260.758842) (xy 453.539774 -260.710207) (xy 453.57386 -260.666064)
			(xy 453.614009 -260.627355) (xy 453.659367 -260.594904) (xy 453.708967 -260.569403) (xy 453.761751 -260.551396)
			(xy 453.816594 -260.541266) (xy 453.872328 -260.539229) (xy 453.927765 -260.545329) (xy 453.981722 -260.559435)
			(xy 454.033051 -260.581247) (xy 454.080657 -260.610301) (xy 454.123525 -260.645976) (xy 454.160742 -260.687513)
			(xy 454.191515 -260.734026) (xy 454.215187 -260.784523) (xy 454.231255 -260.83793) (xy 454.239375 -260.893106)
			(xy 454.239884 -260.920992) (xy 455.000358 -260.920992) (xy 455.004429 -260.86537) (xy 455.016555 -260.810933)
			(xy 455.036478 -260.758842) (xy 455.063774 -260.710207) (xy 455.09786 -260.666064) (xy 455.138009 -260.627355)
			(xy 455.183367 -260.594904) (xy 455.232967 -260.569403) (xy 455.285751 -260.551396) (xy 455.340594 -260.541266)
			(xy 455.396328 -260.539229) (xy 455.451765 -260.545329) (xy 455.505722 -260.559435) (xy 455.557051 -260.581247)
			(xy 455.604657 -260.610301) (xy 455.647525 -260.645976) (xy 455.684742 -260.687513) (xy 455.715515 -260.734026)
			(xy 455.739187 -260.784523) (xy 455.755255 -260.83793) (xy 455.763375 -260.893106) (xy 455.763884 -260.920992)
			(xy 456.524358 -260.920992) (xy 456.528429 -260.86537) (xy 456.540555 -260.810933) (xy 456.560478 -260.758842)
			(xy 456.587774 -260.710207) (xy 456.62186 -260.666064) (xy 456.662009 -260.627355) (xy 456.707367 -260.594904)
			(xy 456.756967 -260.569403) (xy 456.809751 -260.551396) (xy 456.864594 -260.541266) (xy 456.920328 -260.539229)
			(xy 456.975765 -260.545329) (xy 457.029722 -260.559435) (xy 457.081051 -260.581247) (xy 457.128657 -260.610301)
			(xy 457.171525 -260.645976) (xy 457.208742 -260.687513) (xy 457.239515 -260.734026) (xy 457.263187 -260.784523)
			(xy 457.279255 -260.83793) (xy 457.287375 -260.893106) (xy 457.287884 -260.920992) (xy 457.287375 -260.948878)
			(xy 457.283143 -260.977634) (xy 457.669136 -260.977634) (xy 457.673207 -260.922012) (xy 457.685333 -260.867575)
			(xy 457.705256 -260.815484) (xy 457.732552 -260.766849) (xy 457.766638 -260.722706) (xy 457.806787 -260.683997)
			(xy 457.852145 -260.651546) (xy 457.901745 -260.626045) (xy 457.954529 -260.608038) (xy 458.009372 -260.597908)
			(xy 458.065106 -260.595871) (xy 458.120543 -260.601971) (xy 458.1745 -260.616077) (xy 458.225829 -260.637889)
			(xy 458.273435 -260.666943) (xy 458.316303 -260.702618) (xy 458.35352 -260.744155) (xy 458.384293 -260.790668)
			(xy 458.407965 -260.841165) (xy 458.424033 -260.894572) (xy 458.427921 -260.920992) (xy 458.810358 -260.920992)
			(xy 458.814429 -260.86537) (xy 458.826555 -260.810933) (xy 458.846478 -260.758842) (xy 458.873774 -260.710207)
			(xy 458.90786 -260.666064) (xy 458.948009 -260.627355) (xy 458.993367 -260.594904) (xy 459.042967 -260.569403)
			(xy 459.095751 -260.551396) (xy 459.150594 -260.541266) (xy 459.206328 -260.539229) (xy 459.261765 -260.545329)
			(xy 459.315722 -260.559435) (xy 459.367051 -260.581247) (xy 459.414657 -260.610301) (xy 459.457525 -260.645976)
			(xy 459.494742 -260.687513) (xy 459.525515 -260.734026) (xy 459.549187 -260.784523) (xy 459.560518 -260.822186)
			(xy 460.002634 -260.822186) (xy 460.006705 -260.766564) (xy 460.018831 -260.712127) (xy 460.038754 -260.660036)
			(xy 460.06605 -260.611401) (xy 460.100136 -260.567258) (xy 460.140285 -260.528549) (xy 460.185643 -260.496098)
			(xy 460.235243 -260.470597) (xy 460.288027 -260.45259) (xy 460.34287 -260.44246) (xy 460.398604 -260.440423)
			(xy 460.454041 -260.446523) (xy 460.507998 -260.460629) (xy 460.559327 -260.482441) (xy 460.606933 -260.511495)
			(xy 460.649801 -260.54717) (xy 460.687018 -260.588707) (xy 460.717791 -260.63522) (xy 460.741463 -260.685717)
			(xy 460.757531 -260.739124) (xy 460.765651 -260.7943) (xy 460.76616 -260.822186) (xy 460.765651 -260.850072)
			(xy 460.757531 -260.905248) (xy 460.741463 -260.958655) (xy 460.717791 -261.009152) (xy 460.687018 -261.055665)
			(xy 460.649801 -261.097202) (xy 460.606933 -261.132877) (xy 460.559327 -261.161931) (xy 460.507998 -261.183743)
			(xy 460.454041 -261.197849) (xy 460.398604 -261.203949) (xy 460.34287 -261.201912) (xy 460.288027 -261.191782)
			(xy 460.235243 -261.173775) (xy 460.185643 -261.148274) (xy 460.140285 -261.115823) (xy 460.100136 -261.077114)
			(xy 460.06605 -261.032971) (xy 460.038754 -260.984336) (xy 460.018831 -260.932245) (xy 460.006705 -260.877808)
			(xy 460.002634 -260.822186) (xy 459.560518 -260.822186) (xy 459.565255 -260.83793) (xy 459.573375 -260.893106)
			(xy 459.573884 -260.920992) (xy 459.573375 -260.948878) (xy 459.565255 -261.004054) (xy 459.549187 -261.057461)
			(xy 459.525515 -261.107958) (xy 459.494742 -261.154471) (xy 459.457525 -261.196008) (xy 459.414657 -261.231683)
			(xy 459.367051 -261.260737) (xy 459.315722 -261.282549) (xy 459.261765 -261.296655) (xy 459.206328 -261.302755)
			(xy 459.150594 -261.300718) (xy 459.095751 -261.290588) (xy 459.042967 -261.272581) (xy 458.993367 -261.24708)
			(xy 458.948009 -261.214629) (xy 458.90786 -261.17592) (xy 458.873774 -261.131777) (xy 458.846478 -261.083142)
			(xy 458.826555 -261.031051) (xy 458.814429 -260.976614) (xy 458.810358 -260.920992) (xy 458.427921 -260.920992)
			(xy 458.432153 -260.949748) (xy 458.432662 -260.977634) (xy 458.432153 -261.00552) (xy 458.424033 -261.060696)
			(xy 458.407965 -261.114103) (xy 458.384293 -261.1646) (xy 458.35352 -261.211113) (xy 458.316303 -261.25265)
			(xy 458.273435 -261.288325) (xy 458.225829 -261.317379) (xy 458.1745 -261.339191) (xy 458.120543 -261.353297)
			(xy 458.065106 -261.359397) (xy 458.009372 -261.35736) (xy 457.954529 -261.34723) (xy 457.901745 -261.329223)
			(xy 457.852145 -261.303722) (xy 457.806787 -261.271271) (xy 457.766638 -261.232562) (xy 457.732552 -261.188419)
			(xy 457.705256 -261.139784) (xy 457.685333 -261.087693) (xy 457.673207 -261.033256) (xy 457.669136 -260.977634)
			(xy 457.283143 -260.977634) (xy 457.279255 -261.004054) (xy 457.263187 -261.057461) (xy 457.239515 -261.107958)
			(xy 457.208742 -261.154471) (xy 457.171525 -261.196008) (xy 457.128657 -261.231683) (xy 457.081051 -261.260737)
			(xy 457.029722 -261.282549) (xy 456.975765 -261.296655) (xy 456.920328 -261.302755) (xy 456.864594 -261.300718)
			(xy 456.809751 -261.290588) (xy 456.756967 -261.272581) (xy 456.707367 -261.24708) (xy 456.662009 -261.214629)
			(xy 456.62186 -261.17592) (xy 456.587774 -261.131777) (xy 456.560478 -261.083142) (xy 456.540555 -261.031051)
			(xy 456.528429 -260.976614) (xy 456.524358 -260.920992) (xy 455.763884 -260.920992) (xy 455.763375 -260.948878)
			(xy 455.755255 -261.004054) (xy 455.739187 -261.057461) (xy 455.715515 -261.107958) (xy 455.684742 -261.154471)
			(xy 455.647525 -261.196008) (xy 455.604657 -261.231683) (xy 455.557051 -261.260737) (xy 455.505722 -261.282549)
			(xy 455.451765 -261.296655) (xy 455.396328 -261.302755) (xy 455.340594 -261.300718) (xy 455.285751 -261.290588)
			(xy 455.232967 -261.272581) (xy 455.183367 -261.24708) (xy 455.138009 -261.214629) (xy 455.09786 -261.17592)
			(xy 455.063774 -261.131777) (xy 455.036478 -261.083142) (xy 455.016555 -261.031051) (xy 455.004429 -260.976614)
			(xy 455.000358 -260.920992) (xy 454.239884 -260.920992) (xy 454.239375 -260.948878) (xy 454.231255 -261.004054)
			(xy 454.215187 -261.057461) (xy 454.191515 -261.107958) (xy 454.160742 -261.154471) (xy 454.123525 -261.196008)
			(xy 454.080657 -261.231683) (xy 454.033051 -261.260737) (xy 453.981722 -261.282549) (xy 453.927765 -261.296655)
			(xy 453.872328 -261.302755) (xy 453.816594 -261.300718) (xy 453.761751 -261.290588) (xy 453.708967 -261.272581)
			(xy 453.659367 -261.24708) (xy 453.614009 -261.214629) (xy 453.57386 -261.17592) (xy 453.539774 -261.131777)
			(xy 453.512478 -261.083142) (xy 453.492555 -261.031051) (xy 453.480429 -260.976614) (xy 453.476358 -260.920992)
			(xy 452.715884 -260.920992) (xy 452.715375 -260.948878) (xy 452.707255 -261.004054) (xy 452.691187 -261.057461)
			(xy 452.667515 -261.107958) (xy 452.636742 -261.154471) (xy 452.599525 -261.196008) (xy 452.556657 -261.231683)
			(xy 452.509051 -261.260737) (xy 452.457722 -261.282549) (xy 452.403765 -261.296655) (xy 452.348328 -261.302755)
			(xy 452.292594 -261.300718) (xy 452.237751 -261.290588) (xy 452.184967 -261.272581) (xy 452.135367 -261.24708)
			(xy 452.090009 -261.214629) (xy 452.04986 -261.17592) (xy 452.015774 -261.131777) (xy 451.988478 -261.083142)
			(xy 451.968555 -261.031051) (xy 451.956429 -260.976614) (xy 451.952358 -260.920992) (xy 451.191884 -260.920992)
			(xy 451.191375 -260.948878) (xy 451.183255 -261.004054) (xy 451.167187 -261.057461) (xy 451.143515 -261.107958)
			(xy 451.112742 -261.154471) (xy 451.075525 -261.196008) (xy 451.032657 -261.231683) (xy 450.985051 -261.260737)
			(xy 450.933722 -261.282549) (xy 450.879765 -261.296655) (xy 450.824328 -261.302755) (xy 450.768594 -261.300718)
			(xy 450.713751 -261.290588) (xy 450.660967 -261.272581) (xy 450.611367 -261.24708) (xy 450.566009 -261.214629)
			(xy 450.52586 -261.17592) (xy 450.491774 -261.131777) (xy 450.464478 -261.083142) (xy 450.444555 -261.031051)
			(xy 450.432429 -260.976614) (xy 450.428358 -260.920992) (xy 449.668059 -260.920992) (xy 449.668467 -260.930483)
			(xy 449.675847 -260.95658) (xy 449.68984 -260.979811) (xy 449.709457 -260.998537) (xy 449.733313 -261.011436)
			(xy 449.759724 -261.017597) (xy 449.786826 -261.016585) (xy 449.812703 -261.008471) (xy 449.824348 -261.00151)
			(xy 449.847502 -260.987199) (xy 449.89702 -260.964601) (xy 449.949249 -260.949277) (xy 450.003127 -260.94154)
			(xy 450.030342 -260.941058) (xy 450.057589 -260.941615) (xy 450.111527 -260.949376) (xy 450.163812 -260.964733)
			(xy 450.21338 -260.987375) (xy 450.259221 -261.016839) (xy 450.300402 -261.052528) (xy 450.336086 -261.093713)
			(xy 450.365546 -261.139557) (xy 450.388182 -261.189127) (xy 450.403533 -261.241414) (xy 450.411288 -261.295353)
			(xy 450.411288 -261.349847) (xy 450.403533 -261.403786) (xy 450.388182 -261.456073) (xy 450.365546 -261.505643)
			(xy 450.336086 -261.551487) (xy 450.300402 -261.592672) (xy 450.259221 -261.628361) (xy 450.21338 -261.657825)
			(xy 450.163812 -261.680467) (xy 450.111527 -261.695824) (xy 450.057589 -261.703585) (xy 450.030342 -261.704074)
			(xy 450.003273 -261.703617) (xy 449.949679 -261.695969) (xy 449.897704 -261.680821) (xy 449.848392 -261.658478)
			(xy 449.802735 -261.629387) (xy 449.761649 -261.594134) (xy 449.725959 -261.553427) (xy 449.696383 -261.508082)
			(xy 449.673514 -261.459012) (xy 449.657813 -261.407202) (xy 449.649593 -261.353692) (xy 449.648834 -261.32663)
			(xy 449.648254 -261.313076) (xy 449.640865 -261.286985) (xy 449.626869 -261.26376) (xy 449.607252 -261.245038)
			(xy 449.583398 -261.232141) (xy 449.556991 -261.225979) (xy 449.529893 -261.226986) (xy 449.504016 -261.235091)
			(xy 449.49237 -261.242048) (xy 449.469209 -261.256346) (xy 449.419694 -261.278949) (xy 449.367467 -261.294276)
			(xy 449.313591 -261.302016) (xy 449.286376 -261.3025) (xy 449.259125 -261.302029) (xy 449.205179 -261.294269)
			(xy 449.152886 -261.278912) (xy 449.103311 -261.256269) (xy 449.057462 -261.226801) (xy 449.016274 -261.191109)
			(xy 448.980585 -261.149918) (xy 448.95112 -261.104068) (xy 448.92848 -261.054491) (xy 448.913126 -261.002197)
			(xy 448.90537 -260.948251) (xy 409.128593 -260.948251) (xy 409.109672 -261.057644) (xy 409.10637 -261.077456)
			(xy 409.105608 -261.086092) (xy 409.105608 -261.941056) (xy 459.446628 -261.941056) (xy 459.450699 -261.885434)
			(xy 459.462825 -261.830997) (xy 459.482748 -261.778906) (xy 459.510044 -261.730271) (xy 459.54413 -261.686128)
			(xy 459.584279 -261.647419) (xy 459.629637 -261.614968) (xy 459.679237 -261.589467) (xy 459.732021 -261.57146)
			(xy 459.786864 -261.56133) (xy 459.842598 -261.559293) (xy 459.898035 -261.565393) (xy 459.951992 -261.579499)
			(xy 460.003321 -261.601311) (xy 460.050927 -261.630365) (xy 460.093795 -261.66604) (xy 460.131012 -261.707577)
			(xy 460.161785 -261.75409) (xy 460.185457 -261.804587) (xy 460.201525 -261.857994) (xy 460.209645 -261.91317)
			(xy 460.210154 -261.941056) (xy 460.209645 -261.968942) (xy 460.201525 -262.024118) (xy 460.185457 -262.077525)
			(xy 460.161785 -262.128022) (xy 460.131012 -262.174535) (xy 460.093795 -262.216072) (xy 460.050927 -262.251747)
			(xy 460.003321 -262.280801) (xy 459.951992 -262.302613) (xy 459.898035 -262.316719) (xy 459.842598 -262.322819)
			(xy 459.786864 -262.320782) (xy 459.732021 -262.310652) (xy 459.679237 -262.292645) (xy 459.629637 -262.267144)
			(xy 459.584279 -262.234693) (xy 459.54413 -262.195984) (xy 459.510044 -262.151841) (xy 459.482748 -262.103206)
			(xy 459.462825 -262.051115) (xy 459.450699 -261.996678) (xy 459.446628 -261.941056) (xy 409.105608 -261.941056)
			(xy 409.105608 -270.89989) (xy 433.198785 -270.89989) (xy 433.202791 -270.704835) (xy 433.214801 -270.510109)
			(xy 433.234796 -270.31604) (xy 433.262741 -270.122956) (xy 433.29859 -269.931181) (xy 433.342282 -269.741041)
			(xy 433.393743 -269.552854) (xy 433.452887 -269.366939) (xy 433.519614 -269.183608) (xy 433.593811 -269.003172)
			(xy 433.675353 -268.825934) (xy 433.764104 -268.652193) (xy 433.859912 -268.482242) (xy 433.962617 -268.316368)
			(xy 434.072045 -268.15485) (xy 434.188012 -267.997961) (xy 434.310323 -267.845966) (xy 434.43877 -267.69912)
			(xy 434.573138 -267.557671) (xy 434.7132 -267.421858) (xy 434.858719 -267.291909) (xy 435.009451 -267.168045)
			(xy 435.165141 -267.050473) (xy 435.325527 -266.939393) (xy 435.490338 -266.83499) (xy 435.659296 -266.737442)
			(xy 435.832117 -266.646913) (xy 436.008509 -266.563555) (xy 436.188174 -266.487509) (xy 436.370809 -266.418904)
			(xy 436.556108 -266.357854) (xy 436.743756 -266.304464) (xy 436.933438 -266.258822) (xy 437.124835 -266.221006)
			(xy 437.317622 -266.19108) (xy 437.511475 -266.169094) (xy 437.706068 -266.155085) (xy 437.901071 -266.149077)
			(xy 438.096157 -266.15108) (xy 438.290996 -266.161091) (xy 438.48526 -266.179092) (xy 438.678621 -266.205054)
			(xy 438.870754 -266.238932) (xy 439.061333 -266.280669) (xy 439.250038 -266.330196) (xy 439.436551 -266.387428)
			(xy 439.620557 -266.452269) (xy 439.801745 -266.52461) (xy 439.979811 -266.604328) (xy 440.154454 -266.69129)
			(xy 440.32538 -266.785349) (xy 440.492299 -266.886345) (xy 440.654932 -266.99411) (xy 440.813003 -267.10846)
			(xy 440.966246 -267.229203) (xy 441.114403 -267.356137) (xy 441.257224 -267.489045) (xy 441.394468 -267.627705)
			(xy 441.525904 -267.771883) (xy 441.651309 -267.921336) (xy 441.770473 -268.07581) (xy 441.883194 -268.235047)
			(xy 441.989283 -268.398778) (xy 442.088561 -268.566725) (xy 442.180859 -268.738608) (xy 442.266024 -268.914134)
			(xy 442.34391 -269.093009) (xy 442.414387 -269.274931) (xy 442.477335 -269.459593) (xy 442.53265 -269.646683)
			(xy 442.580236 -269.835887) (xy 442.620015 -270.026884) (xy 442.651919 -270.219354) (xy 442.675894 -270.412972)
			(xy 442.6919 -270.60741) (xy 442.699909 -270.802342) (xy 442.70041 -270.89989) (xy 442.699909 -270.997438)
			(xy 442.6919 -271.19237) (xy 442.675894 -271.386808) (xy 442.651919 -271.580426) (xy 442.620015 -271.772896)
			(xy 442.580236 -271.963893) (xy 442.53265 -272.153097) (xy 442.477335 -272.340187) (xy 442.414387 -272.524849)
			(xy 442.34391 -272.706771) (xy 442.266024 -272.885646) (xy 442.180859 -273.061172) (xy 442.09302 -273.224752)
			(xy 459.941166 -273.224752) (xy 459.945237 -273.16913) (xy 459.957363 -273.114693) (xy 459.977286 -273.062602)
			(xy 460.004582 -273.013967) (xy 460.038668 -272.969824) (xy 460.078817 -272.931115) (xy 460.124175 -272.898664)
			(xy 460.173775 -272.873163) (xy 460.226559 -272.855156) (xy 460.281402 -272.845026) (xy 460.337136 -272.842989)
			(xy 460.392573 -272.849089) (xy 460.44653 -272.863195) (xy 460.497859 -272.885007) (xy 460.545465 -272.914061)
			(xy 460.588333 -272.949736) (xy 460.62555 -272.991273) (xy 460.656323 -273.037786) (xy 460.679995 -273.088283)
			(xy 460.696063 -273.14169) (xy 460.704183 -273.196866) (xy 460.704692 -273.224752) (xy 460.704183 -273.252638)
			(xy 460.696063 -273.307814) (xy 460.679995 -273.361221) (xy 460.656323 -273.411718) (xy 460.62555 -273.458231)
			(xy 460.588333 -273.499768) (xy 460.545465 -273.535443) (xy 460.497859 -273.564497) (xy 460.44653 -273.586309)
			(xy 460.413936 -273.59483) (xy 463.155028 -273.59483) (xy 463.159099 -273.539208) (xy 463.171225 -273.484771)
			(xy 463.191148 -273.43268) (xy 463.218444 -273.384045) (xy 463.25253 -273.339902) (xy 463.292679 -273.301193)
			(xy 463.338037 -273.268742) (xy 463.387637 -273.243241) (xy 463.440421 -273.225234) (xy 463.495264 -273.215104)
			(xy 463.550998 -273.213067) (xy 463.606435 -273.219167) (xy 463.660392 -273.233273) (xy 463.711721 -273.255085)
			(xy 463.759327 -273.284139) (xy 463.802195 -273.319814) (xy 463.839412 -273.361351) (xy 463.870185 -273.407864)
			(xy 463.893857 -273.458361) (xy 463.909925 -273.511768) (xy 463.918045 -273.566944) (xy 463.918554 -273.59483)
			(xy 463.918045 -273.622716) (xy 463.909925 -273.677892) (xy 463.893857 -273.731299) (xy 463.870185 -273.781796)
			(xy 463.839412 -273.828309) (xy 463.802195 -273.869846) (xy 463.759327 -273.905521) (xy 463.711721 -273.934575)
			(xy 463.660392 -273.956387) (xy 463.606435 -273.970493) (xy 463.550998 -273.976593) (xy 463.495264 -273.974556)
			(xy 463.440421 -273.964426) (xy 463.387637 -273.946419) (xy 463.338037 -273.920918) (xy 463.292679 -273.888467)
			(xy 463.25253 -273.849758) (xy 463.218444 -273.805615) (xy 463.191148 -273.75698) (xy 463.171225 -273.704889)
			(xy 463.159099 -273.650452) (xy 463.155028 -273.59483) (xy 460.413936 -273.59483) (xy 460.392573 -273.600415)
			(xy 460.337136 -273.606515) (xy 460.281402 -273.604478) (xy 460.226559 -273.594348) (xy 460.173775 -273.576341)
			(xy 460.124175 -273.55084) (xy 460.078817 -273.518389) (xy 460.038668 -273.47968) (xy 460.004582 -273.435537)
			(xy 459.977286 -273.386902) (xy 459.957363 -273.334811) (xy 459.945237 -273.280374) (xy 459.941166 -273.224752)
			(xy 442.09302 -273.224752) (xy 442.088561 -273.233055) (xy 441.989283 -273.401002) (xy 441.883194 -273.564733)
			(xy 441.770473 -273.72397) (xy 441.651309 -273.878444) (xy 441.525904 -274.027897) (xy 441.394468 -274.172075)
			(xy 441.257224 -274.310735) (xy 441.114403 -274.443643) (xy 440.966246 -274.570577) (xy 440.813003 -274.69132)
			(xy 440.72343 -274.756118) (xy 457.316076 -274.756118) (xy 457.320147 -274.700496) (xy 457.332273 -274.646059)
			(xy 457.352196 -274.593968) (xy 457.379492 -274.545333) (xy 457.413578 -274.50119) (xy 457.453727 -274.462481)
			(xy 457.499085 -274.43003) (xy 457.548685 -274.404529) (xy 457.601469 -274.386522) (xy 457.656312 -274.376392)
			(xy 457.712046 -274.374355) (xy 457.767483 -274.380455) (xy 457.82144 -274.394561) (xy 457.872769 -274.416373)
			(xy 457.920375 -274.445427) (xy 457.963243 -274.481102) (xy 458.00046 -274.522639) (xy 458.031233 -274.569152)
			(xy 458.054905 -274.619649) (xy 458.070973 -274.673056) (xy 458.079093 -274.728232) (xy 458.079602 -274.756118)
			(xy 458.079093 -274.784004) (xy 458.070973 -274.83918) (xy 458.055232 -274.8915) (xy 459.445866 -274.8915)
			(xy 459.449937 -274.835878) (xy 459.462063 -274.781441) (xy 459.481986 -274.72935) (xy 459.509282 -274.680715)
			(xy 459.543368 -274.636572) (xy 459.583517 -274.597863) (xy 459.628875 -274.565412) (xy 459.678475 -274.539911)
			(xy 459.731259 -274.521904) (xy 459.786102 -274.511774) (xy 459.841836 -274.509737) (xy 459.897273 -274.515837)
			(xy 459.95123 -274.529943) (xy 460.002559 -274.551755) (xy 460.050165 -274.580809) (xy 460.086239 -274.61083)
			(xy 463.093306 -274.61083) (xy 463.097377 -274.555208) (xy 463.109503 -274.500771) (xy 463.129426 -274.44868)
			(xy 463.156722 -274.400045) (xy 463.190808 -274.355902) (xy 463.230957 -274.317193) (xy 463.276315 -274.284742)
			(xy 463.325915 -274.259241) (xy 463.378699 -274.241234) (xy 463.433542 -274.231104) (xy 463.489276 -274.229067)
			(xy 463.544713 -274.235167) (xy 463.59867 -274.249273) (xy 463.649999 -274.271085) (xy 463.697605 -274.300139)
			(xy 463.740473 -274.335814) (xy 463.77769 -274.377351) (xy 463.808463 -274.423864) (xy 463.832135 -274.474361)
			(xy 463.848203 -274.527768) (xy 463.856323 -274.582944) (xy 463.856832 -274.61083) (xy 463.856323 -274.638716)
			(xy 463.848203 -274.693892) (xy 463.832135 -274.747299) (xy 463.808463 -274.797796) (xy 463.77769 -274.844309)
			(xy 463.740473 -274.885846) (xy 463.697605 -274.921521) (xy 463.649999 -274.950575) (xy 463.59867 -274.972387)
			(xy 463.544713 -274.986493) (xy 463.489276 -274.992593) (xy 463.433542 -274.990556) (xy 463.378699 -274.980426)
			(xy 463.325915 -274.962419) (xy 463.276315 -274.936918) (xy 463.230957 -274.904467) (xy 463.190808 -274.865758)
			(xy 463.156722 -274.821615) (xy 463.129426 -274.77298) (xy 463.109503 -274.720889) (xy 463.097377 -274.666452)
			(xy 463.093306 -274.61083) (xy 460.086239 -274.61083) (xy 460.093033 -274.616484) (xy 460.13025 -274.658021)
			(xy 460.161023 -274.704534) (xy 460.184695 -274.755031) (xy 460.200763 -274.808438) (xy 460.208883 -274.863614)
			(xy 460.209392 -274.8915) (xy 460.208883 -274.919386) (xy 460.200763 -274.974562) (xy 460.184695 -275.027969)
			(xy 460.161023 -275.078466) (xy 460.13025 -275.124979) (xy 460.093033 -275.166516) (xy 460.050165 -275.202191)
			(xy 460.002559 -275.231245) (xy 459.95123 -275.253057) (xy 459.897273 -275.267163) (xy 459.841836 -275.273263)
			(xy 459.786102 -275.271226) (xy 459.731259 -275.261096) (xy 459.678475 -275.243089) (xy 459.628875 -275.217588)
			(xy 459.583517 -275.185137) (xy 459.543368 -275.146428) (xy 459.509282 -275.102285) (xy 459.481986 -275.05365)
			(xy 459.462063 -275.001559) (xy 459.449937 -274.947122) (xy 459.445866 -274.8915) (xy 458.055232 -274.8915)
			(xy 458.054905 -274.892587) (xy 458.031233 -274.943084) (xy 458.00046 -274.989597) (xy 457.963243 -275.031134)
			(xy 457.920375 -275.066809) (xy 457.872769 -275.095863) (xy 457.82144 -275.117675) (xy 457.767483 -275.131781)
			(xy 457.712046 -275.137881) (xy 457.656312 -275.135844) (xy 457.601469 -275.125714) (xy 457.548685 -275.107707)
			(xy 457.499085 -275.082206) (xy 457.453727 -275.049755) (xy 457.413578 -275.011046) (xy 457.379492 -274.966903)
			(xy 457.352196 -274.918268) (xy 457.332273 -274.866177) (xy 457.320147 -274.81174) (xy 457.316076 -274.756118)
			(xy 440.72343 -274.756118) (xy 440.654932 -274.80567) (xy 440.492299 -274.913435) (xy 440.32538 -275.014431)
			(xy 440.154454 -275.10849) (xy 439.979811 -275.195452) (xy 439.801745 -275.27517) (xy 439.668473 -275.32838)
			(xy 460.941672 -275.32838) (xy 460.945743 -275.272758) (xy 460.957869 -275.218321) (xy 460.977792 -275.16623)
			(xy 461.005088 -275.117595) (xy 461.039174 -275.073452) (xy 461.079323 -275.034743) (xy 461.124681 -275.002292)
			(xy 461.174281 -274.976791) (xy 461.227065 -274.958784) (xy 461.281908 -274.948654) (xy 461.337642 -274.946617)
			(xy 461.393079 -274.952717) (xy 461.447036 -274.966823) (xy 461.498365 -274.988635) (xy 461.545971 -275.017689)
			(xy 461.588839 -275.053364) (xy 461.626056 -275.094901) (xy 461.656829 -275.141414) (xy 461.680501 -275.191911)
			(xy 461.696569 -275.245318) (xy 461.704689 -275.300494) (xy 461.705198 -275.32838) (xy 461.704689 -275.356266)
			(xy 461.696569 -275.411442) (xy 461.680501 -275.464849) (xy 461.656829 -275.515346) (xy 461.626056 -275.561859)
			(xy 461.588839 -275.603396) (xy 461.56068 -275.62683) (xy 463.093306 -275.62683) (xy 463.097377 -275.571208)
			(xy 463.109503 -275.516771) (xy 463.129426 -275.46468) (xy 463.156722 -275.416045) (xy 463.190808 -275.371902)
			(xy 463.230957 -275.333193) (xy 463.276315 -275.300742) (xy 463.325915 -275.275241) (xy 463.378699 -275.257234)
			(xy 463.433542 -275.247104) (xy 463.489276 -275.245067) (xy 463.544713 -275.251167) (xy 463.59867 -275.265273)
			(xy 463.649999 -275.287085) (xy 463.697605 -275.316139) (xy 463.740473 -275.351814) (xy 463.77769 -275.393351)
			(xy 463.808463 -275.439864) (xy 463.832135 -275.490361) (xy 463.848203 -275.543768) (xy 463.856323 -275.598944)
			(xy 463.856832 -275.62683) (xy 463.856323 -275.654716) (xy 463.848203 -275.709892) (xy 463.832135 -275.763299)
			(xy 463.808463 -275.813796) (xy 463.77769 -275.860309) (xy 463.740473 -275.901846) (xy 463.697605 -275.937521)
			(xy 463.649999 -275.966575) (xy 463.59867 -275.988387) (xy 463.544713 -276.002493) (xy 463.489276 -276.008593)
			(xy 463.433542 -276.006556) (xy 463.378699 -275.996426) (xy 463.325915 -275.978419) (xy 463.276315 -275.952918)
			(xy 463.230957 -275.920467) (xy 463.190808 -275.881758) (xy 463.156722 -275.837615) (xy 463.129426 -275.78898)
			(xy 463.109503 -275.736889) (xy 463.097377 -275.682452) (xy 463.093306 -275.62683) (xy 461.56068 -275.62683)
			(xy 461.545971 -275.639071) (xy 461.498365 -275.668125) (xy 461.447036 -275.689937) (xy 461.393079 -275.704043)
			(xy 461.337642 -275.710143) (xy 461.281908 -275.708106) (xy 461.227065 -275.697976) (xy 461.174281 -275.679969)
			(xy 461.124681 -275.654468) (xy 461.079323 -275.622017) (xy 461.039174 -275.583308) (xy 461.005088 -275.539165)
			(xy 460.977792 -275.49053) (xy 460.957869 -275.438439) (xy 460.945743 -275.384002) (xy 460.941672 -275.32838)
			(xy 439.668473 -275.32838) (xy 439.620557 -275.347511) (xy 439.436551 -275.412352) (xy 439.250038 -275.469584)
			(xy 439.061333 -275.519111) (xy 438.870754 -275.560848) (xy 438.678621 -275.594726) (xy 438.48526 -275.620688)
			(xy 438.290996 -275.638689) (xy 438.096157 -275.6487) (xy 437.901071 -275.650703) (xy 437.706068 -275.644695)
			(xy 437.511475 -275.630686) (xy 437.317622 -275.6087) (xy 437.124835 -275.578774) (xy 436.933438 -275.540958)
			(xy 436.743756 -275.495316) (xy 436.556108 -275.441926) (xy 436.370809 -275.380876) (xy 436.188174 -275.312271)
			(xy 436.008509 -275.236225) (xy 435.832117 -275.152867) (xy 435.659296 -275.062338) (xy 435.490338 -274.96479)
			(xy 435.325527 -274.860387) (xy 435.165141 -274.749307) (xy 435.009451 -274.631735) (xy 434.858719 -274.507871)
			(xy 434.7132 -274.377922) (xy 434.573138 -274.242109) (xy 434.43877 -274.10066) (xy 434.310323 -273.953814)
			(xy 434.188012 -273.801819) (xy 434.072045 -273.64493) (xy 433.962617 -273.483412) (xy 433.859912 -273.317538)
			(xy 433.764104 -273.147587) (xy 433.675353 -272.973846) (xy 433.593811 -272.796608) (xy 433.519614 -272.616172)
			(xy 433.452887 -272.432841) (xy 433.393743 -272.246926) (xy 433.342282 -272.058739) (xy 433.29859 -271.868599)
			(xy 433.262741 -271.676824) (xy 433.234796 -271.48374) (xy 433.214801 -271.289671) (xy 433.202791 -271.094945)
			(xy 433.198785 -270.89989) (xy 409.105608 -270.89989) (xy 409.105608 -272.231866) (xy 409.107132 -272.238724)
			(xy 409.109876 -272.24838) (xy 409.121517 -272.26471) (xy 409.129738 -272.270474) (xy 409.146248 -272.280634)
			(xy 409.146502 -272.280888) (xy 409.147518 -272.281396) (xy 409.198572 -272.315432) (xy 409.19908 -272.315432)
			(xy 409.209912 -272.321882) (xy 409.234975 -272.324287) (xy 409.246832 -272.320004) (xy 409.247086 -272.320004)
			(xy 409.267306 -272.311862) (xy 409.309353 -272.300363) (xy 409.352546 -272.294493) (xy 409.37434 -272.294096)
			(xy 409.374848 -272.294096) (xy 409.388311 -272.294285) (xy 409.415141 -272.296575) (xy 409.428442 -272.298668)
			(xy 409.440634 -272.3007) (xy 409.46324 -272.293842) (xy 409.531058 -272.228818) (xy 409.537824 -272.22177)
			(xy 409.545914 -272.204004) (xy 409.546806 -272.194274) (xy 409.54706 -272.189956) (xy 409.546552 -272.185892)
			(xy 409.545505 -272.176848) (xy 409.544363 -272.158674) (xy 409.544266 -272.14957) (xy 409.544754 -272.124747)
			(xy 409.552791 -272.075756) (xy 409.568648 -272.028711) (xy 409.591906 -271.98485) (xy 409.621954 -271.945331)
			(xy 409.658 -271.911193) (xy 409.699094 -271.883336) (xy 409.744154 -271.862495) (xy 409.791991 -271.849217)
			(xy 409.841346 -271.843854) (xy 409.890919 -271.846547) (xy 409.939403 -271.857224) (xy 409.985521 -271.875604)
			(xy 410.028058 -271.901203) (xy 410.065893 -271.933346) (xy 410.09803 -271.971187) (xy 410.123621 -272.013729)
			(xy 410.141993 -272.05985) (xy 410.152661 -272.108337) (xy 410.154893 -272.14957) (xy 411.443944 -272.14957)
			(xy 411.447904 -272.100516) (xy 411.459681 -272.052732) (xy 411.478972 -272.007456) (xy 411.505275 -271.96586)
			(xy 411.53791 -271.929023) (xy 411.576031 -271.897898) (xy 411.618652 -271.873291) (xy 411.664668 -271.855839)
			(xy 411.712887 -271.845995) (xy 411.762062 -271.844014) (xy 411.810917 -271.849946) (xy 411.858188 -271.863638)
			(xy 411.90265 -271.884736) (xy 411.943153 -271.912692) (xy 411.978646 -271.946784) (xy 412.008211 -271.986128)
			(xy 412.031082 -272.029705) (xy 412.046666 -272.076386) (xy 412.054561 -272.124963) (xy 412.055056 -272.14957)
			(xy 413.343864 -272.14957) (xy 413.347824 -272.100516) (xy 413.359601 -272.052732) (xy 413.378892 -272.007456)
			(xy 413.405195 -271.96586) (xy 413.43783 -271.929023) (xy 413.475951 -271.897898) (xy 413.518572 -271.873291)
			(xy 413.564588 -271.855839) (xy 413.612807 -271.845995) (xy 413.661982 -271.844014) (xy 413.710837 -271.849946)
			(xy 413.758108 -271.863638) (xy 413.80257 -271.884736) (xy 413.843073 -271.912692) (xy 413.878566 -271.946784)
			(xy 413.908131 -271.986128) (xy 413.931002 -272.029705) (xy 413.946586 -272.076386) (xy 413.954481 -272.124963)
			(xy 413.954976 -272.14957) (xy 415.243784 -272.14957) (xy 415.247744 -272.100516) (xy 415.259521 -272.052732)
			(xy 415.278812 -272.007456) (xy 415.305115 -271.96586) (xy 415.33775 -271.929023) (xy 415.375871 -271.897898)
			(xy 415.418492 -271.873291) (xy 415.464508 -271.855839) (xy 415.512727 -271.845995) (xy 415.561902 -271.844014)
			(xy 415.610757 -271.849946) (xy 415.658028 -271.863638) (xy 415.70249 -271.884736) (xy 415.742993 -271.912692)
			(xy 415.778486 -271.946784) (xy 415.808051 -271.986128) (xy 415.830922 -272.029705) (xy 415.846506 -272.076386)
			(xy 415.854401 -272.124963) (xy 415.854896 -272.14957) (xy 417.143958 -272.14957) (xy 417.147918 -272.100516)
			(xy 417.159695 -272.052732) (xy 417.178986 -272.007456) (xy 417.205289 -271.96586) (xy 417.237924 -271.929023)
			(xy 417.276045 -271.897898) (xy 417.318666 -271.873291) (xy 417.364682 -271.855839) (xy 417.412901 -271.845995)
			(xy 417.462076 -271.844014) (xy 417.510931 -271.849946) (xy 417.558202 -271.863638) (xy 417.602664 -271.884736)
			(xy 417.643167 -271.912692) (xy 417.67866 -271.946784) (xy 417.708225 -271.986128) (xy 417.731096 -272.029705)
			(xy 417.74668 -272.076386) (xy 417.754575 -272.124963) (xy 417.75507 -272.14957) (xy 419.043878 -272.14957)
			(xy 419.047838 -272.100516) (xy 419.059615 -272.052732) (xy 419.078906 -272.007456) (xy 419.105209 -271.96586)
			(xy 419.137844 -271.929023) (xy 419.175965 -271.897898) (xy 419.218586 -271.873291) (xy 419.264602 -271.855839)
			(xy 419.312821 -271.845995) (xy 419.361996 -271.844014) (xy 419.410851 -271.849946) (xy 419.458122 -271.863638)
			(xy 419.502584 -271.884736) (xy 419.543087 -271.912692) (xy 419.57858 -271.946784) (xy 419.608145 -271.986128)
			(xy 419.631016 -272.029705) (xy 419.6466 -272.076386) (xy 419.654495 -272.124963) (xy 419.65499 -272.14957)
			(xy 420.943798 -272.14957) (xy 420.947758 -272.100516) (xy 420.959535 -272.052732) (xy 420.978826 -272.007456)
			(xy 421.005129 -271.96586) (xy 421.037764 -271.929023) (xy 421.075885 -271.897898) (xy 421.118506 -271.873291)
			(xy 421.164522 -271.855839) (xy 421.212741 -271.845995) (xy 421.261916 -271.844014) (xy 421.310771 -271.849946)
			(xy 421.358042 -271.863638) (xy 421.402504 -271.884736) (xy 421.443007 -271.912692) (xy 421.4785 -271.946784)
			(xy 421.508065 -271.986128) (xy 421.530936 -272.029705) (xy 421.54652 -272.076386) (xy 421.554415 -272.124963)
			(xy 421.55491 -272.14957) (xy 422.843972 -272.14957) (xy 422.847932 -272.100516) (xy 422.859709 -272.052732)
			(xy 422.879 -272.007456) (xy 422.905303 -271.96586) (xy 422.937938 -271.929023) (xy 422.976059 -271.897898)
			(xy 423.01868 -271.873291) (xy 423.064696 -271.855839) (xy 423.112915 -271.845995) (xy 423.16209 -271.844014)
			(xy 423.210945 -271.849946) (xy 423.258216 -271.863638) (xy 423.302678 -271.884736) (xy 423.343181 -271.912692)
			(xy 423.378674 -271.946784) (xy 423.408239 -271.986128) (xy 423.43111 -272.029705) (xy 423.446694 -272.076386)
			(xy 423.454589 -272.124963) (xy 423.455084 -272.14957) (xy 424.744146 -272.14957) (xy 424.748106 -272.100516)
			(xy 424.759883 -272.052732) (xy 424.779174 -272.007456) (xy 424.805477 -271.96586) (xy 424.838112 -271.929023)
			(xy 424.876233 -271.897898) (xy 424.918854 -271.873291) (xy 424.96487 -271.855839) (xy 425.013089 -271.845995)
			(xy 425.062264 -271.844014) (xy 425.111119 -271.849946) (xy 425.15839 -271.863638) (xy 425.202852 -271.884736)
			(xy 425.243355 -271.912692) (xy 425.278848 -271.946784) (xy 425.308413 -271.986128) (xy 425.331284 -272.029705)
			(xy 425.346868 -272.076386) (xy 425.354763 -272.124963) (xy 425.355258 -272.14957) (xy 426.644066 -272.14957)
			(xy 426.648026 -272.100516) (xy 426.659803 -272.052732) (xy 426.679094 -272.007456) (xy 426.705397 -271.96586)
			(xy 426.738032 -271.929023) (xy 426.776153 -271.897898) (xy 426.818774 -271.873291) (xy 426.86479 -271.855839)
			(xy 426.913009 -271.845995) (xy 426.962184 -271.844014) (xy 427.011039 -271.849946) (xy 427.05831 -271.863638)
			(xy 427.102772 -271.884736) (xy 427.143275 -271.912692) (xy 427.178768 -271.946784) (xy 427.208333 -271.986128)
			(xy 427.231204 -272.029705) (xy 427.246788 -272.076386) (xy 427.254683 -272.124963) (xy 427.255178 -272.14957)
			(xy 428.543986 -272.14957) (xy 428.547946 -272.100516) (xy 428.559723 -272.052732) (xy 428.579014 -272.007456)
			(xy 428.605317 -271.96586) (xy 428.637952 -271.929023) (xy 428.676073 -271.897898) (xy 428.718694 -271.873291)
			(xy 428.76471 -271.855839) (xy 428.812929 -271.845995) (xy 428.862104 -271.844014) (xy 428.910959 -271.849946)
			(xy 428.95823 -271.863638) (xy 429.002692 -271.884736) (xy 429.043195 -271.912692) (xy 429.078688 -271.946784)
			(xy 429.108253 -271.986128) (xy 429.131124 -272.029705) (xy 429.146708 -272.076386) (xy 429.154603 -272.124963)
			(xy 429.155098 -272.14957) (xy 429.154603 -272.174177) (xy 429.146708 -272.222754) (xy 429.131124 -272.269435)
			(xy 429.108253 -272.313012) (xy 429.078688 -272.352356) (xy 429.043195 -272.386448) (xy 429.002692 -272.414404)
			(xy 428.95823 -272.435502) (xy 428.910959 -272.449194) (xy 428.862104 -272.455126) (xy 428.812929 -272.453145)
			(xy 428.76471 -272.443301) (xy 428.718694 -272.425849) (xy 428.676073 -272.401242) (xy 428.637952 -272.370117)
			(xy 428.605317 -272.33328) (xy 428.579014 -272.291684) (xy 428.559723 -272.246408) (xy 428.547946 -272.198624)
			(xy 428.543986 -272.14957) (xy 427.255178 -272.14957) (xy 427.254683 -272.174177) (xy 427.246788 -272.222754)
			(xy 427.231204 -272.269435) (xy 427.208333 -272.313012) (xy 427.178768 -272.352356) (xy 427.143275 -272.386448)
			(xy 427.102772 -272.414404) (xy 427.05831 -272.435502) (xy 427.011039 -272.449194) (xy 426.962184 -272.455126)
			(xy 426.913009 -272.453145) (xy 426.86479 -272.443301) (xy 426.818774 -272.425849) (xy 426.776153 -272.401242)
			(xy 426.738032 -272.370117) (xy 426.705397 -272.33328) (xy 426.679094 -272.291684) (xy 426.659803 -272.246408)
			(xy 426.648026 -272.198624) (xy 426.644066 -272.14957) (xy 425.355258 -272.14957) (xy 425.354763 -272.174177)
			(xy 425.346868 -272.222754) (xy 425.331284 -272.269435) (xy 425.308413 -272.313012) (xy 425.278848 -272.352356)
			(xy 425.243355 -272.386448) (xy 425.202852 -272.414404) (xy 425.15839 -272.435502) (xy 425.111119 -272.449194)
			(xy 425.062264 -272.455126) (xy 425.013089 -272.453145) (xy 424.96487 -272.443301) (xy 424.918854 -272.425849)
			(xy 424.876233 -272.401242) (xy 424.838112 -272.370117) (xy 424.805477 -272.33328) (xy 424.779174 -272.291684)
			(xy 424.759883 -272.246408) (xy 424.748106 -272.198624) (xy 424.744146 -272.14957) (xy 423.455084 -272.14957)
			(xy 423.454589 -272.174177) (xy 423.446694 -272.222754) (xy 423.43111 -272.269435) (xy 423.408239 -272.313012)
			(xy 423.378674 -272.352356) (xy 423.343181 -272.386448) (xy 423.302678 -272.414404) (xy 423.258216 -272.435502)
			(xy 423.210945 -272.449194) (xy 423.16209 -272.455126) (xy 423.112915 -272.453145) (xy 423.064696 -272.443301)
			(xy 423.01868 -272.425849) (xy 422.976059 -272.401242) (xy 422.937938 -272.370117) (xy 422.905303 -272.33328)
			(xy 422.879 -272.291684) (xy 422.859709 -272.246408) (xy 422.847932 -272.198624) (xy 422.843972 -272.14957)
			(xy 421.55491 -272.14957) (xy 421.554415 -272.174177) (xy 421.54652 -272.222754) (xy 421.530936 -272.269435)
			(xy 421.508065 -272.313012) (xy 421.4785 -272.352356) (xy 421.443007 -272.386448) (xy 421.402504 -272.414404)
			(xy 421.358042 -272.435502) (xy 421.310771 -272.449194) (xy 421.261916 -272.455126) (xy 421.212741 -272.453145)
			(xy 421.164522 -272.443301) (xy 421.118506 -272.425849) (xy 421.075885 -272.401242) (xy 421.037764 -272.370117)
			(xy 421.005129 -272.33328) (xy 420.978826 -272.291684) (xy 420.959535 -272.246408) (xy 420.947758 -272.198624)
			(xy 420.943798 -272.14957) (xy 419.65499 -272.14957) (xy 419.654495 -272.174177) (xy 419.6466 -272.222754)
			(xy 419.631016 -272.269435) (xy 419.608145 -272.313012) (xy 419.57858 -272.352356) (xy 419.543087 -272.386448)
			(xy 419.502584 -272.414404) (xy 419.458122 -272.435502) (xy 419.410851 -272.449194) (xy 419.361996 -272.455126)
			(xy 419.312821 -272.453145) (xy 419.264602 -272.443301) (xy 419.218586 -272.425849) (xy 419.175965 -272.401242)
			(xy 419.137844 -272.370117) (xy 419.105209 -272.33328) (xy 419.078906 -272.291684) (xy 419.059615 -272.246408)
			(xy 419.047838 -272.198624) (xy 419.043878 -272.14957) (xy 417.75507 -272.14957) (xy 417.754575 -272.174177)
			(xy 417.74668 -272.222754) (xy 417.731096 -272.269435) (xy 417.708225 -272.313012) (xy 417.67866 -272.352356)
			(xy 417.643167 -272.386448) (xy 417.602664 -272.414404) (xy 417.558202 -272.435502) (xy 417.510931 -272.449194)
			(xy 417.462076 -272.455126) (xy 417.412901 -272.453145) (xy 417.364682 -272.443301) (xy 417.318666 -272.425849)
			(xy 417.276045 -272.401242) (xy 417.237924 -272.370117) (xy 417.205289 -272.33328) (xy 417.178986 -272.291684)
			(xy 417.159695 -272.246408) (xy 417.147918 -272.198624) (xy 417.143958 -272.14957) (xy 415.854896 -272.14957)
			(xy 415.854401 -272.174177) (xy 415.846506 -272.222754) (xy 415.830922 -272.269435) (xy 415.808051 -272.313012)
			(xy 415.778486 -272.352356) (xy 415.742993 -272.386448) (xy 415.70249 -272.414404) (xy 415.658028 -272.435502)
			(xy 415.610757 -272.449194) (xy 415.561902 -272.455126) (xy 415.512727 -272.453145) (xy 415.464508 -272.443301)
			(xy 415.418492 -272.425849) (xy 415.375871 -272.401242) (xy 415.33775 -272.370117) (xy 415.305115 -272.33328)
			(xy 415.278812 -272.291684) (xy 415.259521 -272.246408) (xy 415.247744 -272.198624) (xy 415.243784 -272.14957)
			(xy 413.954976 -272.14957) (xy 413.954481 -272.174177) (xy 413.946586 -272.222754) (xy 413.931002 -272.269435)
			(xy 413.908131 -272.313012) (xy 413.878566 -272.352356) (xy 413.843073 -272.386448) (xy 413.80257 -272.414404)
			(xy 413.758108 -272.435502) (xy 413.710837 -272.449194) (xy 413.661982 -272.455126) (xy 413.612807 -272.453145)
			(xy 413.564588 -272.443301) (xy 413.518572 -272.425849) (xy 413.475951 -272.401242) (xy 413.43783 -272.370117)
			(xy 413.405195 -272.33328) (xy 413.378892 -272.291684) (xy 413.359601 -272.246408) (xy 413.347824 -272.198624)
			(xy 413.343864 -272.14957) (xy 412.055056 -272.14957) (xy 412.054561 -272.174177) (xy 412.046666 -272.222754)
			(xy 412.031082 -272.269435) (xy 412.008211 -272.313012) (xy 411.978646 -272.352356) (xy 411.943153 -272.386448)
			(xy 411.90265 -272.414404) (xy 411.858188 -272.435502) (xy 411.810917 -272.449194) (xy 411.762062 -272.455126)
			(xy 411.712887 -272.453145) (xy 411.664668 -272.443301) (xy 411.618652 -272.425849) (xy 411.576031 -272.401242)
			(xy 411.53791 -272.370117) (xy 411.505275 -272.33328) (xy 411.478972 -272.291684) (xy 411.459681 -272.246408)
			(xy 411.447904 -272.198624) (xy 411.443944 -272.14957) (xy 410.154893 -272.14957) (xy 410.155344 -272.15791)
			(xy 410.149972 -272.207264) (xy 410.136686 -272.255099) (xy 410.115836 -272.300155) (xy 410.087972 -272.341243)
			(xy 410.053828 -272.377283) (xy 410.014302 -272.407324) (xy 409.970438 -272.430575) (xy 409.923389 -272.446423)
			(xy 409.874397 -272.45445) (xy 409.849574 -272.454878) (xy 409.840597 -272.454768) (xy 409.822678 -272.453625)
			(xy 409.81376 -272.452592) (xy 409.81249 -272.452592) (xy 409.800852 -272.451989) (xy 409.779009 -272.460042)
			(xy 409.77058 -272.468086) (xy 409.714446 -272.52676) (xy 409.706618 -272.535783) (xy 409.6996 -272.558582)
			(xy 409.700984 -272.570448) (xy 409.703114 -272.583936) (xy 409.705402 -272.611149) (xy 409.705556 -272.624804)
			(xy 409.705374 -272.638331) (xy 409.703084 -272.665288) (xy 409.700984 -272.678652) (xy 409.698952 -272.69059)
			(xy 409.70581 -272.713196) (xy 409.760674 -272.770854) (xy 409.78455 -272.778982) (xy 409.796996 -272.77695)
			(xy 409.810047 -272.774934) (xy 409.836369 -272.772769) (xy 409.849574 -272.772632) (xy 409.875286 -272.773108)
			(xy 409.926079 -272.781149) (xy 409.974987 -272.797037) (xy 410.020808 -272.820381) (xy 410.062413 -272.850606)
			(xy 410.098777 -272.886967) (xy 410.129005 -272.928569) (xy 410.152353 -272.974389) (xy 410.168245 -273.023296)
			(xy 410.17629 -273.074088) (xy 410.17629 -273.099784) (xy 410.493984 -273.099784) (xy 410.497944 -273.05073)
			(xy 410.509721 -273.002946) (xy 410.529012 -272.95767) (xy 410.555315 -272.916074) (xy 410.58795 -272.879237)
			(xy 410.626071 -272.848112) (xy 410.668692 -272.823505) (xy 410.714708 -272.806053) (xy 410.762927 -272.796209)
			(xy 410.812102 -272.794228) (xy 410.860957 -272.80016) (xy 410.908228 -272.813852) (xy 410.95269 -272.83495)
			(xy 410.993193 -272.862906) (xy 411.028686 -272.896998) (xy 411.058251 -272.936342) (xy 411.081122 -272.979919)
			(xy 411.096706 -273.0266) (xy 411.104601 -273.075177) (xy 411.105096 -273.099784) (xy 411.104601 -273.124391)
			(xy 411.104422 -273.125492) (xy 411.4231 -273.125492) (xy 411.4231 -273.074076) (xy 411.431143 -273.023294)
			(xy 411.447031 -272.974395) (xy 411.470374 -272.928583) (xy 411.500595 -272.886987) (xy 411.536951 -272.850631)
			(xy 411.578547 -272.82041) (xy 411.624359 -272.797067) (xy 411.673258 -272.781179) (xy 411.72404 -272.773136)
			(xy 411.775456 -272.773136) (xy 411.826238 -272.781179) (xy 411.875137 -272.797067) (xy 411.920949 -272.82041)
			(xy 411.962545 -272.850631) (xy 411.998901 -272.886987) (xy 412.029122 -272.928583) (xy 412.052465 -272.974395)
			(xy 412.068353 -273.023294) (xy 412.076396 -273.074076) (xy 412.0769 -273.099784) (xy 412.394158 -273.099784)
			(xy 412.398118 -273.05073) (xy 412.409895 -273.002946) (xy 412.429186 -272.95767) (xy 412.455489 -272.916074)
			(xy 412.488124 -272.879237) (xy 412.526245 -272.848112) (xy 412.568866 -272.823505) (xy 412.614882 -272.806053)
			(xy 412.663101 -272.796209) (xy 412.712276 -272.794228) (xy 412.761131 -272.80016) (xy 412.808402 -272.813852)
			(xy 412.852864 -272.83495) (xy 412.893367 -272.862906) (xy 412.92886 -272.896998) (xy 412.958425 -272.936342)
			(xy 412.981296 -272.979919) (xy 412.99688 -273.0266) (xy 413.004775 -273.075177) (xy 413.00527 -273.099784)
			(xy 413.004775 -273.124391) (xy 413.004596 -273.125492) (xy 413.32302 -273.125492) (xy 413.32302 -273.074076)
			(xy 413.331063 -273.023294) (xy 413.346951 -272.974395) (xy 413.370294 -272.928583) (xy 413.400515 -272.886987)
			(xy 413.436871 -272.850631) (xy 413.478467 -272.82041) (xy 413.524279 -272.797067) (xy 413.573178 -272.781179)
			(xy 413.62396 -272.773136) (xy 413.675376 -272.773136) (xy 413.726158 -272.781179) (xy 413.775057 -272.797067)
			(xy 413.820869 -272.82041) (xy 413.862465 -272.850631) (xy 413.898821 -272.886987) (xy 413.929042 -272.928583)
			(xy 413.952385 -272.974395) (xy 413.968273 -273.023294) (xy 413.976316 -273.074076) (xy 413.97682 -273.099784)
			(xy 414.294078 -273.099784) (xy 414.298038 -273.05073) (xy 414.309815 -273.002946) (xy 414.329106 -272.95767)
			(xy 414.355409 -272.916074) (xy 414.388044 -272.879237) (xy 414.426165 -272.848112) (xy 414.468786 -272.823505)
			(xy 414.514802 -272.806053) (xy 414.563021 -272.796209) (xy 414.612196 -272.794228) (xy 414.661051 -272.80016)
			(xy 414.708322 -272.813852) (xy 414.752784 -272.83495) (xy 414.793287 -272.862906) (xy 414.82878 -272.896998)
			(xy 414.858345 -272.936342) (xy 414.881216 -272.979919) (xy 414.8968 -273.0266) (xy 414.904695 -273.075177)
			(xy 414.90519 -273.099784) (xy 414.904695 -273.124391) (xy 414.904516 -273.125492) (xy 415.22294 -273.125492)
			(xy 415.22294 -273.074076) (xy 415.230983 -273.023294) (xy 415.246871 -272.974395) (xy 415.270214 -272.928583)
			(xy 415.300435 -272.886987) (xy 415.336791 -272.850631) (xy 415.378387 -272.82041) (xy 415.424199 -272.797067)
			(xy 415.473098 -272.781179) (xy 415.52388 -272.773136) (xy 415.575296 -272.773136) (xy 415.626078 -272.781179)
			(xy 415.674977 -272.797067) (xy 415.720789 -272.82041) (xy 415.762385 -272.850631) (xy 415.798741 -272.886987)
			(xy 415.828962 -272.928583) (xy 415.852305 -272.974395) (xy 415.868193 -273.023294) (xy 415.876236 -273.074076)
			(xy 415.87674 -273.099784) (xy 416.193998 -273.099784) (xy 416.197958 -273.05073) (xy 416.209735 -273.002946)
			(xy 416.229026 -272.95767) (xy 416.255329 -272.916074) (xy 416.287964 -272.879237) (xy 416.326085 -272.848112)
			(xy 416.368706 -272.823505) (xy 416.414722 -272.806053) (xy 416.462941 -272.796209) (xy 416.512116 -272.794228)
			(xy 416.560971 -272.80016) (xy 416.608242 -272.813852) (xy 416.652704 -272.83495) (xy 416.693207 -272.862906)
			(xy 416.7287 -272.896998) (xy 416.758265 -272.936342) (xy 416.781136 -272.979919) (xy 416.79672 -273.0266)
			(xy 416.804615 -273.075177) (xy 416.80511 -273.099784) (xy 416.804615 -273.124391) (xy 416.804436 -273.125492)
			(xy 417.123114 -273.125492) (xy 417.123114 -273.074076) (xy 417.131157 -273.023294) (xy 417.147045 -272.974395)
			(xy 417.170388 -272.928583) (xy 417.200609 -272.886987) (xy 417.236965 -272.850631) (xy 417.278561 -272.82041)
			(xy 417.324373 -272.797067) (xy 417.373272 -272.781179) (xy 417.424054 -272.773136) (xy 417.47547 -272.773136)
			(xy 417.526252 -272.781179) (xy 417.575151 -272.797067) (xy 417.620963 -272.82041) (xy 417.662559 -272.850631)
			(xy 417.698915 -272.886987) (xy 417.729136 -272.928583) (xy 417.752479 -272.974395) (xy 417.768367 -273.023294)
			(xy 417.77641 -273.074076) (xy 417.776914 -273.099784) (xy 418.094172 -273.099784) (xy 418.098132 -273.05073)
			(xy 418.109909 -273.002946) (xy 418.1292 -272.95767) (xy 418.155503 -272.916074) (xy 418.188138 -272.879237)
			(xy 418.226259 -272.848112) (xy 418.26888 -272.823505) (xy 418.314896 -272.806053) (xy 418.363115 -272.796209)
			(xy 418.41229 -272.794228) (xy 418.461145 -272.80016) (xy 418.508416 -272.813852) (xy 418.552878 -272.83495)
			(xy 418.593381 -272.862906) (xy 418.628874 -272.896998) (xy 418.658439 -272.936342) (xy 418.68131 -272.979919)
			(xy 418.696894 -273.0266) (xy 418.704789 -273.075177) (xy 418.705284 -273.099784) (xy 418.704789 -273.124391)
			(xy 418.70461 -273.125492) (xy 419.023034 -273.125492) (xy 419.023034 -273.074076) (xy 419.031077 -273.023294)
			(xy 419.046965 -272.974395) (xy 419.070308 -272.928583) (xy 419.100529 -272.886987) (xy 419.136885 -272.850631)
			(xy 419.178481 -272.82041) (xy 419.224293 -272.797067) (xy 419.273192 -272.781179) (xy 419.323974 -272.773136)
			(xy 419.37539 -272.773136) (xy 419.426172 -272.781179) (xy 419.475071 -272.797067) (xy 419.520883 -272.82041)
			(xy 419.562479 -272.850631) (xy 419.598835 -272.886987) (xy 419.629056 -272.928583) (xy 419.652399 -272.974395)
			(xy 419.668287 -273.023294) (xy 419.67633 -273.074076) (xy 419.676834 -273.099784) (xy 419.994092 -273.099784)
			(xy 419.998052 -273.05073) (xy 420.009829 -273.002946) (xy 420.02912 -272.95767) (xy 420.055423 -272.916074)
			(xy 420.088058 -272.879237) (xy 420.126179 -272.848112) (xy 420.1688 -272.823505) (xy 420.214816 -272.806053)
			(xy 420.263035 -272.796209) (xy 420.31221 -272.794228) (xy 420.361065 -272.80016) (xy 420.408336 -272.813852)
			(xy 420.452798 -272.83495) (xy 420.493301 -272.862906) (xy 420.528794 -272.896998) (xy 420.558359 -272.936342)
			(xy 420.58123 -272.979919) (xy 420.596814 -273.0266) (xy 420.604709 -273.075177) (xy 420.605204 -273.099784)
			(xy 420.604709 -273.124391) (xy 420.60453 -273.125492) (xy 420.922954 -273.125492) (xy 420.922954 -273.074076)
			(xy 420.930997 -273.023294) (xy 420.946885 -272.974395) (xy 420.970228 -272.928583) (xy 421.000449 -272.886987)
			(xy 421.036805 -272.850631) (xy 421.078401 -272.82041) (xy 421.124213 -272.797067) (xy 421.173112 -272.781179)
			(xy 421.223894 -272.773136) (xy 421.27531 -272.773136) (xy 421.326092 -272.781179) (xy 421.374991 -272.797067)
			(xy 421.420803 -272.82041) (xy 421.462399 -272.850631) (xy 421.498755 -272.886987) (xy 421.528976 -272.928583)
			(xy 421.552319 -272.974395) (xy 421.568207 -273.023294) (xy 421.57625 -273.074076) (xy 421.576754 -273.099784)
			(xy 421.894012 -273.099784) (xy 421.897972 -273.05073) (xy 421.909749 -273.002946) (xy 421.92904 -272.95767)
			(xy 421.955343 -272.916074) (xy 421.987978 -272.879237) (xy 422.026099 -272.848112) (xy 422.06872 -272.823505)
			(xy 422.114736 -272.806053) (xy 422.162955 -272.796209) (xy 422.21213 -272.794228) (xy 422.260985 -272.80016)
			(xy 422.308256 -272.813852) (xy 422.352718 -272.83495) (xy 422.393221 -272.862906) (xy 422.428714 -272.896998)
			(xy 422.458279 -272.936342) (xy 422.48115 -272.979919) (xy 422.496734 -273.0266) (xy 422.504629 -273.075177)
			(xy 422.505124 -273.099784) (xy 422.504629 -273.124391) (xy 422.50445 -273.125492) (xy 422.823128 -273.125492)
			(xy 422.823128 -273.074076) (xy 422.831171 -273.023294) (xy 422.847059 -272.974395) (xy 422.870402 -272.928583)
			(xy 422.900623 -272.886987) (xy 422.936979 -272.850631) (xy 422.978575 -272.82041) (xy 423.024387 -272.797067)
			(xy 423.073286 -272.781179) (xy 423.124068 -272.773136) (xy 423.175484 -272.773136) (xy 423.226266 -272.781179)
			(xy 423.275165 -272.797067) (xy 423.320977 -272.82041) (xy 423.362573 -272.850631) (xy 423.398929 -272.886987)
			(xy 423.42915 -272.928583) (xy 423.452493 -272.974395) (xy 423.468381 -273.023294) (xy 423.476424 -273.074076)
			(xy 423.476928 -273.099784) (xy 423.794186 -273.099784) (xy 423.798146 -273.05073) (xy 423.809923 -273.002946)
			(xy 423.829214 -272.95767) (xy 423.855517 -272.916074) (xy 423.888152 -272.879237) (xy 423.926273 -272.848112)
			(xy 423.968894 -272.823505) (xy 424.01491 -272.806053) (xy 424.063129 -272.796209) (xy 424.112304 -272.794228)
			(xy 424.161159 -272.80016) (xy 424.20843 -272.813852) (xy 424.252892 -272.83495) (xy 424.293395 -272.862906)
			(xy 424.328888 -272.896998) (xy 424.358453 -272.936342) (xy 424.381324 -272.979919) (xy 424.396908 -273.0266)
			(xy 424.404803 -273.075177) (xy 424.405298 -273.099784) (xy 424.404803 -273.124391) (xy 424.404624 -273.125492)
			(xy 424.723048 -273.125492) (xy 424.723048 -273.074076) (xy 424.731091 -273.023294) (xy 424.746979 -272.974395)
			(xy 424.770322 -272.928583) (xy 424.800543 -272.886987) (xy 424.836899 -272.850631) (xy 424.878495 -272.82041)
			(xy 424.924307 -272.797067) (xy 424.973206 -272.781179) (xy 425.023988 -272.773136) (xy 425.075404 -272.773136)
			(xy 425.126186 -272.781179) (xy 425.175085 -272.797067) (xy 425.220897 -272.82041) (xy 425.262493 -272.850631)
			(xy 425.298849 -272.886987) (xy 425.32907 -272.928583) (xy 425.352413 -272.974395) (xy 425.368301 -273.023294)
			(xy 425.376344 -273.074076) (xy 425.376848 -273.099784) (xy 425.69436 -273.099784) (xy 425.69832 -273.05073)
			(xy 425.710097 -273.002946) (xy 425.729388 -272.95767) (xy 425.755691 -272.916074) (xy 425.788326 -272.879237)
			(xy 425.826447 -272.848112) (xy 425.869068 -272.823505) (xy 425.915084 -272.806053) (xy 425.963303 -272.796209)
			(xy 426.012478 -272.794228) (xy 426.061333 -272.80016) (xy 426.108604 -272.813852) (xy 426.153066 -272.83495)
			(xy 426.193569 -272.862906) (xy 426.229062 -272.896998) (xy 426.258627 -272.936342) (xy 426.281498 -272.979919)
			(xy 426.297082 -273.0266) (xy 426.304977 -273.075177) (xy 426.305472 -273.099784) (xy 426.304977 -273.124391)
			(xy 426.304798 -273.125492) (xy 426.622968 -273.125492) (xy 426.622968 -273.074076) (xy 426.631011 -273.023294)
			(xy 426.646899 -272.974395) (xy 426.670242 -272.928583) (xy 426.700463 -272.886987) (xy 426.736819 -272.850631)
			(xy 426.778415 -272.82041) (xy 426.824227 -272.797067) (xy 426.873126 -272.781179) (xy 426.923908 -272.773136)
			(xy 426.975324 -272.773136) (xy 427.026106 -272.781179) (xy 427.075005 -272.797067) (xy 427.120817 -272.82041)
			(xy 427.162413 -272.850631) (xy 427.198769 -272.886987) (xy 427.22899 -272.928583) (xy 427.252333 -272.974395)
			(xy 427.268221 -273.023294) (xy 427.276264 -273.074076) (xy 427.276768 -273.099784) (xy 427.59428 -273.099784)
			(xy 427.59824 -273.05073) (xy 427.610017 -273.002946) (xy 427.629308 -272.95767) (xy 427.655611 -272.916074)
			(xy 427.688246 -272.879237) (xy 427.726367 -272.848112) (xy 427.768988 -272.823505) (xy 427.815004 -272.806053)
			(xy 427.863223 -272.796209) (xy 427.912398 -272.794228) (xy 427.961253 -272.80016) (xy 428.008524 -272.813852)
			(xy 428.052986 -272.83495) (xy 428.093489 -272.862906) (xy 428.128982 -272.896998) (xy 428.158547 -272.936342)
			(xy 428.181418 -272.979919) (xy 428.197002 -273.0266) (xy 428.204897 -273.075177) (xy 428.205392 -273.099784)
			(xy 428.204897 -273.124391) (xy 428.204718 -273.125492) (xy 428.522888 -273.125492) (xy 428.522888 -273.074076)
			(xy 428.530931 -273.023294) (xy 428.546819 -272.974395) (xy 428.570162 -272.928583) (xy 428.600383 -272.886987)
			(xy 428.636739 -272.850631) (xy 428.678335 -272.82041) (xy 428.724147 -272.797067) (xy 428.773046 -272.781179)
			(xy 428.823828 -272.773136) (xy 428.875244 -272.773136) (xy 428.926026 -272.781179) (xy 428.974925 -272.797067)
			(xy 429.020737 -272.82041) (xy 429.062333 -272.850631) (xy 429.098689 -272.886987) (xy 429.12891 -272.928583)
			(xy 429.152253 -272.974395) (xy 429.168141 -273.023294) (xy 429.176184 -273.074076) (xy 429.176688 -273.099784)
			(xy 429.4942 -273.099784) (xy 429.49816 -273.05073) (xy 429.509937 -273.002946) (xy 429.529228 -272.95767)
			(xy 429.555531 -272.916074) (xy 429.588166 -272.879237) (xy 429.626287 -272.848112) (xy 429.668908 -272.823505)
			(xy 429.714924 -272.806053) (xy 429.763143 -272.796209) (xy 429.812318 -272.794228) (xy 429.861173 -272.80016)
			(xy 429.908444 -272.813852) (xy 429.952906 -272.83495) (xy 429.993409 -272.862906) (xy 430.028902 -272.896998)
			(xy 430.058467 -272.936342) (xy 430.081338 -272.979919) (xy 430.096922 -273.0266) (xy 430.104817 -273.075177)
			(xy 430.105312 -273.099784) (xy 430.104817 -273.124391) (xy 430.096922 -273.172968) (xy 430.081338 -273.219649)
			(xy 430.058467 -273.263226) (xy 430.028902 -273.30257) (xy 429.993409 -273.336662) (xy 429.952906 -273.364618)
			(xy 429.908444 -273.385716) (xy 429.861173 -273.399408) (xy 429.812318 -273.40534) (xy 429.763143 -273.403359)
			(xy 429.714924 -273.393515) (xy 429.668908 -273.376063) (xy 429.626287 -273.351456) (xy 429.588166 -273.320331)
			(xy 429.555531 -273.283494) (xy 429.529228 -273.241898) (xy 429.509937 -273.196622) (xy 429.49816 -273.148838)
			(xy 429.4942 -273.099784) (xy 429.176688 -273.099784) (xy 429.176184 -273.125492) (xy 429.168141 -273.176274)
			(xy 429.152253 -273.225173) (xy 429.12891 -273.270985) (xy 429.098689 -273.312581) (xy 429.062333 -273.348937)
			(xy 429.020737 -273.379158) (xy 428.974925 -273.402501) (xy 428.926026 -273.418389) (xy 428.875244 -273.426432)
			(xy 428.823828 -273.426432) (xy 428.773046 -273.418389) (xy 428.724147 -273.402501) (xy 428.678335 -273.379158)
			(xy 428.636739 -273.348937) (xy 428.600383 -273.312581) (xy 428.570162 -273.270985) (xy 428.546819 -273.225173)
			(xy 428.530931 -273.176274) (xy 428.522888 -273.125492) (xy 428.204718 -273.125492) (xy 428.197002 -273.172968)
			(xy 428.181418 -273.219649) (xy 428.158547 -273.263226) (xy 428.128982 -273.30257) (xy 428.093489 -273.336662)
			(xy 428.052986 -273.364618) (xy 428.008524 -273.385716) (xy 427.961253 -273.399408) (xy 427.912398 -273.40534)
			(xy 427.863223 -273.403359) (xy 427.815004 -273.393515) (xy 427.768988 -273.376063) (xy 427.726367 -273.351456)
			(xy 427.688246 -273.320331) (xy 427.655611 -273.283494) (xy 427.629308 -273.241898) (xy 427.610017 -273.196622)
			(xy 427.59824 -273.148838) (xy 427.59428 -273.099784) (xy 427.276768 -273.099784) (xy 427.276264 -273.125492)
			(xy 427.268221 -273.176274) (xy 427.252333 -273.225173) (xy 427.22899 -273.270985) (xy 427.198769 -273.312581)
			(xy 427.162413 -273.348937) (xy 427.120817 -273.379158) (xy 427.075005 -273.402501) (xy 427.026106 -273.418389)
			(xy 426.975324 -273.426432) (xy 426.923908 -273.426432) (xy 426.873126 -273.418389) (xy 426.824227 -273.402501)
			(xy 426.778415 -273.379158) (xy 426.736819 -273.348937) (xy 426.700463 -273.312581) (xy 426.670242 -273.270985)
			(xy 426.646899 -273.225173) (xy 426.631011 -273.176274) (xy 426.622968 -273.125492) (xy 426.304798 -273.125492)
			(xy 426.297082 -273.172968) (xy 426.281498 -273.219649) (xy 426.258627 -273.263226) (xy 426.229062 -273.30257)
			(xy 426.193569 -273.336662) (xy 426.153066 -273.364618) (xy 426.108604 -273.385716) (xy 426.061333 -273.399408)
			(xy 426.012478 -273.40534) (xy 425.963303 -273.403359) (xy 425.915084 -273.393515) (xy 425.869068 -273.376063)
			(xy 425.826447 -273.351456) (xy 425.788326 -273.320331) (xy 425.755691 -273.283494) (xy 425.729388 -273.241898)
			(xy 425.710097 -273.196622) (xy 425.69832 -273.148838) (xy 425.69436 -273.099784) (xy 425.376848 -273.099784)
			(xy 425.376344 -273.125492) (xy 425.368301 -273.176274) (xy 425.352413 -273.225173) (xy 425.32907 -273.270985)
			(xy 425.298849 -273.312581) (xy 425.262493 -273.348937) (xy 425.220897 -273.379158) (xy 425.175085 -273.402501)
			(xy 425.126186 -273.418389) (xy 425.075404 -273.426432) (xy 425.023988 -273.426432) (xy 424.973206 -273.418389)
			(xy 424.924307 -273.402501) (xy 424.878495 -273.379158) (xy 424.836899 -273.348937) (xy 424.800543 -273.312581)
			(xy 424.770322 -273.270985) (xy 424.746979 -273.225173) (xy 424.731091 -273.176274) (xy 424.723048 -273.125492)
			(xy 424.404624 -273.125492) (xy 424.396908 -273.172968) (xy 424.381324 -273.219649) (xy 424.358453 -273.263226)
			(xy 424.328888 -273.30257) (xy 424.293395 -273.336662) (xy 424.252892 -273.364618) (xy 424.20843 -273.385716)
			(xy 424.161159 -273.399408) (xy 424.112304 -273.40534) (xy 424.063129 -273.403359) (xy 424.01491 -273.393515)
			(xy 423.968894 -273.376063) (xy 423.926273 -273.351456) (xy 423.888152 -273.320331) (xy 423.855517 -273.283494)
			(xy 423.829214 -273.241898) (xy 423.809923 -273.196622) (xy 423.798146 -273.148838) (xy 423.794186 -273.099784)
			(xy 423.476928 -273.099784) (xy 423.476424 -273.125492) (xy 423.468381 -273.176274) (xy 423.452493 -273.225173)
			(xy 423.42915 -273.270985) (xy 423.398929 -273.312581) (xy 423.362573 -273.348937) (xy 423.320977 -273.379158)
			(xy 423.275165 -273.402501) (xy 423.226266 -273.418389) (xy 423.175484 -273.426432) (xy 423.124068 -273.426432)
			(xy 423.073286 -273.418389) (xy 423.024387 -273.402501) (xy 422.978575 -273.379158) (xy 422.936979 -273.348937)
			(xy 422.900623 -273.312581) (xy 422.870402 -273.270985) (xy 422.847059 -273.225173) (xy 422.831171 -273.176274)
			(xy 422.823128 -273.125492) (xy 422.50445 -273.125492) (xy 422.496734 -273.172968) (xy 422.48115 -273.219649)
			(xy 422.458279 -273.263226) (xy 422.428714 -273.30257) (xy 422.393221 -273.336662) (xy 422.352718 -273.364618)
			(xy 422.308256 -273.385716) (xy 422.260985 -273.399408) (xy 422.21213 -273.40534) (xy 422.162955 -273.403359)
			(xy 422.114736 -273.393515) (xy 422.06872 -273.376063) (xy 422.026099 -273.351456) (xy 421.987978 -273.320331)
			(xy 421.955343 -273.283494) (xy 421.92904 -273.241898) (xy 421.909749 -273.196622) (xy 421.897972 -273.148838)
			(xy 421.894012 -273.099784) (xy 421.576754 -273.099784) (xy 421.57625 -273.125492) (xy 421.568207 -273.176274)
			(xy 421.552319 -273.225173) (xy 421.528976 -273.270985) (xy 421.498755 -273.312581) (xy 421.462399 -273.348937)
			(xy 421.420803 -273.379158) (xy 421.374991 -273.402501) (xy 421.326092 -273.418389) (xy 421.27531 -273.426432)
			(xy 421.223894 -273.426432) (xy 421.173112 -273.418389) (xy 421.124213 -273.402501) (xy 421.078401 -273.379158)
			(xy 421.036805 -273.348937) (xy 421.000449 -273.312581) (xy 420.970228 -273.270985) (xy 420.946885 -273.225173)
			(xy 420.930997 -273.176274) (xy 420.922954 -273.125492) (xy 420.60453 -273.125492) (xy 420.596814 -273.172968)
			(xy 420.58123 -273.219649) (xy 420.558359 -273.263226) (xy 420.528794 -273.30257) (xy 420.493301 -273.336662)
			(xy 420.452798 -273.364618) (xy 420.408336 -273.385716) (xy 420.361065 -273.399408) (xy 420.31221 -273.40534)
			(xy 420.263035 -273.403359) (xy 420.214816 -273.393515) (xy 420.1688 -273.376063) (xy 420.126179 -273.351456)
			(xy 420.088058 -273.320331) (xy 420.055423 -273.283494) (xy 420.02912 -273.241898) (xy 420.009829 -273.196622)
			(xy 419.998052 -273.148838) (xy 419.994092 -273.099784) (xy 419.676834 -273.099784) (xy 419.67633 -273.125492)
			(xy 419.668287 -273.176274) (xy 419.652399 -273.225173) (xy 419.629056 -273.270985) (xy 419.598835 -273.312581)
			(xy 419.562479 -273.348937) (xy 419.520883 -273.379158) (xy 419.475071 -273.402501) (xy 419.426172 -273.418389)
			(xy 419.37539 -273.426432) (xy 419.323974 -273.426432) (xy 419.273192 -273.418389) (xy 419.224293 -273.402501)
			(xy 419.178481 -273.379158) (xy 419.136885 -273.348937) (xy 419.100529 -273.312581) (xy 419.070308 -273.270985)
			(xy 419.046965 -273.225173) (xy 419.031077 -273.176274) (xy 419.023034 -273.125492) (xy 418.70461 -273.125492)
			(xy 418.696894 -273.172968) (xy 418.68131 -273.219649) (xy 418.658439 -273.263226) (xy 418.628874 -273.30257)
			(xy 418.593381 -273.336662) (xy 418.552878 -273.364618) (xy 418.508416 -273.385716) (xy 418.461145 -273.399408)
			(xy 418.41229 -273.40534) (xy 418.363115 -273.403359) (xy 418.314896 -273.393515) (xy 418.26888 -273.376063)
			(xy 418.226259 -273.351456) (xy 418.188138 -273.320331) (xy 418.155503 -273.283494) (xy 418.1292 -273.241898)
			(xy 418.109909 -273.196622) (xy 418.098132 -273.148838) (xy 418.094172 -273.099784) (xy 417.776914 -273.099784)
			(xy 417.77641 -273.125492) (xy 417.768367 -273.176274) (xy 417.752479 -273.225173) (xy 417.729136 -273.270985)
			(xy 417.698915 -273.312581) (xy 417.662559 -273.348937) (xy 417.620963 -273.379158) (xy 417.575151 -273.402501)
			(xy 417.526252 -273.418389) (xy 417.47547 -273.426432) (xy 417.424054 -273.426432) (xy 417.373272 -273.418389)
			(xy 417.324373 -273.402501) (xy 417.278561 -273.379158) (xy 417.236965 -273.348937) (xy 417.200609 -273.312581)
			(xy 417.170388 -273.270985) (xy 417.147045 -273.225173) (xy 417.131157 -273.176274) (xy 417.123114 -273.125492)
			(xy 416.804436 -273.125492) (xy 416.79672 -273.172968) (xy 416.781136 -273.219649) (xy 416.758265 -273.263226)
			(xy 416.7287 -273.30257) (xy 416.693207 -273.336662) (xy 416.652704 -273.364618) (xy 416.608242 -273.385716)
			(xy 416.560971 -273.399408) (xy 416.512116 -273.40534) (xy 416.462941 -273.403359) (xy 416.414722 -273.393515)
			(xy 416.368706 -273.376063) (xy 416.326085 -273.351456) (xy 416.287964 -273.320331) (xy 416.255329 -273.283494)
			(xy 416.229026 -273.241898) (xy 416.209735 -273.196622) (xy 416.197958 -273.148838) (xy 416.193998 -273.099784)
			(xy 415.87674 -273.099784) (xy 415.876236 -273.125492) (xy 415.868193 -273.176274) (xy 415.852305 -273.225173)
			(xy 415.828962 -273.270985) (xy 415.798741 -273.312581) (xy 415.762385 -273.348937) (xy 415.720789 -273.379158)
			(xy 415.674977 -273.402501) (xy 415.626078 -273.418389) (xy 415.575296 -273.426432) (xy 415.52388 -273.426432)
			(xy 415.473098 -273.418389) (xy 415.424199 -273.402501) (xy 415.378387 -273.379158) (xy 415.336791 -273.348937)
			(xy 415.300435 -273.312581) (xy 415.270214 -273.270985) (xy 415.246871 -273.225173) (xy 415.230983 -273.176274)
			(xy 415.22294 -273.125492) (xy 414.904516 -273.125492) (xy 414.8968 -273.172968) (xy 414.881216 -273.219649)
			(xy 414.858345 -273.263226) (xy 414.82878 -273.30257) (xy 414.793287 -273.336662) (xy 414.752784 -273.364618)
			(xy 414.708322 -273.385716) (xy 414.661051 -273.399408) (xy 414.612196 -273.40534) (xy 414.563021 -273.403359)
			(xy 414.514802 -273.393515) (xy 414.468786 -273.376063) (xy 414.426165 -273.351456) (xy 414.388044 -273.320331)
			(xy 414.355409 -273.283494) (xy 414.329106 -273.241898) (xy 414.309815 -273.196622) (xy 414.298038 -273.148838)
			(xy 414.294078 -273.099784) (xy 413.97682 -273.099784) (xy 413.976316 -273.125492) (xy 413.968273 -273.176274)
			(xy 413.952385 -273.225173) (xy 413.929042 -273.270985) (xy 413.898821 -273.312581) (xy 413.862465 -273.348937)
			(xy 413.820869 -273.379158) (xy 413.775057 -273.402501) (xy 413.726158 -273.418389) (xy 413.675376 -273.426432)
			(xy 413.62396 -273.426432) (xy 413.573178 -273.418389) (xy 413.524279 -273.402501) (xy 413.478467 -273.379158)
			(xy 413.436871 -273.348937) (xy 413.400515 -273.312581) (xy 413.370294 -273.270985) (xy 413.346951 -273.225173)
			(xy 413.331063 -273.176274) (xy 413.32302 -273.125492) (xy 413.004596 -273.125492) (xy 412.99688 -273.172968)
			(xy 412.981296 -273.219649) (xy 412.958425 -273.263226) (xy 412.92886 -273.30257) (xy 412.893367 -273.336662)
			(xy 412.852864 -273.364618) (xy 412.808402 -273.385716) (xy 412.761131 -273.399408) (xy 412.712276 -273.40534)
			(xy 412.663101 -273.403359) (xy 412.614882 -273.393515) (xy 412.568866 -273.376063) (xy 412.526245 -273.351456)
			(xy 412.488124 -273.320331) (xy 412.455489 -273.283494) (xy 412.429186 -273.241898) (xy 412.409895 -273.196622)
			(xy 412.398118 -273.148838) (xy 412.394158 -273.099784) (xy 412.0769 -273.099784) (xy 412.076396 -273.125492)
			(xy 412.068353 -273.176274) (xy 412.052465 -273.225173) (xy 412.029122 -273.270985) (xy 411.998901 -273.312581)
			(xy 411.962545 -273.348937) (xy 411.920949 -273.379158) (xy 411.875137 -273.402501) (xy 411.826238 -273.418389)
			(xy 411.775456 -273.426432) (xy 411.72404 -273.426432) (xy 411.673258 -273.418389) (xy 411.624359 -273.402501)
			(xy 411.578547 -273.379158) (xy 411.536951 -273.348937) (xy 411.500595 -273.312581) (xy 411.470374 -273.270985)
			(xy 411.447031 -273.225173) (xy 411.431143 -273.176274) (xy 411.4231 -273.125492) (xy 411.104422 -273.125492)
			(xy 411.096706 -273.172968) (xy 411.081122 -273.219649) (xy 411.058251 -273.263226) (xy 411.028686 -273.30257)
			(xy 410.993193 -273.336662) (xy 410.95269 -273.364618) (xy 410.908228 -273.385716) (xy 410.860957 -273.399408)
			(xy 410.812102 -273.40534) (xy 410.762927 -273.403359) (xy 410.714708 -273.393515) (xy 410.668692 -273.376063)
			(xy 410.626071 -273.351456) (xy 410.58795 -273.320331) (xy 410.555315 -273.283494) (xy 410.529012 -273.241898)
			(xy 410.509721 -273.196622) (xy 410.497944 -273.148838) (xy 410.493984 -273.099784) (xy 410.17629 -273.099784)
			(xy 410.17629 -273.125512) (xy 410.168245 -273.176304) (xy 410.152353 -273.225211) (xy 410.129005 -273.271031)
			(xy 410.098777 -273.312633) (xy 410.062413 -273.348994) (xy 410.020808 -273.379219) (xy 409.974987 -273.402563)
			(xy 409.926079 -273.418451) (xy 409.875286 -273.426492) (xy 409.849574 -273.426936) (xy 409.83637 -273.426781)
			(xy 409.810049 -273.424619) (xy 409.796996 -273.422618) (xy 409.78455 -273.420586) (xy 409.760674 -273.428714)
			(xy 409.70581 -273.486372) (xy 409.698952 -273.508978) (xy 409.700984 -273.520916) (xy 409.703095 -273.534279)
			(xy 409.705382 -273.561237) (xy 409.705556 -273.574764) (xy 409.705376 -273.588291) (xy 409.703088 -273.615249)
			(xy 409.700984 -273.628612) (xy 409.698952 -273.64055) (xy 409.70581 -273.663156) (xy 409.760674 -273.720814)
			(xy 409.78455 -273.728942) (xy 409.796996 -273.72691) (xy 409.810047 -273.724894) (xy 409.836369 -273.722729)
			(xy 409.849574 -273.722592) (xy 409.875282 -273.723068) (xy 409.926065 -273.731108) (xy 409.974964 -273.746993)
			(xy 410.020777 -273.770332) (xy 410.062374 -273.800551) (xy 410.098732 -273.836906) (xy 410.128954 -273.878501)
			(xy 410.152297 -273.924312) (xy 410.168186 -273.97321) (xy 410.17623 -274.023992) (xy 410.17623 -274.049744)
			(xy 410.493984 -274.049744) (xy 410.497944 -274.00069) (xy 410.509721 -273.952906) (xy 410.529012 -273.90763)
			(xy 410.555315 -273.866034) (xy 410.58795 -273.829197) (xy 410.626071 -273.798072) (xy 410.668692 -273.773465)
			(xy 410.714708 -273.756013) (xy 410.762927 -273.746169) (xy 410.812102 -273.744188) (xy 410.860957 -273.75012)
			(xy 410.908228 -273.763812) (xy 410.95269 -273.78491) (xy 410.993193 -273.812866) (xy 411.028686 -273.846958)
			(xy 411.058251 -273.886302) (xy 411.081122 -273.929879) (xy 411.096706 -273.97656) (xy 411.104601 -274.025137)
			(xy 411.105096 -274.049744) (xy 411.104601 -274.074351) (xy 411.104422 -274.075452) (xy 411.4231 -274.075452)
			(xy 411.4231 -274.024036) (xy 411.431143 -273.973254) (xy 411.447031 -273.924355) (xy 411.470374 -273.878543)
			(xy 411.500595 -273.836947) (xy 411.536951 -273.800591) (xy 411.578547 -273.77037) (xy 411.624359 -273.747027)
			(xy 411.673258 -273.731139) (xy 411.72404 -273.723096) (xy 411.775456 -273.723096) (xy 411.826238 -273.731139)
			(xy 411.875137 -273.747027) (xy 411.920949 -273.77037) (xy 411.962545 -273.800591) (xy 411.998901 -273.836947)
			(xy 412.029122 -273.878543) (xy 412.052465 -273.924355) (xy 412.068353 -273.973254) (xy 412.076396 -274.024036)
			(xy 412.0769 -274.049744) (xy 412.394158 -274.049744) (xy 412.398118 -274.00069) (xy 412.409895 -273.952906)
			(xy 412.429186 -273.90763) (xy 412.455489 -273.866034) (xy 412.488124 -273.829197) (xy 412.526245 -273.798072)
			(xy 412.568866 -273.773465) (xy 412.614882 -273.756013) (xy 412.663101 -273.746169) (xy 412.712276 -273.744188)
			(xy 412.761131 -273.75012) (xy 412.808402 -273.763812) (xy 412.852864 -273.78491) (xy 412.893367 -273.812866)
			(xy 412.92886 -273.846958) (xy 412.958425 -273.886302) (xy 412.981296 -273.929879) (xy 412.99688 -273.97656)
			(xy 413.004775 -274.025137) (xy 413.00527 -274.049744) (xy 413.004775 -274.074351) (xy 413.004596 -274.075452)
			(xy 413.32302 -274.075452) (xy 413.32302 -274.024036) (xy 413.331063 -273.973254) (xy 413.346951 -273.924355)
			(xy 413.370294 -273.878543) (xy 413.400515 -273.836947) (xy 413.436871 -273.800591) (xy 413.478467 -273.77037)
			(xy 413.524279 -273.747027) (xy 413.573178 -273.731139) (xy 413.62396 -273.723096) (xy 413.675376 -273.723096)
			(xy 413.726158 -273.731139) (xy 413.775057 -273.747027) (xy 413.820869 -273.77037) (xy 413.862465 -273.800591)
			(xy 413.898821 -273.836947) (xy 413.929042 -273.878543) (xy 413.952385 -273.924355) (xy 413.968273 -273.973254)
			(xy 413.976316 -274.024036) (xy 413.97682 -274.049744) (xy 414.294078 -274.049744) (xy 414.298038 -274.00069)
			(xy 414.309815 -273.952906) (xy 414.329106 -273.90763) (xy 414.355409 -273.866034) (xy 414.388044 -273.829197)
			(xy 414.426165 -273.798072) (xy 414.468786 -273.773465) (xy 414.514802 -273.756013) (xy 414.563021 -273.746169)
			(xy 414.612196 -273.744188) (xy 414.661051 -273.75012) (xy 414.708322 -273.763812) (xy 414.752784 -273.78491)
			(xy 414.793287 -273.812866) (xy 414.82878 -273.846958) (xy 414.858345 -273.886302) (xy 414.881216 -273.929879)
			(xy 414.8968 -273.97656) (xy 414.904695 -274.025137) (xy 414.90519 -274.049744) (xy 414.904695 -274.074351)
			(xy 414.904516 -274.075452) (xy 415.22294 -274.075452) (xy 415.22294 -274.024036) (xy 415.230983 -273.973254)
			(xy 415.246871 -273.924355) (xy 415.270214 -273.878543) (xy 415.300435 -273.836947) (xy 415.336791 -273.800591)
			(xy 415.378387 -273.77037) (xy 415.424199 -273.747027) (xy 415.473098 -273.731139) (xy 415.52388 -273.723096)
			(xy 415.575296 -273.723096) (xy 415.626078 -273.731139) (xy 415.674977 -273.747027) (xy 415.720789 -273.77037)
			(xy 415.762385 -273.800591) (xy 415.798741 -273.836947) (xy 415.828962 -273.878543) (xy 415.852305 -273.924355)
			(xy 415.868193 -273.973254) (xy 415.876236 -274.024036) (xy 415.87674 -274.049744) (xy 416.193998 -274.049744)
			(xy 416.197958 -274.00069) (xy 416.209735 -273.952906) (xy 416.229026 -273.90763) (xy 416.255329 -273.866034)
			(xy 416.287964 -273.829197) (xy 416.326085 -273.798072) (xy 416.368706 -273.773465) (xy 416.414722 -273.756013)
			(xy 416.462941 -273.746169) (xy 416.512116 -273.744188) (xy 416.560971 -273.75012) (xy 416.608242 -273.763812)
			(xy 416.652704 -273.78491) (xy 416.693207 -273.812866) (xy 416.7287 -273.846958) (xy 416.758265 -273.886302)
			(xy 416.781136 -273.929879) (xy 416.79672 -273.97656) (xy 416.804615 -274.025137) (xy 416.80511 -274.049744)
			(xy 416.804615 -274.074351) (xy 416.804436 -274.075452) (xy 417.123114 -274.075452) (xy 417.123114 -274.024036)
			(xy 417.131157 -273.973254) (xy 417.147045 -273.924355) (xy 417.170388 -273.878543) (xy 417.200609 -273.836947)
			(xy 417.236965 -273.800591) (xy 417.278561 -273.77037) (xy 417.324373 -273.747027) (xy 417.373272 -273.731139)
			(xy 417.424054 -273.723096) (xy 417.47547 -273.723096) (xy 417.526252 -273.731139) (xy 417.575151 -273.747027)
			(xy 417.620963 -273.77037) (xy 417.662559 -273.800591) (xy 417.698915 -273.836947) (xy 417.729136 -273.878543)
			(xy 417.752479 -273.924355) (xy 417.768367 -273.973254) (xy 417.77641 -274.024036) (xy 417.776914 -274.049744)
			(xy 418.094172 -274.049744) (xy 418.098132 -274.00069) (xy 418.109909 -273.952906) (xy 418.1292 -273.90763)
			(xy 418.155503 -273.866034) (xy 418.188138 -273.829197) (xy 418.226259 -273.798072) (xy 418.26888 -273.773465)
			(xy 418.314896 -273.756013) (xy 418.363115 -273.746169) (xy 418.41229 -273.744188) (xy 418.461145 -273.75012)
			(xy 418.508416 -273.763812) (xy 418.552878 -273.78491) (xy 418.593381 -273.812866) (xy 418.628874 -273.846958)
			(xy 418.658439 -273.886302) (xy 418.68131 -273.929879) (xy 418.696894 -273.97656) (xy 418.704789 -274.025137)
			(xy 418.705284 -274.049744) (xy 418.704789 -274.074351) (xy 418.70461 -274.075452) (xy 419.023034 -274.075452)
			(xy 419.023034 -274.024036) (xy 419.031077 -273.973254) (xy 419.046965 -273.924355) (xy 419.070308 -273.878543)
			(xy 419.100529 -273.836947) (xy 419.136885 -273.800591) (xy 419.178481 -273.77037) (xy 419.224293 -273.747027)
			(xy 419.273192 -273.731139) (xy 419.323974 -273.723096) (xy 419.37539 -273.723096) (xy 419.426172 -273.731139)
			(xy 419.475071 -273.747027) (xy 419.520883 -273.77037) (xy 419.562479 -273.800591) (xy 419.598835 -273.836947)
			(xy 419.629056 -273.878543) (xy 419.652399 -273.924355) (xy 419.668287 -273.973254) (xy 419.67633 -274.024036)
			(xy 419.676834 -274.049744) (xy 419.994092 -274.049744) (xy 419.998052 -274.00069) (xy 420.009829 -273.952906)
			(xy 420.02912 -273.90763) (xy 420.055423 -273.866034) (xy 420.088058 -273.829197) (xy 420.126179 -273.798072)
			(xy 420.1688 -273.773465) (xy 420.214816 -273.756013) (xy 420.263035 -273.746169) (xy 420.31221 -273.744188)
			(xy 420.361065 -273.75012) (xy 420.408336 -273.763812) (xy 420.452798 -273.78491) (xy 420.493301 -273.812866)
			(xy 420.528794 -273.846958) (xy 420.558359 -273.886302) (xy 420.58123 -273.929879) (xy 420.596814 -273.97656)
			(xy 420.604709 -274.025137) (xy 420.605204 -274.049744) (xy 420.604709 -274.074351) (xy 420.60453 -274.075452)
			(xy 420.922954 -274.075452) (xy 420.922954 -274.024036) (xy 420.930997 -273.973254) (xy 420.946885 -273.924355)
			(xy 420.970228 -273.878543) (xy 421.000449 -273.836947) (xy 421.036805 -273.800591) (xy 421.078401 -273.77037)
			(xy 421.124213 -273.747027) (xy 421.173112 -273.731139) (xy 421.223894 -273.723096) (xy 421.27531 -273.723096)
			(xy 421.326092 -273.731139) (xy 421.374991 -273.747027) (xy 421.420803 -273.77037) (xy 421.462399 -273.800591)
			(xy 421.498755 -273.836947) (xy 421.528976 -273.878543) (xy 421.552319 -273.924355) (xy 421.568207 -273.973254)
			(xy 421.57625 -274.024036) (xy 421.576754 -274.049744) (xy 421.894012 -274.049744) (xy 421.897972 -274.00069)
			(xy 421.909749 -273.952906) (xy 421.92904 -273.90763) (xy 421.955343 -273.866034) (xy 421.987978 -273.829197)
			(xy 422.026099 -273.798072) (xy 422.06872 -273.773465) (xy 422.114736 -273.756013) (xy 422.162955 -273.746169)
			(xy 422.21213 -273.744188) (xy 422.260985 -273.75012) (xy 422.308256 -273.763812) (xy 422.352718 -273.78491)
			(xy 422.393221 -273.812866) (xy 422.428714 -273.846958) (xy 422.458279 -273.886302) (xy 422.48115 -273.929879)
			(xy 422.496734 -273.97656) (xy 422.504629 -274.025137) (xy 422.505124 -274.049744) (xy 422.504629 -274.074351)
			(xy 422.50445 -274.075452) (xy 422.823128 -274.075452) (xy 422.823128 -274.024036) (xy 422.831171 -273.973254)
			(xy 422.847059 -273.924355) (xy 422.870402 -273.878543) (xy 422.900623 -273.836947) (xy 422.936979 -273.800591)
			(xy 422.978575 -273.77037) (xy 423.024387 -273.747027) (xy 423.073286 -273.731139) (xy 423.124068 -273.723096)
			(xy 423.175484 -273.723096) (xy 423.226266 -273.731139) (xy 423.275165 -273.747027) (xy 423.320977 -273.77037)
			(xy 423.362573 -273.800591) (xy 423.398929 -273.836947) (xy 423.42915 -273.878543) (xy 423.452493 -273.924355)
			(xy 423.468381 -273.973254) (xy 423.476424 -274.024036) (xy 423.476928 -274.049744) (xy 423.79444 -274.049744)
			(xy 423.7984 -274.00069) (xy 423.810177 -273.952906) (xy 423.829468 -273.90763) (xy 423.855771 -273.866034)
			(xy 423.888406 -273.829197) (xy 423.926527 -273.798072) (xy 423.969148 -273.773465) (xy 424.015164 -273.756013)
			(xy 424.063383 -273.746169) (xy 424.112558 -273.744188) (xy 424.161413 -273.75012) (xy 424.208684 -273.763812)
			(xy 424.253146 -273.78491) (xy 424.293649 -273.812866) (xy 424.329142 -273.846958) (xy 424.358707 -273.886302)
			(xy 424.381578 -273.929879) (xy 424.397162 -273.97656) (xy 424.405057 -274.025137) (xy 424.405552 -274.049744)
			(xy 424.405057 -274.074351) (xy 424.404878 -274.075452) (xy 424.723048 -274.075452) (xy 424.723048 -274.024036)
			(xy 424.731091 -273.973254) (xy 424.746979 -273.924355) (xy 424.770322 -273.878543) (xy 424.800543 -273.836947)
			(xy 424.836899 -273.800591) (xy 424.878495 -273.77037) (xy 424.924307 -273.747027) (xy 424.973206 -273.731139)
			(xy 425.023988 -273.723096) (xy 425.075404 -273.723096) (xy 425.126186 -273.731139) (xy 425.175085 -273.747027)
			(xy 425.220897 -273.77037) (xy 425.262493 -273.800591) (xy 425.298849 -273.836947) (xy 425.32907 -273.878543)
			(xy 425.352413 -273.924355) (xy 425.368301 -273.973254) (xy 425.376344 -274.024036) (xy 425.376848 -274.049744)
			(xy 425.69436 -274.049744) (xy 425.69832 -274.00069) (xy 425.710097 -273.952906) (xy 425.729388 -273.90763)
			(xy 425.755691 -273.866034) (xy 425.788326 -273.829197) (xy 425.826447 -273.798072) (xy 425.869068 -273.773465)
			(xy 425.915084 -273.756013) (xy 425.963303 -273.746169) (xy 426.012478 -273.744188) (xy 426.061333 -273.75012)
			(xy 426.108604 -273.763812) (xy 426.153066 -273.78491) (xy 426.193569 -273.812866) (xy 426.229062 -273.846958)
			(xy 426.258627 -273.886302) (xy 426.281498 -273.929879) (xy 426.297082 -273.97656) (xy 426.304977 -274.025137)
			(xy 426.305472 -274.049744) (xy 426.304977 -274.074351) (xy 426.304798 -274.075452) (xy 426.622968 -274.075452)
			(xy 426.622968 -274.024036) (xy 426.631011 -273.973254) (xy 426.646899 -273.924355) (xy 426.670242 -273.878543)
			(xy 426.700463 -273.836947) (xy 426.736819 -273.800591) (xy 426.778415 -273.77037) (xy 426.824227 -273.747027)
			(xy 426.873126 -273.731139) (xy 426.923908 -273.723096) (xy 426.975324 -273.723096) (xy 427.026106 -273.731139)
			(xy 427.075005 -273.747027) (xy 427.120817 -273.77037) (xy 427.162413 -273.800591) (xy 427.198769 -273.836947)
			(xy 427.22899 -273.878543) (xy 427.252333 -273.924355) (xy 427.268221 -273.973254) (xy 427.276264 -274.024036)
			(xy 427.276768 -274.049744) (xy 427.59428 -274.049744) (xy 427.59824 -274.00069) (xy 427.610017 -273.952906)
			(xy 427.629308 -273.90763) (xy 427.655611 -273.866034) (xy 427.688246 -273.829197) (xy 427.726367 -273.798072)
			(xy 427.768988 -273.773465) (xy 427.815004 -273.756013) (xy 427.863223 -273.746169) (xy 427.912398 -273.744188)
			(xy 427.961253 -273.75012) (xy 428.008524 -273.763812) (xy 428.052986 -273.78491) (xy 428.093489 -273.812866)
			(xy 428.128982 -273.846958) (xy 428.158547 -273.886302) (xy 428.181418 -273.929879) (xy 428.197002 -273.97656)
			(xy 428.204897 -274.025137) (xy 428.205392 -274.049744) (xy 428.204897 -274.074351) (xy 428.204718 -274.075452)
			(xy 428.522888 -274.075452) (xy 428.522888 -274.024036) (xy 428.530931 -273.973254) (xy 428.546819 -273.924355)
			(xy 428.570162 -273.878543) (xy 428.600383 -273.836947) (xy 428.636739 -273.800591) (xy 428.678335 -273.77037)
			(xy 428.724147 -273.747027) (xy 428.773046 -273.731139) (xy 428.823828 -273.723096) (xy 428.875244 -273.723096)
			(xy 428.926026 -273.731139) (xy 428.974925 -273.747027) (xy 429.020737 -273.77037) (xy 429.062333 -273.800591)
			(xy 429.098689 -273.836947) (xy 429.12891 -273.878543) (xy 429.152253 -273.924355) (xy 429.168141 -273.973254)
			(xy 429.176184 -274.024036) (xy 429.176688 -274.049744) (xy 429.4942 -274.049744) (xy 429.49816 -274.00069)
			(xy 429.509937 -273.952906) (xy 429.529228 -273.90763) (xy 429.555531 -273.866034) (xy 429.588166 -273.829197)
			(xy 429.626287 -273.798072) (xy 429.668908 -273.773465) (xy 429.714924 -273.756013) (xy 429.763143 -273.746169)
			(xy 429.812318 -273.744188) (xy 429.861173 -273.75012) (xy 429.908444 -273.763812) (xy 429.952906 -273.78491)
			(xy 429.993409 -273.812866) (xy 430.028902 -273.846958) (xy 430.058467 -273.886302) (xy 430.081338 -273.929879)
			(xy 430.096922 -273.97656) (xy 430.104817 -274.025137) (xy 430.105312 -274.049744) (xy 430.44416 -274.049744)
			(xy 430.44812 -274.00069) (xy 430.459897 -273.952906) (xy 430.479188 -273.90763) (xy 430.505491 -273.866034)
			(xy 430.538126 -273.829197) (xy 430.576247 -273.798072) (xy 430.618868 -273.773465) (xy 430.664884 -273.756013)
			(xy 430.713103 -273.746169) (xy 430.762278 -273.744188) (xy 430.811133 -273.75012) (xy 430.858404 -273.763812)
			(xy 430.902866 -273.78491) (xy 430.943369 -273.812866) (xy 430.978862 -273.846958) (xy 431.008427 -273.886302)
			(xy 431.031298 -273.929879) (xy 431.046882 -273.97656) (xy 431.054777 -274.025137) (xy 431.055272 -274.049744)
			(xy 431.054777 -274.074351) (xy 431.046882 -274.122928) (xy 431.031298 -274.169609) (xy 431.008427 -274.213186)
			(xy 430.978862 -274.25253) (xy 430.943369 -274.286622) (xy 430.902866 -274.314578) (xy 430.858404 -274.335676)
			(xy 430.811133 -274.349368) (xy 430.762278 -274.3553) (xy 430.713103 -274.353319) (xy 430.664884 -274.343475)
			(xy 430.618868 -274.326023) (xy 430.576247 -274.301416) (xy 430.538126 -274.270291) (xy 430.505491 -274.233454)
			(xy 430.479188 -274.191858) (xy 430.459897 -274.146582) (xy 430.44812 -274.098798) (xy 430.44416 -274.049744)
			(xy 430.105312 -274.049744) (xy 430.104817 -274.074351) (xy 430.096922 -274.122928) (xy 430.081338 -274.169609)
			(xy 430.058467 -274.213186) (xy 430.028902 -274.25253) (xy 429.993409 -274.286622) (xy 429.952906 -274.314578)
			(xy 429.908444 -274.335676) (xy 429.861173 -274.349368) (xy 429.812318 -274.3553) (xy 429.763143 -274.353319)
			(xy 429.714924 -274.343475) (xy 429.668908 -274.326023) (xy 429.626287 -274.301416) (xy 429.588166 -274.270291)
			(xy 429.555531 -274.233454) (xy 429.529228 -274.191858) (xy 429.509937 -274.146582) (xy 429.49816 -274.098798)
			(xy 429.4942 -274.049744) (xy 429.176688 -274.049744) (xy 429.176184 -274.075452) (xy 429.168141 -274.126234)
			(xy 429.152253 -274.175133) (xy 429.12891 -274.220945) (xy 429.098689 -274.262541) (xy 429.062333 -274.298897)
			(xy 429.020737 -274.329118) (xy 428.974925 -274.352461) (xy 428.926026 -274.368349) (xy 428.875244 -274.376392)
			(xy 428.823828 -274.376392) (xy 428.773046 -274.368349) (xy 428.724147 -274.352461) (xy 428.678335 -274.329118)
			(xy 428.636739 -274.298897) (xy 428.600383 -274.262541) (xy 428.570162 -274.220945) (xy 428.546819 -274.175133)
			(xy 428.530931 -274.126234) (xy 428.522888 -274.075452) (xy 428.204718 -274.075452) (xy 428.197002 -274.122928)
			(xy 428.181418 -274.169609) (xy 428.158547 -274.213186) (xy 428.128982 -274.25253) (xy 428.093489 -274.286622)
			(xy 428.052986 -274.314578) (xy 428.008524 -274.335676) (xy 427.961253 -274.349368) (xy 427.912398 -274.3553)
			(xy 427.863223 -274.353319) (xy 427.815004 -274.343475) (xy 427.768988 -274.326023) (xy 427.726367 -274.301416)
			(xy 427.688246 -274.270291) (xy 427.655611 -274.233454) (xy 427.629308 -274.191858) (xy 427.610017 -274.146582)
			(xy 427.59824 -274.098798) (xy 427.59428 -274.049744) (xy 427.276768 -274.049744) (xy 427.276264 -274.075452)
			(xy 427.268221 -274.126234) (xy 427.252333 -274.175133) (xy 427.22899 -274.220945) (xy 427.198769 -274.262541)
			(xy 427.162413 -274.298897) (xy 427.120817 -274.329118) (xy 427.075005 -274.352461) (xy 427.026106 -274.368349)
			(xy 426.975324 -274.376392) (xy 426.923908 -274.376392) (xy 426.873126 -274.368349) (xy 426.824227 -274.352461)
			(xy 426.778415 -274.329118) (xy 426.736819 -274.298897) (xy 426.700463 -274.262541) (xy 426.670242 -274.220945)
			(xy 426.646899 -274.175133) (xy 426.631011 -274.126234) (xy 426.622968 -274.075452) (xy 426.304798 -274.075452)
			(xy 426.297082 -274.122928) (xy 426.281498 -274.169609) (xy 426.258627 -274.213186) (xy 426.229062 -274.25253)
			(xy 426.193569 -274.286622) (xy 426.153066 -274.314578) (xy 426.108604 -274.335676) (xy 426.061333 -274.349368)
			(xy 426.012478 -274.3553) (xy 425.963303 -274.353319) (xy 425.915084 -274.343475) (xy 425.869068 -274.326023)
			(xy 425.826447 -274.301416) (xy 425.788326 -274.270291) (xy 425.755691 -274.233454) (xy 425.729388 -274.191858)
			(xy 425.710097 -274.146582) (xy 425.69832 -274.098798) (xy 425.69436 -274.049744) (xy 425.376848 -274.049744)
			(xy 425.376344 -274.075452) (xy 425.368301 -274.126234) (xy 425.352413 -274.175133) (xy 425.32907 -274.220945)
			(xy 425.298849 -274.262541) (xy 425.262493 -274.298897) (xy 425.220897 -274.329118) (xy 425.175085 -274.352461)
			(xy 425.126186 -274.368349) (xy 425.075404 -274.376392) (xy 425.023988 -274.376392) (xy 424.973206 -274.368349)
			(xy 424.924307 -274.352461) (xy 424.878495 -274.329118) (xy 424.836899 -274.298897) (xy 424.800543 -274.262541)
			(xy 424.770322 -274.220945) (xy 424.746979 -274.175133) (xy 424.731091 -274.126234) (xy 424.723048 -274.075452)
			(xy 424.404878 -274.075452) (xy 424.397162 -274.122928) (xy 424.381578 -274.169609) (xy 424.358707 -274.213186)
			(xy 424.329142 -274.25253) (xy 424.293649 -274.286622) (xy 424.253146 -274.314578) (xy 424.208684 -274.335676)
			(xy 424.161413 -274.349368) (xy 424.112558 -274.3553) (xy 424.063383 -274.353319) (xy 424.015164 -274.343475)
			(xy 423.969148 -274.326023) (xy 423.926527 -274.301416) (xy 423.888406 -274.270291) (xy 423.855771 -274.233454)
			(xy 423.829468 -274.191858) (xy 423.810177 -274.146582) (xy 423.7984 -274.098798) (xy 423.79444 -274.049744)
			(xy 423.476928 -274.049744) (xy 423.476424 -274.075452) (xy 423.468381 -274.126234) (xy 423.452493 -274.175133)
			(xy 423.42915 -274.220945) (xy 423.398929 -274.262541) (xy 423.362573 -274.298897) (xy 423.320977 -274.329118)
			(xy 423.275165 -274.352461) (xy 423.226266 -274.368349) (xy 423.175484 -274.376392) (xy 423.124068 -274.376392)
			(xy 423.073286 -274.368349) (xy 423.024387 -274.352461) (xy 422.978575 -274.329118) (xy 422.936979 -274.298897)
			(xy 422.900623 -274.262541) (xy 422.870402 -274.220945) (xy 422.847059 -274.175133) (xy 422.831171 -274.126234)
			(xy 422.823128 -274.075452) (xy 422.50445 -274.075452) (xy 422.496734 -274.122928) (xy 422.48115 -274.169609)
			(xy 422.458279 -274.213186) (xy 422.428714 -274.25253) (xy 422.393221 -274.286622) (xy 422.352718 -274.314578)
			(xy 422.308256 -274.335676) (xy 422.260985 -274.349368) (xy 422.21213 -274.3553) (xy 422.162955 -274.353319)
			(xy 422.114736 -274.343475) (xy 422.06872 -274.326023) (xy 422.026099 -274.301416) (xy 421.987978 -274.270291)
			(xy 421.955343 -274.233454) (xy 421.92904 -274.191858) (xy 421.909749 -274.146582) (xy 421.897972 -274.098798)
			(xy 421.894012 -274.049744) (xy 421.576754 -274.049744) (xy 421.57625 -274.075452) (xy 421.568207 -274.126234)
			(xy 421.552319 -274.175133) (xy 421.528976 -274.220945) (xy 421.498755 -274.262541) (xy 421.462399 -274.298897)
			(xy 421.420803 -274.329118) (xy 421.374991 -274.352461) (xy 421.326092 -274.368349) (xy 421.27531 -274.376392)
			(xy 421.223894 -274.376392) (xy 421.173112 -274.368349) (xy 421.124213 -274.352461) (xy 421.078401 -274.329118)
			(xy 421.036805 -274.298897) (xy 421.000449 -274.262541) (xy 420.970228 -274.220945) (xy 420.946885 -274.175133)
			(xy 420.930997 -274.126234) (xy 420.922954 -274.075452) (xy 420.60453 -274.075452) (xy 420.596814 -274.122928)
			(xy 420.58123 -274.169609) (xy 420.558359 -274.213186) (xy 420.528794 -274.25253) (xy 420.493301 -274.286622)
			(xy 420.452798 -274.314578) (xy 420.408336 -274.335676) (xy 420.361065 -274.349368) (xy 420.31221 -274.3553)
			(xy 420.263035 -274.353319) (xy 420.214816 -274.343475) (xy 420.1688 -274.326023) (xy 420.126179 -274.301416)
			(xy 420.088058 -274.270291) (xy 420.055423 -274.233454) (xy 420.02912 -274.191858) (xy 420.009829 -274.146582)
			(xy 419.998052 -274.098798) (xy 419.994092 -274.049744) (xy 419.676834 -274.049744) (xy 419.67633 -274.075452)
			(xy 419.668287 -274.126234) (xy 419.652399 -274.175133) (xy 419.629056 -274.220945) (xy 419.598835 -274.262541)
			(xy 419.562479 -274.298897) (xy 419.520883 -274.329118) (xy 419.475071 -274.352461) (xy 419.426172 -274.368349)
			(xy 419.37539 -274.376392) (xy 419.323974 -274.376392) (xy 419.273192 -274.368349) (xy 419.224293 -274.352461)
			(xy 419.178481 -274.329118) (xy 419.136885 -274.298897) (xy 419.100529 -274.262541) (xy 419.070308 -274.220945)
			(xy 419.046965 -274.175133) (xy 419.031077 -274.126234) (xy 419.023034 -274.075452) (xy 418.70461 -274.075452)
			(xy 418.696894 -274.122928) (xy 418.68131 -274.169609) (xy 418.658439 -274.213186) (xy 418.628874 -274.25253)
			(xy 418.593381 -274.286622) (xy 418.552878 -274.314578) (xy 418.508416 -274.335676) (xy 418.461145 -274.349368)
			(xy 418.41229 -274.3553) (xy 418.363115 -274.353319) (xy 418.314896 -274.343475) (xy 418.26888 -274.326023)
			(xy 418.226259 -274.301416) (xy 418.188138 -274.270291) (xy 418.155503 -274.233454) (xy 418.1292 -274.191858)
			(xy 418.109909 -274.146582) (xy 418.098132 -274.098798) (xy 418.094172 -274.049744) (xy 417.776914 -274.049744)
			(xy 417.77641 -274.075452) (xy 417.768367 -274.126234) (xy 417.752479 -274.175133) (xy 417.729136 -274.220945)
			(xy 417.698915 -274.262541) (xy 417.662559 -274.298897) (xy 417.620963 -274.329118) (xy 417.575151 -274.352461)
			(xy 417.526252 -274.368349) (xy 417.47547 -274.376392) (xy 417.424054 -274.376392) (xy 417.373272 -274.368349)
			(xy 417.324373 -274.352461) (xy 417.278561 -274.329118) (xy 417.236965 -274.298897) (xy 417.200609 -274.262541)
			(xy 417.170388 -274.220945) (xy 417.147045 -274.175133) (xy 417.131157 -274.126234) (xy 417.123114 -274.075452)
			(xy 416.804436 -274.075452) (xy 416.79672 -274.122928) (xy 416.781136 -274.169609) (xy 416.758265 -274.213186)
			(xy 416.7287 -274.25253) (xy 416.693207 -274.286622) (xy 416.652704 -274.314578) (xy 416.608242 -274.335676)
			(xy 416.560971 -274.349368) (xy 416.512116 -274.3553) (xy 416.462941 -274.353319) (xy 416.414722 -274.343475)
			(xy 416.368706 -274.326023) (xy 416.326085 -274.301416) (xy 416.287964 -274.270291) (xy 416.255329 -274.233454)
			(xy 416.229026 -274.191858) (xy 416.209735 -274.146582) (xy 416.197958 -274.098798) (xy 416.193998 -274.049744)
			(xy 415.87674 -274.049744) (xy 415.876236 -274.075452) (xy 415.868193 -274.126234) (xy 415.852305 -274.175133)
			(xy 415.828962 -274.220945) (xy 415.798741 -274.262541) (xy 415.762385 -274.298897) (xy 415.720789 -274.329118)
			(xy 415.674977 -274.352461) (xy 415.626078 -274.368349) (xy 415.575296 -274.376392) (xy 415.52388 -274.376392)
			(xy 415.473098 -274.368349) (xy 415.424199 -274.352461) (xy 415.378387 -274.329118) (xy 415.336791 -274.298897)
			(xy 415.300435 -274.262541) (xy 415.270214 -274.220945) (xy 415.246871 -274.175133) (xy 415.230983 -274.126234)
			(xy 415.22294 -274.075452) (xy 414.904516 -274.075452) (xy 414.8968 -274.122928) (xy 414.881216 -274.169609)
			(xy 414.858345 -274.213186) (xy 414.82878 -274.25253) (xy 414.793287 -274.286622) (xy 414.752784 -274.314578)
			(xy 414.708322 -274.335676) (xy 414.661051 -274.349368) (xy 414.612196 -274.3553) (xy 414.563021 -274.353319)
			(xy 414.514802 -274.343475) (xy 414.468786 -274.326023) (xy 414.426165 -274.301416) (xy 414.388044 -274.270291)
			(xy 414.355409 -274.233454) (xy 414.329106 -274.191858) (xy 414.309815 -274.146582) (xy 414.298038 -274.098798)
			(xy 414.294078 -274.049744) (xy 413.97682 -274.049744) (xy 413.976316 -274.075452) (xy 413.968273 -274.126234)
			(xy 413.952385 -274.175133) (xy 413.929042 -274.220945) (xy 413.898821 -274.262541) (xy 413.862465 -274.298897)
			(xy 413.820869 -274.329118) (xy 413.775057 -274.352461) (xy 413.726158 -274.368349) (xy 413.675376 -274.376392)
			(xy 413.62396 -274.376392) (xy 413.573178 -274.368349) (xy 413.524279 -274.352461) (xy 413.478467 -274.329118)
			(xy 413.436871 -274.298897) (xy 413.400515 -274.262541) (xy 413.370294 -274.220945) (xy 413.346951 -274.175133)
			(xy 413.331063 -274.126234) (xy 413.32302 -274.075452) (xy 413.004596 -274.075452) (xy 412.99688 -274.122928)
			(xy 412.981296 -274.169609) (xy 412.958425 -274.213186) (xy 412.92886 -274.25253) (xy 412.893367 -274.286622)
			(xy 412.852864 -274.314578) (xy 412.808402 -274.335676) (xy 412.761131 -274.349368) (xy 412.712276 -274.3553)
			(xy 412.663101 -274.353319) (xy 412.614882 -274.343475) (xy 412.568866 -274.326023) (xy 412.526245 -274.301416)
			(xy 412.488124 -274.270291) (xy 412.455489 -274.233454) (xy 412.429186 -274.191858) (xy 412.409895 -274.146582)
			(xy 412.398118 -274.098798) (xy 412.394158 -274.049744) (xy 412.0769 -274.049744) (xy 412.076396 -274.075452)
			(xy 412.068353 -274.126234) (xy 412.052465 -274.175133) (xy 412.029122 -274.220945) (xy 411.998901 -274.262541)
			(xy 411.962545 -274.298897) (xy 411.920949 -274.329118) (xy 411.875137 -274.352461) (xy 411.826238 -274.368349)
			(xy 411.775456 -274.376392) (xy 411.72404 -274.376392) (xy 411.673258 -274.368349) (xy 411.624359 -274.352461)
			(xy 411.578547 -274.329118) (xy 411.536951 -274.298897) (xy 411.500595 -274.262541) (xy 411.470374 -274.220945)
			(xy 411.447031 -274.175133) (xy 411.431143 -274.126234) (xy 411.4231 -274.075452) (xy 411.104422 -274.075452)
			(xy 411.096706 -274.122928) (xy 411.081122 -274.169609) (xy 411.058251 -274.213186) (xy 411.028686 -274.25253)
			(xy 410.993193 -274.286622) (xy 410.95269 -274.314578) (xy 410.908228 -274.335676) (xy 410.860957 -274.349368)
			(xy 410.812102 -274.3553) (xy 410.762927 -274.353319) (xy 410.714708 -274.343475) (xy 410.668692 -274.326023)
			(xy 410.626071 -274.301416) (xy 410.58795 -274.270291) (xy 410.555315 -274.233454) (xy 410.529012 -274.191858)
			(xy 410.509721 -274.146582) (xy 410.497944 -274.098798) (xy 410.493984 -274.049744) (xy 410.17623 -274.049744)
			(xy 410.17623 -274.075408) (xy 410.168186 -274.12619) (xy 410.152297 -274.175088) (xy 410.128954 -274.220899)
			(xy 410.098732 -274.262494) (xy 410.062374 -274.298849) (xy 410.020777 -274.329068) (xy 409.974964 -274.352407)
			(xy 409.926065 -274.368292) (xy 409.875282 -274.376332) (xy 409.849574 -274.376896) (xy 409.83701 -274.376731)
			(xy 409.811962 -274.374698) (xy 409.799536 -274.372832) (xy 409.798774 -274.372832) (xy 409.786956 -274.371726)
			(xy 409.764441 -274.379143) (xy 409.755594 -274.387056) (xy 409.71089 -274.431506) (xy 409.703016 -274.453096)
			(xy 409.704286 -274.46478) (xy 409.706064 -274.499578) (xy 409.706064 -274.595336) (xy 409.706532 -274.60599)
			(xy 409.715232 -274.62544) (xy 409.722828 -274.632928) (xy 409.778708 -274.683474) (xy 409.786939 -274.690108)
			(xy 409.807011 -274.696672) (xy 409.81757 -274.696174) (xy 409.817824 -274.696174) (xy 409.849828 -274.69465)
			(xy 409.875085 -274.695174) (xy 409.92491 -274.703492) (xy 409.972687 -274.719898) (xy 410.017112 -274.743943)
			(xy 410.056973 -274.774972) (xy 410.091184 -274.812138) (xy 410.118811 -274.854428) (xy 410.139102 -274.900689)
			(xy 410.151502 -274.949658) (xy 410.155673 -275) (xy 410.153546 -275.025666) (xy 410.472886 -275.025666)
			(xy 410.472886 -274.97425) (xy 410.480929 -274.923468) (xy 410.496817 -274.874569) (xy 410.52016 -274.828757)
			(xy 410.550381 -274.787161) (xy 410.586737 -274.750805) (xy 410.628333 -274.720584) (xy 410.674145 -274.697241)
			(xy 410.723044 -274.681353) (xy 410.773826 -274.67331) (xy 410.825242 -274.67331) (xy 410.876024 -274.681353)
			(xy 410.924923 -274.697241) (xy 410.970735 -274.720584) (xy 411.012331 -274.750805) (xy 411.048687 -274.787161)
			(xy 411.078908 -274.828757) (xy 411.102251 -274.874569) (xy 411.118139 -274.923468) (xy 411.126182 -274.97425)
			(xy 411.126686 -274.999958) (xy 411.444198 -274.999958) (xy 411.448158 -274.950904) (xy 411.459935 -274.90312)
			(xy 411.479226 -274.857844) (xy 411.505529 -274.816248) (xy 411.538164 -274.779411) (xy 411.576285 -274.748286)
			(xy 411.618906 -274.723679) (xy 411.664922 -274.706227) (xy 411.713141 -274.696383) (xy 411.762316 -274.694402)
			(xy 411.811171 -274.700334) (xy 411.858442 -274.714026) (xy 411.902904 -274.735124) (xy 411.943407 -274.76308)
			(xy 411.9789 -274.797172) (xy 412.008465 -274.836516) (xy 412.031336 -274.880093) (xy 412.04692 -274.926774)
			(xy 412.054815 -274.975351) (xy 412.05531 -274.999958) (xy 412.054815 -275.024565) (xy 412.054677 -275.025412)
			(xy 412.37306 -275.025412) (xy 412.37306 -274.973996) (xy 412.381103 -274.923214) (xy 412.396991 -274.874315)
			(xy 412.420334 -274.828503) (xy 412.450555 -274.786907) (xy 412.486911 -274.750551) (xy 412.528507 -274.72033)
			(xy 412.574319 -274.696987) (xy 412.623218 -274.681099) (xy 412.674 -274.673056) (xy 412.725416 -274.673056)
			(xy 412.776198 -274.681099) (xy 412.825097 -274.696987) (xy 412.870909 -274.72033) (xy 412.912505 -274.750551)
			(xy 412.948861 -274.786907) (xy 412.979082 -274.828503) (xy 413.002425 -274.874315) (xy 413.018313 -274.923214)
			(xy 413.026356 -274.973996) (xy 413.02686 -274.999704) (xy 413.026855 -274.999958) (xy 413.344118 -274.999958)
			(xy 413.348078 -274.950904) (xy 413.359855 -274.90312) (xy 413.379146 -274.857844) (xy 413.405449 -274.816248)
			(xy 413.438084 -274.779411) (xy 413.476205 -274.748286) (xy 413.518826 -274.723679) (xy 413.564842 -274.706227)
			(xy 413.613061 -274.696383) (xy 413.662236 -274.694402) (xy 413.711091 -274.700334) (xy 413.758362 -274.714026)
			(xy 413.802824 -274.735124) (xy 413.843327 -274.76308) (xy 413.87882 -274.797172) (xy 413.908385 -274.836516)
			(xy 413.931256 -274.880093) (xy 413.94684 -274.926774) (xy 413.954735 -274.975351) (xy 413.95523 -274.999958)
			(xy 413.954735 -275.024565) (xy 413.954556 -275.025666) (xy 414.27298 -275.025666) (xy 414.27298 -274.97425)
			(xy 414.281023 -274.923468) (xy 414.296911 -274.874569) (xy 414.320254 -274.828757) (xy 414.350475 -274.787161)
			(xy 414.386831 -274.750805) (xy 414.428427 -274.720584) (xy 414.474239 -274.697241) (xy 414.523138 -274.681353)
			(xy 414.57392 -274.67331) (xy 414.625336 -274.67331) (xy 414.676118 -274.681353) (xy 414.725017 -274.697241)
			(xy 414.770829 -274.720584) (xy 414.812425 -274.750805) (xy 414.848781 -274.787161) (xy 414.879002 -274.828757)
			(xy 414.902345 -274.874569) (xy 414.918233 -274.923468) (xy 414.926276 -274.97425) (xy 414.92678 -274.999958)
			(xy 415.244038 -274.999958) (xy 415.247998 -274.950904) (xy 415.259775 -274.90312) (xy 415.279066 -274.857844)
			(xy 415.305369 -274.816248) (xy 415.338004 -274.779411) (xy 415.376125 -274.748286) (xy 415.418746 -274.723679)
			(xy 415.464762 -274.706227) (xy 415.512981 -274.696383) (xy 415.562156 -274.694402) (xy 415.611011 -274.700334)
			(xy 415.658282 -274.714026) (xy 415.702744 -274.735124) (xy 415.743247 -274.76308) (xy 415.77874 -274.797172)
			(xy 415.808305 -274.836516) (xy 415.831176 -274.880093) (xy 415.84676 -274.926774) (xy 415.854655 -274.975351)
			(xy 415.85515 -274.999958) (xy 415.854655 -275.024565) (xy 415.854517 -275.025412) (xy 416.1729 -275.025412)
			(xy 416.1729 -274.973996) (xy 416.180943 -274.923214) (xy 416.196831 -274.874315) (xy 416.220174 -274.828503)
			(xy 416.250395 -274.786907) (xy 416.286751 -274.750551) (xy 416.328347 -274.72033) (xy 416.374159 -274.696987)
			(xy 416.423058 -274.681099) (xy 416.47384 -274.673056) (xy 416.525256 -274.673056) (xy 416.576038 -274.681099)
			(xy 416.624937 -274.696987) (xy 416.670749 -274.72033) (xy 416.712345 -274.750551) (xy 416.748701 -274.786907)
			(xy 416.778922 -274.828503) (xy 416.802265 -274.874315) (xy 416.818153 -274.923214) (xy 416.826196 -274.973996)
			(xy 416.8267 -274.999704) (xy 416.826695 -274.999958) (xy 417.144212 -274.999958) (xy 417.148172 -274.950904)
			(xy 417.159949 -274.90312) (xy 417.17924 -274.857844) (xy 417.205543 -274.816248) (xy 417.238178 -274.779411)
			(xy 417.276299 -274.748286) (xy 417.31892 -274.723679) (xy 417.364936 -274.706227) (xy 417.413155 -274.696383)
			(xy 417.46233 -274.694402) (xy 417.511185 -274.700334) (xy 417.558456 -274.714026) (xy 417.602918 -274.735124)
			(xy 417.643421 -274.76308) (xy 417.678914 -274.797172) (xy 417.708479 -274.836516) (xy 417.73135 -274.880093)
			(xy 417.746934 -274.926774) (xy 417.754829 -274.975351) (xy 417.755324 -274.999958) (xy 417.754829 -275.024565)
			(xy 417.75465 -275.025666) (xy 418.07282 -275.025666) (xy 418.07282 -274.97425) (xy 418.080863 -274.923468)
			(xy 418.096751 -274.874569) (xy 418.120094 -274.828757) (xy 418.150315 -274.787161) (xy 418.186671 -274.750805)
			(xy 418.228267 -274.720584) (xy 418.274079 -274.697241) (xy 418.322978 -274.681353) (xy 418.37376 -274.67331)
			(xy 418.425176 -274.67331) (xy 418.475958 -274.681353) (xy 418.524857 -274.697241) (xy 418.570669 -274.720584)
			(xy 418.612265 -274.750805) (xy 418.648621 -274.787161) (xy 418.678842 -274.828757) (xy 418.702185 -274.874569)
			(xy 418.718073 -274.923468) (xy 418.726116 -274.97425) (xy 418.72662 -274.999958) (xy 419.044132 -274.999958)
			(xy 419.048092 -274.950904) (xy 419.059869 -274.90312) (xy 419.07916 -274.857844) (xy 419.105463 -274.816248)
			(xy 419.138098 -274.779411) (xy 419.176219 -274.748286) (xy 419.21884 -274.723679) (xy 419.264856 -274.706227)
			(xy 419.313075 -274.696383) (xy 419.36225 -274.694402) (xy 419.411105 -274.700334) (xy 419.458376 -274.714026)
			(xy 419.502838 -274.735124) (xy 419.543341 -274.76308) (xy 419.578834 -274.797172) (xy 419.608399 -274.836516)
			(xy 419.63127 -274.880093) (xy 419.646854 -274.926774) (xy 419.654749 -274.975351) (xy 419.655244 -274.999958)
			(xy 419.654749 -275.024565) (xy 419.654611 -275.025412) (xy 419.972994 -275.025412) (xy 419.972994 -274.973996)
			(xy 419.981037 -274.923214) (xy 419.996925 -274.874315) (xy 420.020268 -274.828503) (xy 420.050489 -274.786907)
			(xy 420.086845 -274.750551) (xy 420.128441 -274.72033) (xy 420.174253 -274.696987) (xy 420.223152 -274.681099)
			(xy 420.273934 -274.673056) (xy 420.32535 -274.673056) (xy 420.376132 -274.681099) (xy 420.425031 -274.696987)
			(xy 420.470843 -274.72033) (xy 420.512439 -274.750551) (xy 420.548795 -274.786907) (xy 420.579016 -274.828503)
			(xy 420.602359 -274.874315) (xy 420.618247 -274.923214) (xy 420.62629 -274.973996) (xy 420.626794 -274.999704)
			(xy 420.626789 -274.999958) (xy 420.944052 -274.999958) (xy 420.948012 -274.950904) (xy 420.959789 -274.90312)
			(xy 420.97908 -274.857844) (xy 421.005383 -274.816248) (xy 421.038018 -274.779411) (xy 421.076139 -274.748286)
			(xy 421.11876 -274.723679) (xy 421.164776 -274.706227) (xy 421.212995 -274.696383) (xy 421.26217 -274.694402)
			(xy 421.311025 -274.700334) (xy 421.358296 -274.714026) (xy 421.402758 -274.735124) (xy 421.443261 -274.76308)
			(xy 421.478754 -274.797172) (xy 421.508319 -274.836516) (xy 421.53119 -274.880093) (xy 421.546774 -274.926774)
			(xy 421.554669 -274.975351) (xy 421.555164 -274.999958) (xy 421.554669 -275.024565) (xy 421.55449 -275.025666)
			(xy 421.872914 -275.025666) (xy 421.872914 -274.97425) (xy 421.880957 -274.923468) (xy 421.896845 -274.874569)
			(xy 421.920188 -274.828757) (xy 421.950409 -274.787161) (xy 421.986765 -274.750805) (xy 422.028361 -274.720584)
			(xy 422.074173 -274.697241) (xy 422.123072 -274.681353) (xy 422.173854 -274.67331) (xy 422.22527 -274.67331)
			(xy 422.276052 -274.681353) (xy 422.324951 -274.697241) (xy 422.370763 -274.720584) (xy 422.412359 -274.750805)
			(xy 422.448715 -274.787161) (xy 422.478936 -274.828757) (xy 422.502279 -274.874569) (xy 422.518167 -274.923468)
			(xy 422.52621 -274.97425) (xy 422.526714 -274.999958) (xy 422.843972 -274.999958) (xy 422.847932 -274.950904)
			(xy 422.859709 -274.90312) (xy 422.879 -274.857844) (xy 422.905303 -274.816248) (xy 422.937938 -274.779411)
			(xy 422.976059 -274.748286) (xy 423.01868 -274.723679) (xy 423.064696 -274.706227) (xy 423.112915 -274.696383)
			(xy 423.16209 -274.694402) (xy 423.210945 -274.700334) (xy 423.258216 -274.714026) (xy 423.302678 -274.735124)
			(xy 423.343181 -274.76308) (xy 423.378674 -274.797172) (xy 423.408239 -274.836516) (xy 423.43111 -274.880093)
			(xy 423.446694 -274.926774) (xy 423.454589 -274.975351) (xy 423.455084 -274.999958) (xy 423.454589 -275.024565)
			(xy 423.454451 -275.025412) (xy 423.773088 -275.025412) (xy 423.773088 -274.973996) (xy 423.781131 -274.923214)
			(xy 423.797019 -274.874315) (xy 423.820362 -274.828503) (xy 423.850583 -274.786907) (xy 423.886939 -274.750551)
			(xy 423.928535 -274.72033) (xy 423.974347 -274.696987) (xy 424.023246 -274.681099) (xy 424.074028 -274.673056)
			(xy 424.125444 -274.673056) (xy 424.176226 -274.681099) (xy 424.225125 -274.696987) (xy 424.270937 -274.72033)
			(xy 424.312533 -274.750551) (xy 424.348889 -274.786907) (xy 424.37911 -274.828503) (xy 424.402453 -274.874315)
			(xy 424.418341 -274.923214) (xy 424.426384 -274.973996) (xy 424.426888 -274.999704) (xy 424.426883 -274.999958)
			(xy 424.743892 -274.999958) (xy 424.747852 -274.950904) (xy 424.759629 -274.90312) (xy 424.77892 -274.857844)
			(xy 424.805223 -274.816248) (xy 424.837858 -274.779411) (xy 424.875979 -274.748286) (xy 424.9186 -274.723679)
			(xy 424.964616 -274.706227) (xy 425.012835 -274.696383) (xy 425.06201 -274.694402) (xy 425.110865 -274.700334)
			(xy 425.158136 -274.714026) (xy 425.202598 -274.735124) (xy 425.243101 -274.76308) (xy 425.278594 -274.797172)
			(xy 425.308159 -274.836516) (xy 425.33103 -274.880093) (xy 425.346614 -274.926774) (xy 425.354509 -274.975351)
			(xy 425.355004 -274.999958) (xy 425.354509 -275.024565) (xy 425.35433 -275.025666) (xy 425.673008 -275.025666)
			(xy 425.673008 -274.97425) (xy 425.681051 -274.923468) (xy 425.696939 -274.874569) (xy 425.720282 -274.828757)
			(xy 425.750503 -274.787161) (xy 425.786859 -274.750805) (xy 425.828455 -274.720584) (xy 425.874267 -274.697241)
			(xy 425.923166 -274.681353) (xy 425.973948 -274.67331) (xy 426.025364 -274.67331) (xy 426.076146 -274.681353)
			(xy 426.125045 -274.697241) (xy 426.170857 -274.720584) (xy 426.212453 -274.750805) (xy 426.248809 -274.787161)
			(xy 426.27903 -274.828757) (xy 426.302373 -274.874569) (xy 426.318261 -274.923468) (xy 426.326304 -274.97425)
			(xy 426.326808 -274.999958) (xy 426.643812 -274.999958) (xy 426.647772 -274.950904) (xy 426.659549 -274.90312)
			(xy 426.67884 -274.857844) (xy 426.705143 -274.816248) (xy 426.737778 -274.779411) (xy 426.775899 -274.748286)
			(xy 426.81852 -274.723679) (xy 426.864536 -274.706227) (xy 426.912755 -274.696383) (xy 426.96193 -274.694402)
			(xy 427.010785 -274.700334) (xy 427.058056 -274.714026) (xy 427.102518 -274.735124) (xy 427.143021 -274.76308)
			(xy 427.178514 -274.797172) (xy 427.208079 -274.836516) (xy 427.23095 -274.880093) (xy 427.246534 -274.926774)
			(xy 427.254429 -274.975351) (xy 427.254924 -274.999958) (xy 427.254429 -275.024565) (xy 427.25425 -275.025666)
			(xy 427.572928 -275.025666) (xy 427.572928 -274.97425) (xy 427.580971 -274.923468) (xy 427.596859 -274.874569)
			(xy 427.620202 -274.828757) (xy 427.650423 -274.787161) (xy 427.686779 -274.750805) (xy 427.728375 -274.720584)
			(xy 427.774187 -274.697241) (xy 427.823086 -274.681353) (xy 427.873868 -274.67331) (xy 427.925284 -274.67331)
			(xy 427.976066 -274.681353) (xy 428.024965 -274.697241) (xy 428.070777 -274.720584) (xy 428.112373 -274.750805)
			(xy 428.148729 -274.787161) (xy 428.17895 -274.828757) (xy 428.202293 -274.874569) (xy 428.218181 -274.923468)
			(xy 428.226224 -274.97425) (xy 428.226728 -274.999958) (xy 428.543986 -274.999958) (xy 428.547946 -274.950904)
			(xy 428.559723 -274.90312) (xy 428.579014 -274.857844) (xy 428.605317 -274.816248) (xy 428.637952 -274.779411)
			(xy 428.676073 -274.748286) (xy 428.718694 -274.723679) (xy 428.76471 -274.706227) (xy 428.812929 -274.696383)
			(xy 428.862104 -274.694402) (xy 428.910959 -274.700334) (xy 428.95823 -274.714026) (xy 429.002692 -274.735124)
			(xy 429.043195 -274.76308) (xy 429.078688 -274.797172) (xy 429.108253 -274.836516) (xy 429.131124 -274.880093)
			(xy 429.146708 -274.926774) (xy 429.154603 -274.975351) (xy 429.155098 -274.999958) (xy 429.154603 -275.024565)
			(xy 429.154465 -275.025412) (xy 429.473356 -275.025412) (xy 429.473356 -274.973996) (xy 429.481399 -274.923214)
			(xy 429.497287 -274.874315) (xy 429.52063 -274.828503) (xy 429.550851 -274.786907) (xy 429.587207 -274.750551)
			(xy 429.628803 -274.72033) (xy 429.674615 -274.696987) (xy 429.723514 -274.681099) (xy 429.774296 -274.673056)
			(xy 429.825712 -274.673056) (xy 429.876494 -274.681099) (xy 429.925393 -274.696987) (xy 429.971205 -274.72033)
			(xy 430.012801 -274.750551) (xy 430.049157 -274.786907) (xy 430.079378 -274.828503) (xy 430.102721 -274.874315)
			(xy 430.118609 -274.923214) (xy 430.126652 -274.973996) (xy 430.127156 -274.999704) (xy 430.126652 -275.025412)
			(xy 430.423316 -275.025412) (xy 430.423316 -274.973996) (xy 430.431359 -274.923214) (xy 430.447247 -274.874315)
			(xy 430.47059 -274.828503) (xy 430.500811 -274.786907) (xy 430.537167 -274.750551) (xy 430.578763 -274.72033)
			(xy 430.624575 -274.696987) (xy 430.673474 -274.681099) (xy 430.724256 -274.673056) (xy 430.775672 -274.673056)
			(xy 430.826454 -274.681099) (xy 430.875353 -274.696987) (xy 430.921165 -274.72033) (xy 430.962761 -274.750551)
			(xy 430.999117 -274.786907) (xy 431.029338 -274.828503) (xy 431.052681 -274.874315) (xy 431.068569 -274.923214)
			(xy 431.076612 -274.973996) (xy 431.077116 -274.999704) (xy 431.077111 -274.999958) (xy 431.394374 -274.999958)
			(xy 431.398334 -274.950904) (xy 431.410111 -274.90312) (xy 431.429402 -274.857844) (xy 431.455705 -274.816248)
			(xy 431.48834 -274.779411) (xy 431.526461 -274.748286) (xy 431.569082 -274.723679) (xy 431.615098 -274.706227)
			(xy 431.663317 -274.696383) (xy 431.712492 -274.694402) (xy 431.761347 -274.700334) (xy 431.808618 -274.714026)
			(xy 431.85308 -274.735124) (xy 431.893583 -274.76308) (xy 431.929076 -274.797172) (xy 431.958641 -274.836516)
			(xy 431.981512 -274.880093) (xy 431.997096 -274.926774) (xy 432.004991 -274.975351) (xy 432.005486 -274.999958)
			(xy 432.004991 -275.024565) (xy 431.997096 -275.073142) (xy 431.981512 -275.119823) (xy 431.958641 -275.1634)
			(xy 431.929076 -275.202744) (xy 431.893583 -275.236836) (xy 431.85308 -275.264792) (xy 431.808618 -275.28589)
			(xy 431.761347 -275.299582) (xy 431.712492 -275.305514) (xy 431.663317 -275.303533) (xy 431.615098 -275.293689)
			(xy 431.569082 -275.276237) (xy 431.526461 -275.25163) (xy 431.48834 -275.220505) (xy 431.455705 -275.183668)
			(xy 431.429402 -275.142072) (xy 431.410111 -275.096796) (xy 431.398334 -275.049012) (xy 431.394374 -274.999958)
			(xy 431.077111 -274.999958) (xy 431.076612 -275.025412) (xy 431.068569 -275.076194) (xy 431.052681 -275.125093)
			(xy 431.029338 -275.170905) (xy 430.999117 -275.212501) (xy 430.962761 -275.248857) (xy 430.921165 -275.279078)
			(xy 430.875353 -275.302421) (xy 430.826454 -275.318309) (xy 430.775672 -275.326352) (xy 430.724256 -275.326352)
			(xy 430.673474 -275.318309) (xy 430.624575 -275.302421) (xy 430.578763 -275.279078) (xy 430.537167 -275.248857)
			(xy 430.500811 -275.212501) (xy 430.47059 -275.170905) (xy 430.447247 -275.125093) (xy 430.431359 -275.076194)
			(xy 430.423316 -275.025412) (xy 430.126652 -275.025412) (xy 430.118609 -275.076194) (xy 430.102721 -275.125093)
			(xy 430.079378 -275.170905) (xy 430.049157 -275.212501) (xy 430.012801 -275.248857) (xy 429.971205 -275.279078)
			(xy 429.925393 -275.302421) (xy 429.876494 -275.318309) (xy 429.825712 -275.326352) (xy 429.774296 -275.326352)
			(xy 429.723514 -275.318309) (xy 429.674615 -275.302421) (xy 429.628803 -275.279078) (xy 429.587207 -275.248857)
			(xy 429.550851 -275.212501) (xy 429.52063 -275.170905) (xy 429.497287 -275.125093) (xy 429.481399 -275.076194)
			(xy 429.473356 -275.025412) (xy 429.154465 -275.025412) (xy 429.146708 -275.073142) (xy 429.131124 -275.119823)
			(xy 429.108253 -275.1634) (xy 429.078688 -275.202744) (xy 429.043195 -275.236836) (xy 429.002692 -275.264792)
			(xy 428.95823 -275.28589) (xy 428.910959 -275.299582) (xy 428.862104 -275.305514) (xy 428.812929 -275.303533)
			(xy 428.76471 -275.293689) (xy 428.718694 -275.276237) (xy 428.676073 -275.25163) (xy 428.637952 -275.220505)
			(xy 428.605317 -275.183668) (xy 428.579014 -275.142072) (xy 428.559723 -275.096796) (xy 428.547946 -275.049012)
			(xy 428.543986 -274.999958) (xy 428.226728 -274.999958) (xy 428.226224 -275.025666) (xy 428.218181 -275.076448)
			(xy 428.202293 -275.125347) (xy 428.17895 -275.171159) (xy 428.148729 -275.212755) (xy 428.112373 -275.249111)
			(xy 428.070777 -275.279332) (xy 428.024965 -275.302675) (xy 427.976066 -275.318563) (xy 427.925284 -275.326606)
			(xy 427.873868 -275.326606) (xy 427.823086 -275.318563) (xy 427.774187 -275.302675) (xy 427.728375 -275.279332)
			(xy 427.686779 -275.249111) (xy 427.650423 -275.212755) (xy 427.620202 -275.171159) (xy 427.596859 -275.125347)
			(xy 427.580971 -275.076448) (xy 427.572928 -275.025666) (xy 427.25425 -275.025666) (xy 427.246534 -275.073142)
			(xy 427.23095 -275.119823) (xy 427.208079 -275.1634) (xy 427.178514 -275.202744) (xy 427.143021 -275.236836)
			(xy 427.102518 -275.264792) (xy 427.058056 -275.28589) (xy 427.010785 -275.299582) (xy 426.96193 -275.305514)
			(xy 426.912755 -275.303533) (xy 426.864536 -275.293689) (xy 426.81852 -275.276237) (xy 426.775899 -275.25163)
			(xy 426.737778 -275.220505) (xy 426.705143 -275.183668) (xy 426.67884 -275.142072) (xy 426.659549 -275.096796)
			(xy 426.647772 -275.049012) (xy 426.643812 -274.999958) (xy 426.326808 -274.999958) (xy 426.326304 -275.025666)
			(xy 426.318261 -275.076448) (xy 426.302373 -275.125347) (xy 426.27903 -275.171159) (xy 426.248809 -275.212755)
			(xy 426.212453 -275.249111) (xy 426.170857 -275.279332) (xy 426.125045 -275.302675) (xy 426.076146 -275.318563)
			(xy 426.025364 -275.326606) (xy 425.973948 -275.326606) (xy 425.923166 -275.318563) (xy 425.874267 -275.302675)
			(xy 425.828455 -275.279332) (xy 425.786859 -275.249111) (xy 425.750503 -275.212755) (xy 425.720282 -275.171159)
			(xy 425.696939 -275.125347) (xy 425.681051 -275.076448) (xy 425.673008 -275.025666) (xy 425.35433 -275.025666)
			(xy 425.346614 -275.073142) (xy 425.33103 -275.119823) (xy 425.308159 -275.1634) (xy 425.278594 -275.202744)
			(xy 425.243101 -275.236836) (xy 425.202598 -275.264792) (xy 425.158136 -275.28589) (xy 425.110865 -275.299582)
			(xy 425.06201 -275.305514) (xy 425.012835 -275.303533) (xy 424.964616 -275.293689) (xy 424.9186 -275.276237)
			(xy 424.875979 -275.25163) (xy 424.837858 -275.220505) (xy 424.805223 -275.183668) (xy 424.77892 -275.142072)
			(xy 424.759629 -275.096796) (xy 424.747852 -275.049012) (xy 424.743892 -274.999958) (xy 424.426883 -274.999958)
			(xy 424.426384 -275.025412) (xy 424.418341 -275.076194) (xy 424.402453 -275.125093) (xy 424.37911 -275.170905)
			(xy 424.348889 -275.212501) (xy 424.312533 -275.248857) (xy 424.270937 -275.279078) (xy 424.225125 -275.302421)
			(xy 424.176226 -275.318309) (xy 424.125444 -275.326352) (xy 424.074028 -275.326352) (xy 424.023246 -275.318309)
			(xy 423.974347 -275.302421) (xy 423.928535 -275.279078) (xy 423.886939 -275.248857) (xy 423.850583 -275.212501)
			(xy 423.820362 -275.170905) (xy 423.797019 -275.125093) (xy 423.781131 -275.076194) (xy 423.773088 -275.025412)
			(xy 423.454451 -275.025412) (xy 423.446694 -275.073142) (xy 423.43111 -275.119823) (xy 423.408239 -275.1634)
			(xy 423.378674 -275.202744) (xy 423.343181 -275.236836) (xy 423.302678 -275.264792) (xy 423.258216 -275.28589)
			(xy 423.210945 -275.299582) (xy 423.16209 -275.305514) (xy 423.112915 -275.303533) (xy 423.064696 -275.293689)
			(xy 423.01868 -275.276237) (xy 422.976059 -275.25163) (xy 422.937938 -275.220505) (xy 422.905303 -275.183668)
			(xy 422.879 -275.142072) (xy 422.859709 -275.096796) (xy 422.847932 -275.049012) (xy 422.843972 -274.999958)
			(xy 422.526714 -274.999958) (xy 422.52621 -275.025666) (xy 422.518167 -275.076448) (xy 422.502279 -275.125347)
			(xy 422.478936 -275.171159) (xy 422.448715 -275.212755) (xy 422.412359 -275.249111) (xy 422.370763 -275.279332)
			(xy 422.324951 -275.302675) (xy 422.276052 -275.318563) (xy 422.22527 -275.326606) (xy 422.173854 -275.326606)
			(xy 422.123072 -275.318563) (xy 422.074173 -275.302675) (xy 422.028361 -275.279332) (xy 421.986765 -275.249111)
			(xy 421.950409 -275.212755) (xy 421.920188 -275.171159) (xy 421.896845 -275.125347) (xy 421.880957 -275.076448)
			(xy 421.872914 -275.025666) (xy 421.55449 -275.025666) (xy 421.546774 -275.073142) (xy 421.53119 -275.119823)
			(xy 421.508319 -275.1634) (xy 421.478754 -275.202744) (xy 421.443261 -275.236836) (xy 421.402758 -275.264792)
			(xy 421.358296 -275.28589) (xy 421.311025 -275.299582) (xy 421.26217 -275.305514) (xy 421.212995 -275.303533)
			(xy 421.164776 -275.293689) (xy 421.11876 -275.276237) (xy 421.076139 -275.25163) (xy 421.038018 -275.220505)
			(xy 421.005383 -275.183668) (xy 420.97908 -275.142072) (xy 420.959789 -275.096796) (xy 420.948012 -275.049012)
			(xy 420.944052 -274.999958) (xy 420.626789 -274.999958) (xy 420.62629 -275.025412) (xy 420.618247 -275.076194)
			(xy 420.602359 -275.125093) (xy 420.579016 -275.170905) (xy 420.548795 -275.212501) (xy 420.512439 -275.248857)
			(xy 420.470843 -275.279078) (xy 420.425031 -275.302421) (xy 420.376132 -275.318309) (xy 420.32535 -275.326352)
			(xy 420.273934 -275.326352) (xy 420.223152 -275.318309) (xy 420.174253 -275.302421) (xy 420.128441 -275.279078)
			(xy 420.086845 -275.248857) (xy 420.050489 -275.212501) (xy 420.020268 -275.170905) (xy 419.996925 -275.125093)
			(xy 419.981037 -275.076194) (xy 419.972994 -275.025412) (xy 419.654611 -275.025412) (xy 419.646854 -275.073142)
			(xy 419.63127 -275.119823) (xy 419.608399 -275.1634) (xy 419.578834 -275.202744) (xy 419.543341 -275.236836)
			(xy 419.502838 -275.264792) (xy 419.458376 -275.28589) (xy 419.411105 -275.299582) (xy 419.36225 -275.305514)
			(xy 419.313075 -275.303533) (xy 419.264856 -275.293689) (xy 419.21884 -275.276237) (xy 419.176219 -275.25163)
			(xy 419.138098 -275.220505) (xy 419.105463 -275.183668) (xy 419.07916 -275.142072) (xy 419.059869 -275.096796)
			(xy 419.048092 -275.049012) (xy 419.044132 -274.999958) (xy 418.72662 -274.999958) (xy 418.726116 -275.025666)
			(xy 418.718073 -275.076448) (xy 418.702185 -275.125347) (xy 418.678842 -275.171159) (xy 418.648621 -275.212755)
			(xy 418.612265 -275.249111) (xy 418.570669 -275.279332) (xy 418.524857 -275.302675) (xy 418.475958 -275.318563)
			(xy 418.425176 -275.326606) (xy 418.37376 -275.326606) (xy 418.322978 -275.318563) (xy 418.274079 -275.302675)
			(xy 418.228267 -275.279332) (xy 418.186671 -275.249111) (xy 418.150315 -275.212755) (xy 418.120094 -275.171159)
			(xy 418.096751 -275.125347) (xy 418.080863 -275.076448) (xy 418.07282 -275.025666) (xy 417.75465 -275.025666)
			(xy 417.746934 -275.073142) (xy 417.73135 -275.119823) (xy 417.708479 -275.1634) (xy 417.678914 -275.202744)
			(xy 417.643421 -275.236836) (xy 417.602918 -275.264792) (xy 417.558456 -275.28589) (xy 417.511185 -275.299582)
			(xy 417.46233 -275.305514) (xy 417.413155 -275.303533) (xy 417.364936 -275.293689) (xy 417.31892 -275.276237)
			(xy 417.276299 -275.25163) (xy 417.238178 -275.220505) (xy 417.205543 -275.183668) (xy 417.17924 -275.142072)
			(xy 417.159949 -275.096796) (xy 417.148172 -275.049012) (xy 417.144212 -274.999958) (xy 416.826695 -274.999958)
			(xy 416.826196 -275.025412) (xy 416.818153 -275.076194) (xy 416.802265 -275.125093) (xy 416.778922 -275.170905)
			(xy 416.748701 -275.212501) (xy 416.712345 -275.248857) (xy 416.670749 -275.279078) (xy 416.624937 -275.302421)
			(xy 416.576038 -275.318309) (xy 416.525256 -275.326352) (xy 416.47384 -275.326352) (xy 416.423058 -275.318309)
			(xy 416.374159 -275.302421) (xy 416.328347 -275.279078) (xy 416.286751 -275.248857) (xy 416.250395 -275.212501)
			(xy 416.220174 -275.170905) (xy 416.196831 -275.125093) (xy 416.180943 -275.076194) (xy 416.1729 -275.025412)
			(xy 415.854517 -275.025412) (xy 415.84676 -275.073142) (xy 415.831176 -275.119823) (xy 415.808305 -275.1634)
			(xy 415.77874 -275.202744) (xy 415.743247 -275.236836) (xy 415.702744 -275.264792) (xy 415.658282 -275.28589)
			(xy 415.611011 -275.299582) (xy 415.562156 -275.305514) (xy 415.512981 -275.303533) (xy 415.464762 -275.293689)
			(xy 415.418746 -275.276237) (xy 415.376125 -275.25163) (xy 415.338004 -275.220505) (xy 415.305369 -275.183668)
			(xy 415.279066 -275.142072) (xy 415.259775 -275.096796) (xy 415.247998 -275.049012) (xy 415.244038 -274.999958)
			(xy 414.92678 -274.999958) (xy 414.926276 -275.025666) (xy 414.918233 -275.076448) (xy 414.902345 -275.125347)
			(xy 414.879002 -275.171159) (xy 414.848781 -275.212755) (xy 414.812425 -275.249111) (xy 414.770829 -275.279332)
			(xy 414.725017 -275.302675) (xy 414.676118 -275.318563) (xy 414.625336 -275.326606) (xy 414.57392 -275.326606)
			(xy 414.523138 -275.318563) (xy 414.474239 -275.302675) (xy 414.428427 -275.279332) (xy 414.386831 -275.249111)
			(xy 414.350475 -275.212755) (xy 414.320254 -275.171159) (xy 414.296911 -275.125347) (xy 414.281023 -275.076448)
			(xy 414.27298 -275.025666) (xy 413.954556 -275.025666) (xy 413.94684 -275.073142) (xy 413.931256 -275.119823)
			(xy 413.908385 -275.1634) (xy 413.87882 -275.202744) (xy 413.843327 -275.236836) (xy 413.802824 -275.264792)
			(xy 413.758362 -275.28589) (xy 413.711091 -275.299582) (xy 413.662236 -275.305514) (xy 413.613061 -275.303533)
			(xy 413.564842 -275.293689) (xy 413.518826 -275.276237) (xy 413.476205 -275.25163) (xy 413.438084 -275.220505)
			(xy 413.405449 -275.183668) (xy 413.379146 -275.142072) (xy 413.359855 -275.096796) (xy 413.348078 -275.049012)
			(xy 413.344118 -274.999958) (xy 413.026855 -274.999958) (xy 413.026356 -275.025412) (xy 413.018313 -275.076194)
			(xy 413.002425 -275.125093) (xy 412.979082 -275.170905) (xy 412.948861 -275.212501) (xy 412.912505 -275.248857)
			(xy 412.870909 -275.279078) (xy 412.825097 -275.302421) (xy 412.776198 -275.318309) (xy 412.725416 -275.326352)
			(xy 412.674 -275.326352) (xy 412.623218 -275.318309) (xy 412.574319 -275.302421) (xy 412.528507 -275.279078)
			(xy 412.486911 -275.248857) (xy 412.450555 -275.212501) (xy 412.420334 -275.170905) (xy 412.396991 -275.125093)
			(xy 412.381103 -275.076194) (xy 412.37306 -275.025412) (xy 412.054677 -275.025412) (xy 412.04692 -275.073142)
			(xy 412.031336 -275.119823) (xy 412.008465 -275.1634) (xy 411.9789 -275.202744) (xy 411.943407 -275.236836)
			(xy 411.902904 -275.264792) (xy 411.858442 -275.28589) (xy 411.811171 -275.299582) (xy 411.762316 -275.305514)
			(xy 411.713141 -275.303533) (xy 411.664922 -275.293689) (xy 411.618906 -275.276237) (xy 411.576285 -275.25163)
			(xy 411.538164 -275.220505) (xy 411.505529 -275.183668) (xy 411.479226 -275.142072) (xy 411.459935 -275.096796)
			(xy 411.448158 -275.049012) (xy 411.444198 -274.999958) (xy 411.126686 -274.999958) (xy 411.126182 -275.025666)
			(xy 411.118139 -275.076448) (xy 411.102251 -275.125347) (xy 411.078908 -275.171159) (xy 411.048687 -275.212755)
			(xy 411.012331 -275.249111) (xy 410.970735 -275.279332) (xy 410.924923 -275.302675) (xy 410.876024 -275.318563)
			(xy 410.825242 -275.326606) (xy 410.773826 -275.326606) (xy 410.723044 -275.318563) (xy 410.674145 -275.302675)
			(xy 410.628333 -275.279332) (xy 410.586737 -275.249111) (xy 410.550381 -275.212755) (xy 410.52016 -275.171159)
			(xy 410.496817 -275.125347) (xy 410.480929 -275.076448) (xy 410.472886 -275.025666) (xy 410.153546 -275.025666)
			(xy 410.151502 -275.050342) (xy 410.139102 -275.099311) (xy 410.118811 -275.145572) (xy 410.091184 -275.187862)
			(xy 410.056973 -275.225028) (xy 410.017112 -275.256057) (xy 409.972687 -275.280102) (xy 409.92491 -275.296508)
			(xy 409.875085 -275.304826) (xy 409.849828 -275.305266) (xy 409.817824 -275.303742) (xy 409.81757 -275.303742)
			(xy 409.807001 -275.3032) (xy 409.786902 -275.309747) (xy 409.778708 -275.316442) (xy 409.722828 -275.366988)
			(xy 409.715318 -275.374533) (xy 409.706656 -275.393952) (xy 409.706064 -275.40458) (xy 409.706064 -275.451824)
			(xy 409.705556 -275.470366) (xy 409.705556 -275.476208) (xy 409.705424 -275.489603) (xy 409.703265 -275.516306)
			(xy 409.701238 -275.529548) (xy 409.699206 -275.541232) (xy 409.706318 -275.563838) (xy 409.770834 -275.631402)
			(xy 409.779274 -275.639431) (xy 409.801107 -275.64748) (xy 409.812744 -275.646896) (xy 409.813506 -275.646896)
			(xy 409.82255 -275.645848) (xy 409.840724 -275.644706) (xy 409.849828 -275.64461) (xy 409.87508 -275.645134)
			(xy 409.924896 -275.653451) (xy 409.972663 -275.669853) (xy 410.017079 -275.693893) (xy 410.056932 -275.724916)
			(xy 410.091137 -275.762075) (xy 410.118759 -275.804357) (xy 410.139045 -275.850608) (xy 410.151443 -275.899568)
			(xy 410.155613 -275.9499) (xy 410.153482 -275.975626) (xy 410.472886 -275.975626) (xy 410.472886 -275.92421)
			(xy 410.480929 -275.873428) (xy 410.496817 -275.824529) (xy 410.52016 -275.778717) (xy 410.550381 -275.737121)
			(xy 410.586737 -275.700765) (xy 410.628333 -275.670544) (xy 410.674145 -275.647201) (xy 410.723044 -275.631313)
			(xy 410.773826 -275.62327) (xy 410.825242 -275.62327) (xy 410.876024 -275.631313) (xy 410.924923 -275.647201)
			(xy 410.970735 -275.670544) (xy 411.012331 -275.700765) (xy 411.048687 -275.737121) (xy 411.078908 -275.778717)
			(xy 411.102251 -275.824529) (xy 411.118139 -275.873428) (xy 411.126182 -275.92421) (xy 411.126686 -275.949918)
			(xy 411.444198 -275.949918) (xy 411.448158 -275.900864) (xy 411.459935 -275.85308) (xy 411.479226 -275.807804)
			(xy 411.505529 -275.766208) (xy 411.538164 -275.729371) (xy 411.576285 -275.698246) (xy 411.618906 -275.673639)
			(xy 411.664922 -275.656187) (xy 411.713141 -275.646343) (xy 411.762316 -275.644362) (xy 411.811171 -275.650294)
			(xy 411.858442 -275.663986) (xy 411.902904 -275.685084) (xy 411.943407 -275.71304) (xy 411.9789 -275.747132)
			(xy 412.008465 -275.786476) (xy 412.031336 -275.830053) (xy 412.04692 -275.876734) (xy 412.054815 -275.925311)
			(xy 412.05531 -275.949918) (xy 412.054815 -275.974525) (xy 412.054677 -275.975372) (xy 412.37306 -275.975372)
			(xy 412.37306 -275.923956) (xy 412.381103 -275.873174) (xy 412.396991 -275.824275) (xy 412.420334 -275.778463)
			(xy 412.450555 -275.736867) (xy 412.486911 -275.700511) (xy 412.528507 -275.67029) (xy 412.574319 -275.646947)
			(xy 412.623218 -275.631059) (xy 412.674 -275.623016) (xy 412.725416 -275.623016) (xy 412.776198 -275.631059)
			(xy 412.825097 -275.646947) (xy 412.870909 -275.67029) (xy 412.912505 -275.700511) (xy 412.948861 -275.736867)
			(xy 412.979082 -275.778463) (xy 413.002425 -275.824275) (xy 413.018313 -275.873174) (xy 413.026356 -275.923956)
			(xy 413.02686 -275.949664) (xy 413.026855 -275.949918) (xy 413.344118 -275.949918) (xy 413.348078 -275.900864)
			(xy 413.359855 -275.85308) (xy 413.379146 -275.807804) (xy 413.405449 -275.766208) (xy 413.438084 -275.729371)
			(xy 413.476205 -275.698246) (xy 413.518826 -275.673639) (xy 413.564842 -275.656187) (xy 413.613061 -275.646343)
			(xy 413.662236 -275.644362) (xy 413.711091 -275.650294) (xy 413.758362 -275.663986) (xy 413.802824 -275.685084)
			(xy 413.843327 -275.71304) (xy 413.87882 -275.747132) (xy 413.908385 -275.786476) (xy 413.931256 -275.830053)
			(xy 413.94684 -275.876734) (xy 413.954735 -275.925311) (xy 413.95523 -275.949918) (xy 413.954735 -275.974525)
			(xy 413.954556 -275.975626) (xy 414.27298 -275.975626) (xy 414.27298 -275.92421) (xy 414.281023 -275.873428)
			(xy 414.296911 -275.824529) (xy 414.320254 -275.778717) (xy 414.350475 -275.737121) (xy 414.386831 -275.700765)
			(xy 414.428427 -275.670544) (xy 414.474239 -275.647201) (xy 414.523138 -275.631313) (xy 414.57392 -275.62327)
			(xy 414.625336 -275.62327) (xy 414.676118 -275.631313) (xy 414.725017 -275.647201) (xy 414.770829 -275.670544)
			(xy 414.812425 -275.700765) (xy 414.848781 -275.737121) (xy 414.879002 -275.778717) (xy 414.902345 -275.824529)
			(xy 414.918233 -275.873428) (xy 414.926276 -275.92421) (xy 414.92678 -275.949918) (xy 415.244038 -275.949918)
			(xy 415.247998 -275.900864) (xy 415.259775 -275.85308) (xy 415.279066 -275.807804) (xy 415.305369 -275.766208)
			(xy 415.338004 -275.729371) (xy 415.376125 -275.698246) (xy 415.418746 -275.673639) (xy 415.464762 -275.656187)
			(xy 415.512981 -275.646343) (xy 415.562156 -275.644362) (xy 415.611011 -275.650294) (xy 415.658282 -275.663986)
			(xy 415.702744 -275.685084) (xy 415.743247 -275.71304) (xy 415.77874 -275.747132) (xy 415.808305 -275.786476)
			(xy 415.831176 -275.830053) (xy 415.84676 -275.876734) (xy 415.854655 -275.925311) (xy 415.85515 -275.949918)
			(xy 415.854655 -275.974525) (xy 415.854517 -275.975372) (xy 416.1729 -275.975372) (xy 416.1729 -275.923956)
			(xy 416.180943 -275.873174) (xy 416.196831 -275.824275) (xy 416.220174 -275.778463) (xy 416.250395 -275.736867)
			(xy 416.286751 -275.700511) (xy 416.328347 -275.67029) (xy 416.374159 -275.646947) (xy 416.423058 -275.631059)
			(xy 416.47384 -275.623016) (xy 416.525256 -275.623016) (xy 416.576038 -275.631059) (xy 416.624937 -275.646947)
			(xy 416.670749 -275.67029) (xy 416.712345 -275.700511) (xy 416.748701 -275.736867) (xy 416.778922 -275.778463)
			(xy 416.802265 -275.824275) (xy 416.818153 -275.873174) (xy 416.826196 -275.923956) (xy 416.8267 -275.949664)
			(xy 416.826695 -275.949918) (xy 417.144212 -275.949918) (xy 417.148172 -275.900864) (xy 417.159949 -275.85308)
			(xy 417.17924 -275.807804) (xy 417.205543 -275.766208) (xy 417.238178 -275.729371) (xy 417.276299 -275.698246)
			(xy 417.31892 -275.673639) (xy 417.364936 -275.656187) (xy 417.413155 -275.646343) (xy 417.46233 -275.644362)
			(xy 417.511185 -275.650294) (xy 417.558456 -275.663986) (xy 417.602918 -275.685084) (xy 417.643421 -275.71304)
			(xy 417.678914 -275.747132) (xy 417.708479 -275.786476) (xy 417.73135 -275.830053) (xy 417.746934 -275.876734)
			(xy 417.754829 -275.925311) (xy 417.755324 -275.949918) (xy 417.754829 -275.974525) (xy 417.75465 -275.975626)
			(xy 418.07282 -275.975626) (xy 418.07282 -275.92421) (xy 418.080863 -275.873428) (xy 418.096751 -275.824529)
			(xy 418.120094 -275.778717) (xy 418.150315 -275.737121) (xy 418.186671 -275.700765) (xy 418.228267 -275.670544)
			(xy 418.274079 -275.647201) (xy 418.322978 -275.631313) (xy 418.37376 -275.62327) (xy 418.425176 -275.62327)
			(xy 418.475958 -275.631313) (xy 418.524857 -275.647201) (xy 418.570669 -275.670544) (xy 418.612265 -275.700765)
			(xy 418.648621 -275.737121) (xy 418.678842 -275.778717) (xy 418.702185 -275.824529) (xy 418.718073 -275.873428)
			(xy 418.726116 -275.92421) (xy 418.72662 -275.949918) (xy 419.044132 -275.949918) (xy 419.048092 -275.900864)
			(xy 419.059869 -275.85308) (xy 419.07916 -275.807804) (xy 419.105463 -275.766208) (xy 419.138098 -275.729371)
			(xy 419.176219 -275.698246) (xy 419.21884 -275.673639) (xy 419.264856 -275.656187) (xy 419.313075 -275.646343)
			(xy 419.36225 -275.644362) (xy 419.411105 -275.650294) (xy 419.458376 -275.663986) (xy 419.502838 -275.685084)
			(xy 419.543341 -275.71304) (xy 419.578834 -275.747132) (xy 419.608399 -275.786476) (xy 419.63127 -275.830053)
			(xy 419.646854 -275.876734) (xy 419.654749 -275.925311) (xy 419.655244 -275.949918) (xy 419.654749 -275.974525)
			(xy 419.654611 -275.975372) (xy 419.972994 -275.975372) (xy 419.972994 -275.923956) (xy 419.981037 -275.873174)
			(xy 419.996925 -275.824275) (xy 420.020268 -275.778463) (xy 420.050489 -275.736867) (xy 420.086845 -275.700511)
			(xy 420.128441 -275.67029) (xy 420.174253 -275.646947) (xy 420.223152 -275.631059) (xy 420.273934 -275.623016)
			(xy 420.32535 -275.623016) (xy 420.376132 -275.631059) (xy 420.425031 -275.646947) (xy 420.470843 -275.67029)
			(xy 420.512439 -275.700511) (xy 420.548795 -275.736867) (xy 420.579016 -275.778463) (xy 420.602359 -275.824275)
			(xy 420.618247 -275.873174) (xy 420.62629 -275.923956) (xy 420.626794 -275.949664) (xy 420.626789 -275.949918)
			(xy 420.944052 -275.949918) (xy 420.948012 -275.900864) (xy 420.959789 -275.85308) (xy 420.97908 -275.807804)
			(xy 421.005383 -275.766208) (xy 421.038018 -275.729371) (xy 421.076139 -275.698246) (xy 421.11876 -275.673639)
			(xy 421.164776 -275.656187) (xy 421.212995 -275.646343) (xy 421.26217 -275.644362) (xy 421.311025 -275.650294)
			(xy 421.358296 -275.663986) (xy 421.402758 -275.685084) (xy 421.443261 -275.71304) (xy 421.478754 -275.747132)
			(xy 421.508319 -275.786476) (xy 421.53119 -275.830053) (xy 421.546774 -275.876734) (xy 421.554669 -275.925311)
			(xy 421.555164 -275.949918) (xy 421.554669 -275.974525) (xy 421.55449 -275.975626) (xy 421.872914 -275.975626)
			(xy 421.872914 -275.92421) (xy 421.880957 -275.873428) (xy 421.896845 -275.824529) (xy 421.920188 -275.778717)
			(xy 421.950409 -275.737121) (xy 421.986765 -275.700765) (xy 422.028361 -275.670544) (xy 422.074173 -275.647201)
			(xy 422.123072 -275.631313) (xy 422.173854 -275.62327) (xy 422.22527 -275.62327) (xy 422.276052 -275.631313)
			(xy 422.324951 -275.647201) (xy 422.370763 -275.670544) (xy 422.412359 -275.700765) (xy 422.448715 -275.737121)
			(xy 422.478936 -275.778717) (xy 422.502279 -275.824529) (xy 422.518167 -275.873428) (xy 422.52621 -275.92421)
			(xy 422.526714 -275.949918) (xy 422.844226 -275.949918) (xy 422.848186 -275.900864) (xy 422.859963 -275.85308)
			(xy 422.879254 -275.807804) (xy 422.905557 -275.766208) (xy 422.938192 -275.729371) (xy 422.976313 -275.698246)
			(xy 423.018934 -275.673639) (xy 423.06495 -275.656187) (xy 423.113169 -275.646343) (xy 423.162344 -275.644362)
			(xy 423.211199 -275.650294) (xy 423.25847 -275.663986) (xy 423.302932 -275.685084) (xy 423.343435 -275.71304)
			(xy 423.378928 -275.747132) (xy 423.408493 -275.786476) (xy 423.431364 -275.830053) (xy 423.446948 -275.876734)
			(xy 423.454843 -275.925311) (xy 423.455338 -275.949918) (xy 423.454843 -275.974525) (xy 423.454705 -275.975372)
			(xy 423.773088 -275.975372) (xy 423.773088 -275.923956) (xy 423.781131 -275.873174) (xy 423.797019 -275.824275)
			(xy 423.820362 -275.778463) (xy 423.850583 -275.736867) (xy 423.886939 -275.700511) (xy 423.928535 -275.67029)
			(xy 423.974347 -275.646947) (xy 424.023246 -275.631059) (xy 424.074028 -275.623016) (xy 424.125444 -275.623016)
			(xy 424.176226 -275.631059) (xy 424.225125 -275.646947) (xy 424.270937 -275.67029) (xy 424.312533 -275.700511)
			(xy 424.348889 -275.736867) (xy 424.37911 -275.778463) (xy 424.402453 -275.824275) (xy 424.418341 -275.873174)
			(xy 424.426384 -275.923956) (xy 424.426888 -275.949664) (xy 424.426883 -275.949918) (xy 424.744146 -275.949918)
			(xy 424.748106 -275.900864) (xy 424.759883 -275.85308) (xy 424.779174 -275.807804) (xy 424.805477 -275.766208)
			(xy 424.838112 -275.729371) (xy 424.876233 -275.698246) (xy 424.918854 -275.673639) (xy 424.96487 -275.656187)
			(xy 425.013089 -275.646343) (xy 425.062264 -275.644362) (xy 425.111119 -275.650294) (xy 425.15839 -275.663986)
			(xy 425.202852 -275.685084) (xy 425.243355 -275.71304) (xy 425.278848 -275.747132) (xy 425.308413 -275.786476)
			(xy 425.331284 -275.830053) (xy 425.346868 -275.876734) (xy 425.354763 -275.925311) (xy 425.355258 -275.949918)
			(xy 425.354763 -275.974525) (xy 425.354584 -275.975626) (xy 425.673008 -275.975626) (xy 425.673008 -275.92421)
			(xy 425.681051 -275.873428) (xy 425.696939 -275.824529) (xy 425.720282 -275.778717) (xy 425.750503 -275.737121)
			(xy 425.786859 -275.700765) (xy 425.828455 -275.670544) (xy 425.874267 -275.647201) (xy 425.923166 -275.631313)
			(xy 425.973948 -275.62327) (xy 426.025364 -275.62327) (xy 426.076146 -275.631313) (xy 426.125045 -275.647201)
			(xy 426.170857 -275.670544) (xy 426.212453 -275.700765) (xy 426.248809 -275.737121) (xy 426.27903 -275.778717)
			(xy 426.302373 -275.824529) (xy 426.318261 -275.873428) (xy 426.326304 -275.92421) (xy 426.326808 -275.949918)
			(xy 426.644066 -275.949918) (xy 426.648026 -275.900864) (xy 426.659803 -275.85308) (xy 426.679094 -275.807804)
			(xy 426.705397 -275.766208) (xy 426.738032 -275.729371) (xy 426.776153 -275.698246) (xy 426.818774 -275.673639)
			(xy 426.86479 -275.656187) (xy 426.913009 -275.646343) (xy 426.962184 -275.644362) (xy 427.011039 -275.650294)
			(xy 427.05831 -275.663986) (xy 427.102772 -275.685084) (xy 427.143275 -275.71304) (xy 427.178768 -275.747132)
			(xy 427.208333 -275.786476) (xy 427.231204 -275.830053) (xy 427.246788 -275.876734) (xy 427.254683 -275.925311)
			(xy 427.255178 -275.949918) (xy 427.254683 -275.974525) (xy 427.254504 -275.975626) (xy 427.572928 -275.975626)
			(xy 427.572928 -275.92421) (xy 427.580971 -275.873428) (xy 427.596859 -275.824529) (xy 427.620202 -275.778717)
			(xy 427.650423 -275.737121) (xy 427.686779 -275.700765) (xy 427.728375 -275.670544) (xy 427.774187 -275.647201)
			(xy 427.823086 -275.631313) (xy 427.873868 -275.62327) (xy 427.925284 -275.62327) (xy 427.976066 -275.631313)
			(xy 428.024965 -275.647201) (xy 428.070777 -275.670544) (xy 428.112373 -275.700765) (xy 428.148729 -275.737121)
			(xy 428.17895 -275.778717) (xy 428.202293 -275.824529) (xy 428.218181 -275.873428) (xy 428.226224 -275.92421)
			(xy 428.226728 -275.949918) (xy 428.54424 -275.949918) (xy 428.5482 -275.900864) (xy 428.559977 -275.85308)
			(xy 428.579268 -275.807804) (xy 428.605571 -275.766208) (xy 428.638206 -275.729371) (xy 428.676327 -275.698246)
			(xy 428.718948 -275.673639) (xy 428.764964 -275.656187) (xy 428.813183 -275.646343) (xy 428.862358 -275.644362)
			(xy 428.911213 -275.650294) (xy 428.958484 -275.663986) (xy 429.002946 -275.685084) (xy 429.043449 -275.71304)
			(xy 429.078942 -275.747132) (xy 429.108507 -275.786476) (xy 429.131378 -275.830053) (xy 429.146962 -275.876734)
			(xy 429.154857 -275.925311) (xy 429.155352 -275.949918) (xy 429.4942 -275.949918) (xy 429.49816 -275.900864)
			(xy 429.509937 -275.85308) (xy 429.529228 -275.807804) (xy 429.555531 -275.766208) (xy 429.588166 -275.729371)
			(xy 429.626287 -275.698246) (xy 429.668908 -275.673639) (xy 429.714924 -275.656187) (xy 429.763143 -275.646343)
			(xy 429.812318 -275.644362) (xy 429.861173 -275.650294) (xy 429.908444 -275.663986) (xy 429.952906 -275.685084)
			(xy 429.993409 -275.71304) (xy 430.028902 -275.747132) (xy 430.058467 -275.786476) (xy 430.081338 -275.830053)
			(xy 430.096922 -275.876734) (xy 430.104817 -275.925311) (xy 430.105312 -275.949918) (xy 430.44416 -275.949918)
			(xy 430.44812 -275.900864) (xy 430.459897 -275.85308) (xy 430.479188 -275.807804) (xy 430.505491 -275.766208)
			(xy 430.538126 -275.729371) (xy 430.576247 -275.698246) (xy 430.618868 -275.673639) (xy 430.664884 -275.656187)
			(xy 430.713103 -275.646343) (xy 430.762278 -275.644362) (xy 430.811133 -275.650294) (xy 430.858404 -275.663986)
			(xy 430.902866 -275.685084) (xy 430.943369 -275.71304) (xy 430.978862 -275.747132) (xy 431.008427 -275.786476)
			(xy 431.031298 -275.830053) (xy 431.046882 -275.876734) (xy 431.054777 -275.925311) (xy 431.055272 -275.949918)
			(xy 431.054777 -275.974525) (xy 431.046882 -276.023102) (xy 431.031298 -276.069783) (xy 431.008427 -276.11336)
			(xy 430.978862 -276.152704) (xy 430.943369 -276.186796) (xy 430.902866 -276.214752) (xy 430.858404 -276.23585)
			(xy 430.811133 -276.249542) (xy 430.762278 -276.255474) (xy 430.713103 -276.253493) (xy 430.664884 -276.243649)
			(xy 430.618868 -276.226197) (xy 430.576247 -276.20159) (xy 430.538126 -276.170465) (xy 430.505491 -276.133628)
			(xy 430.479188 -276.092032) (xy 430.459897 -276.046756) (xy 430.44812 -275.998972) (xy 430.44416 -275.949918)
			(xy 430.105312 -275.949918) (xy 430.104817 -275.974525) (xy 430.096922 -276.023102) (xy 430.081338 -276.069783)
			(xy 430.058467 -276.11336) (xy 430.028902 -276.152704) (xy 429.993409 -276.186796) (xy 429.952906 -276.214752)
			(xy 429.908444 -276.23585) (xy 429.861173 -276.249542) (xy 429.812318 -276.255474) (xy 429.763143 -276.253493)
			(xy 429.714924 -276.243649) (xy 429.668908 -276.226197) (xy 429.626287 -276.20159) (xy 429.588166 -276.170465)
			(xy 429.555531 -276.133628) (xy 429.529228 -276.092032) (xy 429.509937 -276.046756) (xy 429.49816 -275.998972)
			(xy 429.4942 -275.949918) (xy 429.155352 -275.949918) (xy 429.154857 -275.974525) (xy 429.146962 -276.023102)
			(xy 429.131378 -276.069783) (xy 429.108507 -276.11336) (xy 429.078942 -276.152704) (xy 429.043449 -276.186796)
			(xy 429.002946 -276.214752) (xy 428.958484 -276.23585) (xy 428.911213 -276.249542) (xy 428.862358 -276.255474)
			(xy 428.813183 -276.253493) (xy 428.764964 -276.243649) (xy 428.718948 -276.226197) (xy 428.676327 -276.20159)
			(xy 428.638206 -276.170465) (xy 428.605571 -276.133628) (xy 428.579268 -276.092032) (xy 428.559977 -276.046756)
			(xy 428.5482 -275.998972) (xy 428.54424 -275.949918) (xy 428.226728 -275.949918) (xy 428.226224 -275.975626)
			(xy 428.218181 -276.026408) (xy 428.202293 -276.075307) (xy 428.17895 -276.121119) (xy 428.148729 -276.162715)
			(xy 428.112373 -276.199071) (xy 428.070777 -276.229292) (xy 428.024965 -276.252635) (xy 427.976066 -276.268523)
			(xy 427.925284 -276.276566) (xy 427.873868 -276.276566) (xy 427.823086 -276.268523) (xy 427.774187 -276.252635)
			(xy 427.728375 -276.229292) (xy 427.686779 -276.199071) (xy 427.650423 -276.162715) (xy 427.620202 -276.121119)
			(xy 427.596859 -276.075307) (xy 427.580971 -276.026408) (xy 427.572928 -275.975626) (xy 427.254504 -275.975626)
			(xy 427.246788 -276.023102) (xy 427.231204 -276.069783) (xy 427.208333 -276.11336) (xy 427.178768 -276.152704)
			(xy 427.143275 -276.186796) (xy 427.102772 -276.214752) (xy 427.05831 -276.23585) (xy 427.011039 -276.249542)
			(xy 426.962184 -276.255474) (xy 426.913009 -276.253493) (xy 426.86479 -276.243649) (xy 426.818774 -276.226197)
			(xy 426.776153 -276.20159) (xy 426.738032 -276.170465) (xy 426.705397 -276.133628) (xy 426.679094 -276.092032)
			(xy 426.659803 -276.046756) (xy 426.648026 -275.998972) (xy 426.644066 -275.949918) (xy 426.326808 -275.949918)
			(xy 426.326304 -275.975626) (xy 426.318261 -276.026408) (xy 426.302373 -276.075307) (xy 426.27903 -276.121119)
			(xy 426.248809 -276.162715) (xy 426.212453 -276.199071) (xy 426.170857 -276.229292) (xy 426.125045 -276.252635)
			(xy 426.076146 -276.268523) (xy 426.025364 -276.276566) (xy 425.973948 -276.276566) (xy 425.923166 -276.268523)
			(xy 425.874267 -276.252635) (xy 425.828455 -276.229292) (xy 425.786859 -276.199071) (xy 425.750503 -276.162715)
			(xy 425.720282 -276.121119) (xy 425.696939 -276.075307) (xy 425.681051 -276.026408) (xy 425.673008 -275.975626)
			(xy 425.354584 -275.975626) (xy 425.346868 -276.023102) (xy 425.331284 -276.069783) (xy 425.308413 -276.11336)
			(xy 425.278848 -276.152704) (xy 425.243355 -276.186796) (xy 425.202852 -276.214752) (xy 425.15839 -276.23585)
			(xy 425.111119 -276.249542) (xy 425.062264 -276.255474) (xy 425.013089 -276.253493) (xy 424.96487 -276.243649)
			(xy 424.918854 -276.226197) (xy 424.876233 -276.20159) (xy 424.838112 -276.170465) (xy 424.805477 -276.133628)
			(xy 424.779174 -276.092032) (xy 424.759883 -276.046756) (xy 424.748106 -275.998972) (xy 424.744146 -275.949918)
			(xy 424.426883 -275.949918) (xy 424.426384 -275.975372) (xy 424.418341 -276.026154) (xy 424.402453 -276.075053)
			(xy 424.37911 -276.120865) (xy 424.348889 -276.162461) (xy 424.312533 -276.198817) (xy 424.270937 -276.229038)
			(xy 424.225125 -276.252381) (xy 424.176226 -276.268269) (xy 424.125444 -276.276312) (xy 424.074028 -276.276312)
			(xy 424.023246 -276.268269) (xy 423.974347 -276.252381) (xy 423.928535 -276.229038) (xy 423.886939 -276.198817)
			(xy 423.850583 -276.162461) (xy 423.820362 -276.120865) (xy 423.797019 -276.075053) (xy 423.781131 -276.026154)
			(xy 423.773088 -275.975372) (xy 423.454705 -275.975372) (xy 423.446948 -276.023102) (xy 423.431364 -276.069783)
			(xy 423.408493 -276.11336) (xy 423.378928 -276.152704) (xy 423.343435 -276.186796) (xy 423.302932 -276.214752)
			(xy 423.25847 -276.23585) (xy 423.211199 -276.249542) (xy 423.162344 -276.255474) (xy 423.113169 -276.253493)
			(xy 423.06495 -276.243649) (xy 423.018934 -276.226197) (xy 422.976313 -276.20159) (xy 422.938192 -276.170465)
			(xy 422.905557 -276.133628) (xy 422.879254 -276.092032) (xy 422.859963 -276.046756) (xy 422.848186 -275.998972)
			(xy 422.844226 -275.949918) (xy 422.526714 -275.949918) (xy 422.52621 -275.975626) (xy 422.518167 -276.026408)
			(xy 422.502279 -276.075307) (xy 422.478936 -276.121119) (xy 422.448715 -276.162715) (xy 422.412359 -276.199071)
			(xy 422.370763 -276.229292) (xy 422.324951 -276.252635) (xy 422.276052 -276.268523) (xy 422.22527 -276.276566)
			(xy 422.173854 -276.276566) (xy 422.123072 -276.268523) (xy 422.074173 -276.252635) (xy 422.028361 -276.229292)
			(xy 421.986765 -276.199071) (xy 421.950409 -276.162715) (xy 421.920188 -276.121119) (xy 421.896845 -276.075307)
			(xy 421.880957 -276.026408) (xy 421.872914 -275.975626) (xy 421.55449 -275.975626) (xy 421.546774 -276.023102)
			(xy 421.53119 -276.069783) (xy 421.508319 -276.11336) (xy 421.478754 -276.152704) (xy 421.443261 -276.186796)
			(xy 421.402758 -276.214752) (xy 421.358296 -276.23585) (xy 421.311025 -276.249542) (xy 421.26217 -276.255474)
			(xy 421.212995 -276.253493) (xy 421.164776 -276.243649) (xy 421.11876 -276.226197) (xy 421.076139 -276.20159)
			(xy 421.038018 -276.170465) (xy 421.005383 -276.133628) (xy 420.97908 -276.092032) (xy 420.959789 -276.046756)
			(xy 420.948012 -275.998972) (xy 420.944052 -275.949918) (xy 420.626789 -275.949918) (xy 420.62629 -275.975372)
			(xy 420.618247 -276.026154) (xy 420.602359 -276.075053) (xy 420.579016 -276.120865) (xy 420.548795 -276.162461)
			(xy 420.512439 -276.198817) (xy 420.470843 -276.229038) (xy 420.425031 -276.252381) (xy 420.376132 -276.268269)
			(xy 420.32535 -276.276312) (xy 420.273934 -276.276312) (xy 420.223152 -276.268269) (xy 420.174253 -276.252381)
			(xy 420.128441 -276.229038) (xy 420.086845 -276.198817) (xy 420.050489 -276.162461) (xy 420.020268 -276.120865)
			(xy 419.996925 -276.075053) (xy 419.981037 -276.026154) (xy 419.972994 -275.975372) (xy 419.654611 -275.975372)
			(xy 419.646854 -276.023102) (xy 419.63127 -276.069783) (xy 419.608399 -276.11336) (xy 419.578834 -276.152704)
			(xy 419.543341 -276.186796) (xy 419.502838 -276.214752) (xy 419.458376 -276.23585) (xy 419.411105 -276.249542)
			(xy 419.36225 -276.255474) (xy 419.313075 -276.253493) (xy 419.264856 -276.243649) (xy 419.21884 -276.226197)
			(xy 419.176219 -276.20159) (xy 419.138098 -276.170465) (xy 419.105463 -276.133628) (xy 419.07916 -276.092032)
			(xy 419.059869 -276.046756) (xy 419.048092 -275.998972) (xy 419.044132 -275.949918) (xy 418.72662 -275.949918)
			(xy 418.726116 -275.975626) (xy 418.718073 -276.026408) (xy 418.702185 -276.075307) (xy 418.678842 -276.121119)
			(xy 418.648621 -276.162715) (xy 418.612265 -276.199071) (xy 418.570669 -276.229292) (xy 418.524857 -276.252635)
			(xy 418.475958 -276.268523) (xy 418.425176 -276.276566) (xy 418.37376 -276.276566) (xy 418.322978 -276.268523)
			(xy 418.274079 -276.252635) (xy 418.228267 -276.229292) (xy 418.186671 -276.199071) (xy 418.150315 -276.162715)
			(xy 418.120094 -276.121119) (xy 418.096751 -276.075307) (xy 418.080863 -276.026408) (xy 418.07282 -275.975626)
			(xy 417.75465 -275.975626) (xy 417.746934 -276.023102) (xy 417.73135 -276.069783) (xy 417.708479 -276.11336)
			(xy 417.678914 -276.152704) (xy 417.643421 -276.186796) (xy 417.602918 -276.214752) (xy 417.558456 -276.23585)
			(xy 417.511185 -276.249542) (xy 417.46233 -276.255474) (xy 417.413155 -276.253493) (xy 417.364936 -276.243649)
			(xy 417.31892 -276.226197) (xy 417.276299 -276.20159) (xy 417.238178 -276.170465) (xy 417.205543 -276.133628)
			(xy 417.17924 -276.092032) (xy 417.159949 -276.046756) (xy 417.148172 -275.998972) (xy 417.144212 -275.949918)
			(xy 416.826695 -275.949918) (xy 416.826196 -275.975372) (xy 416.818153 -276.026154) (xy 416.802265 -276.075053)
			(xy 416.778922 -276.120865) (xy 416.748701 -276.162461) (xy 416.712345 -276.198817) (xy 416.670749 -276.229038)
			(xy 416.624937 -276.252381) (xy 416.576038 -276.268269) (xy 416.525256 -276.276312) (xy 416.47384 -276.276312)
			(xy 416.423058 -276.268269) (xy 416.374159 -276.252381) (xy 416.328347 -276.229038) (xy 416.286751 -276.198817)
			(xy 416.250395 -276.162461) (xy 416.220174 -276.120865) (xy 416.196831 -276.075053) (xy 416.180943 -276.026154)
			(xy 416.1729 -275.975372) (xy 415.854517 -275.975372) (xy 415.84676 -276.023102) (xy 415.831176 -276.069783)
			(xy 415.808305 -276.11336) (xy 415.77874 -276.152704) (xy 415.743247 -276.186796) (xy 415.702744 -276.214752)
			(xy 415.658282 -276.23585) (xy 415.611011 -276.249542) (xy 415.562156 -276.255474) (xy 415.512981 -276.253493)
			(xy 415.464762 -276.243649) (xy 415.418746 -276.226197) (xy 415.376125 -276.20159) (xy 415.338004 -276.170465)
			(xy 415.305369 -276.133628) (xy 415.279066 -276.092032) (xy 415.259775 -276.046756) (xy 415.247998 -275.998972)
			(xy 415.244038 -275.949918) (xy 414.92678 -275.949918) (xy 414.926276 -275.975626) (xy 414.918233 -276.026408)
			(xy 414.902345 -276.075307) (xy 414.879002 -276.121119) (xy 414.848781 -276.162715) (xy 414.812425 -276.199071)
			(xy 414.770829 -276.229292) (xy 414.725017 -276.252635) (xy 414.676118 -276.268523) (xy 414.625336 -276.276566)
			(xy 414.57392 -276.276566) (xy 414.523138 -276.268523) (xy 414.474239 -276.252635) (xy 414.428427 -276.229292)
			(xy 414.386831 -276.199071) (xy 414.350475 -276.162715) (xy 414.320254 -276.121119) (xy 414.296911 -276.075307)
			(xy 414.281023 -276.026408) (xy 414.27298 -275.975626) (xy 413.954556 -275.975626) (xy 413.94684 -276.023102)
			(xy 413.931256 -276.069783) (xy 413.908385 -276.11336) (xy 413.87882 -276.152704) (xy 413.843327 -276.186796)
			(xy 413.802824 -276.214752) (xy 413.758362 -276.23585) (xy 413.711091 -276.249542) (xy 413.662236 -276.255474)
			(xy 413.613061 -276.253493) (xy 413.564842 -276.243649) (xy 413.518826 -276.226197) (xy 413.476205 -276.20159)
			(xy 413.438084 -276.170465) (xy 413.405449 -276.133628) (xy 413.379146 -276.092032) (xy 413.359855 -276.046756)
			(xy 413.348078 -275.998972) (xy 413.344118 -275.949918) (xy 413.026855 -275.949918) (xy 413.026356 -275.975372)
			(xy 413.018313 -276.026154) (xy 413.002425 -276.075053) (xy 412.979082 -276.120865) (xy 412.948861 -276.162461)
			(xy 412.912505 -276.198817) (xy 412.870909 -276.229038) (xy 412.825097 -276.252381) (xy 412.776198 -276.268269)
			(xy 412.725416 -276.276312) (xy 412.674 -276.276312) (xy 412.623218 -276.268269) (xy 412.574319 -276.252381)
			(xy 412.528507 -276.229038) (xy 412.486911 -276.198817) (xy 412.450555 -276.162461) (xy 412.420334 -276.120865)
			(xy 412.396991 -276.075053) (xy 412.381103 -276.026154) (xy 412.37306 -275.975372) (xy 412.054677 -275.975372)
			(xy 412.04692 -276.023102) (xy 412.031336 -276.069783) (xy 412.008465 -276.11336) (xy 411.9789 -276.152704)
			(xy 411.943407 -276.186796) (xy 411.902904 -276.214752) (xy 411.858442 -276.23585) (xy 411.811171 -276.249542)
			(xy 411.762316 -276.255474) (xy 411.713141 -276.253493) (xy 411.664922 -276.243649) (xy 411.618906 -276.226197)
			(xy 411.576285 -276.20159) (xy 411.538164 -276.170465) (xy 411.505529 -276.133628) (xy 411.479226 -276.092032)
			(xy 411.459935 -276.046756) (xy 411.448158 -275.998972) (xy 411.444198 -275.949918) (xy 411.126686 -275.949918)
			(xy 411.126182 -275.975626) (xy 411.118139 -276.026408) (xy 411.102251 -276.075307) (xy 411.078908 -276.121119)
			(xy 411.048687 -276.162715) (xy 411.012331 -276.199071) (xy 410.970735 -276.229292) (xy 410.924923 -276.252635)
			(xy 410.876024 -276.268523) (xy 410.825242 -276.276566) (xy 410.773826 -276.276566) (xy 410.723044 -276.268523)
			(xy 410.674145 -276.252635) (xy 410.628333 -276.229292) (xy 410.586737 -276.199071) (xy 410.550381 -276.162715)
			(xy 410.52016 -276.121119) (xy 410.496817 -276.075307) (xy 410.480929 -276.026408) (xy 410.472886 -275.975626)
			(xy 410.153482 -275.975626) (xy 410.151443 -276.000232) (xy 410.139045 -276.049192) (xy 410.118759 -276.095443)
			(xy 410.091137 -276.137725) (xy 410.056932 -276.174884) (xy 410.017079 -276.205907) (xy 409.972663 -276.229947)
			(xy 409.924896 -276.246349) (xy 409.87508 -276.254666) (xy 409.849828 -276.255226) (xy 409.840787 -276.255122)
			(xy 409.822741 -276.253979) (xy 409.81376 -276.25294) (xy 409.812744 -276.25294) (xy 409.801043 -276.252289)
			(xy 409.779065 -276.260352) (xy 409.77058 -276.268434) (xy 409.70581 -276.336506) (xy 409.698952 -276.359112)
			(xy 409.700984 -276.37105) (xy 409.703098 -276.384412) (xy 409.705389 -276.411371) (xy 409.705556 -276.424898)
			(xy 409.705374 -276.438425) (xy 409.703084 -276.465382) (xy 409.700984 -276.478746) (xy 409.698952 -276.490684)
			(xy 409.699491 -276.492462) (xy 455.756008 -276.492462) (xy 455.760079 -276.43684) (xy 455.772205 -276.382403)
			(xy 455.792128 -276.330312) (xy 455.819424 -276.281677) (xy 455.85351 -276.237534) (xy 455.893659 -276.198825)
			(xy 455.939017 -276.166374) (xy 455.988617 -276.140873) (xy 456.041401 -276.122866) (xy 456.096244 -276.112736)
			(xy 456.151978 -276.110699) (xy 456.207415 -276.116799) (xy 456.261372 -276.130905) (xy 456.312701 -276.152717)
			(xy 456.360307 -276.181771) (xy 456.403175 -276.217446) (xy 456.440392 -276.258983) (xy 456.471165 -276.305496)
			(xy 456.494837 -276.355993) (xy 456.510905 -276.4094) (xy 456.519025 -276.464576) (xy 456.519534 -276.492462)
			(xy 456.519025 -276.520348) (xy 456.510905 -276.575524) (xy 456.494837 -276.628931) (xy 456.488321 -276.64283)
			(xy 461.074006 -276.64283) (xy 461.078077 -276.587208) (xy 461.090203 -276.532771) (xy 461.110126 -276.48068)
			(xy 461.137422 -276.432045) (xy 461.171508 -276.387902) (xy 461.211657 -276.349193) (xy 461.257015 -276.316742)
			(xy 461.306615 -276.291241) (xy 461.359399 -276.273234) (xy 461.414242 -276.263104) (xy 461.469976 -276.261067)
			(xy 461.525413 -276.267167) (xy 461.57937 -276.281273) (xy 461.630699 -276.303085) (xy 461.678305 -276.332139)
			(xy 461.721173 -276.367814) (xy 461.75839 -276.409351) (xy 461.789163 -276.455864) (xy 461.812835 -276.506361)
			(xy 461.828903 -276.559768) (xy 461.837023 -276.614944) (xy 461.837532 -276.64283) (xy 463.093306 -276.64283)
			(xy 463.097377 -276.587208) (xy 463.109503 -276.532771) (xy 463.129426 -276.48068) (xy 463.156722 -276.432045)
			(xy 463.190808 -276.387902) (xy 463.230957 -276.349193) (xy 463.276315 -276.316742) (xy 463.325915 -276.291241)
			(xy 463.378699 -276.273234) (xy 463.433542 -276.263104) (xy 463.489276 -276.261067) (xy 463.544713 -276.267167)
			(xy 463.59867 -276.281273) (xy 463.649999 -276.303085) (xy 463.697605 -276.332139) (xy 463.740473 -276.367814)
			(xy 463.77769 -276.409351) (xy 463.808463 -276.455864) (xy 463.832135 -276.506361) (xy 463.848203 -276.559768)
			(xy 463.856323 -276.614944) (xy 463.856832 -276.64283) (xy 463.856323 -276.670716) (xy 463.848203 -276.725892)
			(xy 463.832135 -276.779299) (xy 463.808463 -276.829796) (xy 463.77769 -276.876309) (xy 463.740473 -276.917846)
			(xy 463.697605 -276.953521) (xy 463.649999 -276.982575) (xy 463.59867 -277.004387) (xy 463.544713 -277.018493)
			(xy 463.489276 -277.024593) (xy 463.433542 -277.022556) (xy 463.378699 -277.012426) (xy 463.325915 -276.994419)
			(xy 463.276315 -276.968918) (xy 463.230957 -276.936467) (xy 463.190808 -276.897758) (xy 463.156722 -276.853615)
			(xy 463.129426 -276.80498) (xy 463.109503 -276.752889) (xy 463.097377 -276.698452) (xy 463.093306 -276.64283)
			(xy 461.837532 -276.64283) (xy 461.837023 -276.670716) (xy 461.828903 -276.725892) (xy 461.812835 -276.779299)
			(xy 461.789163 -276.829796) (xy 461.75839 -276.876309) (xy 461.721173 -276.917846) (xy 461.678305 -276.953521)
			(xy 461.630699 -276.982575) (xy 461.57937 -277.004387) (xy 461.525413 -277.018493) (xy 461.469976 -277.024593)
			(xy 461.414242 -277.022556) (xy 461.359399 -277.012426) (xy 461.306615 -276.994419) (xy 461.257015 -276.968918)
			(xy 461.211657 -276.936467) (xy 461.171508 -276.897758) (xy 461.137422 -276.853615) (xy 461.110126 -276.80498)
			(xy 461.090203 -276.752889) (xy 461.078077 -276.698452) (xy 461.074006 -276.64283) (xy 456.488321 -276.64283)
			(xy 456.471165 -276.679428) (xy 456.440392 -276.725941) (xy 456.403175 -276.767478) (xy 456.360307 -276.803153)
			(xy 456.312701 -276.832207) (xy 456.261372 -276.854019) (xy 456.207415 -276.868125) (xy 456.151978 -276.874225)
			(xy 456.096244 -276.872188) (xy 456.041401 -276.862058) (xy 455.988617 -276.844051) (xy 455.939017 -276.81855)
			(xy 455.893659 -276.786099) (xy 455.85351 -276.74739) (xy 455.819424 -276.703247) (xy 455.792128 -276.654612)
			(xy 455.772205 -276.602521) (xy 455.760079 -276.548084) (xy 455.756008 -276.492462) (xy 409.699491 -276.492462)
			(xy 409.70581 -276.51329) (xy 409.77058 -276.581362) (xy 409.779068 -276.589448) (xy 409.801043 -276.597541)
			(xy 409.812744 -276.596856) (xy 409.813252 -276.596856) (xy 409.822359 -276.5958) (xy 409.84066 -276.594654)
			(xy 409.849828 -276.59457) (xy 409.87465 -276.595058) (xy 409.923641 -276.603094) (xy 409.970686 -276.61895)
			(xy 410.014546 -276.642208) (xy 410.054065 -276.672256) (xy 410.088203 -276.708301) (xy 410.116059 -276.749394)
			(xy 410.136901 -276.794453) (xy 410.150178 -276.842289) (xy 410.155542 -276.891644) (xy 410.155095 -276.899878)
			(xy 410.493984 -276.899878) (xy 410.497944 -276.850824) (xy 410.509721 -276.80304) (xy 410.529012 -276.757764)
			(xy 410.555315 -276.716168) (xy 410.58795 -276.679331) (xy 410.626071 -276.648206) (xy 410.668692 -276.623599)
			(xy 410.714708 -276.606147) (xy 410.762927 -276.596303) (xy 410.812102 -276.594322) (xy 410.860957 -276.600254)
			(xy 410.908228 -276.613946) (xy 410.95269 -276.635044) (xy 410.993193 -276.663) (xy 411.028686 -276.697092)
			(xy 411.058251 -276.736436) (xy 411.081122 -276.780013) (xy 411.096706 -276.826694) (xy 411.104601 -276.875271)
			(xy 411.105096 -276.899878) (xy 411.444198 -276.899878) (xy 411.448158 -276.850824) (xy 411.459935 -276.80304)
			(xy 411.479226 -276.757764) (xy 411.505529 -276.716168) (xy 411.538164 -276.679331) (xy 411.576285 -276.648206)
			(xy 411.618906 -276.623599) (xy 411.664922 -276.606147) (xy 411.713141 -276.596303) (xy 411.762316 -276.594322)
			(xy 411.811171 -276.600254) (xy 411.858442 -276.613946) (xy 411.902904 -276.635044) (xy 411.943407 -276.663)
			(xy 411.9789 -276.697092) (xy 412.008465 -276.736436) (xy 412.031336 -276.780013) (xy 412.04692 -276.826694)
			(xy 412.054815 -276.875271) (xy 412.05531 -276.899878) (xy 412.394158 -276.899878) (xy 412.398118 -276.850824)
			(xy 412.409895 -276.80304) (xy 412.429186 -276.757764) (xy 412.455489 -276.716168) (xy 412.488124 -276.679331)
			(xy 412.526245 -276.648206) (xy 412.568866 -276.623599) (xy 412.614882 -276.606147) (xy 412.663101 -276.596303)
			(xy 412.712276 -276.594322) (xy 412.761131 -276.600254) (xy 412.808402 -276.613946) (xy 412.852864 -276.635044)
			(xy 412.893367 -276.663) (xy 412.92886 -276.697092) (xy 412.958425 -276.736436) (xy 412.981296 -276.780013)
			(xy 412.99688 -276.826694) (xy 413.004775 -276.875271) (xy 413.00527 -276.899878) (xy 413.344118 -276.899878)
			(xy 413.348078 -276.850824) (xy 413.359855 -276.80304) (xy 413.379146 -276.757764) (xy 413.405449 -276.716168)
			(xy 413.438084 -276.679331) (xy 413.476205 -276.648206) (xy 413.518826 -276.623599) (xy 413.564842 -276.606147)
			(xy 413.613061 -276.596303) (xy 413.662236 -276.594322) (xy 413.711091 -276.600254) (xy 413.758362 -276.613946)
			(xy 413.802824 -276.635044) (xy 413.843327 -276.663) (xy 413.87882 -276.697092) (xy 413.908385 -276.736436)
			(xy 413.931256 -276.780013) (xy 413.94684 -276.826694) (xy 413.954735 -276.875271) (xy 413.95523 -276.899878)
			(xy 414.294078 -276.899878) (xy 414.298038 -276.850824) (xy 414.309815 -276.80304) (xy 414.329106 -276.757764)
			(xy 414.355409 -276.716168) (xy 414.388044 -276.679331) (xy 414.426165 -276.648206) (xy 414.468786 -276.623599)
			(xy 414.514802 -276.606147) (xy 414.563021 -276.596303) (xy 414.612196 -276.594322) (xy 414.661051 -276.600254)
			(xy 414.708322 -276.613946) (xy 414.752784 -276.635044) (xy 414.793287 -276.663) (xy 414.82878 -276.697092)
			(xy 414.858345 -276.736436) (xy 414.881216 -276.780013) (xy 414.8968 -276.826694) (xy 414.904695 -276.875271)
			(xy 414.90519 -276.899878) (xy 415.244038 -276.899878) (xy 415.247998 -276.850824) (xy 415.259775 -276.80304)
			(xy 415.279066 -276.757764) (xy 415.305369 -276.716168) (xy 415.338004 -276.679331) (xy 415.376125 -276.648206)
			(xy 415.418746 -276.623599) (xy 415.464762 -276.606147) (xy 415.512981 -276.596303) (xy 415.562156 -276.594322)
			(xy 415.611011 -276.600254) (xy 415.658282 -276.613946) (xy 415.702744 -276.635044) (xy 415.743247 -276.663)
			(xy 415.77874 -276.697092) (xy 415.808305 -276.736436) (xy 415.831176 -276.780013) (xy 415.84676 -276.826694)
			(xy 415.854655 -276.875271) (xy 415.85515 -276.899878) (xy 416.193998 -276.899878) (xy 416.197958 -276.850824)
			(xy 416.209735 -276.80304) (xy 416.229026 -276.757764) (xy 416.255329 -276.716168) (xy 416.287964 -276.679331)
			(xy 416.326085 -276.648206) (xy 416.368706 -276.623599) (xy 416.414722 -276.606147) (xy 416.462941 -276.596303)
			(xy 416.512116 -276.594322) (xy 416.560971 -276.600254) (xy 416.608242 -276.613946) (xy 416.652704 -276.635044)
			(xy 416.693207 -276.663) (xy 416.7287 -276.697092) (xy 416.758265 -276.736436) (xy 416.781136 -276.780013)
			(xy 416.79672 -276.826694) (xy 416.804615 -276.875271) (xy 416.80511 -276.899878) (xy 417.144212 -276.899878)
			(xy 417.148172 -276.850824) (xy 417.159949 -276.80304) (xy 417.17924 -276.757764) (xy 417.205543 -276.716168)
			(xy 417.238178 -276.679331) (xy 417.276299 -276.648206) (xy 417.31892 -276.623599) (xy 417.364936 -276.606147)
			(xy 417.413155 -276.596303) (xy 417.46233 -276.594322) (xy 417.511185 -276.600254) (xy 417.558456 -276.613946)
			(xy 417.602918 -276.635044) (xy 417.643421 -276.663) (xy 417.678914 -276.697092) (xy 417.708479 -276.736436)
			(xy 417.73135 -276.780013) (xy 417.746934 -276.826694) (xy 417.754829 -276.875271) (xy 417.755324 -276.899878)
			(xy 418.094172 -276.899878) (xy 418.098132 -276.850824) (xy 418.109909 -276.80304) (xy 418.1292 -276.757764)
			(xy 418.155503 -276.716168) (xy 418.188138 -276.679331) (xy 418.226259 -276.648206) (xy 418.26888 -276.623599)
			(xy 418.314896 -276.606147) (xy 418.363115 -276.596303) (xy 418.41229 -276.594322) (xy 418.461145 -276.600254)
			(xy 418.508416 -276.613946) (xy 418.552878 -276.635044) (xy 418.593381 -276.663) (xy 418.628874 -276.697092)
			(xy 418.658439 -276.736436) (xy 418.68131 -276.780013) (xy 418.696894 -276.826694) (xy 418.704789 -276.875271)
			(xy 418.705284 -276.899878) (xy 419.044132 -276.899878) (xy 419.048092 -276.850824) (xy 419.059869 -276.80304)
			(xy 419.07916 -276.757764) (xy 419.105463 -276.716168) (xy 419.138098 -276.679331) (xy 419.176219 -276.648206)
			(xy 419.21884 -276.623599) (xy 419.264856 -276.606147) (xy 419.313075 -276.596303) (xy 419.36225 -276.594322)
			(xy 419.411105 -276.600254) (xy 419.458376 -276.613946) (xy 419.502838 -276.635044) (xy 419.543341 -276.663)
			(xy 419.578834 -276.697092) (xy 419.608399 -276.736436) (xy 419.63127 -276.780013) (xy 419.646854 -276.826694)
			(xy 419.654749 -276.875271) (xy 419.655244 -276.899878) (xy 419.994092 -276.899878) (xy 419.998052 -276.850824)
			(xy 420.009829 -276.80304) (xy 420.02912 -276.757764) (xy 420.055423 -276.716168) (xy 420.088058 -276.679331)
			(xy 420.126179 -276.648206) (xy 420.1688 -276.623599) (xy 420.214816 -276.606147) (xy 420.263035 -276.596303)
			(xy 420.31221 -276.594322) (xy 420.361065 -276.600254) (xy 420.408336 -276.613946) (xy 420.452798 -276.635044)
			(xy 420.493301 -276.663) (xy 420.528794 -276.697092) (xy 420.558359 -276.736436) (xy 420.58123 -276.780013)
			(xy 420.596814 -276.826694) (xy 420.604709 -276.875271) (xy 420.605204 -276.899878) (xy 420.944052 -276.899878)
			(xy 420.948012 -276.850824) (xy 420.959789 -276.80304) (xy 420.97908 -276.757764) (xy 421.005383 -276.716168)
			(xy 421.038018 -276.679331) (xy 421.076139 -276.648206) (xy 421.11876 -276.623599) (xy 421.164776 -276.606147)
			(xy 421.212995 -276.596303) (xy 421.26217 -276.594322) (xy 421.311025 -276.600254) (xy 421.358296 -276.613946)
			(xy 421.402758 -276.635044) (xy 421.443261 -276.663) (xy 421.478754 -276.697092) (xy 421.508319 -276.736436)
			(xy 421.53119 -276.780013) (xy 421.546774 -276.826694) (xy 421.554669 -276.875271) (xy 421.555164 -276.899878)
			(xy 421.893758 -276.899878) (xy 421.897718 -276.850824) (xy 421.909495 -276.80304) (xy 421.928786 -276.757764)
			(xy 421.955089 -276.716168) (xy 421.987724 -276.679331) (xy 422.025845 -276.648206) (xy 422.068466 -276.623599)
			(xy 422.114482 -276.606147) (xy 422.162701 -276.596303) (xy 422.211876 -276.594322) (xy 422.260731 -276.600254)
			(xy 422.308002 -276.613946) (xy 422.352464 -276.635044) (xy 422.392967 -276.663) (xy 422.42846 -276.697092)
			(xy 422.458025 -276.736436) (xy 422.480896 -276.780013) (xy 422.49648 -276.826694) (xy 422.504375 -276.875271)
			(xy 422.50487 -276.899878) (xy 422.843972 -276.899878) (xy 422.847932 -276.850824) (xy 422.859709 -276.80304)
			(xy 422.879 -276.757764) (xy 422.905303 -276.716168) (xy 422.937938 -276.679331) (xy 422.976059 -276.648206)
			(xy 423.01868 -276.623599) (xy 423.064696 -276.606147) (xy 423.112915 -276.596303) (xy 423.16209 -276.594322)
			(xy 423.210945 -276.600254) (xy 423.258216 -276.613946) (xy 423.302678 -276.635044) (xy 423.343181 -276.663)
			(xy 423.378674 -276.697092) (xy 423.408239 -276.736436) (xy 423.43111 -276.780013) (xy 423.446694 -276.826694)
			(xy 423.454589 -276.875271) (xy 423.455084 -276.899878) (xy 423.793932 -276.899878) (xy 423.797892 -276.850824)
			(xy 423.809669 -276.80304) (xy 423.82896 -276.757764) (xy 423.855263 -276.716168) (xy 423.887898 -276.679331)
			(xy 423.926019 -276.648206) (xy 423.96864 -276.623599) (xy 424.014656 -276.606147) (xy 424.062875 -276.596303)
			(xy 424.11205 -276.594322) (xy 424.160905 -276.600254) (xy 424.208176 -276.613946) (xy 424.252638 -276.635044)
			(xy 424.293141 -276.663) (xy 424.328634 -276.697092) (xy 424.358199 -276.736436) (xy 424.38107 -276.780013)
			(xy 424.396654 -276.826694) (xy 424.404549 -276.875271) (xy 424.405044 -276.899878) (xy 424.743892 -276.899878)
			(xy 424.747852 -276.850824) (xy 424.759629 -276.80304) (xy 424.77892 -276.757764) (xy 424.805223 -276.716168)
			(xy 424.837858 -276.679331) (xy 424.875979 -276.648206) (xy 424.9186 -276.623599) (xy 424.964616 -276.606147)
			(xy 425.012835 -276.596303) (xy 425.06201 -276.594322) (xy 425.110865 -276.600254) (xy 425.158136 -276.613946)
			(xy 425.202598 -276.635044) (xy 425.243101 -276.663) (xy 425.278594 -276.697092) (xy 425.308159 -276.736436)
			(xy 425.33103 -276.780013) (xy 425.346614 -276.826694) (xy 425.354509 -276.875271) (xy 425.355004 -276.899878)
			(xy 425.693852 -276.899878) (xy 425.697812 -276.850824) (xy 425.709589 -276.80304) (xy 425.72888 -276.757764)
			(xy 425.755183 -276.716168) (xy 425.787818 -276.679331) (xy 425.825939 -276.648206) (xy 425.86856 -276.623599)
			(xy 425.914576 -276.606147) (xy 425.962795 -276.596303) (xy 426.01197 -276.594322) (xy 426.060825 -276.600254)
			(xy 426.108096 -276.613946) (xy 426.152558 -276.635044) (xy 426.193061 -276.663) (xy 426.228554 -276.697092)
			(xy 426.258119 -276.736436) (xy 426.28099 -276.780013) (xy 426.296574 -276.826694) (xy 426.304469 -276.875271)
			(xy 426.304964 -276.899878) (xy 426.643812 -276.899878) (xy 426.647772 -276.850824) (xy 426.659549 -276.80304)
			(xy 426.67884 -276.757764) (xy 426.705143 -276.716168) (xy 426.737778 -276.679331) (xy 426.775899 -276.648206)
			(xy 426.81852 -276.623599) (xy 426.864536 -276.606147) (xy 426.912755 -276.596303) (xy 426.96193 -276.594322)
			(xy 427.010785 -276.600254) (xy 427.058056 -276.613946) (xy 427.102518 -276.635044) (xy 427.143021 -276.663)
			(xy 427.178514 -276.697092) (xy 427.208079 -276.736436) (xy 427.23095 -276.780013) (xy 427.246534 -276.826694)
			(xy 427.254429 -276.875271) (xy 427.254924 -276.899878) (xy 427.593772 -276.899878) (xy 427.597732 -276.850824)
			(xy 427.609509 -276.80304) (xy 427.6288 -276.757764) (xy 427.655103 -276.716168) (xy 427.687738 -276.679331)
			(xy 427.725859 -276.648206) (xy 427.76848 -276.623599) (xy 427.814496 -276.606147) (xy 427.862715 -276.596303)
			(xy 427.91189 -276.594322) (xy 427.960745 -276.600254) (xy 428.008016 -276.613946) (xy 428.052478 -276.635044)
			(xy 428.092981 -276.663) (xy 428.128474 -276.697092) (xy 428.158039 -276.736436) (xy 428.18091 -276.780013)
			(xy 428.196494 -276.826694) (xy 428.204389 -276.875271) (xy 428.204884 -276.899878) (xy 428.543986 -276.899878)
			(xy 428.547946 -276.850824) (xy 428.559723 -276.80304) (xy 428.579014 -276.757764) (xy 428.605317 -276.716168)
			(xy 428.637952 -276.679331) (xy 428.676073 -276.648206) (xy 428.718694 -276.623599) (xy 428.76471 -276.606147)
			(xy 428.812929 -276.596303) (xy 428.862104 -276.594322) (xy 428.910959 -276.600254) (xy 428.95823 -276.613946)
			(xy 429.002692 -276.635044) (xy 429.043195 -276.663) (xy 429.078688 -276.697092) (xy 429.108253 -276.736436)
			(xy 429.131124 -276.780013) (xy 429.146708 -276.826694) (xy 429.154603 -276.875271) (xy 429.155098 -276.899878)
			(xy 429.4942 -276.899878) (xy 429.49816 -276.850824) (xy 429.509937 -276.80304) (xy 429.529228 -276.757764)
			(xy 429.555531 -276.716168) (xy 429.588166 -276.679331) (xy 429.626287 -276.648206) (xy 429.668908 -276.623599)
			(xy 429.714924 -276.606147) (xy 429.763143 -276.596303) (xy 429.812318 -276.594322) (xy 429.861173 -276.600254)
			(xy 429.908444 -276.613946) (xy 429.952906 -276.635044) (xy 429.993409 -276.663) (xy 430.028902 -276.697092)
			(xy 430.058467 -276.736436) (xy 430.081338 -276.780013) (xy 430.096922 -276.826694) (xy 430.104817 -276.875271)
			(xy 430.105312 -276.899878) (xy 430.44416 -276.899878) (xy 430.44812 -276.850824) (xy 430.459897 -276.80304)
			(xy 430.479188 -276.757764) (xy 430.505491 -276.716168) (xy 430.538126 -276.679331) (xy 430.576247 -276.648206)
			(xy 430.618868 -276.623599) (xy 430.664884 -276.606147) (xy 430.713103 -276.596303) (xy 430.762278 -276.594322)
			(xy 430.811133 -276.600254) (xy 430.858404 -276.613946) (xy 430.902866 -276.635044) (xy 430.943369 -276.663)
			(xy 430.978862 -276.697092) (xy 431.008427 -276.736436) (xy 431.031298 -276.780013) (xy 431.046882 -276.826694)
			(xy 431.054777 -276.875271) (xy 431.055272 -276.899878) (xy 431.055267 -276.900132) (xy 431.394374 -276.900132)
			(xy 431.398334 -276.851078) (xy 431.410111 -276.803294) (xy 431.429402 -276.758018) (xy 431.455705 -276.716422)
			(xy 431.48834 -276.679585) (xy 431.526461 -276.64846) (xy 431.569082 -276.623853) (xy 431.615098 -276.606401)
			(xy 431.663317 -276.596557) (xy 431.712492 -276.594576) (xy 431.761347 -276.600508) (xy 431.808618 -276.6142)
			(xy 431.85308 -276.635298) (xy 431.893583 -276.663254) (xy 431.929076 -276.697346) (xy 431.958641 -276.73669)
			(xy 431.981512 -276.780267) (xy 431.997096 -276.826948) (xy 432.004991 -276.875525) (xy 432.005486 -276.900132)
			(xy 432.004991 -276.924739) (xy 431.997096 -276.973316) (xy 431.981512 -277.019997) (xy 431.958641 -277.063574)
			(xy 431.929076 -277.102918) (xy 431.893583 -277.13701) (xy 431.85308 -277.164966) (xy 431.808618 -277.186064)
			(xy 431.761347 -277.199756) (xy 431.712492 -277.205688) (xy 431.663317 -277.203707) (xy 431.615098 -277.193863)
			(xy 431.569082 -277.176411) (xy 431.526461 -277.151804) (xy 431.48834 -277.120679) (xy 431.455705 -277.083842)
			(xy 431.429402 -277.042246) (xy 431.410111 -276.99697) (xy 431.398334 -276.949186) (xy 431.394374 -276.900132)
			(xy 431.055267 -276.900132) (xy 431.054777 -276.924485) (xy 431.046882 -276.973062) (xy 431.031298 -277.019743)
			(xy 431.008427 -277.06332) (xy 430.978862 -277.102664) (xy 430.943369 -277.136756) (xy 430.902866 -277.164712)
			(xy 430.858404 -277.18581) (xy 430.811133 -277.199502) (xy 430.762278 -277.205434) (xy 430.713103 -277.203453)
			(xy 430.664884 -277.193609) (xy 430.618868 -277.176157) (xy 430.576247 -277.15155) (xy 430.538126 -277.120425)
			(xy 430.505491 -277.083588) (xy 430.479188 -277.041992) (xy 430.459897 -276.996716) (xy 430.44812 -276.948932)
			(xy 430.44416 -276.899878) (xy 430.105312 -276.899878) (xy 430.104817 -276.924485) (xy 430.096922 -276.973062)
			(xy 430.081338 -277.019743) (xy 430.058467 -277.06332) (xy 430.028902 -277.102664) (xy 429.993409 -277.136756)
			(xy 429.952906 -277.164712) (xy 429.908444 -277.18581) (xy 429.861173 -277.199502) (xy 429.812318 -277.205434)
			(xy 429.763143 -277.203453) (xy 429.714924 -277.193609) (xy 429.668908 -277.176157) (xy 429.626287 -277.15155)
			(xy 429.588166 -277.120425) (xy 429.555531 -277.083588) (xy 429.529228 -277.041992) (xy 429.509937 -276.996716)
			(xy 429.49816 -276.948932) (xy 429.4942 -276.899878) (xy 429.155098 -276.899878) (xy 429.154603 -276.924485)
			(xy 429.146708 -276.973062) (xy 429.131124 -277.019743) (xy 429.108253 -277.06332) (xy 429.078688 -277.102664)
			(xy 429.043195 -277.136756) (xy 429.002692 -277.164712) (xy 428.95823 -277.18581) (xy 428.910959 -277.199502)
			(xy 428.862104 -277.205434) (xy 428.812929 -277.203453) (xy 428.76471 -277.193609) (xy 428.718694 -277.176157)
			(xy 428.676073 -277.15155) (xy 428.637952 -277.120425) (xy 428.605317 -277.083588) (xy 428.579014 -277.041992)
			(xy 428.559723 -276.996716) (xy 428.547946 -276.948932) (xy 428.543986 -276.899878) (xy 428.204884 -276.899878)
			(xy 428.204389 -276.924485) (xy 428.196494 -276.973062) (xy 428.18091 -277.019743) (xy 428.158039 -277.06332)
			(xy 428.128474 -277.102664) (xy 428.092981 -277.136756) (xy 428.052478 -277.164712) (xy 428.008016 -277.18581)
			(xy 427.960745 -277.199502) (xy 427.91189 -277.205434) (xy 427.862715 -277.203453) (xy 427.814496 -277.193609)
			(xy 427.76848 -277.176157) (xy 427.725859 -277.15155) (xy 427.687738 -277.120425) (xy 427.655103 -277.083588)
			(xy 427.6288 -277.041992) (xy 427.609509 -276.996716) (xy 427.597732 -276.948932) (xy 427.593772 -276.899878)
			(xy 427.254924 -276.899878) (xy 427.254429 -276.924485) (xy 427.246534 -276.973062) (xy 427.23095 -277.019743)
			(xy 427.208079 -277.06332) (xy 427.178514 -277.102664) (xy 427.143021 -277.136756) (xy 427.102518 -277.164712)
			(xy 427.058056 -277.18581) (xy 427.010785 -277.199502) (xy 426.96193 -277.205434) (xy 426.912755 -277.203453)
			(xy 426.864536 -277.193609) (xy 426.81852 -277.176157) (xy 426.775899 -277.15155) (xy 426.737778 -277.120425)
			(xy 426.705143 -277.083588) (xy 426.67884 -277.041992) (xy 426.659549 -276.996716) (xy 426.647772 -276.948932)
			(xy 426.643812 -276.899878) (xy 426.304964 -276.899878) (xy 426.304469 -276.924485) (xy 426.296574 -276.973062)
			(xy 426.28099 -277.019743) (xy 426.258119 -277.06332) (xy 426.228554 -277.102664) (xy 426.193061 -277.136756)
			(xy 426.152558 -277.164712) (xy 426.108096 -277.18581) (xy 426.060825 -277.199502) (xy 426.01197 -277.205434)
			(xy 425.962795 -277.203453) (xy 425.914576 -277.193609) (xy 425.86856 -277.176157) (xy 425.825939 -277.15155)
			(xy 425.787818 -277.120425) (xy 425.755183 -277.083588) (xy 425.72888 -277.041992) (xy 425.709589 -276.996716)
			(xy 425.697812 -276.948932) (xy 425.693852 -276.899878) (xy 425.355004 -276.899878) (xy 425.354509 -276.924485)
			(xy 425.346614 -276.973062) (xy 425.33103 -277.019743) (xy 425.308159 -277.06332) (xy 425.278594 -277.102664)
			(xy 425.243101 -277.136756) (xy 425.202598 -277.164712) (xy 425.158136 -277.18581) (xy 425.110865 -277.199502)
			(xy 425.06201 -277.205434) (xy 425.012835 -277.203453) (xy 424.964616 -277.193609) (xy 424.9186 -277.176157)
			(xy 424.875979 -277.15155) (xy 424.837858 -277.120425) (xy 424.805223 -277.083588) (xy 424.77892 -277.041992)
			(xy 424.759629 -276.996716) (xy 424.747852 -276.948932) (xy 424.743892 -276.899878) (xy 424.405044 -276.899878)
			(xy 424.404549 -276.924485) (xy 424.396654 -276.973062) (xy 424.38107 -277.019743) (xy 424.358199 -277.06332)
			(xy 424.328634 -277.102664) (xy 424.293141 -277.136756) (xy 424.252638 -277.164712) (xy 424.208176 -277.18581)
			(xy 424.160905 -277.199502) (xy 424.11205 -277.205434) (xy 424.062875 -277.203453) (xy 424.014656 -277.193609)
			(xy 423.96864 -277.176157) (xy 423.926019 -277.15155) (xy 423.887898 -277.120425) (xy 423.855263 -277.083588)
			(xy 423.82896 -277.041992) (xy 423.809669 -276.996716) (xy 423.797892 -276.948932) (xy 423.793932 -276.899878)
			(xy 423.455084 -276.899878) (xy 423.454589 -276.924485) (xy 423.446694 -276.973062) (xy 423.43111 -277.019743)
			(xy 423.408239 -277.06332) (xy 423.378674 -277.102664) (xy 423.343181 -277.136756) (xy 423.302678 -277.164712)
			(xy 423.258216 -277.18581) (xy 423.210945 -277.199502) (xy 423.16209 -277.205434) (xy 423.112915 -277.203453)
			(xy 423.064696 -277.193609) (xy 423.01868 -277.176157) (xy 422.976059 -277.15155) (xy 422.937938 -277.120425)
			(xy 422.905303 -277.083588) (xy 422.879 -277.041992) (xy 422.859709 -276.996716) (xy 422.847932 -276.948932)
			(xy 422.843972 -276.899878) (xy 422.50487 -276.899878) (xy 422.504375 -276.924485) (xy 422.49648 -276.973062)
			(xy 422.480896 -277.019743) (xy 422.458025 -277.06332) (xy 422.42846 -277.102664) (xy 422.392967 -277.136756)
			(xy 422.352464 -277.164712) (xy 422.308002 -277.18581) (xy 422.260731 -277.199502) (xy 422.211876 -277.205434)
			(xy 422.162701 -277.203453) (xy 422.114482 -277.193609) (xy 422.068466 -277.176157) (xy 422.025845 -277.15155)
			(xy 421.987724 -277.120425) (xy 421.955089 -277.083588) (xy 421.928786 -277.041992) (xy 421.909495 -276.996716)
			(xy 421.897718 -276.948932) (xy 421.893758 -276.899878) (xy 421.555164 -276.899878) (xy 421.554669 -276.924485)
			(xy 421.546774 -276.973062) (xy 421.53119 -277.019743) (xy 421.508319 -277.06332) (xy 421.478754 -277.102664)
			(xy 421.443261 -277.136756) (xy 421.402758 -277.164712) (xy 421.358296 -277.18581) (xy 421.311025 -277.199502)
			(xy 421.26217 -277.205434) (xy 421.212995 -277.203453) (xy 421.164776 -277.193609) (xy 421.11876 -277.176157)
			(xy 421.076139 -277.15155) (xy 421.038018 -277.120425) (xy 421.005383 -277.083588) (xy 420.97908 -277.041992)
			(xy 420.959789 -276.996716) (xy 420.948012 -276.948932) (xy 420.944052 -276.899878) (xy 420.605204 -276.899878)
			(xy 420.604709 -276.924485) (xy 420.596814 -276.973062) (xy 420.58123 -277.019743) (xy 420.558359 -277.06332)
			(xy 420.528794 -277.102664) (xy 420.493301 -277.136756) (xy 420.452798 -277.164712) (xy 420.408336 -277.18581)
			(xy 420.361065 -277.199502) (xy 420.31221 -277.205434) (xy 420.263035 -277.203453) (xy 420.214816 -277.193609)
			(xy 420.1688 -277.176157) (xy 420.126179 -277.15155) (xy 420.088058 -277.120425) (xy 420.055423 -277.083588)
			(xy 420.02912 -277.041992) (xy 420.009829 -276.996716) (xy 419.998052 -276.948932) (xy 419.994092 -276.899878)
			(xy 419.655244 -276.899878) (xy 419.654749 -276.924485) (xy 419.646854 -276.973062) (xy 419.63127 -277.019743)
			(xy 419.608399 -277.06332) (xy 419.578834 -277.102664) (xy 419.543341 -277.136756) (xy 419.502838 -277.164712)
			(xy 419.458376 -277.18581) (xy 419.411105 -277.199502) (xy 419.36225 -277.205434) (xy 419.313075 -277.203453)
			(xy 419.264856 -277.193609) (xy 419.21884 -277.176157) (xy 419.176219 -277.15155) (xy 419.138098 -277.120425)
			(xy 419.105463 -277.083588) (xy 419.07916 -277.041992) (xy 419.059869 -276.996716) (xy 419.048092 -276.948932)
			(xy 419.044132 -276.899878) (xy 418.705284 -276.899878) (xy 418.704789 -276.924485) (xy 418.696894 -276.973062)
			(xy 418.68131 -277.019743) (xy 418.658439 -277.06332) (xy 418.628874 -277.102664) (xy 418.593381 -277.136756)
			(xy 418.552878 -277.164712) (xy 418.508416 -277.18581) (xy 418.461145 -277.199502) (xy 418.41229 -277.205434)
			(xy 418.363115 -277.203453) (xy 418.314896 -277.193609) (xy 418.26888 -277.176157) (xy 418.226259 -277.15155)
			(xy 418.188138 -277.120425) (xy 418.155503 -277.083588) (xy 418.1292 -277.041992) (xy 418.109909 -276.996716)
			(xy 418.098132 -276.948932) (xy 418.094172 -276.899878) (xy 417.755324 -276.899878) (xy 417.754829 -276.924485)
			(xy 417.746934 -276.973062) (xy 417.73135 -277.019743) (xy 417.708479 -277.06332) (xy 417.678914 -277.102664)
			(xy 417.643421 -277.136756) (xy 417.602918 -277.164712) (xy 417.558456 -277.18581) (xy 417.511185 -277.199502)
			(xy 417.46233 -277.205434) (xy 417.413155 -277.203453) (xy 417.364936 -277.193609) (xy 417.31892 -277.176157)
			(xy 417.276299 -277.15155) (xy 417.238178 -277.120425) (xy 417.205543 -277.083588) (xy 417.17924 -277.041992)
			(xy 417.159949 -276.996716) (xy 417.148172 -276.948932) (xy 417.144212 -276.899878) (xy 416.80511 -276.899878)
			(xy 416.804615 -276.924485) (xy 416.79672 -276.973062) (xy 416.781136 -277.019743) (xy 416.758265 -277.06332)
			(xy 416.7287 -277.102664) (xy 416.693207 -277.136756) (xy 416.652704 -277.164712) (xy 416.608242 -277.18581)
			(xy 416.560971 -277.199502) (xy 416.512116 -277.205434) (xy 416.462941 -277.203453) (xy 416.414722 -277.193609)
			(xy 416.368706 -277.176157) (xy 416.326085 -277.15155) (xy 416.287964 -277.120425) (xy 416.255329 -277.083588)
			(xy 416.229026 -277.041992) (xy 416.209735 -276.996716) (xy 416.197958 -276.948932) (xy 416.193998 -276.899878)
			(xy 415.85515 -276.899878) (xy 415.854655 -276.924485) (xy 415.84676 -276.973062) (xy 415.831176 -277.019743)
			(xy 415.808305 -277.06332) (xy 415.77874 -277.102664) (xy 415.743247 -277.136756) (xy 415.702744 -277.164712)
			(xy 415.658282 -277.18581) (xy 415.611011 -277.199502) (xy 415.562156 -277.205434) (xy 415.512981 -277.203453)
			(xy 415.464762 -277.193609) (xy 415.418746 -277.176157) (xy 415.376125 -277.15155) (xy 415.338004 -277.120425)
			(xy 415.305369 -277.083588) (xy 415.279066 -277.041992) (xy 415.259775 -276.996716) (xy 415.247998 -276.948932)
			(xy 415.244038 -276.899878) (xy 414.90519 -276.899878) (xy 414.904695 -276.924485) (xy 414.8968 -276.973062)
			(xy 414.881216 -277.019743) (xy 414.858345 -277.06332) (xy 414.82878 -277.102664) (xy 414.793287 -277.136756)
			(xy 414.752784 -277.164712) (xy 414.708322 -277.18581) (xy 414.661051 -277.199502) (xy 414.612196 -277.205434)
			(xy 414.563021 -277.203453) (xy 414.514802 -277.193609) (xy 414.468786 -277.176157) (xy 414.426165 -277.15155)
			(xy 414.388044 -277.120425) (xy 414.355409 -277.083588) (xy 414.329106 -277.041992) (xy 414.309815 -276.996716)
			(xy 414.298038 -276.948932) (xy 414.294078 -276.899878) (xy 413.95523 -276.899878) (xy 413.954735 -276.924485)
			(xy 413.94684 -276.973062) (xy 413.931256 -277.019743) (xy 413.908385 -277.06332) (xy 413.87882 -277.102664)
			(xy 413.843327 -277.136756) (xy 413.802824 -277.164712) (xy 413.758362 -277.18581) (xy 413.711091 -277.199502)
			(xy 413.662236 -277.205434) (xy 413.613061 -277.203453) (xy 413.564842 -277.193609) (xy 413.518826 -277.176157)
			(xy 413.476205 -277.15155) (xy 413.438084 -277.120425) (xy 413.405449 -277.083588) (xy 413.379146 -277.041992)
			(xy 413.359855 -276.996716) (xy 413.348078 -276.948932) (xy 413.344118 -276.899878) (xy 413.00527 -276.899878)
			(xy 413.004775 -276.924485) (xy 412.99688 -276.973062) (xy 412.981296 -277.019743) (xy 412.958425 -277.06332)
			(xy 412.92886 -277.102664) (xy 412.893367 -277.136756) (xy 412.852864 -277.164712) (xy 412.808402 -277.18581)
			(xy 412.761131 -277.199502) (xy 412.712276 -277.205434) (xy 412.663101 -277.203453) (xy 412.614882 -277.193609)
			(xy 412.568866 -277.176157) (xy 412.526245 -277.15155) (xy 412.488124 -277.120425) (xy 412.455489 -277.083588)
			(xy 412.429186 -277.041992) (xy 412.409895 -276.996716) (xy 412.398118 -276.948932) (xy 412.394158 -276.899878)
			(xy 412.05531 -276.899878) (xy 412.054815 -276.924485) (xy 412.04692 -276.973062) (xy 412.031336 -277.019743)
			(xy 412.008465 -277.06332) (xy 411.9789 -277.102664) (xy 411.943407 -277.136756) (xy 411.902904 -277.164712)
			(xy 411.858442 -277.18581) (xy 411.811171 -277.199502) (xy 411.762316 -277.205434) (xy 411.713141 -277.203453)
			(xy 411.664922 -277.193609) (xy 411.618906 -277.176157) (xy 411.576285 -277.15155) (xy 411.538164 -277.120425)
			(xy 411.505529 -277.083588) (xy 411.479226 -277.041992) (xy 411.459935 -276.996716) (xy 411.448158 -276.948932)
			(xy 411.444198 -276.899878) (xy 411.105096 -276.899878) (xy 411.104601 -276.924485) (xy 411.096706 -276.973062)
			(xy 411.081122 -277.019743) (xy 411.058251 -277.06332) (xy 411.028686 -277.102664) (xy 410.993193 -277.136756)
			(xy 410.95269 -277.164712) (xy 410.908228 -277.18581) (xy 410.860957 -277.199502) (xy 410.812102 -277.205434)
			(xy 410.762927 -277.203453) (xy 410.714708 -277.193609) (xy 410.668692 -277.176157) (xy 410.626071 -277.15155)
			(xy 410.58795 -277.120425) (xy 410.555315 -277.083588) (xy 410.529012 -277.041992) (xy 410.509721 -276.996716)
			(xy 410.497944 -276.948932) (xy 410.493984 -276.899878) (xy 410.155095 -276.899878) (xy 410.15285 -276.941216)
			(xy 410.142173 -276.989699) (xy 410.123794 -277.035817) (xy 410.098196 -277.078353) (xy 410.066053 -277.116188)
			(xy 410.028213 -277.148325) (xy 409.985672 -277.173916) (xy 409.939551 -277.192288) (xy 409.891066 -277.202956)
			(xy 409.841494 -277.20564) (xy 409.79214 -277.200269) (xy 409.744306 -277.186984) (xy 409.699251 -277.166135)
			(xy 409.658162 -277.138271) (xy 409.622122 -277.104128) (xy 409.592081 -277.064603) (xy 409.568831 -277.02074)
			(xy 409.552982 -276.973692) (xy 409.544954 -276.924701) (xy 409.54452 -276.899878) (xy 409.544626 -276.890837)
			(xy 409.545771 -276.872792) (xy 409.546806 -276.86381) (xy 409.546806 -276.862794) (xy 409.547445 -276.851098)
			(xy 409.539361 -276.829142) (xy 409.531312 -276.82063) (xy 409.46324 -276.75586) (xy 409.440634 -276.749002)
			(xy 409.428696 -276.751034) (xy 409.415333 -276.753145) (xy 409.388375 -276.755434) (xy 409.374848 -276.755606)
			(xy 409.361321 -276.755426) (xy 409.334363 -276.75314) (xy 409.321 -276.751034) (xy 409.309062 -276.749002)
			(xy 409.286456 -276.75586) (xy 409.218384 -276.82063) (xy 409.210314 -276.829124) (xy 409.202252 -276.851094)
			(xy 409.20289 -276.862794) (xy 409.20289 -276.86381) (xy 409.203932 -276.872791) (xy 409.205079 -276.890837)
			(xy 409.205176 -276.899878) (xy 409.204654 -276.925133) (xy 409.196341 -276.974955) (xy 409.17994 -277.022729)
			(xy 409.155899 -277.067152) (xy 409.124875 -277.107012) (xy 409.087713 -277.141222) (xy 409.045427 -277.168848)
			(xy 408.999171 -277.189138) (xy 408.950206 -277.201538) (xy 408.899868 -277.205709) (xy 408.84953 -277.201538)
			(xy 408.800565 -277.189138) (xy 408.754309 -277.168848) (xy 408.712023 -277.141222) (xy 408.674861 -277.107012)
			(xy 408.643837 -277.067152) (xy 408.619796 -277.022729) (xy 408.603395 -276.974955) (xy 408.595082 -276.925133)
			(xy 408.59456 -276.899878) (xy 408.594666 -276.890837) (xy 408.595812 -276.872792) (xy 408.596846 -276.86381)
			(xy 408.596846 -276.862794) (xy 408.597486 -276.851097) (xy 408.589406 -276.829137) (xy 408.581352 -276.82063)
			(xy 408.51328 -276.75586) (xy 408.490674 -276.749002) (xy 408.478736 -276.751034) (xy 408.465436 -276.753138)
			(xy 408.438606 -276.755428) (xy 408.425142 -276.755606) (xy 408.424634 -276.755606) (xy 408.411171 -276.755419)
			(xy 408.38434 -276.753134) (xy 408.37104 -276.751034) (xy 408.359102 -276.749002) (xy 408.336496 -276.75586)
			(xy 408.268424 -276.82063) (xy 408.260349 -276.829122) (xy 408.25228 -276.851094) (xy 408.25293 -276.862794)
			(xy 408.25293 -276.86381) (xy 408.253972 -276.872791) (xy 408.255119 -276.890837) (xy 408.255216 -276.899878)
			(xy 408.254771 -276.923873) (xy 408.247268 -276.971271) (xy 408.232441 -277.016912) (xy 408.210657 -277.059672)
			(xy 408.182452 -277.098497) (xy 408.14852 -277.132432) (xy 408.109698 -277.160641) (xy 408.06694 -277.18243)
			(xy 408.0213 -277.197261) (xy 407.973902 -277.204769) (xy 407.949908 -277.205186) (xy 407.923535 -277.204631)
			(xy 407.871574 -277.19557) (xy 407.821942 -277.177718) (xy 407.776115 -277.151604) (xy 407.735456 -277.118005)
			(xy 407.701174 -277.07792) (xy 407.674288 -277.032542) (xy 407.664412 -277.008082) (xy 407.65984 -276.995636)
			(xy 407.640536 -276.979126) (xy 407.544016 -276.958298) (xy 407.535689 -276.956815) (xy 407.518906 -276.958835)
			(xy 407.503709 -276.966235) (xy 407.497534 -276.972014) (xy 407.134822 -277.334726) (xy 407.132625 -277.336758)
			(xy 458.091284 -277.336758) (xy 458.095355 -277.281136) (xy 458.107481 -277.226699) (xy 458.127404 -277.174608)
			(xy 458.1547 -277.125973) (xy 458.188786 -277.08183) (xy 458.228935 -277.043121) (xy 458.274293 -277.01067)
			(xy 458.323893 -276.985169) (xy 458.376677 -276.967162) (xy 458.43152 -276.957032) (xy 458.487254 -276.954995)
			(xy 458.542691 -276.961095) (xy 458.596648 -276.975201) (xy 458.647977 -276.997013) (xy 458.695583 -277.026067)
			(xy 458.738451 -277.061742) (xy 458.775668 -277.103279) (xy 458.806441 -277.149792) (xy 458.830113 -277.200289)
			(xy 458.846181 -277.253696) (xy 458.854301 -277.308872) (xy 458.854601 -277.325328) (xy 459.280766 -277.325328)
			(xy 459.284837 -277.269706) (xy 459.296963 -277.215269) (xy 459.316886 -277.163178) (xy 459.344182 -277.114543)
			(xy 459.378268 -277.0704) (xy 459.418417 -277.031691) (xy 459.463775 -276.99924) (xy 459.513375 -276.973739)
			(xy 459.566159 -276.955732) (xy 459.621002 -276.945602) (xy 459.676736 -276.943565) (xy 459.732173 -276.949665)
			(xy 459.78613 -276.963771) (xy 459.837459 -276.985583) (xy 459.885065 -277.014637) (xy 459.927933 -277.050312)
			(xy 459.96515 -277.091849) (xy 459.995923 -277.138362) (xy 460.019595 -277.188859) (xy 460.035663 -277.242266)
			(xy 460.043783 -277.297442) (xy 460.044292 -277.325328) (xy 460.043783 -277.353214) (xy 460.035663 -277.40839)
			(xy 460.019595 -277.461797) (xy 459.995923 -277.512294) (xy 459.96515 -277.558807) (xy 459.927933 -277.600344)
			(xy 459.885065 -277.636019) (xy 459.837459 -277.665073) (xy 459.78613 -277.686885) (xy 459.732173 -277.700991)
			(xy 459.676736 -277.707091) (xy 459.621002 -277.705054) (xy 459.566159 -277.694924) (xy 459.513375 -277.676917)
			(xy 459.463775 -277.651416) (xy 459.418417 -277.618965) (xy 459.378268 -277.580256) (xy 459.344182 -277.536113)
			(xy 459.316886 -277.487478) (xy 459.296963 -277.435387) (xy 459.284837 -277.38095) (xy 459.280766 -277.325328)
			(xy 458.854601 -277.325328) (xy 458.85481 -277.336758) (xy 458.854301 -277.364644) (xy 458.846181 -277.41982)
			(xy 458.830113 -277.473227) (xy 458.806441 -277.523724) (xy 458.775668 -277.570237) (xy 458.738451 -277.611774)
			(xy 458.695583 -277.647449) (xy 458.647977 -277.676503) (xy 458.596648 -277.698315) (xy 458.542691 -277.712421)
			(xy 458.487254 -277.718521) (xy 458.43152 -277.716484) (xy 458.376677 -277.706354) (xy 458.323893 -277.688347)
			(xy 458.274293 -277.662846) (xy 458.228935 -277.630395) (xy 458.188786 -277.591686) (xy 458.1547 -277.547543)
			(xy 458.127404 -277.498908) (xy 458.107481 -277.446817) (xy 458.095355 -277.39238) (xy 458.091284 -277.336758)
			(xy 407.132625 -277.336758) (xy 407.127423 -277.341568) (xy 407.108824 -277.349286) (xy 407.098754 -277.349712)
			(xy 406.885394 -277.349712) (xy 406.856438 -277.37689) (xy 406.854914 -277.396956) (xy 406.851104 -277.42896)
			(xy 406.849072 -277.440898) (xy 406.85593 -277.463504) (xy 406.9207 -277.531322) (xy 406.929134 -277.539368)
			(xy 406.950971 -277.547444) (xy 406.96261 -277.546816) (xy 406.963372 -277.546816) (xy 406.97248 -277.545761)
			(xy 406.99078 -277.544616) (xy 406.999948 -277.54453) (xy 407.024764 -277.54502) (xy 407.073742 -277.553056)
			(xy 407.120774 -277.568911) (xy 407.164622 -277.592165) (xy 407.204131 -277.622206) (xy 407.238259 -277.658242)
			(xy 407.266108 -277.699325) (xy 407.286944 -277.744373) (xy 407.300219 -277.792197) (xy 407.305581 -277.841539)
			(xy 407.305131 -277.849838) (xy 407.64385 -277.849838) (xy 407.64781 -277.800784) (xy 407.659587 -277.753)
			(xy 407.678878 -277.707724) (xy 407.705181 -277.666128) (xy 407.737816 -277.629291) (xy 407.775937 -277.598166)
			(xy 407.818558 -277.573559) (xy 407.864574 -277.556107) (xy 407.912793 -277.546263) (xy 407.961968 -277.544282)
			(xy 408.010823 -277.550214) (xy 408.058094 -277.563906) (xy 408.102556 -277.585004) (xy 408.143059 -277.61296)
			(xy 408.178552 -277.647052) (xy 408.208117 -277.686396) (xy 408.230988 -277.729973) (xy 408.246572 -277.776654)
			(xy 408.254467 -277.825231) (xy 408.254962 -277.849838) (xy 408.594064 -277.849838) (xy 408.598024 -277.800784)
			(xy 408.609801 -277.753) (xy 408.629092 -277.707724) (xy 408.655395 -277.666128) (xy 408.68803 -277.629291)
			(xy 408.726151 -277.598166) (xy 408.768772 -277.573559) (xy 408.814788 -277.556107) (xy 408.863007 -277.546263)
			(xy 408.912182 -277.544282) (xy 408.961037 -277.550214) (xy 409.008308 -277.563906) (xy 409.05277 -277.585004)
			(xy 409.093273 -277.61296) (xy 409.128766 -277.647052) (xy 409.158331 -277.686396) (xy 409.181202 -277.729973)
			(xy 409.196786 -277.776654) (xy 409.204681 -277.825231) (xy 409.205176 -277.849838) (xy 409.54377 -277.849838)
			(xy 409.54773 -277.800784) (xy 409.559507 -277.753) (xy 409.578798 -277.707724) (xy 409.605101 -277.666128)
			(xy 409.637736 -277.629291) (xy 409.675857 -277.598166) (xy 409.718478 -277.573559) (xy 409.764494 -277.556107)
			(xy 409.812713 -277.546263) (xy 409.861888 -277.544282) (xy 409.910743 -277.550214) (xy 409.958014 -277.563906)
			(xy 410.002476 -277.585004) (xy 410.042979 -277.61296) (xy 410.078472 -277.647052) (xy 410.108037 -277.686396)
			(xy 410.130908 -277.729973) (xy 410.146492 -277.776654) (xy 410.154387 -277.825231) (xy 410.154882 -277.849838)
			(xy 410.493984 -277.849838) (xy 410.497944 -277.800784) (xy 410.509721 -277.753) (xy 410.529012 -277.707724)
			(xy 410.555315 -277.666128) (xy 410.58795 -277.629291) (xy 410.626071 -277.598166) (xy 410.668692 -277.573559)
			(xy 410.714708 -277.556107) (xy 410.762927 -277.546263) (xy 410.812102 -277.544282) (xy 410.860957 -277.550214)
			(xy 410.908228 -277.563906) (xy 410.95269 -277.585004) (xy 410.993193 -277.61296) (xy 411.028686 -277.647052)
			(xy 411.058251 -277.686396) (xy 411.081122 -277.729973) (xy 411.096706 -277.776654) (xy 411.104601 -277.825231)
			(xy 411.105096 -277.849838) (xy 411.443944 -277.849838) (xy 411.447904 -277.800784) (xy 411.459681 -277.753)
			(xy 411.478972 -277.707724) (xy 411.505275 -277.666128) (xy 411.53791 -277.629291) (xy 411.576031 -277.598166)
			(xy 411.618652 -277.573559) (xy 411.664668 -277.556107) (xy 411.712887 -277.546263) (xy 411.762062 -277.544282)
			(xy 411.810917 -277.550214) (xy 411.858188 -277.563906) (xy 411.90265 -277.585004) (xy 411.943153 -277.61296)
			(xy 411.978646 -277.647052) (xy 412.008211 -277.686396) (xy 412.031082 -277.729973) (xy 412.046666 -277.776654)
			(xy 412.054561 -277.825231) (xy 412.055056 -277.849838) (xy 412.394158 -277.849838) (xy 412.398118 -277.800784)
			(xy 412.409895 -277.753) (xy 412.429186 -277.707724) (xy 412.455489 -277.666128) (xy 412.488124 -277.629291)
			(xy 412.526245 -277.598166) (xy 412.568866 -277.573559) (xy 412.614882 -277.556107) (xy 412.663101 -277.546263)
			(xy 412.712276 -277.544282) (xy 412.761131 -277.550214) (xy 412.808402 -277.563906) (xy 412.852864 -277.585004)
			(xy 412.893367 -277.61296) (xy 412.92886 -277.647052) (xy 412.958425 -277.686396) (xy 412.981296 -277.729973)
			(xy 412.99688 -277.776654) (xy 413.004775 -277.825231) (xy 413.00527 -277.849838) (xy 413.343864 -277.849838)
			(xy 413.347824 -277.800784) (xy 413.359601 -277.753) (xy 413.378892 -277.707724) (xy 413.405195 -277.666128)
			(xy 413.43783 -277.629291) (xy 413.475951 -277.598166) (xy 413.518572 -277.573559) (xy 413.564588 -277.556107)
			(xy 413.612807 -277.546263) (xy 413.661982 -277.544282) (xy 413.710837 -277.550214) (xy 413.758108 -277.563906)
			(xy 413.80257 -277.585004) (xy 413.843073 -277.61296) (xy 413.878566 -277.647052) (xy 413.908131 -277.686396)
			(xy 413.931002 -277.729973) (xy 413.946586 -277.776654) (xy 413.954481 -277.825231) (xy 413.954976 -277.849838)
			(xy 414.294078 -277.849838) (xy 414.298038 -277.800784) (xy 414.309815 -277.753) (xy 414.329106 -277.707724)
			(xy 414.355409 -277.666128) (xy 414.388044 -277.629291) (xy 414.426165 -277.598166) (xy 414.468786 -277.573559)
			(xy 414.514802 -277.556107) (xy 414.563021 -277.546263) (xy 414.612196 -277.544282) (xy 414.661051 -277.550214)
			(xy 414.708322 -277.563906) (xy 414.752784 -277.585004) (xy 414.793287 -277.61296) (xy 414.82878 -277.647052)
			(xy 414.858345 -277.686396) (xy 414.881216 -277.729973) (xy 414.8968 -277.776654) (xy 414.904695 -277.825231)
			(xy 414.90519 -277.849838) (xy 415.243784 -277.849838) (xy 415.247744 -277.800784) (xy 415.259521 -277.753)
			(xy 415.278812 -277.707724) (xy 415.305115 -277.666128) (xy 415.33775 -277.629291) (xy 415.375871 -277.598166)
			(xy 415.418492 -277.573559) (xy 415.464508 -277.556107) (xy 415.512727 -277.546263) (xy 415.561902 -277.544282)
			(xy 415.610757 -277.550214) (xy 415.658028 -277.563906) (xy 415.70249 -277.585004) (xy 415.742993 -277.61296)
			(xy 415.778486 -277.647052) (xy 415.808051 -277.686396) (xy 415.830922 -277.729973) (xy 415.846506 -277.776654)
			(xy 415.854401 -277.825231) (xy 415.854896 -277.849838) (xy 416.193998 -277.849838) (xy 416.197958 -277.800784)
			(xy 416.209735 -277.753) (xy 416.229026 -277.707724) (xy 416.255329 -277.666128) (xy 416.287964 -277.629291)
			(xy 416.326085 -277.598166) (xy 416.368706 -277.573559) (xy 416.414722 -277.556107) (xy 416.462941 -277.546263)
			(xy 416.512116 -277.544282) (xy 416.560971 -277.550214) (xy 416.608242 -277.563906) (xy 416.652704 -277.585004)
			(xy 416.693207 -277.61296) (xy 416.7287 -277.647052) (xy 416.758265 -277.686396) (xy 416.781136 -277.729973)
			(xy 416.79672 -277.776654) (xy 416.804615 -277.825231) (xy 416.80511 -277.849838) (xy 417.143958 -277.849838)
			(xy 417.147918 -277.800784) (xy 417.159695 -277.753) (xy 417.178986 -277.707724) (xy 417.205289 -277.666128)
			(xy 417.237924 -277.629291) (xy 417.276045 -277.598166) (xy 417.318666 -277.573559) (xy 417.364682 -277.556107)
			(xy 417.412901 -277.546263) (xy 417.462076 -277.544282) (xy 417.510931 -277.550214) (xy 417.558202 -277.563906)
			(xy 417.602664 -277.585004) (xy 417.643167 -277.61296) (xy 417.67866 -277.647052) (xy 417.708225 -277.686396)
			(xy 417.731096 -277.729973) (xy 417.74668 -277.776654) (xy 417.754575 -277.825231) (xy 417.75507 -277.849838)
			(xy 418.094172 -277.849838) (xy 418.098132 -277.800784) (xy 418.109909 -277.753) (xy 418.1292 -277.707724)
			(xy 418.155503 -277.666128) (xy 418.188138 -277.629291) (xy 418.226259 -277.598166) (xy 418.26888 -277.573559)
			(xy 418.314896 -277.556107) (xy 418.363115 -277.546263) (xy 418.41229 -277.544282) (xy 418.461145 -277.550214)
			(xy 418.508416 -277.563906) (xy 418.552878 -277.585004) (xy 418.593381 -277.61296) (xy 418.628874 -277.647052)
			(xy 418.658439 -277.686396) (xy 418.68131 -277.729973) (xy 418.696894 -277.776654) (xy 418.704789 -277.825231)
			(xy 418.705284 -277.849838) (xy 419.043878 -277.849838) (xy 419.047838 -277.800784) (xy 419.059615 -277.753)
			(xy 419.078906 -277.707724) (xy 419.105209 -277.666128) (xy 419.137844 -277.629291) (xy 419.175965 -277.598166)
			(xy 419.218586 -277.573559) (xy 419.264602 -277.556107) (xy 419.312821 -277.546263) (xy 419.361996 -277.544282)
			(xy 419.410851 -277.550214) (xy 419.458122 -277.563906) (xy 419.502584 -277.585004) (xy 419.543087 -277.61296)
			(xy 419.57858 -277.647052) (xy 419.608145 -277.686396) (xy 419.631016 -277.729973) (xy 419.6466 -277.776654)
			(xy 419.654495 -277.825231) (xy 419.65499 -277.849838) (xy 419.994092 -277.849838) (xy 419.998052 -277.800784)
			(xy 420.009829 -277.753) (xy 420.02912 -277.707724) (xy 420.055423 -277.666128) (xy 420.088058 -277.629291)
			(xy 420.126179 -277.598166) (xy 420.1688 -277.573559) (xy 420.214816 -277.556107) (xy 420.263035 -277.546263)
			(xy 420.31221 -277.544282) (xy 420.361065 -277.550214) (xy 420.408336 -277.563906) (xy 420.452798 -277.585004)
			(xy 420.493301 -277.61296) (xy 420.528794 -277.647052) (xy 420.558359 -277.686396) (xy 420.58123 -277.729973)
			(xy 420.596814 -277.776654) (xy 420.604709 -277.825231) (xy 420.605204 -277.849838) (xy 420.943798 -277.849838)
			(xy 420.947758 -277.800784) (xy 420.959535 -277.753) (xy 420.978826 -277.707724) (xy 421.005129 -277.666128)
			(xy 421.037764 -277.629291) (xy 421.075885 -277.598166) (xy 421.118506 -277.573559) (xy 421.164522 -277.556107)
			(xy 421.212741 -277.546263) (xy 421.261916 -277.544282) (xy 421.310771 -277.550214) (xy 421.358042 -277.563906)
			(xy 421.402504 -277.585004) (xy 421.443007 -277.61296) (xy 421.4785 -277.647052) (xy 421.508065 -277.686396)
			(xy 421.530936 -277.729973) (xy 421.54652 -277.776654) (xy 421.554415 -277.825231) (xy 421.55491 -277.849838)
			(xy 421.894012 -277.849838) (xy 421.897972 -277.800784) (xy 421.909749 -277.753) (xy 421.92904 -277.707724)
			(xy 421.955343 -277.666128) (xy 421.987978 -277.629291) (xy 422.026099 -277.598166) (xy 422.06872 -277.573559)
			(xy 422.114736 -277.556107) (xy 422.162955 -277.546263) (xy 422.21213 -277.544282) (xy 422.260985 -277.550214)
			(xy 422.308256 -277.563906) (xy 422.352718 -277.585004) (xy 422.393221 -277.61296) (xy 422.428714 -277.647052)
			(xy 422.458279 -277.686396) (xy 422.48115 -277.729973) (xy 422.496734 -277.776654) (xy 422.504629 -277.825231)
			(xy 422.505124 -277.849838) (xy 422.843972 -277.849838) (xy 422.847932 -277.800784) (xy 422.859709 -277.753)
			(xy 422.879 -277.707724) (xy 422.905303 -277.666128) (xy 422.937938 -277.629291) (xy 422.976059 -277.598166)
			(xy 423.01868 -277.573559) (xy 423.064696 -277.556107) (xy 423.112915 -277.546263) (xy 423.16209 -277.544282)
			(xy 423.210945 -277.550214) (xy 423.258216 -277.563906) (xy 423.302678 -277.585004) (xy 423.343181 -277.61296)
			(xy 423.378674 -277.647052) (xy 423.408239 -277.686396) (xy 423.43111 -277.729973) (xy 423.446694 -277.776654)
			(xy 423.454589 -277.825231) (xy 423.455084 -277.849838) (xy 423.794186 -277.849838) (xy 423.798146 -277.800784)
			(xy 423.809923 -277.753) (xy 423.829214 -277.707724) (xy 423.855517 -277.666128) (xy 423.888152 -277.629291)
			(xy 423.926273 -277.598166) (xy 423.968894 -277.573559) (xy 424.01491 -277.556107) (xy 424.063129 -277.546263)
			(xy 424.112304 -277.544282) (xy 424.161159 -277.550214) (xy 424.20843 -277.563906) (xy 424.252892 -277.585004)
			(xy 424.293395 -277.61296) (xy 424.328888 -277.647052) (xy 424.358453 -277.686396) (xy 424.381324 -277.729973)
			(xy 424.396908 -277.776654) (xy 424.404803 -277.825231) (xy 424.405298 -277.849838) (xy 424.743892 -277.849838)
			(xy 424.747852 -277.800784) (xy 424.759629 -277.753) (xy 424.77892 -277.707724) (xy 424.805223 -277.666128)
			(xy 424.837858 -277.629291) (xy 424.875979 -277.598166) (xy 424.9186 -277.573559) (xy 424.964616 -277.556107)
			(xy 425.012835 -277.546263) (xy 425.06201 -277.544282) (xy 425.110865 -277.550214) (xy 425.158136 -277.563906)
			(xy 425.202598 -277.585004) (xy 425.243101 -277.61296) (xy 425.278594 -277.647052) (xy 425.308159 -277.686396)
			(xy 425.33103 -277.729973) (xy 425.346614 -277.776654) (xy 425.354509 -277.825231) (xy 425.355004 -277.849838)
			(xy 425.694106 -277.849838) (xy 425.698066 -277.800784) (xy 425.709843 -277.753) (xy 425.729134 -277.707724)
			(xy 425.755437 -277.666128) (xy 425.788072 -277.629291) (xy 425.826193 -277.598166) (xy 425.868814 -277.573559)
			(xy 425.91483 -277.556107) (xy 425.963049 -277.546263) (xy 426.012224 -277.544282) (xy 426.061079 -277.550214)
			(xy 426.10835 -277.563906) (xy 426.152812 -277.585004) (xy 426.193315 -277.61296) (xy 426.228808 -277.647052)
			(xy 426.258373 -277.686396) (xy 426.281244 -277.729973) (xy 426.296828 -277.776654) (xy 426.304723 -277.825231)
			(xy 426.305218 -277.849838) (xy 426.643812 -277.849838) (xy 426.647772 -277.800784) (xy 426.659549 -277.753)
			(xy 426.67884 -277.707724) (xy 426.705143 -277.666128) (xy 426.737778 -277.629291) (xy 426.775899 -277.598166)
			(xy 426.81852 -277.573559) (xy 426.864536 -277.556107) (xy 426.912755 -277.546263) (xy 426.96193 -277.544282)
			(xy 427.010785 -277.550214) (xy 427.058056 -277.563906) (xy 427.102518 -277.585004) (xy 427.143021 -277.61296)
			(xy 427.178514 -277.647052) (xy 427.208079 -277.686396) (xy 427.23095 -277.729973) (xy 427.246534 -277.776654)
			(xy 427.254429 -277.825231) (xy 427.254924 -277.849838) (xy 427.594026 -277.849838) (xy 427.597986 -277.800784)
			(xy 427.609763 -277.753) (xy 427.629054 -277.707724) (xy 427.655357 -277.666128) (xy 427.687992 -277.629291)
			(xy 427.726113 -277.598166) (xy 427.768734 -277.573559) (xy 427.81475 -277.556107) (xy 427.862969 -277.546263)
			(xy 427.912144 -277.544282) (xy 427.960999 -277.550214) (xy 428.00827 -277.563906) (xy 428.052732 -277.585004)
			(xy 428.093235 -277.61296) (xy 428.128728 -277.647052) (xy 428.158293 -277.686396) (xy 428.181164 -277.729973)
			(xy 428.196748 -277.776654) (xy 428.204643 -277.825231) (xy 428.205138 -277.849838) (xy 428.543986 -277.849838)
			(xy 428.547946 -277.800784) (xy 428.559723 -277.753) (xy 428.579014 -277.707724) (xy 428.605317 -277.666128)
			(xy 428.637952 -277.629291) (xy 428.676073 -277.598166) (xy 428.718694 -277.573559) (xy 428.76471 -277.556107)
			(xy 428.812929 -277.546263) (xy 428.862104 -277.544282) (xy 428.910959 -277.550214) (xy 428.95823 -277.563906)
			(xy 429.002692 -277.585004) (xy 429.043195 -277.61296) (xy 429.078688 -277.647052) (xy 429.108253 -277.686396)
			(xy 429.131124 -277.729973) (xy 429.146708 -277.776654) (xy 429.154603 -277.825231) (xy 429.155098 -277.849838)
			(xy 429.4942 -277.849838) (xy 429.49816 -277.800784) (xy 429.509937 -277.753) (xy 429.529228 -277.707724)
			(xy 429.555531 -277.666128) (xy 429.588166 -277.629291) (xy 429.626287 -277.598166) (xy 429.668908 -277.573559)
			(xy 429.714924 -277.556107) (xy 429.763143 -277.546263) (xy 429.812318 -277.544282) (xy 429.861173 -277.550214)
			(xy 429.908444 -277.563906) (xy 429.952906 -277.585004) (xy 429.993409 -277.61296) (xy 430.028902 -277.647052)
			(xy 430.058467 -277.686396) (xy 430.081338 -277.729973) (xy 430.096922 -277.776654) (xy 430.104817 -277.825231)
			(xy 430.105312 -277.849838) (xy 430.44416 -277.849838) (xy 430.44812 -277.800784) (xy 430.459897 -277.753)
			(xy 430.479188 -277.707724) (xy 430.505491 -277.666128) (xy 430.538126 -277.629291) (xy 430.576247 -277.598166)
			(xy 430.618868 -277.573559) (xy 430.664884 -277.556107) (xy 430.713103 -277.546263) (xy 430.762278 -277.544282)
			(xy 430.811133 -277.550214) (xy 430.858404 -277.563906) (xy 430.902866 -277.585004) (xy 430.943369 -277.61296)
			(xy 430.978862 -277.647052) (xy 431.008427 -277.686396) (xy 431.031298 -277.729973) (xy 431.046882 -277.776654)
			(xy 431.054777 -277.825231) (xy 431.055272 -277.849838) (xy 431.054777 -277.874445) (xy 431.046882 -277.923022)
			(xy 431.031298 -277.969703) (xy 431.008427 -278.01328) (xy 430.978862 -278.052624) (xy 430.943369 -278.086716)
			(xy 430.902866 -278.114672) (xy 430.858404 -278.13577) (xy 430.811133 -278.149462) (xy 430.762278 -278.155394)
			(xy 430.713103 -278.153413) (xy 430.664884 -278.143569) (xy 430.618868 -278.126117) (xy 430.576247 -278.10151)
			(xy 430.538126 -278.070385) (xy 430.505491 -278.033548) (xy 430.479188 -277.991952) (xy 430.459897 -277.946676)
			(xy 430.44812 -277.898892) (xy 430.44416 -277.849838) (xy 430.105312 -277.849838) (xy 430.104817 -277.874445)
			(xy 430.096922 -277.923022) (xy 430.081338 -277.969703) (xy 430.058467 -278.01328) (xy 430.028902 -278.052624)
			(xy 429.993409 -278.086716) (xy 429.952906 -278.114672) (xy 429.908444 -278.13577) (xy 429.861173 -278.149462)
			(xy 429.812318 -278.155394) (xy 429.763143 -278.153413) (xy 429.714924 -278.143569) (xy 429.668908 -278.126117)
			(xy 429.626287 -278.10151) (xy 429.588166 -278.070385) (xy 429.555531 -278.033548) (xy 429.529228 -277.991952)
			(xy 429.509937 -277.946676) (xy 429.49816 -277.898892) (xy 429.4942 -277.849838) (xy 429.155098 -277.849838)
			(xy 429.154603 -277.874445) (xy 429.146708 -277.923022) (xy 429.131124 -277.969703) (xy 429.108253 -278.01328)
			(xy 429.078688 -278.052624) (xy 429.043195 -278.086716) (xy 429.002692 -278.114672) (xy 428.95823 -278.13577)
			(xy 428.910959 -278.149462) (xy 428.862104 -278.155394) (xy 428.812929 -278.153413) (xy 428.76471 -278.143569)
			(xy 428.718694 -278.126117) (xy 428.676073 -278.10151) (xy 428.637952 -278.070385) (xy 428.605317 -278.033548)
			(xy 428.579014 -277.991952) (xy 428.559723 -277.946676) (xy 428.547946 -277.898892) (xy 428.543986 -277.849838)
			(xy 428.205138 -277.849838) (xy 428.204643 -277.874445) (xy 428.196748 -277.923022) (xy 428.181164 -277.969703)
			(xy 428.158293 -278.01328) (xy 428.128728 -278.052624) (xy 428.093235 -278.086716) (xy 428.052732 -278.114672)
			(xy 428.00827 -278.13577) (xy 427.960999 -278.149462) (xy 427.912144 -278.155394) (xy 427.862969 -278.153413)
			(xy 427.81475 -278.143569) (xy 427.768734 -278.126117) (xy 427.726113 -278.10151) (xy 427.687992 -278.070385)
			(xy 427.655357 -278.033548) (xy 427.629054 -277.991952) (xy 427.609763 -277.946676) (xy 427.597986 -277.898892)
			(xy 427.594026 -277.849838) (xy 427.254924 -277.849838) (xy 427.254429 -277.874445) (xy 427.246534 -277.923022)
			(xy 427.23095 -277.969703) (xy 427.208079 -278.01328) (xy 427.178514 -278.052624) (xy 427.143021 -278.086716)
			(xy 427.102518 -278.114672) (xy 427.058056 -278.13577) (xy 427.010785 -278.149462) (xy 426.96193 -278.155394)
			(xy 426.912755 -278.153413) (xy 426.864536 -278.143569) (xy 426.81852 -278.126117) (xy 426.775899 -278.10151)
			(xy 426.737778 -278.070385) (xy 426.705143 -278.033548) (xy 426.67884 -277.991952) (xy 426.659549 -277.946676)
			(xy 426.647772 -277.898892) (xy 426.643812 -277.849838) (xy 426.305218 -277.849838) (xy 426.304723 -277.874445)
			(xy 426.296828 -277.923022) (xy 426.281244 -277.969703) (xy 426.258373 -278.01328) (xy 426.228808 -278.052624)
			(xy 426.193315 -278.086716) (xy 426.152812 -278.114672) (xy 426.10835 -278.13577) (xy 426.061079 -278.149462)
			(xy 426.012224 -278.155394) (xy 425.963049 -278.153413) (xy 425.91483 -278.143569) (xy 425.868814 -278.126117)
			(xy 425.826193 -278.10151) (xy 425.788072 -278.070385) (xy 425.755437 -278.033548) (xy 425.729134 -277.991952)
			(xy 425.709843 -277.946676) (xy 425.698066 -277.898892) (xy 425.694106 -277.849838) (xy 425.355004 -277.849838)
			(xy 425.354509 -277.874445) (xy 425.346614 -277.923022) (xy 425.33103 -277.969703) (xy 425.308159 -278.01328)
			(xy 425.278594 -278.052624) (xy 425.243101 -278.086716) (xy 425.202598 -278.114672) (xy 425.158136 -278.13577)
			(xy 425.110865 -278.149462) (xy 425.06201 -278.155394) (xy 425.012835 -278.153413) (xy 424.964616 -278.143569)
			(xy 424.9186 -278.126117) (xy 424.875979 -278.10151) (xy 424.837858 -278.070385) (xy 424.805223 -278.033548)
			(xy 424.77892 -277.991952) (xy 424.759629 -277.946676) (xy 424.747852 -277.898892) (xy 424.743892 -277.849838)
			(xy 424.405298 -277.849838) (xy 424.404803 -277.874445) (xy 424.396908 -277.923022) (xy 424.381324 -277.969703)
			(xy 424.358453 -278.01328) (xy 424.328888 -278.052624) (xy 424.293395 -278.086716) (xy 424.252892 -278.114672)
			(xy 424.20843 -278.13577) (xy 424.161159 -278.149462) (xy 424.112304 -278.155394) (xy 424.063129 -278.153413)
			(xy 424.01491 -278.143569) (xy 423.968894 -278.126117) (xy 423.926273 -278.10151) (xy 423.888152 -278.070385)
			(xy 423.855517 -278.033548) (xy 423.829214 -277.991952) (xy 423.809923 -277.946676) (xy 423.798146 -277.898892)
			(xy 423.794186 -277.849838) (xy 423.455084 -277.849838) (xy 423.454589 -277.874445) (xy 423.446694 -277.923022)
			(xy 423.43111 -277.969703) (xy 423.408239 -278.01328) (xy 423.378674 -278.052624) (xy 423.343181 -278.086716)
			(xy 423.302678 -278.114672) (xy 423.258216 -278.13577) (xy 423.210945 -278.149462) (xy 423.16209 -278.155394)
			(xy 423.112915 -278.153413) (xy 423.064696 -278.143569) (xy 423.01868 -278.126117) (xy 422.976059 -278.10151)
			(xy 422.937938 -278.070385) (xy 422.905303 -278.033548) (xy 422.879 -277.991952) (xy 422.859709 -277.946676)
			(xy 422.847932 -277.898892) (xy 422.843972 -277.849838) (xy 422.505124 -277.849838) (xy 422.504629 -277.874445)
			(xy 422.496734 -277.923022) (xy 422.48115 -277.969703) (xy 422.458279 -278.01328) (xy 422.428714 -278.052624)
			(xy 422.393221 -278.086716) (xy 422.352718 -278.114672) (xy 422.308256 -278.13577) (xy 422.260985 -278.149462)
			(xy 422.21213 -278.155394) (xy 422.162955 -278.153413) (xy 422.114736 -278.143569) (xy 422.06872 -278.126117)
			(xy 422.026099 -278.10151) (xy 421.987978 -278.070385) (xy 421.955343 -278.033548) (xy 421.92904 -277.991952)
			(xy 421.909749 -277.946676) (xy 421.897972 -277.898892) (xy 421.894012 -277.849838) (xy 421.55491 -277.849838)
			(xy 421.554415 -277.874445) (xy 421.54652 -277.923022) (xy 421.530936 -277.969703) (xy 421.508065 -278.01328)
			(xy 421.4785 -278.052624) (xy 421.443007 -278.086716) (xy 421.402504 -278.114672) (xy 421.358042 -278.13577)
			(xy 421.310771 -278.149462) (xy 421.261916 -278.155394) (xy 421.212741 -278.153413) (xy 421.164522 -278.143569)
			(xy 421.118506 -278.126117) (xy 421.075885 -278.10151) (xy 421.037764 -278.070385) (xy 421.005129 -278.033548)
			(xy 420.978826 -277.991952) (xy 420.959535 -277.946676) (xy 420.947758 -277.898892) (xy 420.943798 -277.849838)
			(xy 420.605204 -277.849838) (xy 420.604709 -277.874445) (xy 420.596814 -277.923022) (xy 420.58123 -277.969703)
			(xy 420.558359 -278.01328) (xy 420.528794 -278.052624) (xy 420.493301 -278.086716) (xy 420.452798 -278.114672)
			(xy 420.408336 -278.13577) (xy 420.361065 -278.149462) (xy 420.31221 -278.155394) (xy 420.263035 -278.153413)
			(xy 420.214816 -278.143569) (xy 420.1688 -278.126117) (xy 420.126179 -278.10151) (xy 420.088058 -278.070385)
			(xy 420.055423 -278.033548) (xy 420.02912 -277.991952) (xy 420.009829 -277.946676) (xy 419.998052 -277.898892)
			(xy 419.994092 -277.849838) (xy 419.65499 -277.849838) (xy 419.654495 -277.874445) (xy 419.6466 -277.923022)
			(xy 419.631016 -277.969703) (xy 419.608145 -278.01328) (xy 419.57858 -278.052624) (xy 419.543087 -278.086716)
			(xy 419.502584 -278.114672) (xy 419.458122 -278.13577) (xy 419.410851 -278.149462) (xy 419.361996 -278.155394)
			(xy 419.312821 -278.153413) (xy 419.264602 -278.143569) (xy 419.218586 -278.126117) (xy 419.175965 -278.10151)
			(xy 419.137844 -278.070385) (xy 419.105209 -278.033548) (xy 419.078906 -277.991952) (xy 419.059615 -277.946676)
			(xy 419.047838 -277.898892) (xy 419.043878 -277.849838) (xy 418.705284 -277.849838) (xy 418.704789 -277.874445)
			(xy 418.696894 -277.923022) (xy 418.68131 -277.969703) (xy 418.658439 -278.01328) (xy 418.628874 -278.052624)
			(xy 418.593381 -278.086716) (xy 418.552878 -278.114672) (xy 418.508416 -278.13577) (xy 418.461145 -278.149462)
			(xy 418.41229 -278.155394) (xy 418.363115 -278.153413) (xy 418.314896 -278.143569) (xy 418.26888 -278.126117)
			(xy 418.226259 -278.10151) (xy 418.188138 -278.070385) (xy 418.155503 -278.033548) (xy 418.1292 -277.991952)
			(xy 418.109909 -277.946676) (xy 418.098132 -277.898892) (xy 418.094172 -277.849838) (xy 417.75507 -277.849838)
			(xy 417.754575 -277.874445) (xy 417.74668 -277.923022) (xy 417.731096 -277.969703) (xy 417.708225 -278.01328)
			(xy 417.67866 -278.052624) (xy 417.643167 -278.086716) (xy 417.602664 -278.114672) (xy 417.558202 -278.13577)
			(xy 417.510931 -278.149462) (xy 417.462076 -278.155394) (xy 417.412901 -278.153413) (xy 417.364682 -278.143569)
			(xy 417.318666 -278.126117) (xy 417.276045 -278.10151) (xy 417.237924 -278.070385) (xy 417.205289 -278.033548)
			(xy 417.178986 -277.991952) (xy 417.159695 -277.946676) (xy 417.147918 -277.898892) (xy 417.143958 -277.849838)
			(xy 416.80511 -277.849838) (xy 416.804615 -277.874445) (xy 416.79672 -277.923022) (xy 416.781136 -277.969703)
			(xy 416.758265 -278.01328) (xy 416.7287 -278.052624) (xy 416.693207 -278.086716) (xy 416.652704 -278.114672)
			(xy 416.608242 -278.13577) (xy 416.560971 -278.149462) (xy 416.512116 -278.155394) (xy 416.462941 -278.153413)
			(xy 416.414722 -278.143569) (xy 416.368706 -278.126117) (xy 416.326085 -278.10151) (xy 416.287964 -278.070385)
			(xy 416.255329 -278.033548) (xy 416.229026 -277.991952) (xy 416.209735 -277.946676) (xy 416.197958 -277.898892)
			(xy 416.193998 -277.849838) (xy 415.854896 -277.849838) (xy 415.854401 -277.874445) (xy 415.846506 -277.923022)
			(xy 415.830922 -277.969703) (xy 415.808051 -278.01328) (xy 415.778486 -278.052624) (xy 415.742993 -278.086716)
			(xy 415.70249 -278.114672) (xy 415.658028 -278.13577) (xy 415.610757 -278.149462) (xy 415.561902 -278.155394)
			(xy 415.512727 -278.153413) (xy 415.464508 -278.143569) (xy 415.418492 -278.126117) (xy 415.375871 -278.10151)
			(xy 415.33775 -278.070385) (xy 415.305115 -278.033548) (xy 415.278812 -277.991952) (xy 415.259521 -277.946676)
			(xy 415.247744 -277.898892) (xy 415.243784 -277.849838) (xy 414.90519 -277.849838) (xy 414.904695 -277.874445)
			(xy 414.8968 -277.923022) (xy 414.881216 -277.969703) (xy 414.858345 -278.01328) (xy 414.82878 -278.052624)
			(xy 414.793287 -278.086716) (xy 414.752784 -278.114672) (xy 414.708322 -278.13577) (xy 414.661051 -278.149462)
			(xy 414.612196 -278.155394) (xy 414.563021 -278.153413) (xy 414.514802 -278.143569) (xy 414.468786 -278.126117)
			(xy 414.426165 -278.10151) (xy 414.388044 -278.070385) (xy 414.355409 -278.033548) (xy 414.329106 -277.991952)
			(xy 414.309815 -277.946676) (xy 414.298038 -277.898892) (xy 414.294078 -277.849838) (xy 413.954976 -277.849838)
			(xy 413.954481 -277.874445) (xy 413.946586 -277.923022) (xy 413.931002 -277.969703) (xy 413.908131 -278.01328)
			(xy 413.878566 -278.052624) (xy 413.843073 -278.086716) (xy 413.80257 -278.114672) (xy 413.758108 -278.13577)
			(xy 413.710837 -278.149462) (xy 413.661982 -278.155394) (xy 413.612807 -278.153413) (xy 413.564588 -278.143569)
			(xy 413.518572 -278.126117) (xy 413.475951 -278.10151) (xy 413.43783 -278.070385) (xy 413.405195 -278.033548)
			(xy 413.378892 -277.991952) (xy 413.359601 -277.946676) (xy 413.347824 -277.898892) (xy 413.343864 -277.849838)
			(xy 413.00527 -277.849838) (xy 413.004775 -277.874445) (xy 412.99688 -277.923022) (xy 412.981296 -277.969703)
			(xy 412.958425 -278.01328) (xy 412.92886 -278.052624) (xy 412.893367 -278.086716) (xy 412.852864 -278.114672)
			(xy 412.808402 -278.13577) (xy 412.761131 -278.149462) (xy 412.712276 -278.155394) (xy 412.663101 -278.153413)
			(xy 412.614882 -278.143569) (xy 412.568866 -278.126117) (xy 412.526245 -278.10151) (xy 412.488124 -278.070385)
			(xy 412.455489 -278.033548) (xy 412.429186 -277.991952) (xy 412.409895 -277.946676) (xy 412.398118 -277.898892)
			(xy 412.394158 -277.849838) (xy 412.055056 -277.849838) (xy 412.054561 -277.874445) (xy 412.046666 -277.923022)
			(xy 412.031082 -277.969703) (xy 412.008211 -278.01328) (xy 411.978646 -278.052624) (xy 411.943153 -278.086716)
			(xy 411.90265 -278.114672) (xy 411.858188 -278.13577) (xy 411.810917 -278.149462) (xy 411.762062 -278.155394)
			(xy 411.712887 -278.153413) (xy 411.664668 -278.143569) (xy 411.618652 -278.126117) (xy 411.576031 -278.10151)
			(xy 411.53791 -278.070385) (xy 411.505275 -278.033548) (xy 411.478972 -277.991952) (xy 411.459681 -277.946676)
			(xy 411.447904 -277.898892) (xy 411.443944 -277.849838) (xy 411.105096 -277.849838) (xy 411.104601 -277.874445)
			(xy 411.096706 -277.923022) (xy 411.081122 -277.969703) (xy 411.058251 -278.01328) (xy 411.028686 -278.052624)
			(xy 410.993193 -278.086716) (xy 410.95269 -278.114672) (xy 410.908228 -278.13577) (xy 410.860957 -278.149462)
			(xy 410.812102 -278.155394) (xy 410.762927 -278.153413) (xy 410.714708 -278.143569) (xy 410.668692 -278.126117)
			(xy 410.626071 -278.10151) (xy 410.58795 -278.070385) (xy 410.555315 -278.033548) (xy 410.529012 -277.991952)
			(xy 410.509721 -277.946676) (xy 410.497944 -277.898892) (xy 410.493984 -277.849838) (xy 410.154882 -277.849838)
			(xy 410.154387 -277.874445) (xy 410.146492 -277.923022) (xy 410.130908 -277.969703) (xy 410.108037 -278.01328)
			(xy 410.078472 -278.052624) (xy 410.042979 -278.086716) (xy 410.002476 -278.114672) (xy 409.958014 -278.13577)
			(xy 409.910743 -278.149462) (xy 409.861888 -278.155394) (xy 409.812713 -278.153413) (xy 409.764494 -278.143569)
			(xy 409.718478 -278.126117) (xy 409.675857 -278.10151) (xy 409.637736 -278.070385) (xy 409.605101 -278.033548)
			(xy 409.578798 -277.991952) (xy 409.559507 -277.946676) (xy 409.54773 -277.898892) (xy 409.54377 -277.849838)
			(xy 409.205176 -277.849838) (xy 409.204681 -277.874445) (xy 409.196786 -277.923022) (xy 409.181202 -277.969703)
			(xy 409.158331 -278.01328) (xy 409.128766 -278.052624) (xy 409.093273 -278.086716) (xy 409.05277 -278.114672)
			(xy 409.008308 -278.13577) (xy 408.961037 -278.149462) (xy 408.912182 -278.155394) (xy 408.863007 -278.153413)
			(xy 408.814788 -278.143569) (xy 408.768772 -278.126117) (xy 408.726151 -278.10151) (xy 408.68803 -278.070385)
			(xy 408.655395 -278.033548) (xy 408.629092 -277.991952) (xy 408.609801 -277.946676) (xy 408.598024 -277.898892)
			(xy 408.594064 -277.849838) (xy 408.254962 -277.849838) (xy 408.254467 -277.874445) (xy 408.246572 -277.923022)
			(xy 408.230988 -277.969703) (xy 408.208117 -278.01328) (xy 408.178552 -278.052624) (xy 408.143059 -278.086716)
			(xy 408.102556 -278.114672) (xy 408.058094 -278.13577) (xy 408.010823 -278.149462) (xy 407.961968 -278.155394)
			(xy 407.912793 -278.153413) (xy 407.864574 -278.143569) (xy 407.818558 -278.126117) (xy 407.775937 -278.10151)
			(xy 407.737816 -278.070385) (xy 407.705181 -278.033548) (xy 407.678878 -277.991952) (xy 407.659587 -277.946676)
			(xy 407.64781 -277.898892) (xy 407.64385 -277.849838) (xy 407.305131 -277.849838) (xy 407.302891 -277.891099)
			(xy 407.292219 -277.93957) (xy 407.273847 -277.985677) (xy 407.248257 -278.028204) (xy 407.216125 -278.066032)
			(xy 407.178296 -278.098163) (xy 407.135768 -278.123751) (xy 407.089661 -278.142122) (xy 407.041189 -278.152793)
			(xy 406.991629 -278.155481) (xy 406.942287 -278.150117) (xy 406.894463 -278.136841) (xy 406.849417 -278.116003)
			(xy 406.808335 -278.088153) (xy 406.772299 -278.054023) (xy 406.742259 -278.014514) (xy 406.719007 -277.970665)
			(xy 406.703154 -277.923632) (xy 406.695119 -277.874654) (xy 406.69464 -277.849838) (xy 406.694744 -277.840797)
			(xy 406.695886 -277.822751) (xy 406.696926 -277.81377) (xy 406.696926 -277.812754) (xy 406.697579 -277.801053)
			(xy 406.689515 -277.779075) (xy 406.681432 -277.77059) (xy 406.622504 -277.714456) (xy 406.613666 -277.706841)
			(xy 406.591441 -277.699833) (xy 406.579832 -277.700994) (xy 406.579324 -277.700994) (xy 406.552411 -277.704899)
			(xy 406.498033 -277.704899) (xy 406.47112 -277.700994) (xy 406.470104 -277.700994) (xy 406.458495 -277.699817)
			(xy 406.436269 -277.706836) (xy 406.427432 -277.714456) (xy 406.368504 -277.77059) (xy 406.360424 -277.779081)
			(xy 406.352341 -277.801053) (xy 406.35301 -277.812754) (xy 406.35301 -277.81377) (xy 406.35405 -277.822751)
			(xy 406.355193 -277.840797) (xy 406.355296 -277.849838) (xy 406.354823 -277.873827) (xy 406.347312 -277.921213)
			(xy 406.332481 -277.966841) (xy 406.310695 -278.009588) (xy 406.282491 -278.0484) (xy 406.248562 -278.082323)
			(xy 406.209745 -278.110521) (xy 406.166995 -278.1323) (xy 406.121365 -278.147123) (xy 406.073977 -278.154626)
			(xy 406.049988 -278.155146) (xy 406.017984 -278.153368) (xy 406.007062 -278.152352) (xy 405.996902 -278.155654)
			(xy 405.991946 -278.157394) (xy 405.982848 -278.162641) (xy 405.978868 -278.166068) (xy 405.92248 -278.216614)
			(xy 405.91498 -278.224163) (xy 405.906337 -278.243582) (xy 405.905716 -278.254206) (xy 405.905716 -278.299418)
			(xy 405.905462 -278.308308) (xy 405.905462 -278.312372) (xy 405.905716 -278.324818) (xy 405.905533 -278.338345)
			(xy 405.903963 -278.356822) (xy 456.56703 -278.356822) (xy 456.571101 -278.3012) (xy 456.583227 -278.246763)
			(xy 456.60315 -278.194672) (xy 456.630446 -278.146037) (xy 456.664532 -278.101894) (xy 456.704681 -278.063185)
			(xy 456.750039 -278.030734) (xy 456.799639 -278.005233) (xy 456.852423 -277.987226) (xy 456.907266 -277.977096)
			(xy 456.963 -277.975059) (xy 457.018437 -277.981159) (xy 457.072394 -277.995265) (xy 457.123723 -278.017077)
			(xy 457.171329 -278.046131) (xy 457.214197 -278.081806) (xy 457.251414 -278.123343) (xy 457.282187 -278.169856)
			(xy 457.305859 -278.220353) (xy 457.321927 -278.27376) (xy 457.330047 -278.328936) (xy 457.330556 -278.356822)
			(xy 457.330047 -278.384708) (xy 457.321927 -278.439884) (xy 457.305859 -278.493291) (xy 457.301129 -278.50338)
			(xy 458.091284 -278.50338) (xy 458.095355 -278.447758) (xy 458.107481 -278.393321) (xy 458.127404 -278.34123)
			(xy 458.1547 -278.292595) (xy 458.188786 -278.248452) (xy 458.228935 -278.209743) (xy 458.274293 -278.177292)
			(xy 458.323893 -278.151791) (xy 458.376677 -278.133784) (xy 458.43152 -278.123654) (xy 458.487254 -278.121617)
			(xy 458.542691 -278.127717) (xy 458.596648 -278.141823) (xy 458.647977 -278.163635) (xy 458.695583 -278.192689)
			(xy 458.738451 -278.228364) (xy 458.775668 -278.269901) (xy 458.806441 -278.316414) (xy 458.830113 -278.366911)
			(xy 458.846181 -278.420318) (xy 458.854301 -278.475494) (xy 458.854606 -278.492204) (xy 459.269336 -278.492204)
			(xy 459.273407 -278.436582) (xy 459.285533 -278.382145) (xy 459.305456 -278.330054) (xy 459.332752 -278.281419)
			(xy 459.366838 -278.237276) (xy 459.406987 -278.198567) (xy 459.452345 -278.166116) (xy 459.501945 -278.140615)
			(xy 459.554729 -278.122608) (xy 459.609572 -278.112478) (xy 459.665306 -278.110441) (xy 459.720743 -278.116541)
			(xy 459.7747 -278.130647) (xy 459.826029 -278.152459) (xy 459.873635 -278.181513) (xy 459.916503 -278.217188)
			(xy 459.95372 -278.258725) (xy 459.984493 -278.305238) (xy 460.008165 -278.355735) (xy 460.024233 -278.409142)
			(xy 460.032353 -278.464318) (xy 460.032862 -278.492204) (xy 460.032353 -278.52009) (xy 460.024233 -278.575266)
			(xy 460.008165 -278.628673) (xy 459.986528 -278.67483) (xy 461.074516 -278.67483) (xy 461.07505 -278.645914)
			(xy 461.083775 -278.588743) (xy 461.101029 -278.533544) (xy 461.126418 -278.481582) (xy 461.159359 -278.434048)
			(xy 461.199098 -278.39203) (xy 461.221582 -278.37384) (xy 461.228957 -278.367547) (xy 461.238758 -278.350839)
			(xy 461.240632 -278.341328) (xy 461.24114 -278.333708) (xy 461.24114 -278.253952) (xy 461.240632 -278.246332)
			(xy 461.238765 -278.236818) (xy 461.228967 -278.220104) (xy 461.221582 -278.21382) (xy 461.199104 -278.195622)
			(xy 461.15937 -278.153603) (xy 461.12643 -278.10607) (xy 461.101041 -278.05411) (xy 461.083783 -277.998914)
			(xy 461.075052 -277.941746) (xy 461.074516 -277.91283) (xy 461.075002 -277.885579) (xy 461.082758 -277.831631)
			(xy 461.098113 -277.779336) (xy 461.120755 -277.729759) (xy 461.150221 -277.683909) (xy 461.185912 -277.642718)
			(xy 461.227103 -277.607027) (xy 461.272953 -277.577561) (xy 461.32253 -277.554919) (xy 461.374825 -277.539564)
			(xy 461.428773 -277.531808) (xy 461.483275 -277.531808) (xy 461.537223 -277.539564) (xy 461.589518 -277.554919)
			(xy 461.639095 -277.577561) (xy 461.684945 -277.607027) (xy 461.726136 -277.642718) (xy 461.741197 -277.6601)
			(xy 463.093306 -277.6601) (xy 463.097377 -277.604478) (xy 463.109503 -277.550041) (xy 463.129426 -277.49795)
			(xy 463.156722 -277.449315) (xy 463.190808 -277.405172) (xy 463.230957 -277.366463) (xy 463.276315 -277.334012)
			(xy 463.325915 -277.308511) (xy 463.378699 -277.290504) (xy 463.433542 -277.280374) (xy 463.489276 -277.278337)
			(xy 463.544713 -277.284437) (xy 463.59867 -277.298543) (xy 463.649999 -277.320355) (xy 463.697605 -277.349409)
			(xy 463.740473 -277.385084) (xy 463.77769 -277.426621) (xy 463.808463 -277.473134) (xy 463.832135 -277.523631)
			(xy 463.848203 -277.577038) (xy 463.856323 -277.632214) (xy 463.856832 -277.6601) (xy 463.856323 -277.687986)
			(xy 463.848203 -277.743162) (xy 463.832135 -277.796569) (xy 463.808463 -277.847066) (xy 463.77769 -277.893579)
			(xy 463.740473 -277.935116) (xy 463.697605 -277.970791) (xy 463.649999 -277.999845) (xy 463.59867 -278.021657)
			(xy 463.544713 -278.035763) (xy 463.489276 -278.041863) (xy 463.433542 -278.039826) (xy 463.378699 -278.029696)
			(xy 463.325915 -278.011689) (xy 463.276315 -277.986188) (xy 463.230957 -277.953737) (xy 463.190808 -277.915028)
			(xy 463.156722 -277.870885) (xy 463.129426 -277.82225) (xy 463.109503 -277.770159) (xy 463.097377 -277.715722)
			(xy 463.093306 -277.6601) (xy 461.741197 -277.6601) (xy 461.761827 -277.683909) (xy 461.791293 -277.729759)
			(xy 461.813935 -277.779336) (xy 461.82929 -277.831631) (xy 461.837046 -277.885579) (xy 461.837532 -277.91283)
			(xy 461.836989 -277.941746) (xy 461.828269 -277.998917) (xy 461.811017 -278.054117) (xy 461.78563 -278.106079)
			(xy 461.75269 -278.153614) (xy 461.712951 -278.19563) (xy 461.690466 -278.21382) (xy 461.683061 -278.220082)
			(xy 461.673278 -278.236813) (xy 461.671416 -278.246332) (xy 461.670908 -278.253952) (xy 461.670908 -278.333708)
			(xy 461.671416 -278.341328) (xy 461.673287 -278.350842) (xy 461.683081 -278.367557) (xy 461.690466 -278.37384)
			(xy 461.712962 -278.392017) (xy 461.752698 -278.434039) (xy 461.785636 -278.481576) (xy 461.811023 -278.53354)
			(xy 461.828276 -278.588741) (xy 461.837 -278.645913) (xy 461.837532 -278.67483) (xy 461.837046 -278.702081)
			(xy 461.82929 -278.756029) (xy 461.813935 -278.808324) (xy 461.791293 -278.857901) (xy 461.761827 -278.903751)
			(xy 461.726136 -278.944942) (xy 461.684945 -278.980633) (xy 461.639095 -279.010099) (xy 461.589518 -279.032741)
			(xy 461.537223 -279.048096) (xy 461.483275 -279.055852) (xy 461.428773 -279.055852) (xy 461.374825 -279.048096)
			(xy 461.32253 -279.032741) (xy 461.272953 -279.010099) (xy 461.227103 -278.980633) (xy 461.185912 -278.944942)
			(xy 461.150221 -278.903751) (xy 461.120755 -278.857901) (xy 461.098113 -278.808324) (xy 461.082758 -278.756029)
			(xy 461.075002 -278.702081) (xy 461.074516 -278.67483) (xy 459.986528 -278.67483) (xy 459.984493 -278.67917)
			(xy 459.95372 -278.725683) (xy 459.916503 -278.76722) (xy 459.873635 -278.802895) (xy 459.826029 -278.831949)
			(xy 459.7747 -278.853761) (xy 459.720743 -278.867867) (xy 459.665306 -278.873967) (xy 459.609572 -278.87193)
			(xy 459.554729 -278.8618) (xy 459.501945 -278.843793) (xy 459.452345 -278.818292) (xy 459.406987 -278.785841)
			(xy 459.366838 -278.747132) (xy 459.332752 -278.702989) (xy 459.305456 -278.654354) (xy 459.285533 -278.602263)
			(xy 459.273407 -278.547826) (xy 459.269336 -278.492204) (xy 458.854606 -278.492204) (xy 458.85481 -278.50338)
			(xy 458.854301 -278.531266) (xy 458.846181 -278.586442) (xy 458.830113 -278.639849) (xy 458.806441 -278.690346)
			(xy 458.775668 -278.736859) (xy 458.738451 -278.778396) (xy 458.695583 -278.814071) (xy 458.647977 -278.843125)
			(xy 458.596648 -278.864937) (xy 458.542691 -278.879043) (xy 458.487254 -278.885143) (xy 458.43152 -278.883106)
			(xy 458.376677 -278.872976) (xy 458.323893 -278.854969) (xy 458.274293 -278.829468) (xy 458.228935 -278.797017)
			(xy 458.188786 -278.758308) (xy 458.1547 -278.714165) (xy 458.127404 -278.66553) (xy 458.107481 -278.613439)
			(xy 458.095355 -278.559002) (xy 458.091284 -278.50338) (xy 457.301129 -278.50338) (xy 457.282187 -278.543788)
			(xy 457.251414 -278.590301) (xy 457.214197 -278.631838) (xy 457.171329 -278.667513) (xy 457.123723 -278.696567)
			(xy 457.072394 -278.718379) (xy 457.018437 -278.732485) (xy 456.963 -278.738585) (xy 456.907266 -278.736548)
			(xy 456.852423 -278.726418) (xy 456.799639 -278.708411) (xy 456.750039 -278.68291) (xy 456.704681 -278.650459)
			(xy 456.664532 -278.61175) (xy 456.630446 -278.567607) (xy 456.60315 -278.518972) (xy 456.583227 -278.466881)
			(xy 456.571101 -278.412444) (xy 456.56703 -278.356822) (xy 405.903963 -278.356822) (xy 405.903242 -278.365302)
			(xy 405.901144 -278.378666) (xy 405.899112 -278.390604) (xy 405.90597 -278.41321) (xy 405.97074 -278.481282)
			(xy 405.979233 -278.489354) (xy 406.001204 -278.497418) (xy 406.012904 -278.496776) (xy 406.013412 -278.496776)
			(xy 406.02252 -278.495722) (xy 406.04082 -278.494579) (xy 406.049988 -278.49449) (xy 406.075247 -278.494982)
			(xy 406.125075 -278.503295) (xy 406.172855 -278.519696) (xy 406.217284 -278.543738) (xy 406.25715 -278.574766)
			(xy 406.291365 -278.611932) (xy 406.318996 -278.654222) (xy 406.339289 -278.700484) (xy 406.35169 -278.749456)
			(xy 406.355862 -278.799798) (xy 406.694144 -278.799798) (xy 406.698104 -278.750744) (xy 406.709881 -278.70296)
			(xy 406.729172 -278.657684) (xy 406.755475 -278.616088) (xy 406.78811 -278.579251) (xy 406.826231 -278.548126)
			(xy 406.868852 -278.523519) (xy 406.914868 -278.506067) (xy 406.963087 -278.496223) (xy 407.012262 -278.494242)
			(xy 407.061117 -278.500174) (xy 407.108388 -278.513866) (xy 407.15285 -278.534964) (xy 407.193353 -278.56292)
			(xy 407.228846 -278.597012) (xy 407.258411 -278.636356) (xy 407.281282 -278.679933) (xy 407.296866 -278.726614)
			(xy 407.304761 -278.775191) (xy 407.305256 -278.799798) (xy 407.64385 -278.799798) (xy 407.64781 -278.750744)
			(xy 407.659587 -278.70296) (xy 407.678878 -278.657684) (xy 407.705181 -278.616088) (xy 407.737816 -278.579251)
			(xy 407.775937 -278.548126) (xy 407.818558 -278.523519) (xy 407.864574 -278.506067) (xy 407.912793 -278.496223)
			(xy 407.961968 -278.494242) (xy 408.010823 -278.500174) (xy 408.058094 -278.513866) (xy 408.102556 -278.534964)
			(xy 408.143059 -278.56292) (xy 408.178552 -278.597012) (xy 408.208117 -278.636356) (xy 408.230988 -278.679933)
			(xy 408.246572 -278.726614) (xy 408.254467 -278.775191) (xy 408.254962 -278.799798) (xy 408.594064 -278.799798)
			(xy 408.598024 -278.750744) (xy 408.609801 -278.70296) (xy 408.629092 -278.657684) (xy 408.655395 -278.616088)
			(xy 408.68803 -278.579251) (xy 408.726151 -278.548126) (xy 408.768772 -278.523519) (xy 408.814788 -278.506067)
			(xy 408.863007 -278.496223) (xy 408.912182 -278.494242) (xy 408.961037 -278.500174) (xy 409.008308 -278.513866)
			(xy 409.05277 -278.534964) (xy 409.093273 -278.56292) (xy 409.128766 -278.597012) (xy 409.158331 -278.636356)
			(xy 409.181202 -278.679933) (xy 409.196786 -278.726614) (xy 409.204681 -278.775191) (xy 409.205176 -278.799798)
			(xy 409.54377 -278.799798) (xy 409.54773 -278.750744) (xy 409.559507 -278.70296) (xy 409.578798 -278.657684)
			(xy 409.605101 -278.616088) (xy 409.637736 -278.579251) (xy 409.675857 -278.548126) (xy 409.718478 -278.523519)
			(xy 409.764494 -278.506067) (xy 409.812713 -278.496223) (xy 409.861888 -278.494242) (xy 409.910743 -278.500174)
			(xy 409.958014 -278.513866) (xy 410.002476 -278.534964) (xy 410.042979 -278.56292) (xy 410.078472 -278.597012)
			(xy 410.108037 -278.636356) (xy 410.130908 -278.679933) (xy 410.146492 -278.726614) (xy 410.154387 -278.775191)
			(xy 410.154882 -278.799798) (xy 410.493984 -278.799798) (xy 410.497944 -278.750744) (xy 410.509721 -278.70296)
			(xy 410.529012 -278.657684) (xy 410.555315 -278.616088) (xy 410.58795 -278.579251) (xy 410.626071 -278.548126)
			(xy 410.668692 -278.523519) (xy 410.714708 -278.506067) (xy 410.762927 -278.496223) (xy 410.812102 -278.494242)
			(xy 410.860957 -278.500174) (xy 410.908228 -278.513866) (xy 410.95269 -278.534964) (xy 410.993193 -278.56292)
			(xy 411.028686 -278.597012) (xy 411.058251 -278.636356) (xy 411.081122 -278.679933) (xy 411.096706 -278.726614)
			(xy 411.104601 -278.775191) (xy 411.105096 -278.799798) (xy 411.443944 -278.799798) (xy 411.447904 -278.750744)
			(xy 411.459681 -278.70296) (xy 411.478972 -278.657684) (xy 411.505275 -278.616088) (xy 411.53791 -278.579251)
			(xy 411.576031 -278.548126) (xy 411.618652 -278.523519) (xy 411.664668 -278.506067) (xy 411.712887 -278.496223)
			(xy 411.762062 -278.494242) (xy 411.810917 -278.500174) (xy 411.858188 -278.513866) (xy 411.90265 -278.534964)
			(xy 411.943153 -278.56292) (xy 411.978646 -278.597012) (xy 412.008211 -278.636356) (xy 412.031082 -278.679933)
			(xy 412.046666 -278.726614) (xy 412.054561 -278.775191) (xy 412.055056 -278.799798) (xy 412.394158 -278.799798)
			(xy 412.398118 -278.750744) (xy 412.409895 -278.70296) (xy 412.429186 -278.657684) (xy 412.455489 -278.616088)
			(xy 412.488124 -278.579251) (xy 412.526245 -278.548126) (xy 412.568866 -278.523519) (xy 412.614882 -278.506067)
			(xy 412.663101 -278.496223) (xy 412.712276 -278.494242) (xy 412.761131 -278.500174) (xy 412.808402 -278.513866)
			(xy 412.852864 -278.534964) (xy 412.893367 -278.56292) (xy 412.92886 -278.597012) (xy 412.958425 -278.636356)
			(xy 412.981296 -278.679933) (xy 412.99688 -278.726614) (xy 413.004775 -278.775191) (xy 413.00527 -278.799798)
			(xy 413.343864 -278.799798) (xy 413.347824 -278.750744) (xy 413.359601 -278.70296) (xy 413.378892 -278.657684)
			(xy 413.405195 -278.616088) (xy 413.43783 -278.579251) (xy 413.475951 -278.548126) (xy 413.518572 -278.523519)
			(xy 413.564588 -278.506067) (xy 413.612807 -278.496223) (xy 413.661982 -278.494242) (xy 413.710837 -278.500174)
			(xy 413.758108 -278.513866) (xy 413.80257 -278.534964) (xy 413.843073 -278.56292) (xy 413.878566 -278.597012)
			(xy 413.908131 -278.636356) (xy 413.931002 -278.679933) (xy 413.946586 -278.726614) (xy 413.954481 -278.775191)
			(xy 413.954976 -278.799798) (xy 414.294078 -278.799798) (xy 414.298038 -278.750744) (xy 414.309815 -278.70296)
			(xy 414.329106 -278.657684) (xy 414.355409 -278.616088) (xy 414.388044 -278.579251) (xy 414.426165 -278.548126)
			(xy 414.468786 -278.523519) (xy 414.514802 -278.506067) (xy 414.563021 -278.496223) (xy 414.612196 -278.494242)
			(xy 414.661051 -278.500174) (xy 414.708322 -278.513866) (xy 414.752784 -278.534964) (xy 414.793287 -278.56292)
			(xy 414.82878 -278.597012) (xy 414.858345 -278.636356) (xy 414.881216 -278.679933) (xy 414.8968 -278.726614)
			(xy 414.904695 -278.775191) (xy 414.90519 -278.799798) (xy 415.243784 -278.799798) (xy 415.247744 -278.750744)
			(xy 415.259521 -278.70296) (xy 415.278812 -278.657684) (xy 415.305115 -278.616088) (xy 415.33775 -278.579251)
			(xy 415.375871 -278.548126) (xy 415.418492 -278.523519) (xy 415.464508 -278.506067) (xy 415.512727 -278.496223)
			(xy 415.561902 -278.494242) (xy 415.610757 -278.500174) (xy 415.658028 -278.513866) (xy 415.70249 -278.534964)
			(xy 415.742993 -278.56292) (xy 415.778486 -278.597012) (xy 415.808051 -278.636356) (xy 415.830922 -278.679933)
			(xy 415.846506 -278.726614) (xy 415.854401 -278.775191) (xy 415.854896 -278.799798) (xy 416.193998 -278.799798)
			(xy 416.197958 -278.750744) (xy 416.209735 -278.70296) (xy 416.229026 -278.657684) (xy 416.255329 -278.616088)
			(xy 416.287964 -278.579251) (xy 416.326085 -278.548126) (xy 416.368706 -278.523519) (xy 416.414722 -278.506067)
			(xy 416.462941 -278.496223) (xy 416.512116 -278.494242) (xy 416.560971 -278.500174) (xy 416.608242 -278.513866)
			(xy 416.652704 -278.534964) (xy 416.693207 -278.56292) (xy 416.7287 -278.597012) (xy 416.758265 -278.636356)
			(xy 416.781136 -278.679933) (xy 416.79672 -278.726614) (xy 416.804615 -278.775191) (xy 416.80511 -278.799798)
			(xy 417.143958 -278.799798) (xy 417.147918 -278.750744) (xy 417.159695 -278.70296) (xy 417.178986 -278.657684)
			(xy 417.205289 -278.616088) (xy 417.237924 -278.579251) (xy 417.276045 -278.548126) (xy 417.318666 -278.523519)
			(xy 417.364682 -278.506067) (xy 417.412901 -278.496223) (xy 417.462076 -278.494242) (xy 417.510931 -278.500174)
			(xy 417.558202 -278.513866) (xy 417.602664 -278.534964) (xy 417.643167 -278.56292) (xy 417.67866 -278.597012)
			(xy 417.708225 -278.636356) (xy 417.731096 -278.679933) (xy 417.74668 -278.726614) (xy 417.754575 -278.775191)
			(xy 417.75507 -278.799798) (xy 418.094172 -278.799798) (xy 418.098132 -278.750744) (xy 418.109909 -278.70296)
			(xy 418.1292 -278.657684) (xy 418.155503 -278.616088) (xy 418.188138 -278.579251) (xy 418.226259 -278.548126)
			(xy 418.26888 -278.523519) (xy 418.314896 -278.506067) (xy 418.363115 -278.496223) (xy 418.41229 -278.494242)
			(xy 418.461145 -278.500174) (xy 418.508416 -278.513866) (xy 418.552878 -278.534964) (xy 418.593381 -278.56292)
			(xy 418.628874 -278.597012) (xy 418.658439 -278.636356) (xy 418.68131 -278.679933) (xy 418.696894 -278.726614)
			(xy 418.704789 -278.775191) (xy 418.705284 -278.799798) (xy 419.043878 -278.799798) (xy 419.047838 -278.750744)
			(xy 419.059615 -278.70296) (xy 419.078906 -278.657684) (xy 419.105209 -278.616088) (xy 419.137844 -278.579251)
			(xy 419.175965 -278.548126) (xy 419.218586 -278.523519) (xy 419.264602 -278.506067) (xy 419.312821 -278.496223)
			(xy 419.361996 -278.494242) (xy 419.410851 -278.500174) (xy 419.458122 -278.513866) (xy 419.502584 -278.534964)
			(xy 419.543087 -278.56292) (xy 419.57858 -278.597012) (xy 419.608145 -278.636356) (xy 419.631016 -278.679933)
			(xy 419.6466 -278.726614) (xy 419.654495 -278.775191) (xy 419.65499 -278.799798) (xy 419.994092 -278.799798)
			(xy 419.998052 -278.750744) (xy 420.009829 -278.70296) (xy 420.02912 -278.657684) (xy 420.055423 -278.616088)
			(xy 420.088058 -278.579251) (xy 420.126179 -278.548126) (xy 420.1688 -278.523519) (xy 420.214816 -278.506067)
			(xy 420.263035 -278.496223) (xy 420.31221 -278.494242) (xy 420.361065 -278.500174) (xy 420.408336 -278.513866)
			(xy 420.452798 -278.534964) (xy 420.493301 -278.56292) (xy 420.528794 -278.597012) (xy 420.558359 -278.636356)
			(xy 420.58123 -278.679933) (xy 420.596814 -278.726614) (xy 420.604709 -278.775191) (xy 420.605204 -278.799798)
			(xy 420.943798 -278.799798) (xy 420.947758 -278.750744) (xy 420.959535 -278.70296) (xy 420.978826 -278.657684)
			(xy 421.005129 -278.616088) (xy 421.037764 -278.579251) (xy 421.075885 -278.548126) (xy 421.118506 -278.523519)
			(xy 421.164522 -278.506067) (xy 421.212741 -278.496223) (xy 421.261916 -278.494242) (xy 421.310771 -278.500174)
			(xy 421.358042 -278.513866) (xy 421.402504 -278.534964) (xy 421.443007 -278.56292) (xy 421.4785 -278.597012)
			(xy 421.508065 -278.636356) (xy 421.530936 -278.679933) (xy 421.54652 -278.726614) (xy 421.554415 -278.775191)
			(xy 421.55491 -278.799798) (xy 421.894012 -278.799798) (xy 421.897972 -278.750744) (xy 421.909749 -278.70296)
			(xy 421.92904 -278.657684) (xy 421.955343 -278.616088) (xy 421.987978 -278.579251) (xy 422.026099 -278.548126)
			(xy 422.06872 -278.523519) (xy 422.114736 -278.506067) (xy 422.162955 -278.496223) (xy 422.21213 -278.494242)
			(xy 422.260985 -278.500174) (xy 422.308256 -278.513866) (xy 422.352718 -278.534964) (xy 422.393221 -278.56292)
			(xy 422.428714 -278.597012) (xy 422.458279 -278.636356) (xy 422.48115 -278.679933) (xy 422.496734 -278.726614)
			(xy 422.504629 -278.775191) (xy 422.505124 -278.799798) (xy 422.843972 -278.799798) (xy 422.847932 -278.750744)
			(xy 422.859709 -278.70296) (xy 422.879 -278.657684) (xy 422.905303 -278.616088) (xy 422.937938 -278.579251)
			(xy 422.976059 -278.548126) (xy 423.01868 -278.523519) (xy 423.064696 -278.506067) (xy 423.112915 -278.496223)
			(xy 423.16209 -278.494242) (xy 423.210945 -278.500174) (xy 423.258216 -278.513866) (xy 423.302678 -278.534964)
			(xy 423.343181 -278.56292) (xy 423.378674 -278.597012) (xy 423.408239 -278.636356) (xy 423.43111 -278.679933)
			(xy 423.446694 -278.726614) (xy 423.454589 -278.775191) (xy 423.455084 -278.799798) (xy 423.794186 -278.799798)
			(xy 423.798146 -278.750744) (xy 423.809923 -278.70296) (xy 423.829214 -278.657684) (xy 423.855517 -278.616088)
			(xy 423.888152 -278.579251) (xy 423.926273 -278.548126) (xy 423.968894 -278.523519) (xy 424.01491 -278.506067)
			(xy 424.063129 -278.496223) (xy 424.112304 -278.494242) (xy 424.161159 -278.500174) (xy 424.20843 -278.513866)
			(xy 424.252892 -278.534964) (xy 424.293395 -278.56292) (xy 424.328888 -278.597012) (xy 424.358453 -278.636356)
			(xy 424.381324 -278.679933) (xy 424.396908 -278.726614) (xy 424.404803 -278.775191) (xy 424.405298 -278.799798)
			(xy 424.743892 -278.799798) (xy 424.747852 -278.750744) (xy 424.759629 -278.70296) (xy 424.77892 -278.657684)
			(xy 424.805223 -278.616088) (xy 424.837858 -278.579251) (xy 424.875979 -278.548126) (xy 424.9186 -278.523519)
			(xy 424.964616 -278.506067) (xy 425.012835 -278.496223) (xy 425.06201 -278.494242) (xy 425.110865 -278.500174)
			(xy 425.158136 -278.513866) (xy 425.202598 -278.534964) (xy 425.243101 -278.56292) (xy 425.278594 -278.597012)
			(xy 425.308159 -278.636356) (xy 425.33103 -278.679933) (xy 425.346614 -278.726614) (xy 425.354509 -278.775191)
			(xy 425.355004 -278.799798) (xy 425.694106 -278.799798) (xy 425.698066 -278.750744) (xy 425.709843 -278.70296)
			(xy 425.729134 -278.657684) (xy 425.755437 -278.616088) (xy 425.788072 -278.579251) (xy 425.826193 -278.548126)
			(xy 425.868814 -278.523519) (xy 425.91483 -278.506067) (xy 425.963049 -278.496223) (xy 426.012224 -278.494242)
			(xy 426.061079 -278.500174) (xy 426.10835 -278.513866) (xy 426.152812 -278.534964) (xy 426.193315 -278.56292)
			(xy 426.228808 -278.597012) (xy 426.258373 -278.636356) (xy 426.281244 -278.679933) (xy 426.296828 -278.726614)
			(xy 426.304723 -278.775191) (xy 426.305218 -278.799798) (xy 426.643812 -278.799798) (xy 426.647772 -278.750744)
			(xy 426.659549 -278.70296) (xy 426.67884 -278.657684) (xy 426.705143 -278.616088) (xy 426.737778 -278.579251)
			(xy 426.775899 -278.548126) (xy 426.81852 -278.523519) (xy 426.864536 -278.506067) (xy 426.912755 -278.496223)
			(xy 426.96193 -278.494242) (xy 427.010785 -278.500174) (xy 427.058056 -278.513866) (xy 427.102518 -278.534964)
			(xy 427.143021 -278.56292) (xy 427.178514 -278.597012) (xy 427.208079 -278.636356) (xy 427.23095 -278.679933)
			(xy 427.246534 -278.726614) (xy 427.254429 -278.775191) (xy 427.254924 -278.799798) (xy 427.594026 -278.799798)
			(xy 427.597986 -278.750744) (xy 427.609763 -278.70296) (xy 427.629054 -278.657684) (xy 427.655357 -278.616088)
			(xy 427.687992 -278.579251) (xy 427.726113 -278.548126) (xy 427.768734 -278.523519) (xy 427.81475 -278.506067)
			(xy 427.862969 -278.496223) (xy 427.912144 -278.494242) (xy 427.960999 -278.500174) (xy 428.00827 -278.513866)
			(xy 428.052732 -278.534964) (xy 428.093235 -278.56292) (xy 428.128728 -278.597012) (xy 428.158293 -278.636356)
			(xy 428.181164 -278.679933) (xy 428.196748 -278.726614) (xy 428.204643 -278.775191) (xy 428.205138 -278.799798)
			(xy 428.543986 -278.799798) (xy 428.547946 -278.750744) (xy 428.559723 -278.70296) (xy 428.579014 -278.657684)
			(xy 428.605317 -278.616088) (xy 428.637952 -278.579251) (xy 428.676073 -278.548126) (xy 428.718694 -278.523519)
			(xy 428.76471 -278.506067) (xy 428.812929 -278.496223) (xy 428.862104 -278.494242) (xy 428.910959 -278.500174)
			(xy 428.95823 -278.513866) (xy 429.002692 -278.534964) (xy 429.043195 -278.56292) (xy 429.078688 -278.597012)
			(xy 429.108253 -278.636356) (xy 429.131124 -278.679933) (xy 429.146708 -278.726614) (xy 429.154603 -278.775191)
			(xy 429.155098 -278.799798) (xy 429.4942 -278.799798) (xy 429.49816 -278.750744) (xy 429.509937 -278.70296)
			(xy 429.529228 -278.657684) (xy 429.555531 -278.616088) (xy 429.588166 -278.579251) (xy 429.626287 -278.548126)
			(xy 429.668908 -278.523519) (xy 429.714924 -278.506067) (xy 429.763143 -278.496223) (xy 429.812318 -278.494242)
			(xy 429.861173 -278.500174) (xy 429.908444 -278.513866) (xy 429.952906 -278.534964) (xy 429.993409 -278.56292)
			(xy 430.028902 -278.597012) (xy 430.058467 -278.636356) (xy 430.081338 -278.679933) (xy 430.096922 -278.726614)
			(xy 430.104817 -278.775191) (xy 430.105312 -278.799798) (xy 430.44416 -278.799798) (xy 430.44812 -278.750744)
			(xy 430.459897 -278.70296) (xy 430.479188 -278.657684) (xy 430.505491 -278.616088) (xy 430.538126 -278.579251)
			(xy 430.576247 -278.548126) (xy 430.618868 -278.523519) (xy 430.664884 -278.506067) (xy 430.713103 -278.496223)
			(xy 430.762278 -278.494242) (xy 430.811133 -278.500174) (xy 430.858404 -278.513866) (xy 430.902866 -278.534964)
			(xy 430.943369 -278.56292) (xy 430.978862 -278.597012) (xy 431.008427 -278.636356) (xy 431.031298 -278.679933)
			(xy 431.046882 -278.726614) (xy 431.054777 -278.775191) (xy 431.055272 -278.799798) (xy 431.054777 -278.824405)
			(xy 431.048786 -278.861266) (xy 447.862958 -278.861266) (xy 447.867029 -278.805644) (xy 447.879155 -278.751207)
			(xy 447.899078 -278.699116) (xy 447.926374 -278.650481) (xy 447.96046 -278.606338) (xy 448.000609 -278.567629)
			(xy 448.045967 -278.535178) (xy 448.095567 -278.509677) (xy 448.148351 -278.49167) (xy 448.203194 -278.48154)
			(xy 448.258928 -278.479503) (xy 448.314365 -278.485603) (xy 448.368322 -278.499709) (xy 448.419651 -278.521521)
			(xy 448.467257 -278.550575) (xy 448.510125 -278.58625) (xy 448.547342 -278.627787) (xy 448.578115 -278.6743)
			(xy 448.601787 -278.724797) (xy 448.617855 -278.778204) (xy 448.625975 -278.83338) (xy 448.626484 -278.861266)
			(xy 448.625975 -278.889152) (xy 448.617855 -278.944328) (xy 448.601787 -278.997735) (xy 448.578115 -279.048232)
			(xy 448.547342 -279.094745) (xy 448.510125 -279.136282) (xy 448.467257 -279.171957) (xy 448.422389 -279.19934)
			(xy 455.00112 -279.19934) (xy 455.005191 -279.143718) (xy 455.017317 -279.089281) (xy 455.03724 -279.03719)
			(xy 455.064536 -278.988555) (xy 455.098622 -278.944412) (xy 455.138771 -278.905703) (xy 455.184129 -278.873252)
			(xy 455.233729 -278.847751) (xy 455.286513 -278.829744) (xy 455.341356 -278.819614) (xy 455.39709 -278.817577)
			(xy 455.452527 -278.823677) (xy 455.506484 -278.837783) (xy 455.557813 -278.859595) (xy 455.605419 -278.888649)
			(xy 455.648287 -278.924324) (xy 455.685504 -278.965861) (xy 455.716277 -279.012374) (xy 455.739949 -279.062871)
			(xy 455.756017 -279.116278) (xy 455.764137 -279.171454) (xy 455.764646 -279.19934) (xy 455.764137 -279.227226)
			(xy 455.756017 -279.282402) (xy 455.739949 -279.335809) (xy 455.716277 -279.386306) (xy 455.685504 -279.432819)
			(xy 455.648287 -279.474356) (xy 455.605419 -279.510031) (xy 455.557813 -279.539085) (xy 455.506484 -279.560897)
			(xy 455.452527 -279.575003) (xy 455.39709 -279.581103) (xy 455.341356 -279.579066) (xy 455.286513 -279.568936)
			(xy 455.233729 -279.550929) (xy 455.184129 -279.525428) (xy 455.138771 -279.492977) (xy 455.098622 -279.454268)
			(xy 455.064536 -279.410125) (xy 455.03724 -279.36149) (xy 455.017317 -279.309399) (xy 455.005191 -279.254962)
			(xy 455.00112 -279.19934) (xy 448.422389 -279.19934) (xy 448.419651 -279.201011) (xy 448.368322 -279.222823)
			(xy 448.314365 -279.236929) (xy 448.258928 -279.243029) (xy 448.203194 -279.240992) (xy 448.148351 -279.230862)
			(xy 448.095567 -279.212855) (xy 448.045967 -279.187354) (xy 448.000609 -279.154903) (xy 447.96046 -279.116194)
			(xy 447.926374 -279.072051) (xy 447.899078 -279.023416) (xy 447.879155 -278.971325) (xy 447.867029 -278.916888)
			(xy 447.862958 -278.861266) (xy 431.048786 -278.861266) (xy 431.046882 -278.872982) (xy 431.031298 -278.919663)
			(xy 431.008427 -278.96324) (xy 430.978862 -279.002584) (xy 430.943369 -279.036676) (xy 430.902866 -279.064632)
			(xy 430.858404 -279.08573) (xy 430.811133 -279.099422) (xy 430.762278 -279.105354) (xy 430.713103 -279.103373)
			(xy 430.664884 -279.093529) (xy 430.618868 -279.076077) (xy 430.576247 -279.05147) (xy 430.538126 -279.020345)
			(xy 430.505491 -278.983508) (xy 430.479188 -278.941912) (xy 430.459897 -278.896636) (xy 430.44812 -278.848852)
			(xy 430.44416 -278.799798) (xy 430.105312 -278.799798) (xy 430.104817 -278.824405) (xy 430.096922 -278.872982)
			(xy 430.081338 -278.919663) (xy 430.058467 -278.96324) (xy 430.028902 -279.002584) (xy 429.993409 -279.036676)
			(xy 429.952906 -279.064632) (xy 429.908444 -279.08573) (xy 429.861173 -279.099422) (xy 429.812318 -279.105354)
			(xy 429.763143 -279.103373) (xy 429.714924 -279.093529) (xy 429.668908 -279.076077) (xy 429.626287 -279.05147)
			(xy 429.588166 -279.020345) (xy 429.555531 -278.983508) (xy 429.529228 -278.941912) (xy 429.509937 -278.896636)
			(xy 429.49816 -278.848852) (xy 429.4942 -278.799798) (xy 429.155098 -278.799798) (xy 429.154603 -278.824405)
			(xy 429.146708 -278.872982) (xy 429.131124 -278.919663) (xy 429.108253 -278.96324) (xy 429.078688 -279.002584)
			(xy 429.043195 -279.036676) (xy 429.002692 -279.064632) (xy 428.95823 -279.08573) (xy 428.910959 -279.099422)
			(xy 428.862104 -279.105354) (xy 428.812929 -279.103373) (xy 428.76471 -279.093529) (xy 428.718694 -279.076077)
			(xy 428.676073 -279.05147) (xy 428.637952 -279.020345) (xy 428.605317 -278.983508) (xy 428.579014 -278.941912)
			(xy 428.559723 -278.896636) (xy 428.547946 -278.848852) (xy 428.543986 -278.799798) (xy 428.205138 -278.799798)
			(xy 428.204643 -278.824405) (xy 428.196748 -278.872982) (xy 428.181164 -278.919663) (xy 428.158293 -278.96324)
			(xy 428.128728 -279.002584) (xy 428.093235 -279.036676) (xy 428.052732 -279.064632) (xy 428.00827 -279.08573)
			(xy 427.960999 -279.099422) (xy 427.912144 -279.105354) (xy 427.862969 -279.103373) (xy 427.81475 -279.093529)
			(xy 427.768734 -279.076077) (xy 427.726113 -279.05147) (xy 427.687992 -279.020345) (xy 427.655357 -278.983508)
			(xy 427.629054 -278.941912) (xy 427.609763 -278.896636) (xy 427.597986 -278.848852) (xy 427.594026 -278.799798)
			(xy 427.254924 -278.799798) (xy 427.254429 -278.824405) (xy 427.246534 -278.872982) (xy 427.23095 -278.919663)
			(xy 427.208079 -278.96324) (xy 427.178514 -279.002584) (xy 427.143021 -279.036676) (xy 427.102518 -279.064632)
			(xy 427.058056 -279.08573) (xy 427.010785 -279.099422) (xy 426.96193 -279.105354) (xy 426.912755 -279.103373)
			(xy 426.864536 -279.093529) (xy 426.81852 -279.076077) (xy 426.775899 -279.05147) (xy 426.737778 -279.020345)
			(xy 426.705143 -278.983508) (xy 426.67884 -278.941912) (xy 426.659549 -278.896636) (xy 426.647772 -278.848852)
			(xy 426.643812 -278.799798) (xy 426.305218 -278.799798) (xy 426.304723 -278.824405) (xy 426.296828 -278.872982)
			(xy 426.281244 -278.919663) (xy 426.258373 -278.96324) (xy 426.228808 -279.002584) (xy 426.193315 -279.036676)
			(xy 426.152812 -279.064632) (xy 426.10835 -279.08573) (xy 426.061079 -279.099422) (xy 426.012224 -279.105354)
			(xy 425.963049 -279.103373) (xy 425.91483 -279.093529) (xy 425.868814 -279.076077) (xy 425.826193 -279.05147)
			(xy 425.788072 -279.020345) (xy 425.755437 -278.983508) (xy 425.729134 -278.941912) (xy 425.709843 -278.896636)
			(xy 425.698066 -278.848852) (xy 425.694106 -278.799798) (xy 425.355004 -278.799798) (xy 425.354509 -278.824405)
			(xy 425.346614 -278.872982) (xy 425.33103 -278.919663) (xy 425.308159 -278.96324) (xy 425.278594 -279.002584)
			(xy 425.243101 -279.036676) (xy 425.202598 -279.064632) (xy 425.158136 -279.08573) (xy 425.110865 -279.099422)
			(xy 425.06201 -279.105354) (xy 425.012835 -279.103373) (xy 424.964616 -279.093529) (xy 424.9186 -279.076077)
			(xy 424.875979 -279.05147) (xy 424.837858 -279.020345) (xy 424.805223 -278.983508) (xy 424.77892 -278.941912)
			(xy 424.759629 -278.896636) (xy 424.747852 -278.848852) (xy 424.743892 -278.799798) (xy 424.405298 -278.799798)
			(xy 424.404803 -278.824405) (xy 424.396908 -278.872982) (xy 424.381324 -278.919663) (xy 424.358453 -278.96324)
			(xy 424.328888 -279.002584) (xy 424.293395 -279.036676) (xy 424.252892 -279.064632) (xy 424.20843 -279.08573)
			(xy 424.161159 -279.099422) (xy 424.112304 -279.105354) (xy 424.063129 -279.103373) (xy 424.01491 -279.093529)
			(xy 423.968894 -279.076077) (xy 423.926273 -279.05147) (xy 423.888152 -279.020345) (xy 423.855517 -278.983508)
			(xy 423.829214 -278.941912) (xy 423.809923 -278.896636) (xy 423.798146 -278.848852) (xy 423.794186 -278.799798)
			(xy 423.455084 -278.799798) (xy 423.454589 -278.824405) (xy 423.446694 -278.872982) (xy 423.43111 -278.919663)
			(xy 423.408239 -278.96324) (xy 423.378674 -279.002584) (xy 423.343181 -279.036676) (xy 423.302678 -279.064632)
			(xy 423.258216 -279.08573) (xy 423.210945 -279.099422) (xy 423.16209 -279.105354) (xy 423.112915 -279.103373)
			(xy 423.064696 -279.093529) (xy 423.01868 -279.076077) (xy 422.976059 -279.05147) (xy 422.937938 -279.020345)
			(xy 422.905303 -278.983508) (xy 422.879 -278.941912) (xy 422.859709 -278.896636) (xy 422.847932 -278.848852)
			(xy 422.843972 -278.799798) (xy 422.505124 -278.799798) (xy 422.504629 -278.824405) (xy 422.496734 -278.872982)
			(xy 422.48115 -278.919663) (xy 422.458279 -278.96324) (xy 422.428714 -279.002584) (xy 422.393221 -279.036676)
			(xy 422.352718 -279.064632) (xy 422.308256 -279.08573) (xy 422.260985 -279.099422) (xy 422.21213 -279.105354)
			(xy 422.162955 -279.103373) (xy 422.114736 -279.093529) (xy 422.06872 -279.076077) (xy 422.026099 -279.05147)
			(xy 421.987978 -279.020345) (xy 421.955343 -278.983508) (xy 421.92904 -278.941912) (xy 421.909749 -278.896636)
			(xy 421.897972 -278.848852) (xy 421.894012 -278.799798) (xy 421.55491 -278.799798) (xy 421.554415 -278.824405)
			(xy 421.54652 -278.872982) (xy 421.530936 -278.919663) (xy 421.508065 -278.96324) (xy 421.4785 -279.002584)
			(xy 421.443007 -279.036676) (xy 421.402504 -279.064632) (xy 421.358042 -279.08573) (xy 421.310771 -279.099422)
			(xy 421.261916 -279.105354) (xy 421.212741 -279.103373) (xy 421.164522 -279.093529) (xy 421.118506 -279.076077)
			(xy 421.075885 -279.05147) (xy 421.037764 -279.020345) (xy 421.005129 -278.983508) (xy 420.978826 -278.941912)
			(xy 420.959535 -278.896636) (xy 420.947758 -278.848852) (xy 420.943798 -278.799798) (xy 420.605204 -278.799798)
			(xy 420.604709 -278.824405) (xy 420.596814 -278.872982) (xy 420.58123 -278.919663) (xy 420.558359 -278.96324)
			(xy 420.528794 -279.002584) (xy 420.493301 -279.036676) (xy 420.452798 -279.064632) (xy 420.408336 -279.08573)
			(xy 420.361065 -279.099422) (xy 420.31221 -279.105354) (xy 420.263035 -279.103373) (xy 420.214816 -279.093529)
			(xy 420.1688 -279.076077) (xy 420.126179 -279.05147) (xy 420.088058 -279.020345) (xy 420.055423 -278.983508)
			(xy 420.02912 -278.941912) (xy 420.009829 -278.896636) (xy 419.998052 -278.848852) (xy 419.994092 -278.799798)
			(xy 419.65499 -278.799798) (xy 419.654495 -278.824405) (xy 419.6466 -278.872982) (xy 419.631016 -278.919663)
			(xy 419.608145 -278.96324) (xy 419.57858 -279.002584) (xy 419.543087 -279.036676) (xy 419.502584 -279.064632)
			(xy 419.458122 -279.08573) (xy 419.410851 -279.099422) (xy 419.361996 -279.105354) (xy 419.312821 -279.103373)
			(xy 419.264602 -279.093529) (xy 419.218586 -279.076077) (xy 419.175965 -279.05147) (xy 419.137844 -279.020345)
			(xy 419.105209 -278.983508) (xy 419.078906 -278.941912) (xy 419.059615 -278.896636) (xy 419.047838 -278.848852)
			(xy 419.043878 -278.799798) (xy 418.705284 -278.799798) (xy 418.704789 -278.824405) (xy 418.696894 -278.872982)
			(xy 418.68131 -278.919663) (xy 418.658439 -278.96324) (xy 418.628874 -279.002584) (xy 418.593381 -279.036676)
			(xy 418.552878 -279.064632) (xy 418.508416 -279.08573) (xy 418.461145 -279.099422) (xy 418.41229 -279.105354)
			(xy 418.363115 -279.103373) (xy 418.314896 -279.093529) (xy 418.26888 -279.076077) (xy 418.226259 -279.05147)
			(xy 418.188138 -279.020345) (xy 418.155503 -278.983508) (xy 418.1292 -278.941912) (xy 418.109909 -278.896636)
			(xy 418.098132 -278.848852) (xy 418.094172 -278.799798) (xy 417.75507 -278.799798) (xy 417.754575 -278.824405)
			(xy 417.74668 -278.872982) (xy 417.731096 -278.919663) (xy 417.708225 -278.96324) (xy 417.67866 -279.002584)
			(xy 417.643167 -279.036676) (xy 417.602664 -279.064632) (xy 417.558202 -279.08573) (xy 417.510931 -279.099422)
			(xy 417.462076 -279.105354) (xy 417.412901 -279.103373) (xy 417.364682 -279.093529) (xy 417.318666 -279.076077)
			(xy 417.276045 -279.05147) (xy 417.237924 -279.020345) (xy 417.205289 -278.983508) (xy 417.178986 -278.941912)
			(xy 417.159695 -278.896636) (xy 417.147918 -278.848852) (xy 417.143958 -278.799798) (xy 416.80511 -278.799798)
			(xy 416.804615 -278.824405) (xy 416.79672 -278.872982) (xy 416.781136 -278.919663) (xy 416.758265 -278.96324)
			(xy 416.7287 -279.002584) (xy 416.693207 -279.036676) (xy 416.652704 -279.064632) (xy 416.608242 -279.08573)
			(xy 416.560971 -279.099422) (xy 416.512116 -279.105354) (xy 416.462941 -279.103373) (xy 416.414722 -279.093529)
			(xy 416.368706 -279.076077) (xy 416.326085 -279.05147) (xy 416.287964 -279.020345) (xy 416.255329 -278.983508)
			(xy 416.229026 -278.941912) (xy 416.209735 -278.896636) (xy 416.197958 -278.848852) (xy 416.193998 -278.799798)
			(xy 415.854896 -278.799798) (xy 415.854401 -278.824405) (xy 415.846506 -278.872982) (xy 415.830922 -278.919663)
			(xy 415.808051 -278.96324) (xy 415.778486 -279.002584) (xy 415.742993 -279.036676) (xy 415.70249 -279.064632)
			(xy 415.658028 -279.08573) (xy 415.610757 -279.099422) (xy 415.561902 -279.105354) (xy 415.512727 -279.103373)
			(xy 415.464508 -279.093529) (xy 415.418492 -279.076077) (xy 415.375871 -279.05147) (xy 415.33775 -279.020345)
			(xy 415.305115 -278.983508) (xy 415.278812 -278.941912) (xy 415.259521 -278.896636) (xy 415.247744 -278.848852)
			(xy 415.243784 -278.799798) (xy 414.90519 -278.799798) (xy 414.904695 -278.824405) (xy 414.8968 -278.872982)
			(xy 414.881216 -278.919663) (xy 414.858345 -278.96324) (xy 414.82878 -279.002584) (xy 414.793287 -279.036676)
			(xy 414.752784 -279.064632) (xy 414.708322 -279.08573) (xy 414.661051 -279.099422) (xy 414.612196 -279.105354)
			(xy 414.563021 -279.103373) (xy 414.514802 -279.093529) (xy 414.468786 -279.076077) (xy 414.426165 -279.05147)
			(xy 414.388044 -279.020345) (xy 414.355409 -278.983508) (xy 414.329106 -278.941912) (xy 414.309815 -278.896636)
			(xy 414.298038 -278.848852) (xy 414.294078 -278.799798) (xy 413.954976 -278.799798) (xy 413.954481 -278.824405)
			(xy 413.946586 -278.872982) (xy 413.931002 -278.919663) (xy 413.908131 -278.96324) (xy 413.878566 -279.002584)
			(xy 413.843073 -279.036676) (xy 413.80257 -279.064632) (xy 413.758108 -279.08573) (xy 413.710837 -279.099422)
			(xy 413.661982 -279.105354) (xy 413.612807 -279.103373) (xy 413.564588 -279.093529) (xy 413.518572 -279.076077)
			(xy 413.475951 -279.05147) (xy 413.43783 -279.020345) (xy 413.405195 -278.983508) (xy 413.378892 -278.941912)
			(xy 413.359601 -278.896636) (xy 413.347824 -278.848852) (xy 413.343864 -278.799798) (xy 413.00527 -278.799798)
			(xy 413.004775 -278.824405) (xy 412.99688 -278.872982) (xy 412.981296 -278.919663) (xy 412.958425 -278.96324)
			(xy 412.92886 -279.002584) (xy 412.893367 -279.036676) (xy 412.852864 -279.064632) (xy 412.808402 -279.08573)
			(xy 412.761131 -279.099422) (xy 412.712276 -279.105354) (xy 412.663101 -279.103373) (xy 412.614882 -279.093529)
			(xy 412.568866 -279.076077) (xy 412.526245 -279.05147) (xy 412.488124 -279.020345) (xy 412.455489 -278.983508)
			(xy 412.429186 -278.941912) (xy 412.409895 -278.896636) (xy 412.398118 -278.848852) (xy 412.394158 -278.799798)
			(xy 412.055056 -278.799798) (xy 412.054561 -278.824405) (xy 412.046666 -278.872982) (xy 412.031082 -278.919663)
			(xy 412.008211 -278.96324) (xy 411.978646 -279.002584) (xy 411.943153 -279.036676) (xy 411.90265 -279.064632)
			(xy 411.858188 -279.08573) (xy 411.810917 -279.099422) (xy 411.762062 -279.105354) (xy 411.712887 -279.103373)
			(xy 411.664668 -279.093529) (xy 411.618652 -279.076077) (xy 411.576031 -279.05147) (xy 411.53791 -279.020345)
			(xy 411.505275 -278.983508) (xy 411.478972 -278.941912) (xy 411.459681 -278.896636) (xy 411.447904 -278.848852)
			(xy 411.443944 -278.799798) (xy 411.105096 -278.799798) (xy 411.104601 -278.824405) (xy 411.096706 -278.872982)
			(xy 411.081122 -278.919663) (xy 411.058251 -278.96324) (xy 411.028686 -279.002584) (xy 410.993193 -279.036676)
			(xy 410.95269 -279.064632) (xy 410.908228 -279.08573) (xy 410.860957 -279.099422) (xy 410.812102 -279.105354)
			(xy 410.762927 -279.103373) (xy 410.714708 -279.093529) (xy 410.668692 -279.076077) (xy 410.626071 -279.05147)
			(xy 410.58795 -279.020345) (xy 410.555315 -278.983508) (xy 410.529012 -278.941912) (xy 410.509721 -278.896636)
			(xy 410.497944 -278.848852) (xy 410.493984 -278.799798) (xy 410.154882 -278.799798) (xy 410.154387 -278.824405)
			(xy 410.146492 -278.872982) (xy 410.130908 -278.919663) (xy 410.108037 -278.96324) (xy 410.078472 -279.002584)
			(xy 410.042979 -279.036676) (xy 410.002476 -279.064632) (xy 409.958014 -279.08573) (xy 409.910743 -279.099422)
			(xy 409.861888 -279.105354) (xy 409.812713 -279.103373) (xy 409.764494 -279.093529) (xy 409.718478 -279.076077)
			(xy 409.675857 -279.05147) (xy 409.637736 -279.020345) (xy 409.605101 -278.983508) (xy 409.578798 -278.941912)
			(xy 409.559507 -278.896636) (xy 409.54773 -278.848852) (xy 409.54377 -278.799798) (xy 409.205176 -278.799798)
			(xy 409.204681 -278.824405) (xy 409.196786 -278.872982) (xy 409.181202 -278.919663) (xy 409.158331 -278.96324)
			(xy 409.128766 -279.002584) (xy 409.093273 -279.036676) (xy 409.05277 -279.064632) (xy 409.008308 -279.08573)
			(xy 408.961037 -279.099422) (xy 408.912182 -279.105354) (xy 408.863007 -279.103373) (xy 408.814788 -279.093529)
			(xy 408.768772 -279.076077) (xy 408.726151 -279.05147) (xy 408.68803 -279.020345) (xy 408.655395 -278.983508)
			(xy 408.629092 -278.941912) (xy 408.609801 -278.896636) (xy 408.598024 -278.848852) (xy 408.594064 -278.799798)
			(xy 408.254962 -278.799798) (xy 408.254467 -278.824405) (xy 408.246572 -278.872982) (xy 408.230988 -278.919663)
			(xy 408.208117 -278.96324) (xy 408.178552 -279.002584) (xy 408.143059 -279.036676) (xy 408.102556 -279.064632)
			(xy 408.058094 -279.08573) (xy 408.010823 -279.099422) (xy 407.961968 -279.105354) (xy 407.912793 -279.103373)
			(xy 407.864574 -279.093529) (xy 407.818558 -279.076077) (xy 407.775937 -279.05147) (xy 407.737816 -279.020345)
			(xy 407.705181 -278.983508) (xy 407.678878 -278.941912) (xy 407.659587 -278.896636) (xy 407.64781 -278.848852)
			(xy 407.64385 -278.799798) (xy 407.305256 -278.799798) (xy 407.304761 -278.824405) (xy 407.296866 -278.872982)
			(xy 407.281282 -278.919663) (xy 407.258411 -278.96324) (xy 407.228846 -279.002584) (xy 407.193353 -279.036676)
			(xy 407.15285 -279.064632) (xy 407.108388 -279.08573) (xy 407.061117 -279.099422) (xy 407.012262 -279.105354)
			(xy 406.963087 -279.103373) (xy 406.914868 -279.093529) (xy 406.868852 -279.076077) (xy 406.826231 -279.05147)
			(xy 406.78811 -279.020345) (xy 406.755475 -278.983508) (xy 406.729172 -278.941912) (xy 406.709881 -278.896636)
			(xy 406.698104 -278.848852) (xy 406.694144 -278.799798) (xy 406.355862 -278.799798) (xy 406.355862 -278.7998)
			(xy 406.35169 -278.850144) (xy 406.339289 -278.899116) (xy 406.318996 -278.945378) (xy 406.291365 -278.987668)
			(xy 406.25715 -279.024834) (xy 406.217284 -279.055862) (xy 406.172855 -279.079904) (xy 406.125075 -279.096305)
			(xy 406.075247 -279.104618) (xy 406.049988 -279.105106) (xy 406.026188 -279.104649) (xy 405.979164 -279.09726)
			(xy 405.933857 -279.082662) (xy 405.891364 -279.061209) (xy 405.852716 -279.033422) (xy 405.818849 -278.999973)
			(xy 405.790583 -278.961673) (xy 405.768604 -278.919451) (xy 405.753444 -278.874329) (xy 405.74547 -278.8274)
			(xy 405.74468 -278.803608) (xy 405.74468 -278.799544) (xy 405.745234 -278.774437) (xy 405.753536 -278.724911)
			(xy 405.76119 -278.700992) (xy 405.76246 -278.697182) (xy 405.76373 -278.689816) (xy 405.765096 -278.677531)
			(xy 405.757524 -278.654044) (xy 405.749252 -278.644858) (xy 405.740362 -278.635968) (xy 405.71674 -278.628856)
			(xy 405.69642 -278.632666) (xy 405.692102 -278.63419) (xy 405.657558 -278.645112) (xy 405.651716 -278.646636)
			(xy 405.646382 -278.647906) (xy 405.628705 -278.651591) (xy 405.59281 -278.655531) (xy 405.574754 -278.65578)
			(xy 405.557228 -278.65578) (xy 405.55545 -278.655526) (xy 405.55418 -278.655526) (xy 405.550624 -278.655272)
			(xy 405.548592 -278.655018) (xy 405.547322 -278.654764) (xy 405.545798 -278.654764) (xy 405.523359 -278.652324)
			(xy 405.47939 -278.64213) (xy 405.458168 -278.634444) (xy 405.45512 -278.633174) (xy 405.448008 -278.63165)
			(xy 405.439761 -278.629916) (xy 405.422983 -278.631404) (xy 405.407613 -278.638291) (xy 405.401272 -278.643842)
			(xy 405.392128 -278.652732) (xy 405.384 -278.676862) (xy 405.386794 -278.693118) (xy 405.388826 -278.700992)
			(xy 405.396506 -278.72497) (xy 405.404803 -278.774626) (xy 405.405336 -278.799798) (xy 405.40485 -278.824622)
			(xy 405.396818 -278.873615) (xy 405.380966 -278.920663) (xy 405.35771 -278.964527) (xy 405.327665 -279.004051)
			(xy 405.291621 -279.038193) (xy 405.250528 -279.066054) (xy 405.205469 -279.086899) (xy 405.157631 -279.10018)
			(xy 405.108275 -279.105547) (xy 405.0587 -279.102858) (xy 405.010214 -279.092184) (xy 404.964093 -279.073806)
			(xy 404.921554 -279.048208) (xy 404.883716 -279.016066) (xy 404.851577 -278.978225) (xy 404.825983 -278.935683)
			(xy 404.807609 -278.889561) (xy 404.796939 -278.841074) (xy 404.794254 -278.791499) (xy 404.799624 -278.742143)
			(xy 404.81291 -278.694307) (xy 404.833759 -278.649249) (xy 404.861623 -278.608159) (xy 404.895769 -278.572118)
			(xy 404.935295 -278.542076) (xy 404.979161 -278.518824) (xy 405.02621 -278.502975) (xy 405.075204 -278.494948)
			(xy 405.100028 -278.49449) (xy 405.109002 -278.49453) (xy 405.126921 -278.495546) (xy 405.135842 -278.496522)
			(xy 405.14778 -278.498046) (xy 405.170132 -278.489918) (xy 405.234648 -278.422608) (xy 405.238492 -278.418403)
			(xy 405.244396 -278.408662) (xy 405.246332 -278.403304) (xy 405.246332 -278.402542) (xy 405.249888 -278.391112)
			(xy 405.24811 -278.379174) (xy 405.24811 -278.37892) (xy 405.247602 -278.374856) (xy 405.245743 -278.362429)
			(xy 405.243707 -278.337382) (xy 405.243538 -278.324818) (xy 405.243538 -278.289004) (xy 405.243792 -278.289004)
			(xy 405.243792 -278.1935) (xy 405.243372 -278.183479) (xy 405.235702 -278.164964) (xy 405.22153 -278.150793)
			(xy 405.203013 -278.143126) (xy 405.192992 -278.1427) (xy 405.186134 -278.1427) (xy 405.179784 -278.144478)
			(xy 405.160221 -278.149452) (xy 405.120211 -278.154803) (xy 405.100028 -278.155146) (xy 405.076034 -278.154678)
			(xy 405.028637 -278.147175) (xy 404.982997 -278.132351) (xy 404.940237 -278.110569) (xy 404.901412 -278.082367)
			(xy 404.867476 -278.048438) (xy 404.839265 -278.009619) (xy 404.817475 -277.966864) (xy 404.80264 -277.921227)
			(xy 404.795128 -277.873832) (xy 404.79472 -277.849838) (xy 404.794824 -277.840797) (xy 404.795966 -277.822751)
			(xy 404.797006 -277.81377) (xy 404.797006 -277.8125) (xy 404.797611 -277.800861) (xy 404.789561 -277.779015)
			(xy 404.781512 -277.77059) (xy 404.722584 -277.714202) (xy 404.713583 -277.706482) (xy 404.690926 -277.699596)
			(xy 404.67915 -277.700994) (xy 404.652237 -277.704899) (xy 404.597859 -277.704899) (xy 404.570946 -277.700994)
			(xy 404.56993 -277.700994) (xy 404.558319 -277.699811) (xy 404.536085 -277.706822) (xy 404.527258 -277.714456)
			(xy 404.46833 -277.77059) (xy 404.460247 -277.77908) (xy 404.45216 -277.801053) (xy 404.452836 -277.812754)
			(xy 404.452836 -277.81377) (xy 404.453877 -277.822751) (xy 404.45502 -277.840797) (xy 404.455122 -277.849838)
			(xy 404.454649 -277.873828) (xy 404.447138 -277.921216) (xy 404.432307 -277.966845) (xy 404.410522 -278.009594)
			(xy 404.382318 -278.048408) (xy 404.34839 -278.082334) (xy 404.309573 -278.110534) (xy 404.266823 -278.132316)
			(xy 404.221192 -278.147143) (xy 404.173804 -278.15465) (xy 404.149814 -278.155146) (xy 404.117556 -278.153368)
			(xy 404.106634 -278.152352) (xy 404.096474 -278.155654) (xy 404.091519 -278.157396) (xy 404.082425 -278.162647)
			(xy 404.07844 -278.166068) (xy 404.022306 -278.21636) (xy 404.01682 -278.221652) (xy 404.008957 -278.234699)
			(xy 404.006812 -278.242014) (xy 404.005288 -278.24811) (xy 404.005288 -278.317452) (xy 404.005542 -278.324564)
			(xy 404.005542 -278.325072) (xy 404.005352 -278.338535) (xy 404.00306 -278.365365) (xy 404.00097 -278.378666)
			(xy 403.998938 -278.390604) (xy 404.005796 -278.41321) (xy 404.070566 -278.481282) (xy 404.07906 -278.489349)
			(xy 404.10103 -278.497402) (xy 404.11273 -278.496776) (xy 404.113238 -278.496776) (xy 404.122346 -278.495723)
			(xy 404.140646 -278.494582) (xy 404.149814 -278.49449) (xy 404.175069 -278.495013) (xy 404.224889 -278.503328)
			(xy 404.272661 -278.51973) (xy 404.317082 -278.543772) (xy 404.35694 -278.574796) (xy 404.391149 -278.611958)
			(xy 404.418774 -278.654243) (xy 404.439063 -278.700499) (xy 404.451462 -278.749463) (xy 404.455633 -278.7998)
			(xy 404.451462 -278.850137) (xy 404.439063 -278.899101) (xy 404.418774 -278.945357) (xy 404.391149 -278.987642)
			(xy 404.35694 -279.024804) (xy 404.317082 -279.055828) (xy 404.272661 -279.07987) (xy 404.224889 -279.096272)
			(xy 404.175069 -279.104587) (xy 404.149814 -279.105106) (xy 404.126012 -279.104651) (xy 404.078986 -279.097265)
			(xy 404.033675 -279.08267) (xy 403.991179 -279.061218) (xy 403.952527 -279.033431) (xy 403.918656 -278.999982)
			(xy 403.890388 -278.961681) (xy 403.868406 -278.919457) (xy 403.853245 -278.874333) (xy 403.84527 -278.827402)
			(xy 403.844506 -278.803608) (xy 403.844506 -278.799544) (xy 403.84506 -278.774436) (xy 403.85336 -278.72491)
			(xy 403.861016 -278.700992) (xy 403.862286 -278.697182) (xy 403.863556 -278.689816) (xy 403.864922 -278.677531)
			(xy 403.857353 -278.654041) (xy 403.849078 -278.644858) (xy 403.840188 -278.635968) (xy 403.816566 -278.628856)
			(xy 403.796246 -278.632666) (xy 403.791928 -278.63419) (xy 403.757384 -278.645112) (xy 403.751542 -278.646636)
			(xy 403.746208 -278.647906) (xy 403.728468 -278.651603) (xy 403.692445 -278.655545) (xy 403.674326 -278.65578)
			(xy 403.660804 -278.655661) (xy 403.633847 -278.653497) (xy 403.620478 -278.651462) (xy 403.60854 -278.64943)
			(xy 403.585934 -278.656288) (xy 403.518624 -278.720296) (xy 403.513544 -278.725884) (xy 403.50777 -278.734108)
			(xy 403.502405 -278.753454) (xy 403.50313 -278.763476) (xy 403.50313 -278.763984) (xy 403.504092 -278.772906)
			(xy 403.505109 -278.790824) (xy 403.505162 -278.799798) (xy 403.504676 -278.824614) (xy 403.496647 -278.873593)
			(xy 403.4808 -278.920628) (xy 403.457553 -278.96448) (xy 403.427518 -279.003993) (xy 403.391485 -279.038126)
			(xy 403.350406 -279.065981) (xy 403.305361 -279.086823) (xy 403.257538 -279.100104) (xy 403.208197 -279.105472)
			(xy 403.158637 -279.102788) (xy 403.110164 -279.092122) (xy 403.064055 -279.073754) (xy 403.021525 -279.048168)
			(xy 402.983694 -279.01604) (xy 402.95156 -278.978214) (xy 402.925968 -278.935688) (xy 402.907593 -278.889582)
			(xy 402.896918 -278.841111) (xy 402.894226 -278.791551) (xy 402.899587 -278.742209) (xy 402.91286 -278.694384)
			(xy 402.933695 -278.649336) (xy 402.961543 -278.608252) (xy 402.995671 -278.572215) (xy 403.03518 -278.542173)
			(xy 403.079028 -278.518919) (xy 403.12606 -278.503064) (xy 403.175038 -278.495027) (xy 403.199854 -278.49449)
			(xy 403.208828 -278.494531) (xy 403.226747 -278.495548) (xy 403.235668 -278.496522) (xy 403.247606 -278.498046)
			(xy 403.269958 -278.489918) (xy 403.334474 -278.422608) (xy 403.338317 -278.418402) (xy 403.344218 -278.40866)
			(xy 403.346158 -278.403304) (xy 403.346158 -278.402542) (xy 403.349714 -278.391112) (xy 403.347936 -278.379174)
			(xy 403.347936 -278.37892) (xy 403.347428 -278.374856) (xy 403.345576 -278.362428) (xy 403.343543 -278.337382)
			(xy 403.343364 -278.324818) (xy 403.343364 -278.25446) (xy 403.342915 -278.243796) (xy 403.334244 -278.224315)
			(xy 403.3266 -278.216868) (xy 403.27072 -278.166322) (xy 403.26249 -278.159684) (xy 403.242418 -278.15311)
			(xy 403.231858 -278.153622) (xy 403.231604 -278.153622) (xy 403.199854 -278.155146) (xy 403.175864 -278.154672)
			(xy 403.128476 -278.14716) (xy 403.082845 -278.132329) (xy 403.040096 -278.110544) (xy 403.001281 -278.082341)
			(xy 402.967354 -278.048413) (xy 402.939152 -278.009597) (xy 402.917368 -277.966847) (xy 402.902538 -277.921217)
			(xy 402.895027 -277.873828) (xy 402.894546 -277.849838) (xy 402.89465 -277.840797) (xy 402.895792 -277.822751)
			(xy 402.896832 -277.81377) (xy 402.896832 -277.812754) (xy 402.897485 -277.801052) (xy 402.889421 -277.779074)
			(xy 402.881338 -277.77059) (xy 402.82241 -277.714456) (xy 402.813573 -277.70684) (xy 402.791346 -277.69983)
			(xy 402.779738 -277.700994) (xy 402.77923 -277.700994) (xy 402.752317 -277.704899) (xy 402.697939 -277.704899)
			(xy 402.671026 -277.700994) (xy 402.67001 -277.700994) (xy 402.658401 -277.699816) (xy 402.636173 -277.706833)
			(xy 402.627338 -277.714456) (xy 402.56841 -277.77059) (xy 402.56033 -277.779081) (xy 402.552246 -277.801053)
			(xy 402.552916 -277.812754) (xy 402.552916 -277.81377) (xy 402.553956 -277.822751) (xy 402.555099 -277.840797)
			(xy 402.555202 -277.849838) (xy 402.554729 -277.873827) (xy 402.547218 -277.921214) (xy 402.532387 -277.966842)
			(xy 402.510601 -278.009589) (xy 402.482397 -278.048402) (xy 402.448469 -278.082326) (xy 402.409652 -278.110524)
			(xy 402.366902 -278.132304) (xy 402.321271 -278.147128) (xy 402.273883 -278.154632) (xy 402.249894 -278.155146)
			(xy 402.217636 -278.153368) (xy 402.206714 -278.152352) (xy 402.196554 -278.155654) (xy 402.1916 -278.157398)
			(xy 402.182508 -278.162651) (xy 402.17852 -278.166068) (xy 402.122386 -278.21636) (xy 402.116894 -278.221648)
			(xy 402.109018 -278.234692) (xy 402.106892 -278.242014) (xy 402.105368 -278.24811) (xy 402.105368 -278.299418)
			(xy 402.105114 -278.301704) (xy 402.105114 -278.313134) (xy 402.105622 -278.324564) (xy 402.105622 -278.325072)
			(xy 402.105432 -278.338535) (xy 402.10314 -278.365365) (xy 402.10105 -278.378666) (xy 402.099018 -278.390604)
			(xy 402.105876 -278.41321) (xy 402.170646 -278.481282) (xy 402.179139 -278.489353) (xy 402.20111 -278.497414)
			(xy 402.21281 -278.496776) (xy 402.213318 -278.496776) (xy 402.222426 -278.495722) (xy 402.240726 -278.49458)
			(xy 402.249894 -278.49449) (xy 402.275152 -278.494982) (xy 402.32498 -278.503296) (xy 402.372759 -278.519698)
			(xy 402.417187 -278.543741) (xy 402.457052 -278.574768) (xy 402.491267 -278.611934) (xy 402.518897 -278.654224)
			(xy 402.539189 -278.700486) (xy 402.55159 -278.749456) (xy 402.555762 -278.7998) (xy 402.55159 -278.850144)
			(xy 402.539189 -278.899114) (xy 402.518897 -278.945376) (xy 402.491267 -278.987666) (xy 402.457052 -279.024832)
			(xy 402.417187 -279.055859) (xy 402.372759 -279.079902) (xy 402.32498 -279.096304) (xy 402.275152 -279.104618)
			(xy 402.249894 -279.105106) (xy 402.226093 -279.10465) (xy 402.179069 -279.097261) (xy 402.133761 -279.082664)
			(xy 402.091268 -279.061212) (xy 402.052619 -279.033424) (xy 402.01875 -278.999975) (xy 401.990484 -278.961675)
			(xy 401.968504 -278.919452) (xy 401.953344 -278.874329) (xy 401.94537 -278.827401) (xy 401.944586 -278.803608)
			(xy 401.944586 -278.799544) (xy 401.94514 -278.774437) (xy 401.953442 -278.724911) (xy 401.961096 -278.700992)
			(xy 401.962366 -278.697182) (xy 401.963636 -278.689816) (xy 401.965002 -278.677531) (xy 401.957431 -278.654043)
			(xy 401.949158 -278.644858) (xy 401.940268 -278.635968) (xy 401.916646 -278.628856) (xy 401.896326 -278.632666)
			(xy 401.892008 -278.63419) (xy 401.878845 -278.638989) (xy 401.851886 -278.646623) (xy 401.83816 -278.64943)
			(xy 401.816062 -278.652986) (xy 401.815554 -278.65324) (xy 401.805435 -278.65442) (xy 401.785101 -278.65569)
			(xy 401.774914 -278.65578) (xy 401.75688 -278.65578) (xy 401.755102 -278.655526) (xy 401.753832 -278.655526)
			(xy 401.750276 -278.655272) (xy 401.748244 -278.655018) (xy 401.74672 -278.654764) (xy 401.745196 -278.654764)
			(xy 401.72195 -278.652264) (xy 401.67644 -278.641555) (xy 401.654518 -278.633428) (xy 401.647914 -278.630634)
			(xy 401.634198 -278.629364) (xy 401.62734 -278.630634) (xy 401.617535 -278.632796) (xy 401.600622 -278.643587)
			(xy 401.589126 -278.66003) (xy 401.584799 -278.679621) (xy 401.586192 -278.689562) (xy 401.587462 -278.696928)
			(xy 401.588732 -278.700738) (xy 401.588732 -278.700992) (xy 401.596412 -278.72497) (xy 401.604709 -278.774626)
			(xy 401.605242 -278.799798) (xy 401.604756 -278.824622) (xy 401.596724 -278.873617) (xy 401.580871 -278.920666)
			(xy 401.557615 -278.964531) (xy 401.527569 -279.004056) (xy 401.491524 -279.038198) (xy 401.45043 -279.06606)
			(xy 401.40537 -279.086906) (xy 401.35753 -279.100187) (xy 401.308173 -279.105553) (xy 401.258597 -279.102863)
			(xy 401.21011 -279.092189) (xy 401.163988 -279.07381) (xy 401.121448 -279.048212) (xy 401.083609 -279.016068)
			(xy 401.05147 -278.978226) (xy 401.025876 -278.935683) (xy 401.007502 -278.889559) (xy 400.996832 -278.841071)
			(xy 400.994148 -278.791495) (xy 400.999519 -278.742138) (xy 401.012806 -278.6943) (xy 401.033656 -278.649242)
			(xy 401.061522 -278.608151) (xy 401.095668 -278.57211) (xy 401.135196 -278.542068) (xy 401.179063 -278.518816)
			(xy 401.226114 -278.502968) (xy 401.27511 -278.494941) (xy 401.299934 -278.49449) (xy 401.300696 -278.49449)
			(xy 401.309416 -278.494556) (xy 401.326826 -278.495571) (xy 401.335494 -278.496522) (xy 401.347432 -278.498046)
			(xy 401.369784 -278.489918) (xy 401.4343 -278.422608) (xy 401.438141 -278.418401) (xy 401.44404 -278.408659)
			(xy 401.445984 -278.403304) (xy 401.445984 -278.402542) (xy 401.44954 -278.391112) (xy 401.447762 -278.37892)
			(xy 401.447762 -278.378666) (xy 401.447254 -278.374602) (xy 401.445408 -278.362238) (xy 401.443377 -278.337318)
			(xy 401.44319 -278.324818) (xy 401.44319 -278.289004) (xy 401.443444 -278.289004) (xy 401.443444 -278.218646)
			(xy 401.442881 -278.206976) (xy 401.432565 -278.186042) (xy 401.423632 -278.178514) (xy 401.398486 -278.15921)
			(xy 401.394351 -278.15618) (xy 401.385137 -278.151692) (xy 401.380198 -278.15032) (xy 401.368514 -278.147272)
			(xy 401.351606 -278.150937) (xy 401.317233 -278.154884) (xy 401.299934 -278.155146) (xy 401.27594 -278.154678)
			(xy 401.228542 -278.147176) (xy 401.182901 -278.132352) (xy 401.140141 -278.110571) (xy 401.101314 -278.082369)
			(xy 401.067378 -278.04844) (xy 401.039166 -278.009621) (xy 401.017375 -277.966866) (xy 401.002541 -277.921228)
			(xy 400.995028 -277.873832) (xy 400.994626 -277.849838) (xy 400.99473 -277.840797) (xy 400.995872 -277.822751)
			(xy 400.996912 -277.81377) (xy 400.996912 -277.812754) (xy 400.997564 -277.801053) (xy 400.989499 -277.779077)
			(xy 400.981418 -277.77059) (xy 400.92249 -277.714456) (xy 400.913652 -277.706843) (xy 400.891427 -277.699842)
			(xy 400.879818 -277.700994) (xy 400.87931 -277.700994) (xy 400.852397 -277.704899) (xy 400.798019 -277.704899)
			(xy 400.771106 -277.700994) (xy 400.77009 -277.700994) (xy 400.758482 -277.69982) (xy 400.736261 -277.706843)
			(xy 400.727418 -277.714456) (xy 400.66849 -277.77059) (xy 400.660412 -277.779082) (xy 400.652332 -277.801054)
			(xy 400.652996 -277.812754) (xy 400.652996 -277.81377) (xy 400.654036 -277.822751) (xy 400.655179 -277.840797)
			(xy 400.655282 -277.849838) (xy 400.654809 -277.873827) (xy 400.647298 -277.921212) (xy 400.632466 -277.966839)
			(xy 400.61068 -278.009585) (xy 400.582476 -278.048396) (xy 400.548547 -278.082318) (xy 400.50973 -278.110514)
			(xy 400.46698 -278.132291) (xy 400.42135 -278.147112) (xy 400.373963 -278.154614) (xy 400.349974 -278.155146)
			(xy 400.317716 -278.153368) (xy 400.306794 -278.152352) (xy 400.296634 -278.155654) (xy 400.291681 -278.1574)
			(xy 400.282592 -278.162655) (xy 400.2786 -278.166068) (xy 400.222466 -278.21636) (xy 400.216975 -278.221648)
			(xy 400.209102 -278.234694) (xy 400.206972 -278.242014) (xy 400.205448 -278.24811) (xy 400.205448 -278.299418)
			(xy 400.205194 -278.301704) (xy 400.205194 -278.313134) (xy 400.205702 -278.324564) (xy 400.205702 -278.325072)
			(xy 400.205512 -278.338535) (xy 400.20322 -278.365365) (xy 400.20113 -278.378666) (xy 400.199098 -278.390604)
			(xy 400.205956 -278.41321) (xy 400.270726 -278.481282) (xy 400.279218 -278.489357) (xy 400.30119 -278.497427)
			(xy 400.31289 -278.496776) (xy 400.313398 -278.496776) (xy 400.322506 -278.495722) (xy 400.340806 -278.494578)
			(xy 400.349974 -278.49449) (xy 400.375233 -278.494981) (xy 400.425063 -278.503292) (xy 400.472846 -278.519692)
			(xy 400.517277 -278.543734) (xy 400.557145 -278.574761) (xy 400.591361 -278.611927) (xy 400.618994 -278.654219)
			(xy 400.639288 -278.700482) (xy 400.65169 -278.749454) (xy 400.655862 -278.7998) (xy 400.65169 -278.850146)
			(xy 400.639288 -278.899118) (xy 400.618994 -278.945381) (xy 400.591361 -278.987673) (xy 400.557145 -279.024839)
			(xy 400.517277 -279.055866) (xy 400.472846 -279.079908) (xy 400.425063 -279.096308) (xy 400.375233 -279.104619)
			(xy 400.349974 -279.105106) (xy 400.326174 -279.104648) (xy 400.279152 -279.097257) (xy 400.233847 -279.082658)
			(xy 400.191356 -279.061205) (xy 400.15271 -279.033417) (xy 400.118844 -278.999968) (xy 400.09058 -278.961669)
			(xy 400.068602 -278.919447) (xy 400.053443 -278.874326) (xy 400.04547 -278.8274) (xy 400.044666 -278.803608)
			(xy 400.044666 -278.799544) (xy 400.04522 -278.774437) (xy 400.053522 -278.724911) (xy 400.061176 -278.700992)
			(xy 400.062446 -278.697182) (xy 400.063716 -278.689816) (xy 400.065082 -278.67753) (xy 400.05752 -278.654035)
			(xy 400.049238 -278.644858) (xy 400.040348 -278.635968) (xy 400.016726 -278.628856) (xy 399.996406 -278.632666)
			(xy 399.992088 -278.63419) (xy 399.978925 -278.638989) (xy 399.951966 -278.646621) (xy 399.93824 -278.64943)
			(xy 399.916142 -278.652986) (xy 399.915634 -278.65324) (xy 399.905515 -278.65442) (xy 399.885181 -278.655688)
			(xy 399.874994 -278.65578) (xy 399.85696 -278.65578) (xy 399.855182 -278.655526) (xy 399.853912 -278.655526)
			(xy 399.850356 -278.655272) (xy 399.848324 -278.655018) (xy 399.8468 -278.654764) (xy 399.845276 -278.654764)
			(xy 399.82203 -278.652263) (xy 399.776522 -278.641551) (xy 399.754598 -278.633428) (xy 399.747994 -278.630634)
			(xy 399.734278 -278.629364) (xy 399.72742 -278.630634) (xy 399.717644 -278.632864) (xy 399.70076 -278.643643)
			(xy 399.689285 -278.660062) (xy 399.684966 -278.679622) (xy 399.686272 -278.689562) (xy 399.687542 -278.696928)
			(xy 399.688812 -278.700738) (xy 399.688812 -278.700992) (xy 399.696493 -278.72497) (xy 399.70479 -278.774626)
			(xy 399.705322 -278.799798) (xy 399.704836 -278.82462) (xy 399.696805 -278.873611) (xy 399.680953 -278.920657)
			(xy 399.6577 -278.964518) (xy 399.627656 -279.00404) (xy 399.591614 -279.03818) (xy 399.550524 -279.06604)
			(xy 399.505468 -279.086885) (xy 399.457632 -279.100166) (xy 399.408279 -279.105533) (xy 399.358707 -279.102845)
			(xy 399.310223 -279.092172) (xy 399.264105 -279.073796) (xy 399.221567 -279.048201) (xy 399.183731 -279.016061)
			(xy 399.151592 -278.978223) (xy 399.125999 -278.935684) (xy 399.107625 -278.889565) (xy 399.096954 -278.841081)
			(xy 399.094267 -278.791509) (xy 399.099636 -278.742156) (xy 399.112919 -278.694321) (xy 399.133766 -278.649266)
			(xy 399.161627 -278.608176) (xy 399.195769 -278.572136) (xy 399.235292 -278.542094) (xy 399.279154 -278.518842)
			(xy 399.326201 -278.502992) (xy 399.375192 -278.494963) (xy 399.400014 -278.49449) (xy 399.400776 -278.49449)
			(xy 399.409496 -278.494555) (xy 399.426906 -278.495569) (xy 399.435574 -278.496522) (xy 399.447512 -278.498046)
			(xy 399.469864 -278.489918) (xy 399.53438 -278.422608) (xy 399.538223 -278.418402) (xy 399.544123 -278.40866)
			(xy 399.546064 -278.403304) (xy 399.546064 -278.402542) (xy 399.54962 -278.391112) (xy 399.547842 -278.37892)
			(xy 399.547842 -278.378666) (xy 399.547334 -278.374602) (xy 399.545488 -278.362237) (xy 399.543457 -278.337318)
			(xy 399.54327 -278.324818) (xy 399.54327 -278.289004) (xy 399.543524 -278.289004) (xy 399.543524 -278.218646)
			(xy 399.54296 -278.206976) (xy 399.532641 -278.186046) (xy 399.523712 -278.178514) (xy 399.498566 -278.15921)
			(xy 399.494431 -278.156181) (xy 399.485215 -278.151697) (xy 399.480278 -278.15032) (xy 399.468594 -278.147272)
			(xy 399.451686 -278.150936) (xy 399.417313 -278.15488) (xy 399.400014 -278.155146) (xy 399.376021 -278.154676)
			(xy 399.328625 -278.147172) (xy 399.282987 -278.132347) (xy 399.24023 -278.110564) (xy 399.201406 -278.082362)
			(xy 399.167472 -278.048434) (xy 399.139263 -278.009615) (xy 399.117473 -277.966861) (xy 399.10264 -277.921225)
			(xy 399.095128 -277.873831) (xy 399.094706 -277.849838) (xy 399.09481 -277.840797) (xy 399.095952 -277.822751)
			(xy 399.096992 -277.81377) (xy 399.096992 -277.812754) (xy 399.097644 -277.801053) (xy 399.089576 -277.779079)
			(xy 399.081498 -277.77059) (xy 399.02257 -277.714456) (xy 399.013731 -277.706848) (xy 398.991507 -277.699855)
			(xy 398.979898 -277.700994) (xy 398.97939 -277.700994) (xy 398.952352 -277.704931) (xy 398.897716 -277.704931)
			(xy 398.870678 -277.700994) (xy 398.858907 -277.699648) (xy 398.83626 -277.706518) (xy 398.827244 -277.714202)
			(xy 398.768316 -277.77059) (xy 398.760276 -277.779026) (xy 398.752206 -277.800862) (xy 398.752822 -277.8125)
			(xy 398.752822 -277.81377) (xy 398.753863 -277.822751) (xy 398.755006 -277.840797) (xy 398.755108 -277.849838)
			(xy 398.754635 -277.873827) (xy 398.747124 -277.921214) (xy 398.732293 -277.966843) (xy 398.710507 -278.009591)
			(xy 398.682303 -278.048404) (xy 398.648375 -278.082328) (xy 398.609558 -278.110527) (xy 398.566808 -278.132308)
			(xy 398.521177 -278.147133) (xy 398.473789 -278.154638) (xy 398.4498 -278.155146) (xy 398.417796 -278.153368)
			(xy 398.406874 -278.152352) (xy 398.396714 -278.155654) (xy 398.391757 -278.157393) (xy 398.382658 -278.162638)
			(xy 398.37868 -278.166068) (xy 398.322292 -278.216614) (xy 398.314791 -278.224162) (xy 398.306145 -278.243581)
			(xy 398.305528 -278.254206) (xy 398.305528 -278.299418) (xy 398.305274 -278.308308) (xy 398.305274 -278.312372)
			(xy 398.305528 -278.324818) (xy 398.305345 -278.338345) (xy 398.303054 -278.365302) (xy 398.300956 -278.378666)
			(xy 398.298924 -278.390604) (xy 398.305782 -278.41321) (xy 398.370552 -278.481282) (xy 398.379046 -278.489352)
			(xy 398.401016 -278.49741) (xy 398.412716 -278.496776) (xy 398.413224 -278.496776) (xy 398.422332 -278.495722)
			(xy 398.440632 -278.49458) (xy 398.4498 -278.49449) (xy 398.475055 -278.495012) (xy 398.524878 -278.503325)
			(xy 398.572652 -278.519726) (xy 398.617075 -278.543767) (xy 398.656935 -278.574791) (xy 398.691145 -278.611953)
			(xy 398.718772 -278.65424) (xy 398.739062 -278.700496) (xy 398.751462 -278.749462) (xy 398.755633 -278.7998)
			(xy 398.751462 -278.850138) (xy 398.739062 -278.899104) (xy 398.718772 -278.94536) (xy 398.691145 -278.987647)
			(xy 398.656935 -279.024809) (xy 398.617075 -279.055833) (xy 398.572652 -279.079874) (xy 398.524878 -279.096275)
			(xy 398.475055 -279.104588) (xy 398.4498 -279.105106) (xy 398.425999 -279.10465) (xy 398.378974 -279.097262)
			(xy 398.333665 -279.082666) (xy 398.291171 -279.061214) (xy 398.252521 -279.033426) (xy 398.218652 -278.999977)
			(xy 398.190385 -278.961677) (xy 398.168405 -278.919454) (xy 398.153244 -278.87433) (xy 398.14527 -278.827401)
			(xy 398.144492 -278.803608) (xy 398.144492 -278.799544) (xy 398.145046 -278.774437) (xy 398.153348 -278.724911)
			(xy 398.161002 -278.700992) (xy 398.162272 -278.697182) (xy 398.163542 -278.689816) (xy 398.164908 -278.677531)
			(xy 398.157338 -278.654042) (xy 398.149064 -278.644858) (xy 398.140174 -278.635968) (xy 398.116552 -278.628856)
			(xy 398.096232 -278.632666) (xy 398.091914 -278.63419) (xy 398.05737 -278.645112) (xy 398.051528 -278.646636)
			(xy 398.046194 -278.647906) (xy 398.028517 -278.651591) (xy 397.992622 -278.655533) (xy 397.974566 -278.65578)
			(xy 397.95704 -278.65578) (xy 397.955262 -278.655526) (xy 397.953992 -278.655526) (xy 397.950436 -278.655272)
			(xy 397.948404 -278.655018) (xy 397.947134 -278.654764) (xy 397.94561 -278.654764) (xy 397.923171 -278.652325)
			(xy 397.879201 -278.642132) (xy 397.85798 -278.634444) (xy 397.854932 -278.633174) (xy 397.84782 -278.63165)
			(xy 397.839572 -278.629914) (xy 397.822792 -278.631398) (xy 397.807419 -278.638284) (xy 397.801084 -278.643842)
			(xy 397.79194 -278.652732) (xy 397.783812 -278.676862) (xy 397.786606 -278.693118) (xy 397.788638 -278.700992)
			(xy 397.79632 -278.724969) (xy 397.804619 -278.774626) (xy 397.805148 -278.799798) (xy 397.804662 -278.824623)
			(xy 397.79663 -278.873618) (xy 397.780776 -278.920669) (xy 397.75752 -278.964535) (xy 397.727473 -279.00406)
			(xy 397.691427 -279.038204) (xy 397.650332 -279.066066) (xy 397.60527 -279.086912) (xy 397.55743 -279.100193)
			(xy 397.508071 -279.105559) (xy 397.458494 -279.102869) (xy 397.410006 -279.092194) (xy 397.363883 -279.073814)
			(xy 397.321342 -279.048215) (xy 397.283503 -279.01607) (xy 397.251363 -278.978227) (xy 397.225769 -278.935682)
			(xy 397.207395 -278.889558) (xy 397.196726 -278.841068) (xy 397.194042 -278.791491) (xy 397.199414 -278.742133)
			(xy 397.212701 -278.694294) (xy 397.233553 -278.649235) (xy 397.26142 -278.608144) (xy 397.295568 -278.572102)
			(xy 397.335097 -278.54206) (xy 397.378966 -278.518809) (xy 397.426019 -278.502961) (xy 397.475015 -278.494935)
			(xy 397.49984 -278.49449) (xy 397.508814 -278.49453) (xy 397.526733 -278.495547) (xy 397.535654 -278.496522)
			(xy 397.547592 -278.498046) (xy 397.569944 -278.489918) (xy 397.63446 -278.422608) (xy 397.638303 -278.418402)
			(xy 397.644206 -278.408661) (xy 397.646144 -278.403304) (xy 397.646144 -278.402542) (xy 397.6497 -278.391112)
			(xy 397.647922 -278.379174) (xy 397.647922 -278.37892) (xy 397.647414 -278.374856) (xy 397.645555 -278.362429)
			(xy 397.643519 -278.337382) (xy 397.64335 -278.324818) (xy 397.64335 -278.289004) (xy 397.643604 -278.289004)
			(xy 397.643604 -278.1935) (xy 397.643116 -278.183492) (xy 397.635456 -278.165) (xy 397.621304 -278.150846)
			(xy 397.602812 -278.143185) (xy 397.592804 -278.1427) (xy 397.585946 -278.1427) (xy 397.579596 -278.144478)
			(xy 397.560033 -278.149453) (xy 397.520023 -278.154805) (xy 397.49984 -278.155146) (xy 397.475844 -278.154703)
			(xy 397.428441 -278.147201) (xy 397.382796 -278.132377) (xy 397.340031 -278.110594) (xy 397.301201 -278.08239)
			(xy 397.267261 -278.048458) (xy 397.239047 -278.009635) (xy 397.217253 -277.966876) (xy 397.202417 -277.921235)
			(xy 397.194903 -277.873834) (xy 397.194532 -277.849838) (xy 397.194636 -277.840797) (xy 397.195778 -277.822751)
			(xy 397.196818 -277.81377) (xy 397.196818 -277.812754) (xy 397.19747 -277.801053) (xy 397.189405 -277.779076)
			(xy 397.181324 -277.77059) (xy 397.113252 -277.70582) (xy 397.090646 -277.698962) (xy 397.078708 -277.700994)
			(xy 397.065408 -277.703096) (xy 397.038578 -277.705384) (xy 397.025114 -277.705566) (xy 397.024352 -277.705566)
			(xy 397.010766 -277.705457) (xy 396.983682 -277.703292) (xy 396.97025 -277.701248) (xy 396.958566 -277.699216)
			(xy 396.93596 -277.706328) (xy 396.868396 -277.770844) (xy 396.86035 -277.779279) (xy 396.852264 -277.801116)
			(xy 396.852902 -277.812754) (xy 396.852902 -277.814024) (xy 396.853936 -277.822942) (xy 396.85508 -277.840861)
			(xy 396.855188 -277.849838) (xy 396.854735 -277.873889) (xy 396.847188 -277.921396) (xy 396.832287 -277.967132)
			(xy 396.8104 -278.009967) (xy 396.782068 -278.04884) (xy 396.747993 -278.082792) (xy 396.709016 -278.110982)
			(xy 396.666102 -278.132712) (xy 396.620312 -278.147447) (xy 396.596616 -278.15159) (xy 396.578074 -278.154384)
			(xy 396.55369 -278.182832) (xy 396.55369 -278.466804) (xy 396.578074 -278.495252) (xy 396.596616 -278.498046)
			(xy 396.620319 -278.502172) (xy 396.666121 -278.516897) (xy 396.709047 -278.538623) (xy 396.748035 -278.566811)
			(xy 396.78212 -278.600764) (xy 396.810459 -278.639643) (xy 396.832351 -278.682484) (xy 396.847253 -278.728229)
			(xy 396.854798 -278.775744) (xy 396.854798 -278.823855) (xy 396.847253 -278.87137) (xy 396.832351 -278.917115)
			(xy 396.810459 -278.959957) (xy 396.78212 -278.998835) (xy 396.748035 -279.032789) (xy 396.709047 -279.060977)
			(xy 396.666122 -279.082703) (xy 396.62032 -279.097428) (xy 396.596616 -279.10155) (xy 396.578074 -279.104344)
			(xy 396.55369 -279.132792) (xy 396.55369 -279.416764) (xy 396.578074 -279.445212) (xy 396.596616 -279.448006)
			(xy 396.620322 -279.452132) (xy 396.666131 -279.466858) (xy 396.709063 -279.488585) (xy 396.748056 -279.516777)
			(xy 396.782146 -279.550734) (xy 396.81049 -279.589617) (xy 396.832385 -279.632463) (xy 396.847291 -279.678214)
			(xy 396.854837 -279.725735) (xy 396.854837 -279.749504) (xy 397.194036 -279.749504) (xy 397.197996 -279.70045)
			(xy 397.209773 -279.652666) (xy 397.229064 -279.60739) (xy 397.255367 -279.565794) (xy 397.288002 -279.528957)
			(xy 397.326123 -279.497832) (xy 397.368744 -279.473225) (xy 397.41476 -279.455773) (xy 397.462979 -279.445929)
			(xy 397.512154 -279.443948) (xy 397.561009 -279.44988) (xy 397.60828 -279.463572) (xy 397.652742 -279.48467)
			(xy 397.693245 -279.512626) (xy 397.728738 -279.546718) (xy 397.758303 -279.586062) (xy 397.781174 -279.629639)
			(xy 397.796758 -279.67632) (xy 397.804653 -279.724897) (xy 397.805148 -279.749504) (xy 397.805143 -279.749758)
			(xy 398.143996 -279.749758) (xy 398.147956 -279.700704) (xy 398.159733 -279.65292) (xy 398.179024 -279.607644)
			(xy 398.205327 -279.566048) (xy 398.237962 -279.529211) (xy 398.276083 -279.498086) (xy 398.318704 -279.473479)
			(xy 398.36472 -279.456027) (xy 398.412939 -279.446183) (xy 398.462114 -279.444202) (xy 398.510969 -279.450134)
			(xy 398.55824 -279.463826) (xy 398.602702 -279.484924) (xy 398.643205 -279.51288) (xy 398.678698 -279.546972)
			(xy 398.708263 -279.586316) (xy 398.731134 -279.629893) (xy 398.746718 -279.676574) (xy 398.754613 -279.725151)
			(xy 398.755103 -279.749504) (xy 399.09421 -279.749504) (xy 399.09817 -279.70045) (xy 399.109947 -279.652666)
			(xy 399.129238 -279.60739) (xy 399.155541 -279.565794) (xy 399.188176 -279.528957) (xy 399.226297 -279.497832)
			(xy 399.268918 -279.473225) (xy 399.314934 -279.455773) (xy 399.363153 -279.445929) (xy 399.412328 -279.443948)
			(xy 399.461183 -279.44988) (xy 399.508454 -279.463572) (xy 399.552916 -279.48467) (xy 399.593419 -279.512626)
			(xy 399.628912 -279.546718) (xy 399.658477 -279.586062) (xy 399.681348 -279.629639) (xy 399.696932 -279.67632)
			(xy 399.704827 -279.724897) (xy 399.705322 -279.749504) (xy 399.705317 -279.749758) (xy 400.04417 -279.749758)
			(xy 400.04813 -279.700704) (xy 400.059907 -279.65292) (xy 400.079198 -279.607644) (xy 400.105501 -279.566048)
			(xy 400.138136 -279.529211) (xy 400.176257 -279.498086) (xy 400.218878 -279.473479) (xy 400.264894 -279.456027)
			(xy 400.313113 -279.446183) (xy 400.362288 -279.444202) (xy 400.411143 -279.450134) (xy 400.458414 -279.463826)
			(xy 400.502876 -279.484924) (xy 400.543379 -279.51288) (xy 400.578872 -279.546972) (xy 400.608437 -279.586316)
			(xy 400.631308 -279.629893) (xy 400.646892 -279.676574) (xy 400.654787 -279.725151) (xy 400.655277 -279.749504)
			(xy 400.99413 -279.749504) (xy 400.99809 -279.70045) (xy 401.009867 -279.652666) (xy 401.029158 -279.60739)
			(xy 401.055461 -279.565794) (xy 401.088096 -279.528957) (xy 401.126217 -279.497832) (xy 401.168838 -279.473225)
			(xy 401.214854 -279.455773) (xy 401.263073 -279.445929) (xy 401.312248 -279.443948) (xy 401.361103 -279.44988)
			(xy 401.408374 -279.463572) (xy 401.452836 -279.48467) (xy 401.493339 -279.512626) (xy 401.528832 -279.546718)
			(xy 401.558397 -279.586062) (xy 401.581268 -279.629639) (xy 401.596852 -279.67632) (xy 401.604747 -279.724897)
			(xy 401.605242 -279.749504) (xy 401.605237 -279.749758) (xy 401.94409 -279.749758) (xy 401.94805 -279.700704)
			(xy 401.959827 -279.65292) (xy 401.979118 -279.607644) (xy 402.005421 -279.566048) (xy 402.038056 -279.529211)
			(xy 402.076177 -279.498086) (xy 402.118798 -279.473479) (xy 402.164814 -279.456027) (xy 402.213033 -279.446183)
			(xy 402.262208 -279.444202) (xy 402.311063 -279.450134) (xy 402.358334 -279.463826) (xy 402.402796 -279.484924)
			(xy 402.443299 -279.51288) (xy 402.478792 -279.546972) (xy 402.508357 -279.586316) (xy 402.531228 -279.629893)
			(xy 402.546812 -279.676574) (xy 402.554707 -279.725151) (xy 402.555197 -279.749504) (xy 402.89405 -279.749504)
			(xy 402.89801 -279.70045) (xy 402.909787 -279.652666) (xy 402.929078 -279.60739) (xy 402.955381 -279.565794)
			(xy 402.988016 -279.528957) (xy 403.026137 -279.497832) (xy 403.068758 -279.473225) (xy 403.114774 -279.455773)
			(xy 403.162993 -279.445929) (xy 403.212168 -279.443948) (xy 403.261023 -279.44988) (xy 403.308294 -279.463572)
			(xy 403.352756 -279.48467) (xy 403.393259 -279.512626) (xy 403.428752 -279.546718) (xy 403.458317 -279.586062)
			(xy 403.481188 -279.629639) (xy 403.496772 -279.67632) (xy 403.504667 -279.724897) (xy 403.505162 -279.749504)
			(xy 403.505157 -279.749758) (xy 403.84401 -279.749758) (xy 403.84797 -279.700704) (xy 403.859747 -279.65292)
			(xy 403.879038 -279.607644) (xy 403.905341 -279.566048) (xy 403.937976 -279.529211) (xy 403.976097 -279.498086)
			(xy 404.018718 -279.473479) (xy 404.064734 -279.456027) (xy 404.112953 -279.446183) (xy 404.162128 -279.444202)
			(xy 404.210983 -279.450134) (xy 404.258254 -279.463826) (xy 404.302716 -279.484924) (xy 404.343219 -279.51288)
			(xy 404.378712 -279.546972) (xy 404.408277 -279.586316) (xy 404.431148 -279.629893) (xy 404.446732 -279.676574)
			(xy 404.454627 -279.725151) (xy 404.455117 -279.749504) (xy 404.79397 -279.749504) (xy 404.79793 -279.70045)
			(xy 404.809707 -279.652666) (xy 404.828998 -279.60739) (xy 404.855301 -279.565794) (xy 404.887936 -279.528957)
			(xy 404.926057 -279.497832) (xy 404.968678 -279.473225) (xy 405.014694 -279.455773) (xy 405.062913 -279.445929)
			(xy 405.112088 -279.443948) (xy 405.160943 -279.44988) (xy 405.208214 -279.463572) (xy 405.252676 -279.48467)
			(xy 405.293179 -279.512626) (xy 405.328672 -279.546718) (xy 405.358237 -279.586062) (xy 405.381108 -279.629639)
			(xy 405.396692 -279.67632) (xy 405.404587 -279.724897) (xy 405.405082 -279.749504) (xy 405.405077 -279.749758)
			(xy 405.744184 -279.749758) (xy 405.748144 -279.700704) (xy 405.759921 -279.65292) (xy 405.779212 -279.607644)
			(xy 405.805515 -279.566048) (xy 405.83815 -279.529211) (xy 405.876271 -279.498086) (xy 405.918892 -279.473479)
			(xy 405.964908 -279.456027) (xy 406.013127 -279.446183) (xy 406.062302 -279.444202) (xy 406.111157 -279.450134)
			(xy 406.158428 -279.463826) (xy 406.20289 -279.484924) (xy 406.243393 -279.51288) (xy 406.278886 -279.546972)
			(xy 406.308451 -279.586316) (xy 406.331322 -279.629893) (xy 406.346906 -279.676574) (xy 406.354801 -279.725151)
			(xy 406.355291 -279.749504) (xy 406.694144 -279.749504) (xy 406.698104 -279.70045) (xy 406.709881 -279.652666)
			(xy 406.729172 -279.60739) (xy 406.755475 -279.565794) (xy 406.78811 -279.528957) (xy 406.826231 -279.497832)
			(xy 406.868852 -279.473225) (xy 406.914868 -279.455773) (xy 406.963087 -279.445929) (xy 407.012262 -279.443948)
			(xy 407.061117 -279.44988) (xy 407.108388 -279.463572) (xy 407.15285 -279.48467) (xy 407.193353 -279.512626)
			(xy 407.228846 -279.546718) (xy 407.258411 -279.586062) (xy 407.281282 -279.629639) (xy 407.296866 -279.67632)
			(xy 407.304761 -279.724897) (xy 407.305256 -279.749504) (xy 407.305251 -279.749758) (xy 407.644104 -279.749758)
			(xy 407.648064 -279.700704) (xy 407.659841 -279.65292) (xy 407.679132 -279.607644) (xy 407.705435 -279.566048)
			(xy 407.73807 -279.529211) (xy 407.776191 -279.498086) (xy 407.818812 -279.473479) (xy 407.864828 -279.456027)
			(xy 407.913047 -279.446183) (xy 407.962222 -279.444202) (xy 408.011077 -279.450134) (xy 408.058348 -279.463826)
			(xy 408.10281 -279.484924) (xy 408.143313 -279.51288) (xy 408.178806 -279.546972) (xy 408.208371 -279.586316)
			(xy 408.231242 -279.629893) (xy 408.246826 -279.676574) (xy 408.254721 -279.725151) (xy 408.255211 -279.749504)
			(xy 408.594064 -279.749504) (xy 408.598024 -279.70045) (xy 408.609801 -279.652666) (xy 408.629092 -279.60739)
			(xy 408.655395 -279.565794) (xy 408.68803 -279.528957) (xy 408.726151 -279.497832) (xy 408.768772 -279.473225)
			(xy 408.814788 -279.455773) (xy 408.863007 -279.445929) (xy 408.912182 -279.443948) (xy 408.961037 -279.44988)
			(xy 409.008308 -279.463572) (xy 409.05277 -279.48467) (xy 409.093273 -279.512626) (xy 409.128766 -279.546718)
			(xy 409.158331 -279.586062) (xy 409.181202 -279.629639) (xy 409.196786 -279.67632) (xy 409.204681 -279.724897)
			(xy 409.205176 -279.749504) (xy 409.205171 -279.749758) (xy 409.544024 -279.749758) (xy 409.547984 -279.700704)
			(xy 409.559761 -279.65292) (xy 409.579052 -279.607644) (xy 409.605355 -279.566048) (xy 409.63799 -279.529211)
			(xy 409.676111 -279.498086) (xy 409.718732 -279.473479) (xy 409.764748 -279.456027) (xy 409.812967 -279.446183)
			(xy 409.862142 -279.444202) (xy 409.910997 -279.450134) (xy 409.958268 -279.463826) (xy 410.00273 -279.484924)
			(xy 410.043233 -279.51288) (xy 410.078726 -279.546972) (xy 410.108291 -279.586316) (xy 410.131162 -279.629893)
			(xy 410.146746 -279.676574) (xy 410.154641 -279.725151) (xy 410.155131 -279.749504) (xy 410.493984 -279.749504)
			(xy 410.497944 -279.70045) (xy 410.509721 -279.652666) (xy 410.529012 -279.60739) (xy 410.555315 -279.565794)
			(xy 410.58795 -279.528957) (xy 410.626071 -279.497832) (xy 410.668692 -279.473225) (xy 410.714708 -279.455773)
			(xy 410.762927 -279.445929) (xy 410.812102 -279.443948) (xy 410.860957 -279.44988) (xy 410.908228 -279.463572)
			(xy 410.95269 -279.48467) (xy 410.993193 -279.512626) (xy 411.028686 -279.546718) (xy 411.058251 -279.586062)
			(xy 411.081122 -279.629639) (xy 411.096706 -279.67632) (xy 411.104601 -279.724897) (xy 411.105096 -279.749504)
			(xy 411.105091 -279.749758) (xy 411.444198 -279.749758) (xy 411.448158 -279.700704) (xy 411.459935 -279.65292)
			(xy 411.479226 -279.607644) (xy 411.505529 -279.566048) (xy 411.538164 -279.529211) (xy 411.576285 -279.498086)
			(xy 411.618906 -279.473479) (xy 411.664922 -279.456027) (xy 411.713141 -279.446183) (xy 411.762316 -279.444202)
			(xy 411.811171 -279.450134) (xy 411.858442 -279.463826) (xy 411.902904 -279.484924) (xy 411.943407 -279.51288)
			(xy 411.9789 -279.546972) (xy 412.008465 -279.586316) (xy 412.031336 -279.629893) (xy 412.04692 -279.676574)
			(xy 412.054815 -279.725151) (xy 412.055305 -279.749504) (xy 412.394158 -279.749504) (xy 412.398118 -279.70045)
			(xy 412.409895 -279.652666) (xy 412.429186 -279.60739) (xy 412.455489 -279.565794) (xy 412.488124 -279.528957)
			(xy 412.526245 -279.497832) (xy 412.568866 -279.473225) (xy 412.614882 -279.455773) (xy 412.663101 -279.445929)
			(xy 412.712276 -279.443948) (xy 412.761131 -279.44988) (xy 412.808402 -279.463572) (xy 412.852864 -279.48467)
			(xy 412.893367 -279.512626) (xy 412.92886 -279.546718) (xy 412.958425 -279.586062) (xy 412.981296 -279.629639)
			(xy 412.99688 -279.67632) (xy 413.004775 -279.724897) (xy 413.00527 -279.749504) (xy 413.005265 -279.749758)
			(xy 413.344118 -279.749758) (xy 413.348078 -279.700704) (xy 413.359855 -279.65292) (xy 413.379146 -279.607644)
			(xy 413.405449 -279.566048) (xy 413.438084 -279.529211) (xy 413.476205 -279.498086) (xy 413.518826 -279.473479)
			(xy 413.564842 -279.456027) (xy 413.613061 -279.446183) (xy 413.662236 -279.444202) (xy 413.711091 -279.450134)
			(xy 413.758362 -279.463826) (xy 413.802824 -279.484924) (xy 413.843327 -279.51288) (xy 413.87882 -279.546972)
			(xy 413.908385 -279.586316) (xy 413.931256 -279.629893) (xy 413.94684 -279.676574) (xy 413.954735 -279.725151)
			(xy 413.955225 -279.749504) (xy 414.294078 -279.749504) (xy 414.298038 -279.70045) (xy 414.309815 -279.652666)
			(xy 414.329106 -279.60739) (xy 414.355409 -279.565794) (xy 414.388044 -279.528957) (xy 414.426165 -279.497832)
			(xy 414.468786 -279.473225) (xy 414.514802 -279.455773) (xy 414.563021 -279.445929) (xy 414.612196 -279.443948)
			(xy 414.661051 -279.44988) (xy 414.708322 -279.463572) (xy 414.752784 -279.48467) (xy 414.793287 -279.512626)
			(xy 414.82878 -279.546718) (xy 414.858345 -279.586062) (xy 414.881216 -279.629639) (xy 414.8968 -279.67632)
			(xy 414.904695 -279.724897) (xy 414.90519 -279.749504) (xy 414.905185 -279.749758) (xy 415.244038 -279.749758)
			(xy 415.247998 -279.700704) (xy 415.259775 -279.65292) (xy 415.279066 -279.607644) (xy 415.305369 -279.566048)
			(xy 415.338004 -279.529211) (xy 415.376125 -279.498086) (xy 415.418746 -279.473479) (xy 415.464762 -279.456027)
			(xy 415.512981 -279.446183) (xy 415.562156 -279.444202) (xy 415.611011 -279.450134) (xy 415.658282 -279.463826)
			(xy 415.702744 -279.484924) (xy 415.743247 -279.51288) (xy 415.77874 -279.546972) (xy 415.808305 -279.586316)
			(xy 415.831176 -279.629893) (xy 415.84676 -279.676574) (xy 415.854655 -279.725151) (xy 415.855145 -279.749504)
			(xy 416.193998 -279.749504) (xy 416.197958 -279.70045) (xy 416.209735 -279.652666) (xy 416.229026 -279.60739)
			(xy 416.255329 -279.565794) (xy 416.287964 -279.528957) (xy 416.326085 -279.497832) (xy 416.368706 -279.473225)
			(xy 416.414722 -279.455773) (xy 416.462941 -279.445929) (xy 416.512116 -279.443948) (xy 416.560971 -279.44988)
			(xy 416.608242 -279.463572) (xy 416.652704 -279.48467) (xy 416.693207 -279.512626) (xy 416.7287 -279.546718)
			(xy 416.758265 -279.586062) (xy 416.781136 -279.629639) (xy 416.79672 -279.67632) (xy 416.804615 -279.724897)
			(xy 416.80511 -279.749504) (xy 416.805105 -279.749758) (xy 417.144212 -279.749758) (xy 417.148172 -279.700704)
			(xy 417.159949 -279.65292) (xy 417.17924 -279.607644) (xy 417.205543 -279.566048) (xy 417.238178 -279.529211)
			(xy 417.276299 -279.498086) (xy 417.31892 -279.473479) (xy 417.364936 -279.456027) (xy 417.413155 -279.446183)
			(xy 417.46233 -279.444202) (xy 417.511185 -279.450134) (xy 417.558456 -279.463826) (xy 417.602918 -279.484924)
			(xy 417.643421 -279.51288) (xy 417.678914 -279.546972) (xy 417.708479 -279.586316) (xy 417.73135 -279.629893)
			(xy 417.746934 -279.676574) (xy 417.754829 -279.725151) (xy 417.755319 -279.749504) (xy 418.094172 -279.749504)
			(xy 418.098132 -279.70045) (xy 418.109909 -279.652666) (xy 418.1292 -279.60739) (xy 418.155503 -279.565794)
			(xy 418.188138 -279.528957) (xy 418.226259 -279.497832) (xy 418.26888 -279.473225) (xy 418.314896 -279.455773)
			(xy 418.363115 -279.445929) (xy 418.41229 -279.443948) (xy 418.461145 -279.44988) (xy 418.508416 -279.463572)
			(xy 418.552878 -279.48467) (xy 418.593381 -279.512626) (xy 418.628874 -279.546718) (xy 418.658439 -279.586062)
			(xy 418.68131 -279.629639) (xy 418.696894 -279.67632) (xy 418.704789 -279.724897) (xy 418.705284 -279.749504)
			(xy 418.705279 -279.749758) (xy 419.044132 -279.749758) (xy 419.048092 -279.700704) (xy 419.059869 -279.65292)
			(xy 419.07916 -279.607644) (xy 419.105463 -279.566048) (xy 419.138098 -279.529211) (xy 419.176219 -279.498086)
			(xy 419.21884 -279.473479) (xy 419.264856 -279.456027) (xy 419.313075 -279.446183) (xy 419.36225 -279.444202)
			(xy 419.411105 -279.450134) (xy 419.458376 -279.463826) (xy 419.502838 -279.484924) (xy 419.543341 -279.51288)
			(xy 419.578834 -279.546972) (xy 419.608399 -279.586316) (xy 419.63127 -279.629893) (xy 419.646854 -279.676574)
			(xy 419.654749 -279.725151) (xy 419.655239 -279.749504) (xy 419.994092 -279.749504) (xy 419.998052 -279.70045)
			(xy 420.009829 -279.652666) (xy 420.02912 -279.60739) (xy 420.055423 -279.565794) (xy 420.088058 -279.528957)
			(xy 420.126179 -279.497832) (xy 420.1688 -279.473225) (xy 420.214816 -279.455773) (xy 420.263035 -279.445929)
			(xy 420.31221 -279.443948) (xy 420.361065 -279.44988) (xy 420.408336 -279.463572) (xy 420.452798 -279.48467)
			(xy 420.493301 -279.512626) (xy 420.528794 -279.546718) (xy 420.558359 -279.586062) (xy 420.58123 -279.629639)
			(xy 420.596814 -279.67632) (xy 420.604709 -279.724897) (xy 420.605204 -279.749504) (xy 420.605199 -279.749758)
			(xy 420.944052 -279.749758) (xy 420.948012 -279.700704) (xy 420.959789 -279.65292) (xy 420.97908 -279.607644)
			(xy 421.005383 -279.566048) (xy 421.038018 -279.529211) (xy 421.076139 -279.498086) (xy 421.11876 -279.473479)
			(xy 421.164776 -279.456027) (xy 421.212995 -279.446183) (xy 421.26217 -279.444202) (xy 421.311025 -279.450134)
			(xy 421.358296 -279.463826) (xy 421.402758 -279.484924) (xy 421.443261 -279.51288) (xy 421.478754 -279.546972)
			(xy 421.508319 -279.586316) (xy 421.53119 -279.629893) (xy 421.546774 -279.676574) (xy 421.554669 -279.725151)
			(xy 421.555159 -279.749504) (xy 421.894012 -279.749504) (xy 421.897972 -279.70045) (xy 421.909749 -279.652666)
			(xy 421.92904 -279.60739) (xy 421.955343 -279.565794) (xy 421.987978 -279.528957) (xy 422.026099 -279.497832)
			(xy 422.06872 -279.473225) (xy 422.114736 -279.455773) (xy 422.162955 -279.445929) (xy 422.21213 -279.443948)
			(xy 422.260985 -279.44988) (xy 422.308256 -279.463572) (xy 422.352718 -279.48467) (xy 422.393221 -279.512626)
			(xy 422.428714 -279.546718) (xy 422.458279 -279.586062) (xy 422.48115 -279.629639) (xy 422.496734 -279.67632)
			(xy 422.504629 -279.724897) (xy 422.505124 -279.749504) (xy 422.505119 -279.749758) (xy 422.843972 -279.749758)
			(xy 422.847932 -279.700704) (xy 422.859709 -279.65292) (xy 422.879 -279.607644) (xy 422.905303 -279.566048)
			(xy 422.937938 -279.529211) (xy 422.976059 -279.498086) (xy 423.01868 -279.473479) (xy 423.064696 -279.456027)
			(xy 423.112915 -279.446183) (xy 423.16209 -279.444202) (xy 423.210945 -279.450134) (xy 423.258216 -279.463826)
			(xy 423.302678 -279.484924) (xy 423.343181 -279.51288) (xy 423.378674 -279.546972) (xy 423.408239 -279.586316)
			(xy 423.43111 -279.629893) (xy 423.446694 -279.676574) (xy 423.454589 -279.725151) (xy 423.455079 -279.749504)
			(xy 423.794186 -279.749504) (xy 423.798146 -279.70045) (xy 423.809923 -279.652666) (xy 423.829214 -279.60739)
			(xy 423.855517 -279.565794) (xy 423.888152 -279.528957) (xy 423.926273 -279.497832) (xy 423.968894 -279.473225)
			(xy 424.01491 -279.455773) (xy 424.063129 -279.445929) (xy 424.112304 -279.443948) (xy 424.161159 -279.44988)
			(xy 424.20843 -279.463572) (xy 424.252892 -279.48467) (xy 424.293395 -279.512626) (xy 424.328888 -279.546718)
			(xy 424.358453 -279.586062) (xy 424.381324 -279.629639) (xy 424.396908 -279.67632) (xy 424.404803 -279.724897)
			(xy 424.405298 -279.749504) (xy 424.405293 -279.749758) (xy 424.744146 -279.749758) (xy 424.748106 -279.700704)
			(xy 424.759883 -279.65292) (xy 424.779174 -279.607644) (xy 424.805477 -279.566048) (xy 424.838112 -279.529211)
			(xy 424.876233 -279.498086) (xy 424.918854 -279.473479) (xy 424.96487 -279.456027) (xy 425.013089 -279.446183)
			(xy 425.062264 -279.444202) (xy 425.111119 -279.450134) (xy 425.15839 -279.463826) (xy 425.202852 -279.484924)
			(xy 425.243355 -279.51288) (xy 425.278848 -279.546972) (xy 425.308413 -279.586316) (xy 425.331284 -279.629893)
			(xy 425.346868 -279.676574) (xy 425.354763 -279.725151) (xy 425.355253 -279.749504) (xy 425.694106 -279.749504)
			(xy 425.698066 -279.70045) (xy 425.709843 -279.652666) (xy 425.729134 -279.60739) (xy 425.755437 -279.565794)
			(xy 425.788072 -279.528957) (xy 425.826193 -279.497832) (xy 425.868814 -279.473225) (xy 425.91483 -279.455773)
			(xy 425.963049 -279.445929) (xy 426.012224 -279.443948) (xy 426.061079 -279.44988) (xy 426.10835 -279.463572)
			(xy 426.152812 -279.48467) (xy 426.193315 -279.512626) (xy 426.228808 -279.546718) (xy 426.258373 -279.586062)
			(xy 426.281244 -279.629639) (xy 426.296828 -279.67632) (xy 426.304723 -279.724897) (xy 426.305218 -279.749504)
			(xy 426.305213 -279.749758) (xy 426.644066 -279.749758) (xy 426.648026 -279.700704) (xy 426.659803 -279.65292)
			(xy 426.679094 -279.607644) (xy 426.705397 -279.566048) (xy 426.738032 -279.529211) (xy 426.776153 -279.498086)
			(xy 426.818774 -279.473479) (xy 426.86479 -279.456027) (xy 426.913009 -279.446183) (xy 426.962184 -279.444202)
			(xy 427.011039 -279.450134) (xy 427.05831 -279.463826) (xy 427.102772 -279.484924) (xy 427.143275 -279.51288)
			(xy 427.178768 -279.546972) (xy 427.208333 -279.586316) (xy 427.231204 -279.629893) (xy 427.246788 -279.676574)
			(xy 427.254683 -279.725151) (xy 427.255178 -279.749758) (xy 427.594026 -279.749758) (xy 427.597986 -279.700704)
			(xy 427.609763 -279.65292) (xy 427.629054 -279.607644) (xy 427.655357 -279.566048) (xy 427.687992 -279.529211)
			(xy 427.726113 -279.498086) (xy 427.768734 -279.473479) (xy 427.81475 -279.456027) (xy 427.862969 -279.446183)
			(xy 427.912144 -279.444202) (xy 427.960999 -279.450134) (xy 428.00827 -279.463826) (xy 428.052732 -279.484924)
			(xy 428.093235 -279.51288) (xy 428.128728 -279.546972) (xy 428.158293 -279.586316) (xy 428.181164 -279.629893)
			(xy 428.196748 -279.676574) (xy 428.204643 -279.725151) (xy 428.205138 -279.749758) (xy 428.543986 -279.749758)
			(xy 428.547946 -279.700704) (xy 428.559723 -279.65292) (xy 428.579014 -279.607644) (xy 428.605317 -279.566048)
			(xy 428.637952 -279.529211) (xy 428.676073 -279.498086) (xy 428.718694 -279.473479) (xy 428.76471 -279.456027)
			(xy 428.812929 -279.446183) (xy 428.862104 -279.444202) (xy 428.910959 -279.450134) (xy 428.95823 -279.463826)
			(xy 429.002692 -279.484924) (xy 429.043195 -279.51288) (xy 429.078688 -279.546972) (xy 429.108253 -279.586316)
			(xy 429.131124 -279.629893) (xy 429.146708 -279.676574) (xy 429.154603 -279.725151) (xy 429.155098 -279.749758)
			(xy 429.4942 -279.749758) (xy 429.49816 -279.700704) (xy 429.509937 -279.65292) (xy 429.529228 -279.607644)
			(xy 429.555531 -279.566048) (xy 429.588166 -279.529211) (xy 429.626287 -279.498086) (xy 429.668908 -279.473479)
			(xy 429.714924 -279.456027) (xy 429.763143 -279.446183) (xy 429.812318 -279.444202) (xy 429.861173 -279.450134)
			(xy 429.908444 -279.463826) (xy 429.952906 -279.484924) (xy 429.993409 -279.51288) (xy 430.028902 -279.546972)
			(xy 430.058467 -279.586316) (xy 430.081338 -279.629893) (xy 430.096922 -279.676574) (xy 430.104817 -279.725151)
			(xy 430.105312 -279.749758) (xy 430.44416 -279.749758) (xy 430.44812 -279.700704) (xy 430.459897 -279.65292)
			(xy 430.479188 -279.607644) (xy 430.505491 -279.566048) (xy 430.538126 -279.529211) (xy 430.576247 -279.498086)
			(xy 430.618868 -279.473479) (xy 430.664884 -279.456027) (xy 430.713103 -279.446183) (xy 430.762278 -279.444202)
			(xy 430.811133 -279.450134) (xy 430.858404 -279.463826) (xy 430.902866 -279.484924) (xy 430.943369 -279.51288)
			(xy 430.978862 -279.546972) (xy 431.008427 -279.586316) (xy 431.031298 -279.629893) (xy 431.046882 -279.676574)
			(xy 431.054777 -279.725151) (xy 431.055272 -279.749758) (xy 431.055267 -279.750012) (xy 431.394374 -279.750012)
			(xy 431.398334 -279.700958) (xy 431.410111 -279.653174) (xy 431.429402 -279.607898) (xy 431.455705 -279.566302)
			(xy 431.48834 -279.529465) (xy 431.526461 -279.49834) (xy 431.569082 -279.473733) (xy 431.615098 -279.456281)
			(xy 431.663317 -279.446437) (xy 431.712492 -279.444456) (xy 431.761347 -279.450388) (xy 431.808618 -279.46408)
			(xy 431.85308 -279.485178) (xy 431.893583 -279.513134) (xy 431.929076 -279.547226) (xy 431.958641 -279.58657)
			(xy 431.981512 -279.630147) (xy 431.997096 -279.676828) (xy 432.004991 -279.725405) (xy 432.005486 -279.750012)
			(xy 432.004991 -279.774619) (xy 431.997096 -279.823196) (xy 431.981512 -279.869877) (xy 431.970835 -279.89022)
			(xy 447.862958 -279.89022) (xy 447.867029 -279.834598) (xy 447.879155 -279.780161) (xy 447.899078 -279.72807)
			(xy 447.926374 -279.679435) (xy 447.96046 -279.635292) (xy 448.000609 -279.596583) (xy 448.045967 -279.564132)
			(xy 448.095567 -279.538631) (xy 448.148351 -279.520624) (xy 448.203194 -279.510494) (xy 448.258928 -279.508457)
			(xy 448.314365 -279.514557) (xy 448.368322 -279.528663) (xy 448.419651 -279.550475) (xy 448.467257 -279.579529)
			(xy 448.510125 -279.615204) (xy 448.547342 -279.656741) (xy 448.569895 -279.69083) (xy 461.074006 -279.69083)
			(xy 461.078077 -279.635208) (xy 461.090203 -279.580771) (xy 461.110126 -279.52868) (xy 461.137422 -279.480045)
			(xy 461.171508 -279.435902) (xy 461.211657 -279.397193) (xy 461.257015 -279.364742) (xy 461.306615 -279.339241)
			(xy 461.359399 -279.321234) (xy 461.414242 -279.311104) (xy 461.469976 -279.309067) (xy 461.525413 -279.315167)
			(xy 461.57937 -279.329273) (xy 461.630699 -279.351085) (xy 461.678305 -279.380139) (xy 461.721173 -279.415814)
			(xy 461.75839 -279.457351) (xy 461.789163 -279.503864) (xy 461.812835 -279.554361) (xy 461.828903 -279.607768)
			(xy 461.837023 -279.662944) (xy 461.837532 -279.69083) (xy 461.837023 -279.718716) (xy 461.828903 -279.773892)
			(xy 461.812835 -279.827299) (xy 461.789163 -279.877796) (xy 461.75839 -279.924309) (xy 461.721173 -279.965846)
			(xy 461.678305 -280.001521) (xy 461.630699 -280.030575) (xy 461.57937 -280.052387) (xy 461.525413 -280.066493)
			(xy 461.469976 -280.072593) (xy 461.414242 -280.070556) (xy 461.359399 -280.060426) (xy 461.306615 -280.042419)
			(xy 461.257015 -280.016918) (xy 461.211657 -279.984467) (xy 461.171508 -279.945758) (xy 461.137422 -279.901615)
			(xy 461.110126 -279.85298) (xy 461.090203 -279.800889) (xy 461.078077 -279.746452) (xy 461.074006 -279.69083)
			(xy 448.569895 -279.69083) (xy 448.578115 -279.703254) (xy 448.601787 -279.753751) (xy 448.617855 -279.807158)
			(xy 448.625975 -279.862334) (xy 448.626484 -279.89022) (xy 448.625975 -279.918106) (xy 448.617855 -279.973282)
			(xy 448.601787 -280.026689) (xy 448.578115 -280.077186) (xy 448.547342 -280.123699) (xy 448.510125 -280.165236)
			(xy 448.467257 -280.200911) (xy 448.428632 -280.224484) (xy 455.005184 -280.224484) (xy 455.009255 -280.168862)
			(xy 455.021381 -280.114425) (xy 455.041304 -280.062334) (xy 455.0686 -280.013699) (xy 455.102686 -279.969556)
			(xy 455.142835 -279.930847) (xy 455.188193 -279.898396) (xy 455.237793 -279.872895) (xy 455.290577 -279.854888)
			(xy 455.34542 -279.844758) (xy 455.401154 -279.842721) (xy 455.456591 -279.848821) (xy 455.510548 -279.862927)
			(xy 455.561877 -279.884739) (xy 455.609483 -279.913793) (xy 455.652351 -279.949468) (xy 455.689568 -279.991005)
			(xy 455.720341 -280.037518) (xy 455.744013 -280.088015) (xy 455.760081 -280.141422) (xy 455.768201 -280.196598)
			(xy 455.76871 -280.224484) (xy 457.024484 -280.224484) (xy 457.028555 -280.168862) (xy 457.040681 -280.114425)
			(xy 457.060604 -280.062334) (xy 457.0879 -280.013699) (xy 457.121986 -279.969556) (xy 457.162135 -279.930847)
			(xy 457.207493 -279.898396) (xy 457.257093 -279.872895) (xy 457.309877 -279.854888) (xy 457.36472 -279.844758)
			(xy 457.420454 -279.842721) (xy 457.475891 -279.848821) (xy 457.529848 -279.862927) (xy 457.581177 -279.884739)
			(xy 457.628783 -279.913793) (xy 457.671651 -279.949468) (xy 457.708868 -279.991005) (xy 457.739641 -280.037518)
			(xy 457.763313 -280.088015) (xy 457.779381 -280.141422) (xy 457.787501 -280.196598) (xy 457.78801 -280.224484)
			(xy 457.787501 -280.25237) (xy 457.779381 -280.307546) (xy 457.763313 -280.360953) (xy 457.739641 -280.41145)
			(xy 457.708868 -280.457963) (xy 457.671651 -280.4995) (xy 457.628783 -280.535175) (xy 457.581177 -280.564229)
			(xy 457.529848 -280.586041) (xy 457.475891 -280.600147) (xy 457.420454 -280.606247) (xy 457.36472 -280.60421)
			(xy 457.309877 -280.59408) (xy 457.257093 -280.576073) (xy 457.207493 -280.550572) (xy 457.162135 -280.518121)
			(xy 457.121986 -280.479412) (xy 457.0879 -280.435269) (xy 457.060604 -280.386634) (xy 457.040681 -280.334543)
			(xy 457.028555 -280.280106) (xy 457.024484 -280.224484) (xy 455.76871 -280.224484) (xy 455.768201 -280.25237)
			(xy 455.760081 -280.307546) (xy 455.744013 -280.360953) (xy 455.720341 -280.41145) (xy 455.689568 -280.457963)
			(xy 455.652351 -280.4995) (xy 455.609483 -280.535175) (xy 455.561877 -280.564229) (xy 455.510548 -280.586041)
			(xy 455.456591 -280.600147) (xy 455.401154 -280.606247) (xy 455.34542 -280.60421) (xy 455.290577 -280.59408)
			(xy 455.237793 -280.576073) (xy 455.188193 -280.550572) (xy 455.142835 -280.518121) (xy 455.102686 -280.479412)
			(xy 455.0686 -280.435269) (xy 455.041304 -280.386634) (xy 455.021381 -280.334543) (xy 455.009255 -280.280106)
			(xy 455.005184 -280.224484) (xy 448.428632 -280.224484) (xy 448.419651 -280.229965) (xy 448.368322 -280.251777)
			(xy 448.314365 -280.265883) (xy 448.258928 -280.271983) (xy 448.203194 -280.269946) (xy 448.148351 -280.259816)
			(xy 448.095567 -280.241809) (xy 448.045967 -280.216308) (xy 448.000609 -280.183857) (xy 447.96046 -280.145148)
			(xy 447.926374 -280.101005) (xy 447.899078 -280.05237) (xy 447.879155 -280.000279) (xy 447.867029 -279.945842)
			(xy 447.862958 -279.89022) (xy 431.970835 -279.89022) (xy 431.958641 -279.913454) (xy 431.929076 -279.952798)
			(xy 431.893583 -279.98689) (xy 431.85308 -280.014846) (xy 431.808618 -280.035944) (xy 431.761347 -280.049636)
			(xy 431.712492 -280.055568) (xy 431.663317 -280.053587) (xy 431.615098 -280.043743) (xy 431.569082 -280.026291)
			(xy 431.526461 -280.001684) (xy 431.48834 -279.970559) (xy 431.455705 -279.933722) (xy 431.429402 -279.892126)
			(xy 431.410111 -279.84685) (xy 431.398334 -279.799066) (xy 431.394374 -279.750012) (xy 431.055267 -279.750012)
			(xy 431.054777 -279.774365) (xy 431.046882 -279.822942) (xy 431.031298 -279.869623) (xy 431.008427 -279.9132)
			(xy 430.978862 -279.952544) (xy 430.943369 -279.986636) (xy 430.902866 -280.014592) (xy 430.858404 -280.03569)
			(xy 430.811133 -280.049382) (xy 430.762278 -280.055314) (xy 430.713103 -280.053333) (xy 430.664884 -280.043489)
			(xy 430.618868 -280.026037) (xy 430.576247 -280.00143) (xy 430.538126 -279.970305) (xy 430.505491 -279.933468)
			(xy 430.479188 -279.891872) (xy 430.459897 -279.846596) (xy 430.44812 -279.798812) (xy 430.44416 -279.749758)
			(xy 430.105312 -279.749758) (xy 430.104817 -279.774365) (xy 430.096922 -279.822942) (xy 430.081338 -279.869623)
			(xy 430.058467 -279.9132) (xy 430.028902 -279.952544) (xy 429.993409 -279.986636) (xy 429.952906 -280.014592)
			(xy 429.908444 -280.03569) (xy 429.861173 -280.049382) (xy 429.812318 -280.055314) (xy 429.763143 -280.053333)
			(xy 429.714924 -280.043489) (xy 429.668908 -280.026037) (xy 429.626287 -280.00143) (xy 429.588166 -279.970305)
			(xy 429.555531 -279.933468) (xy 429.529228 -279.891872) (xy 429.509937 -279.846596) (xy 429.49816 -279.798812)
			(xy 429.4942 -279.749758) (xy 429.155098 -279.749758) (xy 429.154603 -279.774365) (xy 429.146708 -279.822942)
			(xy 429.131124 -279.869623) (xy 429.108253 -279.9132) (xy 429.078688 -279.952544) (xy 429.043195 -279.986636)
			(xy 429.002692 -280.014592) (xy 428.95823 -280.03569) (xy 428.910959 -280.049382) (xy 428.862104 -280.055314)
			(xy 428.812929 -280.053333) (xy 428.76471 -280.043489) (xy 428.718694 -280.026037) (xy 428.676073 -280.00143)
			(xy 428.637952 -279.970305) (xy 428.605317 -279.933468) (xy 428.579014 -279.891872) (xy 428.559723 -279.846596)
			(xy 428.547946 -279.798812) (xy 428.543986 -279.749758) (xy 428.205138 -279.749758) (xy 428.204643 -279.774365)
			(xy 428.196748 -279.822942) (xy 428.181164 -279.869623) (xy 428.158293 -279.9132) (xy 428.128728 -279.952544)
			(xy 428.093235 -279.986636) (xy 428.052732 -280.014592) (xy 428.00827 -280.03569) (xy 427.960999 -280.049382)
			(xy 427.912144 -280.055314) (xy 427.862969 -280.053333) (xy 427.81475 -280.043489) (xy 427.768734 -280.026037)
			(xy 427.726113 -280.00143) (xy 427.687992 -279.970305) (xy 427.655357 -279.933468) (xy 427.629054 -279.891872)
			(xy 427.609763 -279.846596) (xy 427.597986 -279.798812) (xy 427.594026 -279.749758) (xy 427.255178 -279.749758)
			(xy 427.254683 -279.774365) (xy 427.246788 -279.822942) (xy 427.231204 -279.869623) (xy 427.208333 -279.9132)
			(xy 427.178768 -279.952544) (xy 427.143275 -279.986636) (xy 427.102772 -280.014592) (xy 427.05831 -280.03569)
			(xy 427.011039 -280.049382) (xy 426.962184 -280.055314) (xy 426.913009 -280.053333) (xy 426.86479 -280.043489)
			(xy 426.818774 -280.026037) (xy 426.776153 -280.00143) (xy 426.738032 -279.970305) (xy 426.705397 -279.933468)
			(xy 426.679094 -279.891872) (xy 426.659803 -279.846596) (xy 426.648026 -279.798812) (xy 426.644066 -279.749758)
			(xy 426.305213 -279.749758) (xy 426.304723 -279.774111) (xy 426.296828 -279.822688) (xy 426.281244 -279.869369)
			(xy 426.258373 -279.912946) (xy 426.228808 -279.95229) (xy 426.193315 -279.986382) (xy 426.152812 -280.014338)
			(xy 426.10835 -280.035436) (xy 426.061079 -280.049128) (xy 426.012224 -280.05506) (xy 425.963049 -280.053079)
			(xy 425.91483 -280.043235) (xy 425.868814 -280.025783) (xy 425.826193 -280.001176) (xy 425.788072 -279.970051)
			(xy 425.755437 -279.933214) (xy 425.729134 -279.891618) (xy 425.709843 -279.846342) (xy 425.698066 -279.798558)
			(xy 425.694106 -279.749504) (xy 425.355253 -279.749504) (xy 425.355258 -279.749758) (xy 425.354763 -279.774365)
			(xy 425.346868 -279.822942) (xy 425.331284 -279.869623) (xy 425.308413 -279.9132) (xy 425.278848 -279.952544)
			(xy 425.243355 -279.986636) (xy 425.202852 -280.014592) (xy 425.15839 -280.03569) (xy 425.111119 -280.049382)
			(xy 425.062264 -280.055314) (xy 425.013089 -280.053333) (xy 424.96487 -280.043489) (xy 424.918854 -280.026037)
			(xy 424.876233 -280.00143) (xy 424.838112 -279.970305) (xy 424.805477 -279.933468) (xy 424.779174 -279.891872)
			(xy 424.759883 -279.846596) (xy 424.748106 -279.798812) (xy 424.744146 -279.749758) (xy 424.405293 -279.749758)
			(xy 424.404803 -279.774111) (xy 424.396908 -279.822688) (xy 424.381324 -279.869369) (xy 424.358453 -279.912946)
			(xy 424.328888 -279.95229) (xy 424.293395 -279.986382) (xy 424.252892 -280.014338) (xy 424.20843 -280.035436)
			(xy 424.161159 -280.049128) (xy 424.112304 -280.05506) (xy 424.063129 -280.053079) (xy 424.01491 -280.043235)
			(xy 423.968894 -280.025783) (xy 423.926273 -280.001176) (xy 423.888152 -279.970051) (xy 423.855517 -279.933214)
			(xy 423.829214 -279.891618) (xy 423.809923 -279.846342) (xy 423.798146 -279.798558) (xy 423.794186 -279.749504)
			(xy 423.455079 -279.749504) (xy 423.455084 -279.749758) (xy 423.454589 -279.774365) (xy 423.446694 -279.822942)
			(xy 423.43111 -279.869623) (xy 423.408239 -279.9132) (xy 423.378674 -279.952544) (xy 423.343181 -279.986636)
			(xy 423.302678 -280.014592) (xy 423.258216 -280.03569) (xy 423.210945 -280.049382) (xy 423.16209 -280.055314)
			(xy 423.112915 -280.053333) (xy 423.064696 -280.043489) (xy 423.01868 -280.026037) (xy 422.976059 -280.00143)
			(xy 422.937938 -279.970305) (xy 422.905303 -279.933468) (xy 422.879 -279.891872) (xy 422.859709 -279.846596)
			(xy 422.847932 -279.798812) (xy 422.843972 -279.749758) (xy 422.505119 -279.749758) (xy 422.504629 -279.774111)
			(xy 422.496734 -279.822688) (xy 422.48115 -279.869369) (xy 422.458279 -279.912946) (xy 422.428714 -279.95229)
			(xy 422.393221 -279.986382) (xy 422.352718 -280.014338) (xy 422.308256 -280.035436) (xy 422.260985 -280.049128)
			(xy 422.21213 -280.05506) (xy 422.162955 -280.053079) (xy 422.114736 -280.043235) (xy 422.06872 -280.025783)
			(xy 422.026099 -280.001176) (xy 421.987978 -279.970051) (xy 421.955343 -279.933214) (xy 421.92904 -279.891618)
			(xy 421.909749 -279.846342) (xy 421.897972 -279.798558) (xy 421.894012 -279.749504) (xy 421.555159 -279.749504)
			(xy 421.555164 -279.749758) (xy 421.554669 -279.774365) (xy 421.546774 -279.822942) (xy 421.53119 -279.869623)
			(xy 421.508319 -279.9132) (xy 421.478754 -279.952544) (xy 421.443261 -279.986636) (xy 421.402758 -280.014592)
			(xy 421.358296 -280.03569) (xy 421.311025 -280.049382) (xy 421.26217 -280.055314) (xy 421.212995 -280.053333)
			(xy 421.164776 -280.043489) (xy 421.11876 -280.026037) (xy 421.076139 -280.00143) (xy 421.038018 -279.970305)
			(xy 421.005383 -279.933468) (xy 420.97908 -279.891872) (xy 420.959789 -279.846596) (xy 420.948012 -279.798812)
			(xy 420.944052 -279.749758) (xy 420.605199 -279.749758) (xy 420.604709 -279.774111) (xy 420.596814 -279.822688)
			(xy 420.58123 -279.869369) (xy 420.558359 -279.912946) (xy 420.528794 -279.95229) (xy 420.493301 -279.986382)
			(xy 420.452798 -280.014338) (xy 420.408336 -280.035436) (xy 420.361065 -280.049128) (xy 420.31221 -280.05506)
			(xy 420.263035 -280.053079) (xy 420.214816 -280.043235) (xy 420.1688 -280.025783) (xy 420.126179 -280.001176)
			(xy 420.088058 -279.970051) (xy 420.055423 -279.933214) (xy 420.02912 -279.891618) (xy 420.009829 -279.846342)
			(xy 419.998052 -279.798558) (xy 419.994092 -279.749504) (xy 419.655239 -279.749504) (xy 419.655244 -279.749758)
			(xy 419.654749 -279.774365) (xy 419.646854 -279.822942) (xy 419.63127 -279.869623) (xy 419.608399 -279.9132)
			(xy 419.578834 -279.952544) (xy 419.543341 -279.986636) (xy 419.502838 -280.014592) (xy 419.458376 -280.03569)
			(xy 419.411105 -280.049382) (xy 419.36225 -280.055314) (xy 419.313075 -280.053333) (xy 419.264856 -280.043489)
			(xy 419.21884 -280.026037) (xy 419.176219 -280.00143) (xy 419.138098 -279.970305) (xy 419.105463 -279.933468)
			(xy 419.07916 -279.891872) (xy 419.059869 -279.846596) (xy 419.048092 -279.798812) (xy 419.044132 -279.749758)
			(xy 418.705279 -279.749758) (xy 418.704789 -279.774111) (xy 418.696894 -279.822688) (xy 418.68131 -279.869369)
			(xy 418.658439 -279.912946) (xy 418.628874 -279.95229) (xy 418.593381 -279.986382) (xy 418.552878 -280.014338)
			(xy 418.508416 -280.035436) (xy 418.461145 -280.049128) (xy 418.41229 -280.05506) (xy 418.363115 -280.053079)
			(xy 418.314896 -280.043235) (xy 418.26888 -280.025783) (xy 418.226259 -280.001176) (xy 418.188138 -279.970051)
			(xy 418.155503 -279.933214) (xy 418.1292 -279.891618) (xy 418.109909 -279.846342) (xy 418.098132 -279.798558)
			(xy 418.094172 -279.749504) (xy 417.755319 -279.749504) (xy 417.755324 -279.749758) (xy 417.754829 -279.774365)
			(xy 417.746934 -279.822942) (xy 417.73135 -279.869623) (xy 417.708479 -279.9132) (xy 417.678914 -279.952544)
			(xy 417.643421 -279.986636) (xy 417.602918 -280.014592) (xy 417.558456 -280.03569) (xy 417.511185 -280.049382)
			(xy 417.46233 -280.055314) (xy 417.413155 -280.053333) (xy 417.364936 -280.043489) (xy 417.31892 -280.026037)
			(xy 417.276299 -280.00143) (xy 417.238178 -279.970305) (xy 417.205543 -279.933468) (xy 417.17924 -279.891872)
			(xy 417.159949 -279.846596) (xy 417.148172 -279.798812) (xy 417.144212 -279.749758) (xy 416.805105 -279.749758)
			(xy 416.804615 -279.774111) (xy 416.79672 -279.822688) (xy 416.781136 -279.869369) (xy 416.758265 -279.912946)
			(xy 416.7287 -279.95229) (xy 416.693207 -279.986382) (xy 416.652704 -280.014338) (xy 416.608242 -280.035436)
			(xy 416.560971 -280.049128) (xy 416.512116 -280.05506) (xy 416.462941 -280.053079) (xy 416.414722 -280.043235)
			(xy 416.368706 -280.025783) (xy 416.326085 -280.001176) (xy 416.287964 -279.970051) (xy 416.255329 -279.933214)
			(xy 416.229026 -279.891618) (xy 416.209735 -279.846342) (xy 416.197958 -279.798558) (xy 416.193998 -279.749504)
			(xy 415.855145 -279.749504) (xy 415.85515 -279.749758) (xy 415.854655 -279.774365) (xy 415.84676 -279.822942)
			(xy 415.831176 -279.869623) (xy 415.808305 -279.9132) (xy 415.77874 -279.952544) (xy 415.743247 -279.986636)
			(xy 415.702744 -280.014592) (xy 415.658282 -280.03569) (xy 415.611011 -280.049382) (xy 415.562156 -280.055314)
			(xy 415.512981 -280.053333) (xy 415.464762 -280.043489) (xy 415.418746 -280.026037) (xy 415.376125 -280.00143)
			(xy 415.338004 -279.970305) (xy 415.305369 -279.933468) (xy 415.279066 -279.891872) (xy 415.259775 -279.846596)
			(xy 415.247998 -279.798812) (xy 415.244038 -279.749758) (xy 414.905185 -279.749758) (xy 414.904695 -279.774111)
			(xy 414.8968 -279.822688) (xy 414.881216 -279.869369) (xy 414.858345 -279.912946) (xy 414.82878 -279.95229)
			(xy 414.793287 -279.986382) (xy 414.752784 -280.014338) (xy 414.708322 -280.035436) (xy 414.661051 -280.049128)
			(xy 414.612196 -280.05506) (xy 414.563021 -280.053079) (xy 414.514802 -280.043235) (xy 414.468786 -280.025783)
			(xy 414.426165 -280.001176) (xy 414.388044 -279.970051) (xy 414.355409 -279.933214) (xy 414.329106 -279.891618)
			(xy 414.309815 -279.846342) (xy 414.298038 -279.798558) (xy 414.294078 -279.749504) (xy 413.955225 -279.749504)
			(xy 413.95523 -279.749758) (xy 413.954735 -279.774365) (xy 413.94684 -279.822942) (xy 413.931256 -279.869623)
			(xy 413.908385 -279.9132) (xy 413.87882 -279.952544) (xy 413.843327 -279.986636) (xy 413.802824 -280.014592)
			(xy 413.758362 -280.03569) (xy 413.711091 -280.049382) (xy 413.662236 -280.055314) (xy 413.613061 -280.053333)
			(xy 413.564842 -280.043489) (xy 413.518826 -280.026037) (xy 413.476205 -280.00143) (xy 413.438084 -279.970305)
			(xy 413.405449 -279.933468) (xy 413.379146 -279.891872) (xy 413.359855 -279.846596) (xy 413.348078 -279.798812)
			(xy 413.344118 -279.749758) (xy 413.005265 -279.749758) (xy 413.004775 -279.774111) (xy 412.99688 -279.822688)
			(xy 412.981296 -279.869369) (xy 412.958425 -279.912946) (xy 412.92886 -279.95229) (xy 412.893367 -279.986382)
			(xy 412.852864 -280.014338) (xy 412.808402 -280.035436) (xy 412.761131 -280.049128) (xy 412.712276 -280.05506)
			(xy 412.663101 -280.053079) (xy 412.614882 -280.043235) (xy 412.568866 -280.025783) (xy 412.526245 -280.001176)
			(xy 412.488124 -279.970051) (xy 412.455489 -279.933214) (xy 412.429186 -279.891618) (xy 412.409895 -279.846342)
			(xy 412.398118 -279.798558) (xy 412.394158 -279.749504) (xy 412.055305 -279.749504) (xy 412.05531 -279.749758)
			(xy 412.054815 -279.774365) (xy 412.04692 -279.822942) (xy 412.031336 -279.869623) (xy 412.008465 -279.9132)
			(xy 411.9789 -279.952544) (xy 411.943407 -279.986636) (xy 411.902904 -280.014592) (xy 411.858442 -280.03569)
			(xy 411.811171 -280.049382) (xy 411.762316 -280.055314) (xy 411.713141 -280.053333) (xy 411.664922 -280.043489)
			(xy 411.618906 -280.026037) (xy 411.576285 -280.00143) (xy 411.538164 -279.970305) (xy 411.505529 -279.933468)
			(xy 411.479226 -279.891872) (xy 411.459935 -279.846596) (xy 411.448158 -279.798812) (xy 411.444198 -279.749758)
			(xy 411.105091 -279.749758) (xy 411.104601 -279.774111) (xy 411.096706 -279.822688) (xy 411.081122 -279.869369)
			(xy 411.058251 -279.912946) (xy 411.028686 -279.95229) (xy 410.993193 -279.986382) (xy 410.95269 -280.014338)
			(xy 410.908228 -280.035436) (xy 410.860957 -280.049128) (xy 410.812102 -280.05506) (xy 410.762927 -280.053079)
			(xy 410.714708 -280.043235) (xy 410.668692 -280.025783) (xy 410.626071 -280.001176) (xy 410.58795 -279.970051)
			(xy 410.555315 -279.933214) (xy 410.529012 -279.891618) (xy 410.509721 -279.846342) (xy 410.497944 -279.798558)
			(xy 410.493984 -279.749504) (xy 410.155131 -279.749504) (xy 410.155136 -279.749758) (xy 410.154641 -279.774365)
			(xy 410.146746 -279.822942) (xy 410.131162 -279.869623) (xy 410.108291 -279.9132) (xy 410.078726 -279.952544)
			(xy 410.043233 -279.986636) (xy 410.00273 -280.014592) (xy 409.958268 -280.03569) (xy 409.910997 -280.049382)
			(xy 409.862142 -280.055314) (xy 409.812967 -280.053333) (xy 409.764748 -280.043489) (xy 409.718732 -280.026037)
			(xy 409.676111 -280.00143) (xy 409.63799 -279.970305) (xy 409.605355 -279.933468) (xy 409.579052 -279.891872)
			(xy 409.559761 -279.846596) (xy 409.547984 -279.798812) (xy 409.544024 -279.749758) (xy 409.205171 -279.749758)
			(xy 409.204681 -279.774111) (xy 409.196786 -279.822688) (xy 409.181202 -279.869369) (xy 409.158331 -279.912946)
			(xy 409.128766 -279.95229) (xy 409.093273 -279.986382) (xy 409.05277 -280.014338) (xy 409.008308 -280.035436)
			(xy 408.961037 -280.049128) (xy 408.912182 -280.05506) (xy 408.863007 -280.053079) (xy 408.814788 -280.043235)
			(xy 408.768772 -280.025783) (xy 408.726151 -280.001176) (xy 408.68803 -279.970051) (xy 408.655395 -279.933214)
			(xy 408.629092 -279.891618) (xy 408.609801 -279.846342) (xy 408.598024 -279.798558) (xy 408.594064 -279.749504)
			(xy 408.255211 -279.749504) (xy 408.255216 -279.749758) (xy 408.254721 -279.774365) (xy 408.246826 -279.822942)
			(xy 408.231242 -279.869623) (xy 408.208371 -279.9132) (xy 408.178806 -279.952544) (xy 408.143313 -279.986636)
			(xy 408.10281 -280.014592) (xy 408.058348 -280.03569) (xy 408.011077 -280.049382) (xy 407.962222 -280.055314)
			(xy 407.913047 -280.053333) (xy 407.864828 -280.043489) (xy 407.818812 -280.026037) (xy 407.776191 -280.00143)
			(xy 407.73807 -279.970305) (xy 407.705435 -279.933468) (xy 407.679132 -279.891872) (xy 407.659841 -279.846596)
			(xy 407.648064 -279.798812) (xy 407.644104 -279.749758) (xy 407.305251 -279.749758) (xy 407.304761 -279.774111)
			(xy 407.296866 -279.822688) (xy 407.281282 -279.869369) (xy 407.258411 -279.912946) (xy 407.228846 -279.95229)
			(xy 407.193353 -279.986382) (xy 407.15285 -280.014338) (xy 407.108388 -280.035436) (xy 407.061117 -280.049128)
			(xy 407.012262 -280.05506) (xy 406.963087 -280.053079) (xy 406.914868 -280.043235) (xy 406.868852 -280.025783)
			(xy 406.826231 -280.001176) (xy 406.78811 -279.970051) (xy 406.755475 -279.933214) (xy 406.729172 -279.891618)
			(xy 406.709881 -279.846342) (xy 406.698104 -279.798558) (xy 406.694144 -279.749504) (xy 406.355291 -279.749504)
			(xy 406.355296 -279.749758) (xy 406.354801 -279.774365) (xy 406.346906 -279.822942) (xy 406.331322 -279.869623)
			(xy 406.308451 -279.9132) (xy 406.278886 -279.952544) (xy 406.243393 -279.986636) (xy 406.20289 -280.014592)
			(xy 406.158428 -280.03569) (xy 406.111157 -280.049382) (xy 406.062302 -280.055314) (xy 406.013127 -280.053333)
			(xy 405.964908 -280.043489) (xy 405.918892 -280.026037) (xy 405.876271 -280.00143) (xy 405.83815 -279.970305)
			(xy 405.805515 -279.933468) (xy 405.779212 -279.891872) (xy 405.759921 -279.846596) (xy 405.748144 -279.798812)
			(xy 405.744184 -279.749758) (xy 405.405077 -279.749758) (xy 405.404587 -279.774111) (xy 405.396692 -279.822688)
			(xy 405.381108 -279.869369) (xy 405.358237 -279.912946) (xy 405.328672 -279.95229) (xy 405.293179 -279.986382)
			(xy 405.252676 -280.014338) (xy 405.208214 -280.035436) (xy 405.160943 -280.049128) (xy 405.112088 -280.05506)
			(xy 405.062913 -280.053079) (xy 405.014694 -280.043235) (xy 404.968678 -280.025783) (xy 404.926057 -280.001176)
			(xy 404.887936 -279.970051) (xy 404.855301 -279.933214) (xy 404.828998 -279.891618) (xy 404.809707 -279.846342)
			(xy 404.79793 -279.798558) (xy 404.79397 -279.749504) (xy 404.455117 -279.749504) (xy 404.455122 -279.749758)
			(xy 404.454627 -279.774365) (xy 404.446732 -279.822942) (xy 404.431148 -279.869623) (xy 404.408277 -279.9132)
			(xy 404.378712 -279.952544) (xy 404.343219 -279.986636) (xy 404.302716 -280.014592) (xy 404.258254 -280.03569)
			(xy 404.210983 -280.049382) (xy 404.162128 -280.055314) (xy 404.112953 -280.053333) (xy 404.064734 -280.043489)
			(xy 404.018718 -280.026037) (xy 403.976097 -280.00143) (xy 403.937976 -279.970305) (xy 403.905341 -279.933468)
			(xy 403.879038 -279.891872) (xy 403.859747 -279.846596) (xy 403.84797 -279.798812) (xy 403.84401 -279.749758)
			(xy 403.505157 -279.749758) (xy 403.504667 -279.774111) (xy 403.496772 -279.822688) (xy 403.481188 -279.869369)
			(xy 403.458317 -279.912946) (xy 403.428752 -279.95229) (xy 403.393259 -279.986382) (xy 403.352756 -280.014338)
			(xy 403.308294 -280.035436) (xy 403.261023 -280.049128) (xy 403.212168 -280.05506) (xy 403.162993 -280.053079)
			(xy 403.114774 -280.043235) (xy 403.068758 -280.025783) (xy 403.026137 -280.001176) (xy 402.988016 -279.970051)
			(xy 402.955381 -279.933214) (xy 402.929078 -279.891618) (xy 402.909787 -279.846342) (xy 402.89801 -279.798558)
			(xy 402.89405 -279.749504) (xy 402.555197 -279.749504) (xy 402.555202 -279.749758) (xy 402.554707 -279.774365)
			(xy 402.546812 -279.822942) (xy 402.531228 -279.869623) (xy 402.508357 -279.9132) (xy 402.478792 -279.952544)
			(xy 402.443299 -279.986636) (xy 402.402796 -280.014592) (xy 402.358334 -280.03569) (xy 402.311063 -280.049382)
			(xy 402.262208 -280.055314) (xy 402.213033 -280.053333) (xy 402.164814 -280.043489) (xy 402.118798 -280.026037)
			(xy 402.076177 -280.00143) (xy 402.038056 -279.970305) (xy 402.005421 -279.933468) (xy 401.979118 -279.891872)
			(xy 401.959827 -279.846596) (xy 401.94805 -279.798812) (xy 401.94409 -279.749758) (xy 401.605237 -279.749758)
			(xy 401.604747 -279.774111) (xy 401.596852 -279.822688) (xy 401.581268 -279.869369) (xy 401.558397 -279.912946)
			(xy 401.528832 -279.95229) (xy 401.493339 -279.986382) (xy 401.452836 -280.014338) (xy 401.408374 -280.035436)
			(xy 401.361103 -280.049128) (xy 401.312248 -280.05506) (xy 401.263073 -280.053079) (xy 401.214854 -280.043235)
			(xy 401.168838 -280.025783) (xy 401.126217 -280.001176) (xy 401.088096 -279.970051) (xy 401.055461 -279.933214)
			(xy 401.029158 -279.891618) (xy 401.009867 -279.846342) (xy 400.99809 -279.798558) (xy 400.99413 -279.749504)
			(xy 400.655277 -279.749504) (xy 400.655282 -279.749758) (xy 400.654787 -279.774365) (xy 400.646892 -279.822942)
			(xy 400.631308 -279.869623) (xy 400.608437 -279.9132) (xy 400.578872 -279.952544) (xy 400.543379 -279.986636)
			(xy 400.502876 -280.014592) (xy 400.458414 -280.03569) (xy 400.411143 -280.049382) (xy 400.362288 -280.055314)
			(xy 400.313113 -280.053333) (xy 400.264894 -280.043489) (xy 400.218878 -280.026037) (xy 400.176257 -280.00143)
			(xy 400.138136 -279.970305) (xy 400.105501 -279.933468) (xy 400.079198 -279.891872) (xy 400.059907 -279.846596)
			(xy 400.04813 -279.798812) (xy 400.04417 -279.749758) (xy 399.705317 -279.749758) (xy 399.704827 -279.774111)
			(xy 399.696932 -279.822688) (xy 399.681348 -279.869369) (xy 399.658477 -279.912946) (xy 399.628912 -279.95229)
			(xy 399.593419 -279.986382) (xy 399.552916 -280.014338) (xy 399.508454 -280.035436) (xy 399.461183 -280.049128)
			(xy 399.412328 -280.05506) (xy 399.363153 -280.053079) (xy 399.314934 -280.043235) (xy 399.268918 -280.025783)
			(xy 399.226297 -280.001176) (xy 399.188176 -279.970051) (xy 399.155541 -279.933214) (xy 399.129238 -279.891618)
			(xy 399.109947 -279.846342) (xy 399.09817 -279.798558) (xy 399.09421 -279.749504) (xy 398.755103 -279.749504)
			(xy 398.755108 -279.749758) (xy 398.754613 -279.774365) (xy 398.746718 -279.822942) (xy 398.731134 -279.869623)
			(xy 398.708263 -279.9132) (xy 398.678698 -279.952544) (xy 398.643205 -279.986636) (xy 398.602702 -280.014592)
			(xy 398.55824 -280.03569) (xy 398.510969 -280.049382) (xy 398.462114 -280.055314) (xy 398.412939 -280.053333)
			(xy 398.36472 -280.043489) (xy 398.318704 -280.026037) (xy 398.276083 -280.00143) (xy 398.237962 -279.970305)
			(xy 398.205327 -279.933468) (xy 398.179024 -279.891872) (xy 398.159733 -279.846596) (xy 398.147956 -279.798812)
			(xy 398.143996 -279.749758) (xy 397.805143 -279.749758) (xy 397.804653 -279.774111) (xy 397.796758 -279.822688)
			(xy 397.781174 -279.869369) (xy 397.758303 -279.912946) (xy 397.728738 -279.95229) (xy 397.693245 -279.986382)
			(xy 397.652742 -280.014338) (xy 397.60828 -280.035436) (xy 397.561009 -280.049128) (xy 397.512154 -280.05506)
			(xy 397.462979 -280.053079) (xy 397.41476 -280.043235) (xy 397.368744 -280.025783) (xy 397.326123 -280.001176)
			(xy 397.288002 -279.970051) (xy 397.255367 -279.933214) (xy 397.229064 -279.891618) (xy 397.209773 -279.846342)
			(xy 397.197996 -279.798558) (xy 397.194036 -279.749504) (xy 396.854837 -279.749504) (xy 396.854838 -279.773852)
			(xy 396.847294 -279.821374) (xy 396.83239 -279.867125) (xy 396.810497 -279.909972) (xy 396.782155 -279.948856)
			(xy 396.748066 -279.982815) (xy 396.709074 -280.011008) (xy 396.666142 -280.032737) (xy 396.620335 -280.047465)
			(xy 396.596616 -280.05151) (xy 396.578074 -280.054304) (xy 396.55369 -280.082752) (xy 396.55369 -280.366724)
			(xy 396.578074 -280.395172) (xy 396.596616 -280.397966) (xy 396.620318 -280.402092) (xy 396.666116 -280.416817)
			(xy 396.709039 -280.438541) (xy 396.748024 -280.466728) (xy 396.782107 -280.50068) (xy 396.810444 -280.539556)
			(xy 396.832334 -280.582395) (xy 396.847235 -280.628137) (xy 396.854778 -280.675649) (xy 396.854778 -280.699718)
			(xy 397.194036 -280.699718) (xy 397.197996 -280.650664) (xy 397.209773 -280.60288) (xy 397.229064 -280.557604)
			(xy 397.255367 -280.516008) (xy 397.288002 -280.479171) (xy 397.326123 -280.448046) (xy 397.368744 -280.423439)
			(xy 397.41476 -280.405987) (xy 397.462979 -280.396143) (xy 397.512154 -280.394162) (xy 397.561009 -280.400094)
			(xy 397.60828 -280.413786) (xy 397.652742 -280.434884) (xy 397.693245 -280.46284) (xy 397.728738 -280.496932)
			(xy 397.758303 -280.536276) (xy 397.781174 -280.579853) (xy 397.796758 -280.626534) (xy 397.804653 -280.675111)
			(xy 397.805148 -280.699718) (xy 398.143996 -280.699718) (xy 398.147956 -280.650664) (xy 398.159733 -280.60288)
			(xy 398.179024 -280.557604) (xy 398.205327 -280.516008) (xy 398.237962 -280.479171) (xy 398.276083 -280.448046)
			(xy 398.318704 -280.423439) (xy 398.36472 -280.405987) (xy 398.412939 -280.396143) (xy 398.462114 -280.394162)
			(xy 398.510969 -280.400094) (xy 398.55824 -280.413786) (xy 398.602702 -280.434884) (xy 398.643205 -280.46284)
			(xy 398.678698 -280.496932) (xy 398.708263 -280.536276) (xy 398.731134 -280.579853) (xy 398.746718 -280.626534)
			(xy 398.754613 -280.675111) (xy 398.755108 -280.699718) (xy 399.09421 -280.699718) (xy 399.09817 -280.650664)
			(xy 399.109947 -280.60288) (xy 399.129238 -280.557604) (xy 399.155541 -280.516008) (xy 399.188176 -280.479171)
			(xy 399.226297 -280.448046) (xy 399.268918 -280.423439) (xy 399.314934 -280.405987) (xy 399.363153 -280.396143)
			(xy 399.412328 -280.394162) (xy 399.461183 -280.400094) (xy 399.508454 -280.413786) (xy 399.552916 -280.434884)
			(xy 399.593419 -280.46284) (xy 399.628912 -280.496932) (xy 399.658477 -280.536276) (xy 399.681348 -280.579853)
			(xy 399.696932 -280.626534) (xy 399.704827 -280.675111) (xy 399.705322 -280.699718) (xy 400.04417 -280.699718)
			(xy 400.04813 -280.650664) (xy 400.059907 -280.60288) (xy 400.079198 -280.557604) (xy 400.105501 -280.516008)
			(xy 400.138136 -280.479171) (xy 400.176257 -280.448046) (xy 400.218878 -280.423439) (xy 400.264894 -280.405987)
			(xy 400.313113 -280.396143) (xy 400.362288 -280.394162) (xy 400.411143 -280.400094) (xy 400.458414 -280.413786)
			(xy 400.502876 -280.434884) (xy 400.543379 -280.46284) (xy 400.578872 -280.496932) (xy 400.608437 -280.536276)
			(xy 400.631308 -280.579853) (xy 400.646892 -280.626534) (xy 400.654787 -280.675111) (xy 400.655282 -280.699718)
			(xy 400.99413 -280.699718) (xy 400.99809 -280.650664) (xy 401.009867 -280.60288) (xy 401.029158 -280.557604)
			(xy 401.055461 -280.516008) (xy 401.088096 -280.479171) (xy 401.126217 -280.448046) (xy 401.168838 -280.423439)
			(xy 401.214854 -280.405987) (xy 401.263073 -280.396143) (xy 401.312248 -280.394162) (xy 401.361103 -280.400094)
			(xy 401.408374 -280.413786) (xy 401.452836 -280.434884) (xy 401.493339 -280.46284) (xy 401.528832 -280.496932)
			(xy 401.558397 -280.536276) (xy 401.581268 -280.579853) (xy 401.596852 -280.626534) (xy 401.604747 -280.675111)
			(xy 401.605242 -280.699718) (xy 401.94409 -280.699718) (xy 401.94805 -280.650664) (xy 401.959827 -280.60288)
			(xy 401.979118 -280.557604) (xy 402.005421 -280.516008) (xy 402.038056 -280.479171) (xy 402.076177 -280.448046)
			(xy 402.118798 -280.423439) (xy 402.164814 -280.405987) (xy 402.213033 -280.396143) (xy 402.262208 -280.394162)
			(xy 402.311063 -280.400094) (xy 402.358334 -280.413786) (xy 402.402796 -280.434884) (xy 402.443299 -280.46284)
			(xy 402.478792 -280.496932) (xy 402.508357 -280.536276) (xy 402.531228 -280.579853) (xy 402.546812 -280.626534)
			(xy 402.554707 -280.675111) (xy 402.555202 -280.699718) (xy 402.89405 -280.699718) (xy 402.89801 -280.650664)
			(xy 402.909787 -280.60288) (xy 402.929078 -280.557604) (xy 402.955381 -280.516008) (xy 402.988016 -280.479171)
			(xy 403.026137 -280.448046) (xy 403.068758 -280.423439) (xy 403.114774 -280.405987) (xy 403.162993 -280.396143)
			(xy 403.212168 -280.394162) (xy 403.261023 -280.400094) (xy 403.308294 -280.413786) (xy 403.352756 -280.434884)
			(xy 403.393259 -280.46284) (xy 403.428752 -280.496932) (xy 403.458317 -280.536276) (xy 403.481188 -280.579853)
			(xy 403.496772 -280.626534) (xy 403.504667 -280.675111) (xy 403.505162 -280.699718) (xy 403.84401 -280.699718)
			(xy 403.84797 -280.650664) (xy 403.859747 -280.60288) (xy 403.879038 -280.557604) (xy 403.905341 -280.516008)
			(xy 403.937976 -280.479171) (xy 403.976097 -280.448046) (xy 404.018718 -280.423439) (xy 404.064734 -280.405987)
			(xy 404.112953 -280.396143) (xy 404.162128 -280.394162) (xy 404.210983 -280.400094) (xy 404.258254 -280.413786)
			(xy 404.302716 -280.434884) (xy 404.343219 -280.46284) (xy 404.378712 -280.496932) (xy 404.408277 -280.536276)
			(xy 404.431148 -280.579853) (xy 404.446732 -280.626534) (xy 404.454627 -280.675111) (xy 404.455122 -280.699718)
			(xy 404.79397 -280.699718) (xy 404.79793 -280.650664) (xy 404.809707 -280.60288) (xy 404.828998 -280.557604)
			(xy 404.855301 -280.516008) (xy 404.887936 -280.479171) (xy 404.926057 -280.448046) (xy 404.968678 -280.423439)
			(xy 405.014694 -280.405987) (xy 405.062913 -280.396143) (xy 405.112088 -280.394162) (xy 405.160943 -280.400094)
			(xy 405.208214 -280.413786) (xy 405.252676 -280.434884) (xy 405.293179 -280.46284) (xy 405.328672 -280.496932)
			(xy 405.358237 -280.536276) (xy 405.381108 -280.579853) (xy 405.396692 -280.626534) (xy 405.404587 -280.675111)
			(xy 405.405082 -280.699718) (xy 405.744184 -280.699718) (xy 405.748144 -280.650664) (xy 405.759921 -280.60288)
			(xy 405.779212 -280.557604) (xy 405.805515 -280.516008) (xy 405.83815 -280.479171) (xy 405.876271 -280.448046)
			(xy 405.918892 -280.423439) (xy 405.964908 -280.405987) (xy 406.013127 -280.396143) (xy 406.062302 -280.394162)
			(xy 406.111157 -280.400094) (xy 406.158428 -280.413786) (xy 406.20289 -280.434884) (xy 406.243393 -280.46284)
			(xy 406.278886 -280.496932) (xy 406.308451 -280.536276) (xy 406.331322 -280.579853) (xy 406.346906 -280.626534)
			(xy 406.354801 -280.675111) (xy 406.355296 -280.699718) (xy 406.694144 -280.699718) (xy 406.698104 -280.650664)
			(xy 406.709881 -280.60288) (xy 406.729172 -280.557604) (xy 406.755475 -280.516008) (xy 406.78811 -280.479171)
			(xy 406.826231 -280.448046) (xy 406.868852 -280.423439) (xy 406.914868 -280.405987) (xy 406.963087 -280.396143)
			(xy 407.012262 -280.394162) (xy 407.061117 -280.400094) (xy 407.108388 -280.413786) (xy 407.15285 -280.434884)
			(xy 407.193353 -280.46284) (xy 407.228846 -280.496932) (xy 407.258411 -280.536276) (xy 407.281282 -280.579853)
			(xy 407.296866 -280.626534) (xy 407.304761 -280.675111) (xy 407.305256 -280.699718) (xy 407.644104 -280.699718)
			(xy 407.648064 -280.650664) (xy 407.659841 -280.60288) (xy 407.679132 -280.557604) (xy 407.705435 -280.516008)
			(xy 407.73807 -280.479171) (xy 407.776191 -280.448046) (xy 407.818812 -280.423439) (xy 407.864828 -280.405987)
			(xy 407.913047 -280.396143) (xy 407.962222 -280.394162) (xy 408.011077 -280.400094) (xy 408.058348 -280.413786)
			(xy 408.10281 -280.434884) (xy 408.143313 -280.46284) (xy 408.178806 -280.496932) (xy 408.208371 -280.536276)
			(xy 408.231242 -280.579853) (xy 408.246826 -280.626534) (xy 408.254721 -280.675111) (xy 408.255216 -280.699718)
			(xy 408.594064 -280.699718) (xy 408.598024 -280.650664) (xy 408.609801 -280.60288) (xy 408.629092 -280.557604)
			(xy 408.655395 -280.516008) (xy 408.68803 -280.479171) (xy 408.726151 -280.448046) (xy 408.768772 -280.423439)
			(xy 408.814788 -280.405987) (xy 408.863007 -280.396143) (xy 408.912182 -280.394162) (xy 408.961037 -280.400094)
			(xy 409.008308 -280.413786) (xy 409.05277 -280.434884) (xy 409.093273 -280.46284) (xy 409.128766 -280.496932)
			(xy 409.158331 -280.536276) (xy 409.181202 -280.579853) (xy 409.196786 -280.626534) (xy 409.204681 -280.675111)
			(xy 409.205176 -280.699718) (xy 409.544024 -280.699718) (xy 409.547984 -280.650664) (xy 409.559761 -280.60288)
			(xy 409.579052 -280.557604) (xy 409.605355 -280.516008) (xy 409.63799 -280.479171) (xy 409.676111 -280.448046)
			(xy 409.718732 -280.423439) (xy 409.764748 -280.405987) (xy 409.812967 -280.396143) (xy 409.862142 -280.394162)
			(xy 409.910997 -280.400094) (xy 409.958268 -280.413786) (xy 410.00273 -280.434884) (xy 410.043233 -280.46284)
			(xy 410.078726 -280.496932) (xy 410.108291 -280.536276) (xy 410.131162 -280.579853) (xy 410.146746 -280.626534)
			(xy 410.154641 -280.675111) (xy 410.155136 -280.699718) (xy 410.493984 -280.699718) (xy 410.497944 -280.650664)
			(xy 410.509721 -280.60288) (xy 410.529012 -280.557604) (xy 410.555315 -280.516008) (xy 410.58795 -280.479171)
			(xy 410.626071 -280.448046) (xy 410.668692 -280.423439) (xy 410.714708 -280.405987) (xy 410.762927 -280.396143)
			(xy 410.812102 -280.394162) (xy 410.860957 -280.400094) (xy 410.908228 -280.413786) (xy 410.95269 -280.434884)
			(xy 410.993193 -280.46284) (xy 411.028686 -280.496932) (xy 411.058251 -280.536276) (xy 411.081122 -280.579853)
			(xy 411.096706 -280.626534) (xy 411.104601 -280.675111) (xy 411.105096 -280.699718) (xy 411.444198 -280.699718)
			(xy 411.448158 -280.650664) (xy 411.459935 -280.60288) (xy 411.479226 -280.557604) (xy 411.505529 -280.516008)
			(xy 411.538164 -280.479171) (xy 411.576285 -280.448046) (xy 411.618906 -280.423439) (xy 411.664922 -280.405987)
			(xy 411.713141 -280.396143) (xy 411.762316 -280.394162) (xy 411.811171 -280.400094) (xy 411.858442 -280.413786)
			(xy 411.902904 -280.434884) (xy 411.943407 -280.46284) (xy 411.9789 -280.496932) (xy 412.008465 -280.536276)
			(xy 412.031336 -280.579853) (xy 412.04692 -280.626534) (xy 412.054815 -280.675111) (xy 412.05531 -280.699718)
			(xy 412.394158 -280.699718) (xy 412.398118 -280.650664) (xy 412.409895 -280.60288) (xy 412.429186 -280.557604)
			(xy 412.455489 -280.516008) (xy 412.488124 -280.479171) (xy 412.526245 -280.448046) (xy 412.568866 -280.423439)
			(xy 412.614882 -280.405987) (xy 412.663101 -280.396143) (xy 412.712276 -280.394162) (xy 412.761131 -280.400094)
			(xy 412.808402 -280.413786) (xy 412.852864 -280.434884) (xy 412.893367 -280.46284) (xy 412.92886 -280.496932)
			(xy 412.958425 -280.536276) (xy 412.981296 -280.579853) (xy 412.99688 -280.626534) (xy 413.004775 -280.675111)
			(xy 413.00527 -280.699718) (xy 413.344118 -280.699718) (xy 413.348078 -280.650664) (xy 413.359855 -280.60288)
			(xy 413.379146 -280.557604) (xy 413.405449 -280.516008) (xy 413.438084 -280.479171) (xy 413.476205 -280.448046)
			(xy 413.518826 -280.423439) (xy 413.564842 -280.405987) (xy 413.613061 -280.396143) (xy 413.662236 -280.394162)
			(xy 413.711091 -280.400094) (xy 413.758362 -280.413786) (xy 413.802824 -280.434884) (xy 413.843327 -280.46284)
			(xy 413.87882 -280.496932) (xy 413.908385 -280.536276) (xy 413.931256 -280.579853) (xy 413.94684 -280.626534)
			(xy 413.954735 -280.675111) (xy 413.95523 -280.699718) (xy 414.294078 -280.699718) (xy 414.298038 -280.650664)
			(xy 414.309815 -280.60288) (xy 414.329106 -280.557604) (xy 414.355409 -280.516008) (xy 414.388044 -280.479171)
			(xy 414.426165 -280.448046) (xy 414.468786 -280.423439) (xy 414.514802 -280.405987) (xy 414.563021 -280.396143)
			(xy 414.612196 -280.394162) (xy 414.661051 -280.400094) (xy 414.708322 -280.413786) (xy 414.752784 -280.434884)
			(xy 414.793287 -280.46284) (xy 414.82878 -280.496932) (xy 414.858345 -280.536276) (xy 414.881216 -280.579853)
			(xy 414.8968 -280.626534) (xy 414.904695 -280.675111) (xy 414.90519 -280.699718) (xy 415.244038 -280.699718)
			(xy 415.247998 -280.650664) (xy 415.259775 -280.60288) (xy 415.279066 -280.557604) (xy 415.305369 -280.516008)
			(xy 415.338004 -280.479171) (xy 415.376125 -280.448046) (xy 415.418746 -280.423439) (xy 415.464762 -280.405987)
			(xy 415.512981 -280.396143) (xy 415.562156 -280.394162) (xy 415.611011 -280.400094) (xy 415.658282 -280.413786)
			(xy 415.702744 -280.434884) (xy 415.743247 -280.46284) (xy 415.77874 -280.496932) (xy 415.808305 -280.536276)
			(xy 415.831176 -280.579853) (xy 415.84676 -280.626534) (xy 415.854655 -280.675111) (xy 415.85515 -280.699718)
			(xy 416.193998 -280.699718) (xy 416.197958 -280.650664) (xy 416.209735 -280.60288) (xy 416.229026 -280.557604)
			(xy 416.255329 -280.516008) (xy 416.287964 -280.479171) (xy 416.326085 -280.448046) (xy 416.368706 -280.423439)
			(xy 416.414722 -280.405987) (xy 416.462941 -280.396143) (xy 416.512116 -280.394162) (xy 416.560971 -280.400094)
			(xy 416.608242 -280.413786) (xy 416.652704 -280.434884) (xy 416.693207 -280.46284) (xy 416.7287 -280.496932)
			(xy 416.758265 -280.536276) (xy 416.781136 -280.579853) (xy 416.79672 -280.626534) (xy 416.804615 -280.675111)
			(xy 416.80511 -280.699718) (xy 417.144212 -280.699718) (xy 417.148172 -280.650664) (xy 417.159949 -280.60288)
			(xy 417.17924 -280.557604) (xy 417.205543 -280.516008) (xy 417.238178 -280.479171) (xy 417.276299 -280.448046)
			(xy 417.31892 -280.423439) (xy 417.364936 -280.405987) (xy 417.413155 -280.396143) (xy 417.46233 -280.394162)
			(xy 417.511185 -280.400094) (xy 417.558456 -280.413786) (xy 417.602918 -280.434884) (xy 417.643421 -280.46284)
			(xy 417.678914 -280.496932) (xy 417.708479 -280.536276) (xy 417.73135 -280.579853) (xy 417.746934 -280.626534)
			(xy 417.754829 -280.675111) (xy 417.755324 -280.699718) (xy 418.094172 -280.699718) (xy 418.098132 -280.650664)
			(xy 418.109909 -280.60288) (xy 418.1292 -280.557604) (xy 418.155503 -280.516008) (xy 418.188138 -280.479171)
			(xy 418.226259 -280.448046) (xy 418.26888 -280.423439) (xy 418.314896 -280.405987) (xy 418.363115 -280.396143)
			(xy 418.41229 -280.394162) (xy 418.461145 -280.400094) (xy 418.508416 -280.413786) (xy 418.552878 -280.434884)
			(xy 418.593381 -280.46284) (xy 418.628874 -280.496932) (xy 418.658439 -280.536276) (xy 418.68131 -280.579853)
			(xy 418.696894 -280.626534) (xy 418.704789 -280.675111) (xy 418.705284 -280.699718) (xy 419.044132 -280.699718)
			(xy 419.048092 -280.650664) (xy 419.059869 -280.60288) (xy 419.07916 -280.557604) (xy 419.105463 -280.516008)
			(xy 419.138098 -280.479171) (xy 419.176219 -280.448046) (xy 419.21884 -280.423439) (xy 419.264856 -280.405987)
			(xy 419.313075 -280.396143) (xy 419.36225 -280.394162) (xy 419.411105 -280.400094) (xy 419.458376 -280.413786)
			(xy 419.502838 -280.434884) (xy 419.543341 -280.46284) (xy 419.578834 -280.496932) (xy 419.608399 -280.536276)
			(xy 419.63127 -280.579853) (xy 419.646854 -280.626534) (xy 419.654749 -280.675111) (xy 419.655244 -280.699718)
			(xy 419.994092 -280.699718) (xy 419.998052 -280.650664) (xy 420.009829 -280.60288) (xy 420.02912 -280.557604)
			(xy 420.055423 -280.516008) (xy 420.088058 -280.479171) (xy 420.126179 -280.448046) (xy 420.1688 -280.423439)
			(xy 420.214816 -280.405987) (xy 420.263035 -280.396143) (xy 420.31221 -280.394162) (xy 420.361065 -280.400094)
			(xy 420.408336 -280.413786) (xy 420.452798 -280.434884) (xy 420.493301 -280.46284) (xy 420.528794 -280.496932)
			(xy 420.558359 -280.536276) (xy 420.58123 -280.579853) (xy 420.596814 -280.626534) (xy 420.604709 -280.675111)
			(xy 420.605204 -280.699718) (xy 420.944052 -280.699718) (xy 420.948012 -280.650664) (xy 420.959789 -280.60288)
			(xy 420.97908 -280.557604) (xy 421.005383 -280.516008) (xy 421.038018 -280.479171) (xy 421.076139 -280.448046)
			(xy 421.11876 -280.423439) (xy 421.164776 -280.405987) (xy 421.212995 -280.396143) (xy 421.26217 -280.394162)
			(xy 421.311025 -280.400094) (xy 421.358296 -280.413786) (xy 421.402758 -280.434884) (xy 421.443261 -280.46284)
			(xy 421.478754 -280.496932) (xy 421.508319 -280.536276) (xy 421.53119 -280.579853) (xy 421.546774 -280.626534)
			(xy 421.554669 -280.675111) (xy 421.555164 -280.699718) (xy 421.894012 -280.699718) (xy 421.897972 -280.650664)
			(xy 421.909749 -280.60288) (xy 421.92904 -280.557604) (xy 421.955343 -280.516008) (xy 421.987978 -280.479171)
			(xy 422.026099 -280.448046) (xy 422.06872 -280.423439) (xy 422.114736 -280.405987) (xy 422.162955 -280.396143)
			(xy 422.21213 -280.394162) (xy 422.260985 -280.400094) (xy 422.308256 -280.413786) (xy 422.352718 -280.434884)
			(xy 422.393221 -280.46284) (xy 422.428714 -280.496932) (xy 422.458279 -280.536276) (xy 422.48115 -280.579853)
			(xy 422.496734 -280.626534) (xy 422.504629 -280.675111) (xy 422.505124 -280.699718) (xy 422.844226 -280.699718)
			(xy 422.848186 -280.650664) (xy 422.859963 -280.60288) (xy 422.879254 -280.557604) (xy 422.905557 -280.516008)
			(xy 422.938192 -280.479171) (xy 422.976313 -280.448046) (xy 423.018934 -280.423439) (xy 423.06495 -280.405987)
			(xy 423.113169 -280.396143) (xy 423.162344 -280.394162) (xy 423.211199 -280.400094) (xy 423.25847 -280.413786)
			(xy 423.302932 -280.434884) (xy 423.343435 -280.46284) (xy 423.378928 -280.496932) (xy 423.408493 -280.536276)
			(xy 423.431364 -280.579853) (xy 423.446948 -280.626534) (xy 423.454843 -280.675111) (xy 423.455338 -280.699718)
			(xy 423.794186 -280.699718) (xy 423.798146 -280.650664) (xy 423.809923 -280.60288) (xy 423.829214 -280.557604)
			(xy 423.855517 -280.516008) (xy 423.888152 -280.479171) (xy 423.926273 -280.448046) (xy 423.968894 -280.423439)
			(xy 424.01491 -280.405987) (xy 424.063129 -280.396143) (xy 424.112304 -280.394162) (xy 424.161159 -280.400094)
			(xy 424.20843 -280.413786) (xy 424.252892 -280.434884) (xy 424.293395 -280.46284) (xy 424.328888 -280.496932)
			(xy 424.358453 -280.536276) (xy 424.381324 -280.579853) (xy 424.396908 -280.626534) (xy 424.404803 -280.675111)
			(xy 424.405298 -280.699718) (xy 424.744146 -280.699718) (xy 424.748106 -280.650664) (xy 424.759883 -280.60288)
			(xy 424.779174 -280.557604) (xy 424.805477 -280.516008) (xy 424.838112 -280.479171) (xy 424.876233 -280.448046)
			(xy 424.918854 -280.423439) (xy 424.96487 -280.405987) (xy 425.013089 -280.396143) (xy 425.062264 -280.394162)
			(xy 425.111119 -280.400094) (xy 425.15839 -280.413786) (xy 425.202852 -280.434884) (xy 425.243355 -280.46284)
			(xy 425.278848 -280.496932) (xy 425.308413 -280.536276) (xy 425.331284 -280.579853) (xy 425.346868 -280.626534)
			(xy 425.354763 -280.675111) (xy 425.355258 -280.699718) (xy 425.694106 -280.699718) (xy 425.698066 -280.650664)
			(xy 425.709843 -280.60288) (xy 425.729134 -280.557604) (xy 425.755437 -280.516008) (xy 425.788072 -280.479171)
			(xy 425.826193 -280.448046) (xy 425.868814 -280.423439) (xy 425.91483 -280.405987) (xy 425.963049 -280.396143)
			(xy 426.012224 -280.394162) (xy 426.061079 -280.400094) (xy 426.10835 -280.413786) (xy 426.152812 -280.434884)
			(xy 426.193315 -280.46284) (xy 426.228808 -280.496932) (xy 426.258373 -280.536276) (xy 426.281244 -280.579853)
			(xy 426.296828 -280.626534) (xy 426.304723 -280.675111) (xy 426.305218 -280.699718) (xy 426.644066 -280.699718)
			(xy 426.648026 -280.650664) (xy 426.659803 -280.60288) (xy 426.679094 -280.557604) (xy 426.705397 -280.516008)
			(xy 426.738032 -280.479171) (xy 426.776153 -280.448046) (xy 426.818774 -280.423439) (xy 426.86479 -280.405987)
			(xy 426.913009 -280.396143) (xy 426.962184 -280.394162) (xy 427.011039 -280.400094) (xy 427.05831 -280.413786)
			(xy 427.102772 -280.434884) (xy 427.143275 -280.46284) (xy 427.178768 -280.496932) (xy 427.208333 -280.536276)
			(xy 427.231204 -280.579853) (xy 427.246788 -280.626534) (xy 427.254683 -280.675111) (xy 427.255178 -280.699718)
			(xy 427.594026 -280.699718) (xy 427.597986 -280.650664) (xy 427.609763 -280.60288) (xy 427.629054 -280.557604)
			(xy 427.655357 -280.516008) (xy 427.687992 -280.479171) (xy 427.726113 -280.448046) (xy 427.768734 -280.423439)
			(xy 427.81475 -280.405987) (xy 427.862969 -280.396143) (xy 427.912144 -280.394162) (xy 427.960999 -280.400094)
			(xy 428.00827 -280.413786) (xy 428.052732 -280.434884) (xy 428.093235 -280.46284) (xy 428.128728 -280.496932)
			(xy 428.158293 -280.536276) (xy 428.181164 -280.579853) (xy 428.196748 -280.626534) (xy 428.204643 -280.675111)
			(xy 428.205138 -280.699718) (xy 428.54424 -280.699718) (xy 428.5482 -280.650664) (xy 428.559977 -280.60288)
			(xy 428.579268 -280.557604) (xy 428.605571 -280.516008) (xy 428.638206 -280.479171) (xy 428.676327 -280.448046)
			(xy 428.718948 -280.423439) (xy 428.764964 -280.405987) (xy 428.813183 -280.396143) (xy 428.862358 -280.394162)
			(xy 428.911213 -280.400094) (xy 428.958484 -280.413786) (xy 429.002946 -280.434884) (xy 429.043449 -280.46284)
			(xy 429.078942 -280.496932) (xy 429.108507 -280.536276) (xy 429.131378 -280.579853) (xy 429.146962 -280.626534)
			(xy 429.154857 -280.675111) (xy 429.155352 -280.699718) (xy 429.4942 -280.699718) (xy 429.49816 -280.650664)
			(xy 429.509937 -280.60288) (xy 429.529228 -280.557604) (xy 429.555531 -280.516008) (xy 429.588166 -280.479171)
			(xy 429.626287 -280.448046) (xy 429.668908 -280.423439) (xy 429.714924 -280.405987) (xy 429.763143 -280.396143)
			(xy 429.812318 -280.394162) (xy 429.861173 -280.400094) (xy 429.908444 -280.413786) (xy 429.952906 -280.434884)
			(xy 429.993409 -280.46284) (xy 430.028902 -280.496932) (xy 430.058467 -280.536276) (xy 430.081338 -280.579853)
			(xy 430.096922 -280.626534) (xy 430.104817 -280.675111) (xy 430.105312 -280.699718) (xy 430.44416 -280.699718)
			(xy 430.44812 -280.650664) (xy 430.459897 -280.60288) (xy 430.479188 -280.557604) (xy 430.505491 -280.516008)
			(xy 430.538126 -280.479171) (xy 430.576247 -280.448046) (xy 430.618868 -280.423439) (xy 430.664884 -280.405987)
			(xy 430.713103 -280.396143) (xy 430.762278 -280.394162) (xy 430.811133 -280.400094) (xy 430.858404 -280.413786)
			(xy 430.902866 -280.434884) (xy 430.943369 -280.46284) (xy 430.978862 -280.496932) (xy 431.008427 -280.536276)
			(xy 431.031298 -280.579853) (xy 431.046045 -280.624026) (xy 459.436722 -280.624026) (xy 459.440793 -280.568404)
			(xy 459.452919 -280.513967) (xy 459.472842 -280.461876) (xy 459.500138 -280.413241) (xy 459.534224 -280.369098)
			(xy 459.574373 -280.330389) (xy 459.619731 -280.297938) (xy 459.669331 -280.272437) (xy 459.722115 -280.25443)
			(xy 459.776958 -280.2443) (xy 459.832692 -280.242263) (xy 459.888129 -280.248363) (xy 459.942086 -280.262469)
			(xy 459.993415 -280.284281) (xy 460.041021 -280.313335) (xy 460.083889 -280.34901) (xy 460.121106 -280.390547)
			(xy 460.151879 -280.43706) (xy 460.175551 -280.487557) (xy 460.191619 -280.540964) (xy 460.199739 -280.59614)
			(xy 460.200248 -280.624026) (xy 460.199739 -280.651912) (xy 460.191619 -280.707088) (xy 460.175551 -280.760495)
			(xy 460.151879 -280.810992) (xy 460.121106 -280.857505) (xy 460.083889 -280.899042) (xy 460.041021 -280.934717)
			(xy 459.998234 -280.96083) (xy 463.093816 -280.96083) (xy 463.094349 -280.931755) (xy 463.103169 -280.874278)
			(xy 463.12061 -280.818806) (xy 463.146268 -280.766622) (xy 463.179547 -280.718937) (xy 463.219678 -280.676855)
			(xy 463.26573 -280.641351) (xy 463.29092 -280.62682) (xy 463.303112 -280.619962) (xy 463.317082 -280.596594)
			(xy 463.318098 -280.494232) (xy 463.317759 -280.485234) (xy 463.311667 -280.468308) (xy 463.300084 -280.454543)
			(xy 463.292444 -280.449782) (xy 463.267877 -280.435063) (xy 463.223004 -280.399484) (xy 463.183955 -280.357596)
			(xy 463.151606 -280.310341) (xy 463.126686 -280.258782) (xy 463.109753 -280.204076) (xy 463.101189 -280.147453)
			(xy 463.100674 -280.11882) (xy 463.101204 -280.089903) (xy 463.109937 -280.032731) (xy 463.127205 -279.977535)
			(xy 463.152612 -279.92558) (xy 463.185575 -279.878059) (xy 463.205068 -279.856692) (xy 463.205322 -279.856438)
			(xy 463.205576 -279.856184) (xy 463.21186 -279.848819) (xy 463.218912 -279.830806) (xy 463.219292 -279.821132)
			(xy 463.21853 -279.75052) (xy 463.218039 -279.740797) (xy 463.210743 -279.72277) (xy 463.204306 -279.715468)
			(xy 463.203798 -279.71496) (xy 463.203544 -279.714706) (xy 463.183116 -279.693151) (xy 463.148494 -279.644906)
			(xy 463.121768 -279.591877) (xy 463.103584 -279.535347) (xy 463.094381 -279.476681) (xy 463.093816 -279.44699)
			(xy 463.094267 -279.420526) (xy 463.101577 -279.368104) (xy 463.11607 -279.317198) (xy 463.137466 -279.268787)
			(xy 463.165354 -279.223802) (xy 463.199198 -279.183107) (xy 463.238346 -279.147486) (xy 463.282047 -279.117624)
			(xy 463.329458 -279.094095) (xy 463.35442 -279.085294) (xy 463.354674 -279.085294) (xy 463.364624 -279.081443)
			(xy 463.380276 -279.06697) (xy 463.3849 -279.057354) (xy 463.41919 -278.977852) (xy 463.418936 -278.956516)
			(xy 463.414364 -278.94661) (xy 463.403514 -278.92165) (xy 463.388153 -278.869439) (xy 463.380347 -278.815579)
			(xy 463.37982 -278.788368) (xy 463.37982 -278.787606) (xy 463.380261 -278.760352) (xy 463.388018 -278.706399)
			(xy 463.403375 -278.654099) (xy 463.426018 -278.604517) (xy 463.455488 -278.558662) (xy 463.491185 -278.517469)
			(xy 463.53238 -278.481775) (xy 463.578236 -278.452308) (xy 463.62782 -278.429667) (xy 463.68012 -278.414313)
			(xy 463.734074 -278.406559) (xy 463.761328 -278.406098) (xy 463.789236 -278.406582) (xy 463.844453 -278.41475)
			(xy 463.87131 -278.422354) (xy 463.8822 -278.425026) (xy 463.90435 -278.421743) (xy 463.913982 -278.416004)
			(xy 463.988658 -278.366728) (xy 464.000342 -278.347424) (xy 464.001612 -278.335994) (xy 464.004989 -278.308212)
			(xy 464.018922 -278.254008) (xy 464.040623 -278.202421) (xy 464.069624 -278.154556) (xy 464.105306 -278.111439)
			(xy 464.146902 -278.073997) (xy 464.193521 -278.043031) (xy 464.244162 -278.019205) (xy 464.29774 -278.003031)
			(xy 464.353105 -277.994856) (xy 464.381088 -277.994364) (xy 464.408339 -277.994882) (xy 464.462288 -278.002637)
			(xy 464.514583 -278.017991) (xy 464.564161 -278.040631) (xy 464.610012 -278.070097) (xy 464.651203 -278.105788)
			(xy 464.686896 -278.146978) (xy 464.716363 -278.192828) (xy 464.739004 -278.242406) (xy 464.75436 -278.294701)
			(xy 464.762117 -278.348649) (xy 464.762117 -278.403151) (xy 464.75436 -278.457099) (xy 464.739004 -278.509394)
			(xy 464.716363 -278.558972) (xy 464.686896 -278.604822) (xy 464.651203 -278.646012) (xy 464.610012 -278.681703)
			(xy 464.564161 -278.711169) (xy 464.514583 -278.733809) (xy 464.462288 -278.749163) (xy 464.408339 -278.756918)
			(xy 464.381088 -278.75738) (xy 464.35318 -278.75689) (xy 464.297964 -278.748725) (xy 464.271106 -278.741124)
			(xy 464.260213 -278.738466) (xy 464.238067 -278.741741) (xy 464.228434 -278.747474) (xy 464.153758 -278.79675)
			(xy 464.142074 -278.816054) (xy 464.140804 -278.827484) (xy 464.137501 -278.854563) (xy 464.124101 -278.907445)
			(xy 464.103306 -278.95788) (xy 464.07554 -279.004838) (xy 464.041369 -279.047363) (xy 464.001489 -279.084587)
			(xy 463.956715 -279.115753) (xy 463.907958 -279.140223) (xy 463.882232 -279.149302) (xy 463.881978 -279.149302)
			(xy 463.872038 -279.153175) (xy 463.85638 -279.167632) (xy 463.851752 -279.177242) (xy 463.817462 -279.256744)
			(xy 463.817716 -279.27808) (xy 463.822288 -279.287986) (xy 463.833134 -279.312948) (xy 463.848497 -279.365157)
			(xy 463.856305 -279.419017) (xy 463.856832 -279.446228) (xy 463.856832 -279.44699) (xy 463.856307 -279.475907)
			(xy 463.847573 -279.533079) (xy 463.830303 -279.588276) (xy 463.804895 -279.64023) (xy 463.771931 -279.687751)
			(xy 463.752438 -279.709118) (xy 463.752184 -279.709372) (xy 463.75193 -279.709626) (xy 463.745642 -279.716988)
			(xy 463.738592 -279.735004) (xy 463.738214 -279.744678) (xy 463.738976 -279.81529) (xy 463.73946 -279.825014)
			(xy 463.746761 -279.843041) (xy 463.7532 -279.850342) (xy 463.753708 -279.85085) (xy 463.753962 -279.851104)
			(xy 463.774396 -279.872653) (xy 463.809017 -279.9209) (xy 463.835742 -279.97393) (xy 463.853924 -280.030462)
			(xy 463.863125 -280.089128) (xy 463.86369 -280.11882) (xy 463.863165 -280.147896) (xy 463.85435 -280.205375)
			(xy 463.836911 -280.260851) (xy 463.811253 -280.313036) (xy 463.777971 -280.360721) (xy 463.737836 -280.402802)
			(xy 463.691778 -280.438302) (xy 463.666586 -280.45283) (xy 463.654394 -280.459688) (xy 463.640424 -280.483056)
			(xy 463.639408 -280.585418) (xy 463.639709 -280.594419) (xy 463.645818 -280.611348) (xy 463.657415 -280.62511)
			(xy 463.665062 -280.629868) (xy 463.689652 -280.644549) (xy 463.734525 -280.680135) (xy 463.773573 -280.722029)
			(xy 463.805919 -280.76929) (xy 463.830835 -280.820856) (xy 463.847763 -280.875568) (xy 463.85632 -280.932195)
			(xy 463.856832 -280.96083) (xy 463.856346 -280.988081) (xy 463.84859 -281.042029) (xy 463.833235 -281.094324)
			(xy 463.810593 -281.143901) (xy 463.781127 -281.189751) (xy 463.745436 -281.230942) (xy 463.704245 -281.266633)
			(xy 463.658395 -281.296099) (xy 463.608818 -281.318741) (xy 463.556523 -281.334096) (xy 463.502575 -281.341852)
			(xy 463.448073 -281.341852) (xy 463.394125 -281.334096) (xy 463.34183 -281.318741) (xy 463.292253 -281.296099)
			(xy 463.246403 -281.266633) (xy 463.205212 -281.230942) (xy 463.169521 -281.189751) (xy 463.140055 -281.143901)
			(xy 463.117413 -281.094324) (xy 463.102058 -281.042029) (xy 463.094302 -280.988081) (xy 463.093816 -280.96083)
			(xy 459.998234 -280.96083) (xy 459.993415 -280.963771) (xy 459.942086 -280.985583) (xy 459.888129 -280.999689)
			(xy 459.832692 -281.005789) (xy 459.776958 -281.003752) (xy 459.722115 -280.993622) (xy 459.669331 -280.975615)
			(xy 459.619731 -280.950114) (xy 459.574373 -280.917663) (xy 459.534224 -280.878954) (xy 459.500138 -280.834811)
			(xy 459.472842 -280.786176) (xy 459.452919 -280.734085) (xy 459.440793 -280.679648) (xy 459.436722 -280.624026)
			(xy 431.046045 -280.624026) (xy 431.046882 -280.626534) (xy 431.054777 -280.675111) (xy 431.055272 -280.699718)
			(xy 431.054777 -280.724325) (xy 431.046882 -280.772902) (xy 431.031298 -280.819583) (xy 431.008427 -280.86316)
			(xy 430.978862 -280.902504) (xy 430.943369 -280.936596) (xy 430.902866 -280.964552) (xy 430.858404 -280.98565)
			(xy 430.811133 -280.999342) (xy 430.762278 -281.005274) (xy 430.713103 -281.003293) (xy 430.664884 -280.993449)
			(xy 430.618868 -280.975997) (xy 430.576247 -280.95139) (xy 430.538126 -280.920265) (xy 430.505491 -280.883428)
			(xy 430.479188 -280.841832) (xy 430.459897 -280.796556) (xy 430.44812 -280.748772) (xy 430.44416 -280.699718)
			(xy 430.105312 -280.699718) (xy 430.104817 -280.724325) (xy 430.096922 -280.772902) (xy 430.081338 -280.819583)
			(xy 430.058467 -280.86316) (xy 430.028902 -280.902504) (xy 429.993409 -280.936596) (xy 429.952906 -280.964552)
			(xy 429.908444 -280.98565) (xy 429.861173 -280.999342) (xy 429.812318 -281.005274) (xy 429.763143 -281.003293)
			(xy 429.714924 -280.993449) (xy 429.668908 -280.975997) (xy 429.626287 -280.95139) (xy 429.588166 -280.920265)
			(xy 429.555531 -280.883428) (xy 429.529228 -280.841832) (xy 429.509937 -280.796556) (xy 429.49816 -280.748772)
			(xy 429.4942 -280.699718) (xy 429.155352 -280.699718) (xy 429.154857 -280.724325) (xy 429.146962 -280.772902)
			(xy 429.131378 -280.819583) (xy 429.108507 -280.86316) (xy 429.078942 -280.902504) (xy 429.043449 -280.936596)
			(xy 429.002946 -280.964552) (xy 428.958484 -280.98565) (xy 428.911213 -280.999342) (xy 428.862358 -281.005274)
			(xy 428.813183 -281.003293) (xy 428.764964 -280.993449) (xy 428.718948 -280.975997) (xy 428.676327 -280.95139)
			(xy 428.638206 -280.920265) (xy 428.605571 -280.883428) (xy 428.579268 -280.841832) (xy 428.559977 -280.796556)
			(xy 428.5482 -280.748772) (xy 428.54424 -280.699718) (xy 428.205138 -280.699718) (xy 428.204643 -280.724325)
			(xy 428.196748 -280.772902) (xy 428.181164 -280.819583) (xy 428.158293 -280.86316) (xy 428.128728 -280.902504)
			(xy 428.093235 -280.936596) (xy 428.052732 -280.964552) (xy 428.00827 -280.98565) (xy 427.960999 -280.999342)
			(xy 427.912144 -281.005274) (xy 427.862969 -281.003293) (xy 427.81475 -280.993449) (xy 427.768734 -280.975997)
			(xy 427.726113 -280.95139) (xy 427.687992 -280.920265) (xy 427.655357 -280.883428) (xy 427.629054 -280.841832)
			(xy 427.609763 -280.796556) (xy 427.597986 -280.748772) (xy 427.594026 -280.699718) (xy 427.255178 -280.699718)
			(xy 427.254683 -280.724325) (xy 427.246788 -280.772902) (xy 427.231204 -280.819583) (xy 427.208333 -280.86316)
			(xy 427.178768 -280.902504) (xy 427.143275 -280.936596) (xy 427.102772 -280.964552) (xy 427.05831 -280.98565)
			(xy 427.011039 -280.999342) (xy 426.962184 -281.005274) (xy 426.913009 -281.003293) (xy 426.86479 -280.993449)
			(xy 426.818774 -280.975997) (xy 426.776153 -280.95139) (xy 426.738032 -280.920265) (xy 426.705397 -280.883428)
			(xy 426.679094 -280.841832) (xy 426.659803 -280.796556) (xy 426.648026 -280.748772) (xy 426.644066 -280.699718)
			(xy 426.305218 -280.699718) (xy 426.304723 -280.724325) (xy 426.296828 -280.772902) (xy 426.281244 -280.819583)
			(xy 426.258373 -280.86316) (xy 426.228808 -280.902504) (xy 426.193315 -280.936596) (xy 426.152812 -280.964552)
			(xy 426.10835 -280.98565) (xy 426.061079 -280.999342) (xy 426.012224 -281.005274) (xy 425.963049 -281.003293)
			(xy 425.91483 -280.993449) (xy 425.868814 -280.975997) (xy 425.826193 -280.95139) (xy 425.788072 -280.920265)
			(xy 425.755437 -280.883428) (xy 425.729134 -280.841832) (xy 425.709843 -280.796556) (xy 425.698066 -280.748772)
			(xy 425.694106 -280.699718) (xy 425.355258 -280.699718) (xy 425.354763 -280.724325) (xy 425.346868 -280.772902)
			(xy 425.331284 -280.819583) (xy 425.308413 -280.86316) (xy 425.278848 -280.902504) (xy 425.243355 -280.936596)
			(xy 425.202852 -280.964552) (xy 425.15839 -280.98565) (xy 425.111119 -280.999342) (xy 425.062264 -281.005274)
			(xy 425.013089 -281.003293) (xy 424.96487 -280.993449) (xy 424.918854 -280.975997) (xy 424.876233 -280.95139)
			(xy 424.838112 -280.920265) (xy 424.805477 -280.883428) (xy 424.779174 -280.841832) (xy 424.759883 -280.796556)
			(xy 424.748106 -280.748772) (xy 424.744146 -280.699718) (xy 424.405298 -280.699718) (xy 424.404803 -280.724325)
			(xy 424.396908 -280.772902) (xy 424.381324 -280.819583) (xy 424.358453 -280.86316) (xy 424.328888 -280.902504)
			(xy 424.293395 -280.936596) (xy 424.252892 -280.964552) (xy 424.20843 -280.98565) (xy 424.161159 -280.999342)
			(xy 424.112304 -281.005274) (xy 424.063129 -281.003293) (xy 424.01491 -280.993449) (xy 423.968894 -280.975997)
			(xy 423.926273 -280.95139) (xy 423.888152 -280.920265) (xy 423.855517 -280.883428) (xy 423.829214 -280.841832)
			(xy 423.809923 -280.796556) (xy 423.798146 -280.748772) (xy 423.794186 -280.699718) (xy 423.455338 -280.699718)
			(xy 423.454843 -280.724325) (xy 423.446948 -280.772902) (xy 423.431364 -280.819583) (xy 423.408493 -280.86316)
			(xy 423.378928 -280.902504) (xy 423.343435 -280.936596) (xy 423.302932 -280.964552) (xy 423.25847 -280.98565)
			(xy 423.211199 -280.999342) (xy 423.162344 -281.005274) (xy 423.113169 -281.003293) (xy 423.06495 -280.993449)
			(xy 423.018934 -280.975997) (xy 422.976313 -280.95139) (xy 422.938192 -280.920265) (xy 422.905557 -280.883428)
			(xy 422.879254 -280.841832) (xy 422.859963 -280.796556) (xy 422.848186 -280.748772) (xy 422.844226 -280.699718)
			(xy 422.505124 -280.699718) (xy 422.504629 -280.724325) (xy 422.496734 -280.772902) (xy 422.48115 -280.819583)
			(xy 422.458279 -280.86316) (xy 422.428714 -280.902504) (xy 422.393221 -280.936596) (xy 422.352718 -280.964552)
			(xy 422.308256 -280.98565) (xy 422.260985 -280.999342) (xy 422.21213 -281.005274) (xy 422.162955 -281.003293)
			(xy 422.114736 -280.993449) (xy 422.06872 -280.975997) (xy 422.026099 -280.95139) (xy 421.987978 -280.920265)
			(xy 421.955343 -280.883428) (xy 421.92904 -280.841832) (xy 421.909749 -280.796556) (xy 421.897972 -280.748772)
			(xy 421.894012 -280.699718) (xy 421.555164 -280.699718) (xy 421.554669 -280.724325) (xy 421.546774 -280.772902)
			(xy 421.53119 -280.819583) (xy 421.508319 -280.86316) (xy 421.478754 -280.902504) (xy 421.443261 -280.936596)
			(xy 421.402758 -280.964552) (xy 421.358296 -280.98565) (xy 421.311025 -280.999342) (xy 421.26217 -281.005274)
			(xy 421.212995 -281.003293) (xy 421.164776 -280.993449) (xy 421.11876 -280.975997) (xy 421.076139 -280.95139)
			(xy 421.038018 -280.920265) (xy 421.005383 -280.883428) (xy 420.97908 -280.841832) (xy 420.959789 -280.796556)
			(xy 420.948012 -280.748772) (xy 420.944052 -280.699718) (xy 420.605204 -280.699718) (xy 420.604709 -280.724325)
			(xy 420.596814 -280.772902) (xy 420.58123 -280.819583) (xy 420.558359 -280.86316) (xy 420.528794 -280.902504)
			(xy 420.493301 -280.936596) (xy 420.452798 -280.964552) (xy 420.408336 -280.98565) (xy 420.361065 -280.999342)
			(xy 420.31221 -281.005274) (xy 420.263035 -281.003293) (xy 420.214816 -280.993449) (xy 420.1688 -280.975997)
			(xy 420.126179 -280.95139) (xy 420.088058 -280.920265) (xy 420.055423 -280.883428) (xy 420.02912 -280.841832)
			(xy 420.009829 -280.796556) (xy 419.998052 -280.748772) (xy 419.994092 -280.699718) (xy 419.655244 -280.699718)
			(xy 419.654749 -280.724325) (xy 419.646854 -280.772902) (xy 419.63127 -280.819583) (xy 419.608399 -280.86316)
			(xy 419.578834 -280.902504) (xy 419.543341 -280.936596) (xy 419.502838 -280.964552) (xy 419.458376 -280.98565)
			(xy 419.411105 -280.999342) (xy 419.36225 -281.005274) (xy 419.313075 -281.003293) (xy 419.264856 -280.993449)
			(xy 419.21884 -280.975997) (xy 419.176219 -280.95139) (xy 419.138098 -280.920265) (xy 419.105463 -280.883428)
			(xy 419.07916 -280.841832) (xy 419.059869 -280.796556) (xy 419.048092 -280.748772) (xy 419.044132 -280.699718)
			(xy 418.705284 -280.699718) (xy 418.704789 -280.724325) (xy 418.696894 -280.772902) (xy 418.68131 -280.819583)
			(xy 418.658439 -280.86316) (xy 418.628874 -280.902504) (xy 418.593381 -280.936596) (xy 418.552878 -280.964552)
			(xy 418.508416 -280.98565) (xy 418.461145 -280.999342) (xy 418.41229 -281.005274) (xy 418.363115 -281.003293)
			(xy 418.314896 -280.993449) (xy 418.26888 -280.975997) (xy 418.226259 -280.95139) (xy 418.188138 -280.920265)
			(xy 418.155503 -280.883428) (xy 418.1292 -280.841832) (xy 418.109909 -280.796556) (xy 418.098132 -280.748772)
			(xy 418.094172 -280.699718) (xy 417.755324 -280.699718) (xy 417.754829 -280.724325) (xy 417.746934 -280.772902)
			(xy 417.73135 -280.819583) (xy 417.708479 -280.86316) (xy 417.678914 -280.902504) (xy 417.643421 -280.936596)
			(xy 417.602918 -280.964552) (xy 417.558456 -280.98565) (xy 417.511185 -280.999342) (xy 417.46233 -281.005274)
			(xy 417.413155 -281.003293) (xy 417.364936 -280.993449) (xy 417.31892 -280.975997) (xy 417.276299 -280.95139)
			(xy 417.238178 -280.920265) (xy 417.205543 -280.883428) (xy 417.17924 -280.841832) (xy 417.159949 -280.796556)
			(xy 417.148172 -280.748772) (xy 417.144212 -280.699718) (xy 416.80511 -280.699718) (xy 416.804615 -280.724325)
			(xy 416.79672 -280.772902) (xy 416.781136 -280.819583) (xy 416.758265 -280.86316) (xy 416.7287 -280.902504)
			(xy 416.693207 -280.936596) (xy 416.652704 -280.964552) (xy 416.608242 -280.98565) (xy 416.560971 -280.999342)
			(xy 416.512116 -281.005274) (xy 416.462941 -281.003293) (xy 416.414722 -280.993449) (xy 416.368706 -280.975997)
			(xy 416.326085 -280.95139) (xy 416.287964 -280.920265) (xy 416.255329 -280.883428) (xy 416.229026 -280.841832)
			(xy 416.209735 -280.796556) (xy 416.197958 -280.748772) (xy 416.193998 -280.699718) (xy 415.85515 -280.699718)
			(xy 415.854655 -280.724325) (xy 415.84676 -280.772902) (xy 415.831176 -280.819583) (xy 415.808305 -280.86316)
			(xy 415.77874 -280.902504) (xy 415.743247 -280.936596) (xy 415.702744 -280.964552) (xy 415.658282 -280.98565)
			(xy 415.611011 -280.999342) (xy 415.562156 -281.005274) (xy 415.512981 -281.003293) (xy 415.464762 -280.993449)
			(xy 415.418746 -280.975997) (xy 415.376125 -280.95139) (xy 415.338004 -280.920265) (xy 415.305369 -280.883428)
			(xy 415.279066 -280.841832) (xy 415.259775 -280.796556) (xy 415.247998 -280.748772) (xy 415.244038 -280.699718)
			(xy 414.90519 -280.699718) (xy 414.904695 -280.724325) (xy 414.8968 -280.772902) (xy 414.881216 -280.819583)
			(xy 414.858345 -280.86316) (xy 414.82878 -280.902504) (xy 414.793287 -280.936596) (xy 414.752784 -280.964552)
			(xy 414.708322 -280.98565) (xy 414.661051 -280.999342) (xy 414.612196 -281.005274) (xy 414.563021 -281.003293)
			(xy 414.514802 -280.993449) (xy 414.468786 -280.975997) (xy 414.426165 -280.95139) (xy 414.388044 -280.920265)
			(xy 414.355409 -280.883428) (xy 414.329106 -280.841832) (xy 414.309815 -280.796556) (xy 414.298038 -280.748772)
			(xy 414.294078 -280.699718) (xy 413.95523 -280.699718) (xy 413.954735 -280.724325) (xy 413.94684 -280.772902)
			(xy 413.931256 -280.819583) (xy 413.908385 -280.86316) (xy 413.87882 -280.902504) (xy 413.843327 -280.936596)
			(xy 413.802824 -280.964552) (xy 413.758362 -280.98565) (xy 413.711091 -280.999342) (xy 413.662236 -281.005274)
			(xy 413.613061 -281.003293) (xy 413.564842 -280.993449) (xy 413.518826 -280.975997) (xy 413.476205 -280.95139)
			(xy 413.438084 -280.920265) (xy 413.405449 -280.883428) (xy 413.379146 -280.841832) (xy 413.359855 -280.796556)
			(xy 413.348078 -280.748772) (xy 413.344118 -280.699718) (xy 413.00527 -280.699718) (xy 413.004775 -280.724325)
			(xy 412.99688 -280.772902) (xy 412.981296 -280.819583) (xy 412.958425 -280.86316) (xy 412.92886 -280.902504)
			(xy 412.893367 -280.936596) (xy 412.852864 -280.964552) (xy 412.808402 -280.98565) (xy 412.761131 -280.999342)
			(xy 412.712276 -281.005274) (xy 412.663101 -281.003293) (xy 412.614882 -280.993449) (xy 412.568866 -280.975997)
			(xy 412.526245 -280.95139) (xy 412.488124 -280.920265) (xy 412.455489 -280.883428) (xy 412.429186 -280.841832)
			(xy 412.409895 -280.796556) (xy 412.398118 -280.748772) (xy 412.394158 -280.699718) (xy 412.05531 -280.699718)
			(xy 412.054815 -280.724325) (xy 412.04692 -280.772902) (xy 412.031336 -280.819583) (xy 412.008465 -280.86316)
			(xy 411.9789 -280.902504) (xy 411.943407 -280.936596) (xy 411.902904 -280.964552) (xy 411.858442 -280.98565)
			(xy 411.811171 -280.999342) (xy 411.762316 -281.005274) (xy 411.713141 -281.003293) (xy 411.664922 -280.993449)
			(xy 411.618906 -280.975997) (xy 411.576285 -280.95139) (xy 411.538164 -280.920265) (xy 411.505529 -280.883428)
			(xy 411.479226 -280.841832) (xy 411.459935 -280.796556) (xy 411.448158 -280.748772) (xy 411.444198 -280.699718)
			(xy 411.105096 -280.699718) (xy 411.104601 -280.724325) (xy 411.096706 -280.772902) (xy 411.081122 -280.819583)
			(xy 411.058251 -280.86316) (xy 411.028686 -280.902504) (xy 410.993193 -280.936596) (xy 410.95269 -280.964552)
			(xy 410.908228 -280.98565) (xy 410.860957 -280.999342) (xy 410.812102 -281.005274) (xy 410.762927 -281.003293)
			(xy 410.714708 -280.993449) (xy 410.668692 -280.975997) (xy 410.626071 -280.95139) (xy 410.58795 -280.920265)
			(xy 410.555315 -280.883428) (xy 410.529012 -280.841832) (xy 410.509721 -280.796556) (xy 410.497944 -280.748772)
			(xy 410.493984 -280.699718) (xy 410.155136 -280.699718) (xy 410.154641 -280.724325) (xy 410.146746 -280.772902)
			(xy 410.131162 -280.819583) (xy 410.108291 -280.86316) (xy 410.078726 -280.902504) (xy 410.043233 -280.936596)
			(xy 410.00273 -280.964552) (xy 409.958268 -280.98565) (xy 409.910997 -280.999342) (xy 409.862142 -281.005274)
			(xy 409.812967 -281.003293) (xy 409.764748 -280.993449) (xy 409.718732 -280.975997) (xy 409.676111 -280.95139)
			(xy 409.63799 -280.920265) (xy 409.605355 -280.883428) (xy 409.579052 -280.841832) (xy 409.559761 -280.796556)
			(xy 409.547984 -280.748772) (xy 409.544024 -280.699718) (xy 409.205176 -280.699718) (xy 409.204681 -280.724325)
			(xy 409.196786 -280.772902) (xy 409.181202 -280.819583) (xy 409.158331 -280.86316) (xy 409.128766 -280.902504)
			(xy 409.093273 -280.936596) (xy 409.05277 -280.964552) (xy 409.008308 -280.98565) (xy 408.961037 -280.999342)
			(xy 408.912182 -281.005274) (xy 408.863007 -281.003293) (xy 408.814788 -280.993449) (xy 408.768772 -280.975997)
			(xy 408.726151 -280.95139) (xy 408.68803 -280.920265) (xy 408.655395 -280.883428) (xy 408.629092 -280.841832)
			(xy 408.609801 -280.796556) (xy 408.598024 -280.748772) (xy 408.594064 -280.699718) (xy 408.255216 -280.699718)
			(xy 408.254721 -280.724325) (xy 408.246826 -280.772902) (xy 408.231242 -280.819583) (xy 408.208371 -280.86316)
			(xy 408.178806 -280.902504) (xy 408.143313 -280.936596) (xy 408.10281 -280.964552) (xy 408.058348 -280.98565)
			(xy 408.011077 -280.999342) (xy 407.962222 -281.005274) (xy 407.913047 -281.003293) (xy 407.864828 -280.993449)
			(xy 407.818812 -280.975997) (xy 407.776191 -280.95139) (xy 407.73807 -280.920265) (xy 407.705435 -280.883428)
			(xy 407.679132 -280.841832) (xy 407.659841 -280.796556) (xy 407.648064 -280.748772) (xy 407.644104 -280.699718)
			(xy 407.305256 -280.699718) (xy 407.304761 -280.724325) (xy 407.296866 -280.772902) (xy 407.281282 -280.819583)
			(xy 407.258411 -280.86316) (xy 407.228846 -280.902504) (xy 407.193353 -280.936596) (xy 407.15285 -280.964552)
			(xy 407.108388 -280.98565) (xy 407.061117 -280.999342) (xy 407.012262 -281.005274) (xy 406.963087 -281.003293)
			(xy 406.914868 -280.993449) (xy 406.868852 -280.975997) (xy 406.826231 -280.95139) (xy 406.78811 -280.920265)
			(xy 406.755475 -280.883428) (xy 406.729172 -280.841832) (xy 406.709881 -280.796556) (xy 406.698104 -280.748772)
			(xy 406.694144 -280.699718) (xy 406.355296 -280.699718) (xy 406.354801 -280.724325) (xy 406.346906 -280.772902)
			(xy 406.331322 -280.819583) (xy 406.308451 -280.86316) (xy 406.278886 -280.902504) (xy 406.243393 -280.936596)
			(xy 406.20289 -280.964552) (xy 406.158428 -280.98565) (xy 406.111157 -280.999342) (xy 406.062302 -281.005274)
			(xy 406.013127 -281.003293) (xy 405.964908 -280.993449) (xy 405.918892 -280.975997) (xy 405.876271 -280.95139)
			(xy 405.83815 -280.920265) (xy 405.805515 -280.883428) (xy 405.779212 -280.841832) (xy 405.759921 -280.796556)
			(xy 405.748144 -280.748772) (xy 405.744184 -280.699718) (xy 405.405082 -280.699718) (xy 405.404587 -280.724325)
			(xy 405.396692 -280.772902) (xy 405.381108 -280.819583) (xy 405.358237 -280.86316) (xy 405.328672 -280.902504)
			(xy 405.293179 -280.936596) (xy 405.252676 -280.964552) (xy 405.208214 -280.98565) (xy 405.160943 -280.999342)
			(xy 405.112088 -281.005274) (xy 405.062913 -281.003293) (xy 405.014694 -280.993449) (xy 404.968678 -280.975997)
			(xy 404.926057 -280.95139) (xy 404.887936 -280.920265) (xy 404.855301 -280.883428) (xy 404.828998 -280.841832)
			(xy 404.809707 -280.796556) (xy 404.79793 -280.748772) (xy 404.79397 -280.699718) (xy 404.455122 -280.699718)
			(xy 404.454627 -280.724325) (xy 404.446732 -280.772902) (xy 404.431148 -280.819583) (xy 404.408277 -280.86316)
			(xy 404.378712 -280.902504) (xy 404.343219 -280.936596) (xy 404.302716 -280.964552) (xy 404.258254 -280.98565)
			(xy 404.210983 -280.999342) (xy 404.162128 -281.005274) (xy 404.112953 -281.003293) (xy 404.064734 -280.993449)
			(xy 404.018718 -280.975997) (xy 403.976097 -280.95139) (xy 403.937976 -280.920265) (xy 403.905341 -280.883428)
			(xy 403.879038 -280.841832) (xy 403.859747 -280.796556) (xy 403.84797 -280.748772) (xy 403.84401 -280.699718)
			(xy 403.505162 -280.699718) (xy 403.504667 -280.724325) (xy 403.496772 -280.772902) (xy 403.481188 -280.819583)
			(xy 403.458317 -280.86316) (xy 403.428752 -280.902504) (xy 403.393259 -280.936596) (xy 403.352756 -280.964552)
			(xy 403.308294 -280.98565) (xy 403.261023 -280.999342) (xy 403.212168 -281.005274) (xy 403.162993 -281.003293)
			(xy 403.114774 -280.993449) (xy 403.068758 -280.975997) (xy 403.026137 -280.95139) (xy 402.988016 -280.920265)
			(xy 402.955381 -280.883428) (xy 402.929078 -280.841832) (xy 402.909787 -280.796556) (xy 402.89801 -280.748772)
			(xy 402.89405 -280.699718) (xy 402.555202 -280.699718) (xy 402.554707 -280.724325) (xy 402.546812 -280.772902)
			(xy 402.531228 -280.819583) (xy 402.508357 -280.86316) (xy 402.478792 -280.902504) (xy 402.443299 -280.936596)
			(xy 402.402796 -280.964552) (xy 402.358334 -280.98565) (xy 402.311063 -280.999342) (xy 402.262208 -281.005274)
			(xy 402.213033 -281.003293) (xy 402.164814 -280.993449) (xy 402.118798 -280.975997) (xy 402.076177 -280.95139)
			(xy 402.038056 -280.920265) (xy 402.005421 -280.883428) (xy 401.979118 -280.841832) (xy 401.959827 -280.796556)
			(xy 401.94805 -280.748772) (xy 401.94409 -280.699718) (xy 401.605242 -280.699718) (xy 401.604747 -280.724325)
			(xy 401.596852 -280.772902) (xy 401.581268 -280.819583) (xy 401.558397 -280.86316) (xy 401.528832 -280.902504)
			(xy 401.493339 -280.936596) (xy 401.452836 -280.964552) (xy 401.408374 -280.98565) (xy 401.361103 -280.999342)
			(xy 401.312248 -281.005274) (xy 401.263073 -281.003293) (xy 401.214854 -280.993449) (xy 401.168838 -280.975997)
			(xy 401.126217 -280.95139) (xy 401.088096 -280.920265) (xy 401.055461 -280.883428) (xy 401.029158 -280.841832)
			(xy 401.009867 -280.796556) (xy 400.99809 -280.748772) (xy 400.99413 -280.699718) (xy 400.655282 -280.699718)
			(xy 400.654787 -280.724325) (xy 400.646892 -280.772902) (xy 400.631308 -280.819583) (xy 400.608437 -280.86316)
			(xy 400.578872 -280.902504) (xy 400.543379 -280.936596) (xy 400.502876 -280.964552) (xy 400.458414 -280.98565)
			(xy 400.411143 -280.999342) (xy 400.362288 -281.005274) (xy 400.313113 -281.003293) (xy 400.264894 -280.993449)
			(xy 400.218878 -280.975997) (xy 400.176257 -280.95139) (xy 400.138136 -280.920265) (xy 400.105501 -280.883428)
			(xy 400.079198 -280.841832) (xy 400.059907 -280.796556) (xy 400.04813 -280.748772) (xy 400.04417 -280.699718)
			(xy 399.705322 -280.699718) (xy 399.704827 -280.724325) (xy 399.696932 -280.772902) (xy 399.681348 -280.819583)
			(xy 399.658477 -280.86316) (xy 399.628912 -280.902504) (xy 399.593419 -280.936596) (xy 399.552916 -280.964552)
			(xy 399.508454 -280.98565) (xy 399.461183 -280.999342) (xy 399.412328 -281.005274) (xy 399.363153 -281.003293)
			(xy 399.314934 -280.993449) (xy 399.268918 -280.975997) (xy 399.226297 -280.95139) (xy 399.188176 -280.920265)
			(xy 399.155541 -280.883428) (xy 399.129238 -280.841832) (xy 399.109947 -280.796556) (xy 399.09817 -280.748772)
			(xy 399.09421 -280.699718) (xy 398.755108 -280.699718) (xy 398.754613 -280.724325) (xy 398.746718 -280.772902)
			(xy 398.731134 -280.819583) (xy 398.708263 -280.86316) (xy 398.678698 -280.902504) (xy 398.643205 -280.936596)
			(xy 398.602702 -280.964552) (xy 398.55824 -280.98565) (xy 398.510969 -280.999342) (xy 398.462114 -281.005274)
			(xy 398.412939 -281.003293) (xy 398.36472 -280.993449) (xy 398.318704 -280.975997) (xy 398.276083 -280.95139)
			(xy 398.237962 -280.920265) (xy 398.205327 -280.883428) (xy 398.179024 -280.841832) (xy 398.159733 -280.796556)
			(xy 398.147956 -280.748772) (xy 398.143996 -280.699718) (xy 397.805148 -280.699718) (xy 397.804653 -280.724325)
			(xy 397.796758 -280.772902) (xy 397.781174 -280.819583) (xy 397.758303 -280.86316) (xy 397.728738 -280.902504)
			(xy 397.693245 -280.936596) (xy 397.652742 -280.964552) (xy 397.60828 -280.98565) (xy 397.561009 -280.999342)
			(xy 397.512154 -281.005274) (xy 397.462979 -281.003293) (xy 397.41476 -280.993449) (xy 397.368744 -280.975997)
			(xy 397.326123 -280.95139) (xy 397.288002 -280.920265) (xy 397.255367 -280.883428) (xy 397.229064 -280.841832)
			(xy 397.209773 -280.796556) (xy 397.197996 -280.748772) (xy 397.194036 -280.699718) (xy 396.854778 -280.699718)
			(xy 396.854778 -280.723757) (xy 396.847233 -280.771269) (xy 396.832331 -280.81701) (xy 396.810441 -280.859849)
			(xy 396.782103 -280.898725) (xy 396.74802 -280.932676) (xy 396.709035 -280.960862) (xy 396.666111 -280.982585)
			(xy 396.620312 -280.997309) (xy 396.596616 -281.00147) (xy 396.578074 -281.004264) (xy 396.55369 -281.032712)
			(xy 396.55369 -281.316938) (xy 396.578074 -281.345386) (xy 396.596616 -281.34818) (xy 396.620316 -281.352306)
			(xy 396.666113 -281.36703) (xy 396.709034 -281.388754) (xy 396.748017 -281.41694) (xy 396.782098 -281.45089)
			(xy 396.810433 -281.489765) (xy 396.832322 -281.532602) (xy 396.847222 -281.578342) (xy 396.854765 -281.625852)
			(xy 396.854764 -281.649932) (xy 397.194036 -281.649932) (xy 397.197996 -281.600878) (xy 397.209773 -281.553094)
			(xy 397.229064 -281.507818) (xy 397.255367 -281.466222) (xy 397.288002 -281.429385) (xy 397.326123 -281.39826)
			(xy 397.368744 -281.373653) (xy 397.41476 -281.356201) (xy 397.462979 -281.346357) (xy 397.512154 -281.344376)
			(xy 397.561009 -281.350308) (xy 397.60828 -281.364) (xy 397.652742 -281.385098) (xy 397.693245 -281.413054)
			(xy 397.728738 -281.447146) (xy 397.758303 -281.48649) (xy 397.781174 -281.530067) (xy 397.796758 -281.576748)
			(xy 397.804653 -281.625325) (xy 397.805148 -281.649932) (xy 398.143996 -281.649932) (xy 398.147956 -281.600878)
			(xy 398.159733 -281.553094) (xy 398.179024 -281.507818) (xy 398.205327 -281.466222) (xy 398.237962 -281.429385)
			(xy 398.276083 -281.39826) (xy 398.318704 -281.373653) (xy 398.36472 -281.356201) (xy 398.412939 -281.346357)
			(xy 398.462114 -281.344376) (xy 398.510969 -281.350308) (xy 398.55824 -281.364) (xy 398.602702 -281.385098)
			(xy 398.643205 -281.413054) (xy 398.678698 -281.447146) (xy 398.708263 -281.48649) (xy 398.731134 -281.530067)
			(xy 398.746718 -281.576748) (xy 398.754613 -281.625325) (xy 398.755108 -281.649932) (xy 399.09421 -281.649932)
			(xy 399.09817 -281.600878) (xy 399.109947 -281.553094) (xy 399.129238 -281.507818) (xy 399.155541 -281.466222)
			(xy 399.188176 -281.429385) (xy 399.226297 -281.39826) (xy 399.268918 -281.373653) (xy 399.314934 -281.356201)
			(xy 399.363153 -281.346357) (xy 399.412328 -281.344376) (xy 399.461183 -281.350308) (xy 399.508454 -281.364)
			(xy 399.552916 -281.385098) (xy 399.593419 -281.413054) (xy 399.628912 -281.447146) (xy 399.658477 -281.48649)
			(xy 399.681348 -281.530067) (xy 399.696932 -281.576748) (xy 399.704827 -281.625325) (xy 399.705322 -281.649932)
			(xy 400.04417 -281.649932) (xy 400.04813 -281.600878) (xy 400.059907 -281.553094) (xy 400.079198 -281.507818)
			(xy 400.105501 -281.466222) (xy 400.138136 -281.429385) (xy 400.176257 -281.39826) (xy 400.218878 -281.373653)
			(xy 400.264894 -281.356201) (xy 400.313113 -281.346357) (xy 400.362288 -281.344376) (xy 400.411143 -281.350308)
			(xy 400.458414 -281.364) (xy 400.502876 -281.385098) (xy 400.543379 -281.413054) (xy 400.578872 -281.447146)
			(xy 400.608437 -281.48649) (xy 400.631308 -281.530067) (xy 400.646892 -281.576748) (xy 400.654787 -281.625325)
			(xy 400.655282 -281.649932) (xy 400.99413 -281.649932) (xy 400.99809 -281.600878) (xy 401.009867 -281.553094)
			(xy 401.029158 -281.507818) (xy 401.055461 -281.466222) (xy 401.088096 -281.429385) (xy 401.126217 -281.39826)
			(xy 401.168838 -281.373653) (xy 401.214854 -281.356201) (xy 401.263073 -281.346357) (xy 401.312248 -281.344376)
			(xy 401.361103 -281.350308) (xy 401.408374 -281.364) (xy 401.452836 -281.385098) (xy 401.493339 -281.413054)
			(xy 401.528832 -281.447146) (xy 401.558397 -281.48649) (xy 401.581268 -281.530067) (xy 401.596852 -281.576748)
			(xy 401.604747 -281.625325) (xy 401.605242 -281.649932) (xy 401.94409 -281.649932) (xy 401.94805 -281.600878)
			(xy 401.959827 -281.553094) (xy 401.979118 -281.507818) (xy 402.005421 -281.466222) (xy 402.038056 -281.429385)
			(xy 402.076177 -281.39826) (xy 402.118798 -281.373653) (xy 402.164814 -281.356201) (xy 402.213033 -281.346357)
			(xy 402.262208 -281.344376) (xy 402.311063 -281.350308) (xy 402.358334 -281.364) (xy 402.402796 -281.385098)
			(xy 402.443299 -281.413054) (xy 402.478792 -281.447146) (xy 402.508357 -281.48649) (xy 402.531228 -281.530067)
			(xy 402.546812 -281.576748) (xy 402.554707 -281.625325) (xy 402.555202 -281.649932) (xy 402.89405 -281.649932)
			(xy 402.89801 -281.600878) (xy 402.909787 -281.553094) (xy 402.929078 -281.507818) (xy 402.955381 -281.466222)
			(xy 402.988016 -281.429385) (xy 403.026137 -281.39826) (xy 403.068758 -281.373653) (xy 403.114774 -281.356201)
			(xy 403.162993 -281.346357) (xy 403.212168 -281.344376) (xy 403.261023 -281.350308) (xy 403.308294 -281.364)
			(xy 403.352756 -281.385098) (xy 403.393259 -281.413054) (xy 403.428752 -281.447146) (xy 403.458317 -281.48649)
			(xy 403.481188 -281.530067) (xy 403.496772 -281.576748) (xy 403.504667 -281.625325) (xy 403.505162 -281.649932)
			(xy 403.84401 -281.649932) (xy 403.84797 -281.600878) (xy 403.859747 -281.553094) (xy 403.879038 -281.507818)
			(xy 403.905341 -281.466222) (xy 403.937976 -281.429385) (xy 403.976097 -281.39826) (xy 404.018718 -281.373653)
			(xy 404.064734 -281.356201) (xy 404.112953 -281.346357) (xy 404.162128 -281.344376) (xy 404.210983 -281.350308)
			(xy 404.258254 -281.364) (xy 404.302716 -281.385098) (xy 404.343219 -281.413054) (xy 404.378712 -281.447146)
			(xy 404.408277 -281.48649) (xy 404.431148 -281.530067) (xy 404.446732 -281.576748) (xy 404.454627 -281.625325)
			(xy 404.455122 -281.649932) (xy 404.794224 -281.649932) (xy 404.798184 -281.600878) (xy 404.809961 -281.553094)
			(xy 404.829252 -281.507818) (xy 404.855555 -281.466222) (xy 404.88819 -281.429385) (xy 404.926311 -281.39826)
			(xy 404.968932 -281.373653) (xy 405.014948 -281.356201) (xy 405.063167 -281.346357) (xy 405.112342 -281.344376)
			(xy 405.161197 -281.350308) (xy 405.208468 -281.364) (xy 405.25293 -281.385098) (xy 405.293433 -281.413054)
			(xy 405.328926 -281.447146) (xy 405.358491 -281.48649) (xy 405.381362 -281.530067) (xy 405.396946 -281.576748)
			(xy 405.404841 -281.625325) (xy 405.405336 -281.649932) (xy 405.744184 -281.649932) (xy 405.748144 -281.600878)
			(xy 405.759921 -281.553094) (xy 405.779212 -281.507818) (xy 405.805515 -281.466222) (xy 405.83815 -281.429385)
			(xy 405.876271 -281.39826) (xy 405.918892 -281.373653) (xy 405.964908 -281.356201) (xy 406.013127 -281.346357)
			(xy 406.062302 -281.344376) (xy 406.111157 -281.350308) (xy 406.158428 -281.364) (xy 406.20289 -281.385098)
			(xy 406.243393 -281.413054) (xy 406.278886 -281.447146) (xy 406.308451 -281.48649) (xy 406.331322 -281.530067)
			(xy 406.346906 -281.576748) (xy 406.354801 -281.625325) (xy 406.355296 -281.649932) (xy 406.694144 -281.649932)
			(xy 406.698104 -281.600878) (xy 406.709881 -281.553094) (xy 406.729172 -281.507818) (xy 406.755475 -281.466222)
			(xy 406.78811 -281.429385) (xy 406.826231 -281.39826) (xy 406.868852 -281.373653) (xy 406.914868 -281.356201)
			(xy 406.963087 -281.346357) (xy 407.012262 -281.344376) (xy 407.061117 -281.350308) (xy 407.108388 -281.364)
			(xy 407.15285 -281.385098) (xy 407.193353 -281.413054) (xy 407.228846 -281.447146) (xy 407.258411 -281.48649)
			(xy 407.281282 -281.530067) (xy 407.296866 -281.576748) (xy 407.304761 -281.625325) (xy 407.305256 -281.649932)
			(xy 407.644104 -281.649932) (xy 407.648064 -281.600878) (xy 407.659841 -281.553094) (xy 407.679132 -281.507818)
			(xy 407.705435 -281.466222) (xy 407.73807 -281.429385) (xy 407.776191 -281.39826) (xy 407.818812 -281.373653)
			(xy 407.864828 -281.356201) (xy 407.913047 -281.346357) (xy 407.962222 -281.344376) (xy 408.011077 -281.350308)
			(xy 408.058348 -281.364) (xy 408.10281 -281.385098) (xy 408.143313 -281.413054) (xy 408.178806 -281.447146)
			(xy 408.208371 -281.48649) (xy 408.231242 -281.530067) (xy 408.246826 -281.576748) (xy 408.254721 -281.625325)
			(xy 408.255216 -281.649932) (xy 408.594064 -281.649932) (xy 408.598024 -281.600878) (xy 408.609801 -281.553094)
			(xy 408.629092 -281.507818) (xy 408.655395 -281.466222) (xy 408.68803 -281.429385) (xy 408.726151 -281.39826)
			(xy 408.768772 -281.373653) (xy 408.814788 -281.356201) (xy 408.863007 -281.346357) (xy 408.912182 -281.344376)
			(xy 408.961037 -281.350308) (xy 409.008308 -281.364) (xy 409.05277 -281.385098) (xy 409.093273 -281.413054)
			(xy 409.128766 -281.447146) (xy 409.158331 -281.48649) (xy 409.181202 -281.530067) (xy 409.196786 -281.576748)
			(xy 409.204681 -281.625325) (xy 409.205176 -281.649932) (xy 409.544024 -281.649932) (xy 409.547984 -281.600878)
			(xy 409.559761 -281.553094) (xy 409.579052 -281.507818) (xy 409.605355 -281.466222) (xy 409.63799 -281.429385)
			(xy 409.676111 -281.39826) (xy 409.718732 -281.373653) (xy 409.764748 -281.356201) (xy 409.812967 -281.346357)
			(xy 409.862142 -281.344376) (xy 409.910997 -281.350308) (xy 409.958268 -281.364) (xy 410.00273 -281.385098)
			(xy 410.043233 -281.413054) (xy 410.078726 -281.447146) (xy 410.108291 -281.48649) (xy 410.131162 -281.530067)
			(xy 410.146746 -281.576748) (xy 410.154641 -281.625325) (xy 410.155136 -281.649932) (xy 410.493984 -281.649932)
			(xy 410.497944 -281.600878) (xy 410.509721 -281.553094) (xy 410.529012 -281.507818) (xy 410.555315 -281.466222)
			(xy 410.58795 -281.429385) (xy 410.626071 -281.39826) (xy 410.668692 -281.373653) (xy 410.714708 -281.356201)
			(xy 410.762927 -281.346357) (xy 410.812102 -281.344376) (xy 410.860957 -281.350308) (xy 410.908228 -281.364)
			(xy 410.95269 -281.385098) (xy 410.993193 -281.413054) (xy 411.028686 -281.447146) (xy 411.058251 -281.48649)
			(xy 411.081122 -281.530067) (xy 411.096706 -281.576748) (xy 411.104601 -281.625325) (xy 411.105096 -281.649932)
			(xy 411.444198 -281.649932) (xy 411.448158 -281.600878) (xy 411.459935 -281.553094) (xy 411.479226 -281.507818)
			(xy 411.505529 -281.466222) (xy 411.538164 -281.429385) (xy 411.576285 -281.39826) (xy 411.618906 -281.373653)
			(xy 411.664922 -281.356201) (xy 411.713141 -281.346357) (xy 411.762316 -281.344376) (xy 411.811171 -281.350308)
			(xy 411.858442 -281.364) (xy 411.902904 -281.385098) (xy 411.943407 -281.413054) (xy 411.9789 -281.447146)
			(xy 412.008465 -281.48649) (xy 412.031336 -281.530067) (xy 412.04692 -281.576748) (xy 412.054815 -281.625325)
			(xy 412.05531 -281.649932) (xy 412.394158 -281.649932) (xy 412.398118 -281.600878) (xy 412.409895 -281.553094)
			(xy 412.429186 -281.507818) (xy 412.455489 -281.466222) (xy 412.488124 -281.429385) (xy 412.526245 -281.39826)
			(xy 412.568866 -281.373653) (xy 412.614882 -281.356201) (xy 412.663101 -281.346357) (xy 412.712276 -281.344376)
			(xy 412.761131 -281.350308) (xy 412.808402 -281.364) (xy 412.852864 -281.385098) (xy 412.893367 -281.413054)
			(xy 412.92886 -281.447146) (xy 412.958425 -281.48649) (xy 412.981296 -281.530067) (xy 412.99688 -281.576748)
			(xy 413.004775 -281.625325) (xy 413.00527 -281.649932) (xy 413.344118 -281.649932) (xy 413.348078 -281.600878)
			(xy 413.359855 -281.553094) (xy 413.379146 -281.507818) (xy 413.405449 -281.466222) (xy 413.438084 -281.429385)
			(xy 413.476205 -281.39826) (xy 413.518826 -281.373653) (xy 413.564842 -281.356201) (xy 413.613061 -281.346357)
			(xy 413.662236 -281.344376) (xy 413.711091 -281.350308) (xy 413.758362 -281.364) (xy 413.802824 -281.385098)
			(xy 413.843327 -281.413054) (xy 413.87882 -281.447146) (xy 413.908385 -281.48649) (xy 413.931256 -281.530067)
			(xy 413.94684 -281.576748) (xy 413.954735 -281.625325) (xy 413.95523 -281.649932) (xy 414.294078 -281.649932)
			(xy 414.298038 -281.600878) (xy 414.309815 -281.553094) (xy 414.329106 -281.507818) (xy 414.355409 -281.466222)
			(xy 414.388044 -281.429385) (xy 414.426165 -281.39826) (xy 414.468786 -281.373653) (xy 414.514802 -281.356201)
			(xy 414.563021 -281.346357) (xy 414.612196 -281.344376) (xy 414.661051 -281.350308) (xy 414.708322 -281.364)
			(xy 414.752784 -281.385098) (xy 414.793287 -281.413054) (xy 414.82878 -281.447146) (xy 414.858345 -281.48649)
			(xy 414.881216 -281.530067) (xy 414.8968 -281.576748) (xy 414.904695 -281.625325) (xy 414.90519 -281.649932)
			(xy 415.244038 -281.649932) (xy 415.247998 -281.600878) (xy 415.259775 -281.553094) (xy 415.279066 -281.507818)
			(xy 415.305369 -281.466222) (xy 415.338004 -281.429385) (xy 415.376125 -281.39826) (xy 415.418746 -281.373653)
			(xy 415.464762 -281.356201) (xy 415.512981 -281.346357) (xy 415.562156 -281.344376) (xy 415.611011 -281.350308)
			(xy 415.658282 -281.364) (xy 415.702744 -281.385098) (xy 415.743247 -281.413054) (xy 415.77874 -281.447146)
			(xy 415.808305 -281.48649) (xy 415.831176 -281.530067) (xy 415.84676 -281.576748) (xy 415.854655 -281.625325)
			(xy 415.85515 -281.649932) (xy 416.193998 -281.649932) (xy 416.197958 -281.600878) (xy 416.209735 -281.553094)
			(xy 416.229026 -281.507818) (xy 416.255329 -281.466222) (xy 416.287964 -281.429385) (xy 416.326085 -281.39826)
			(xy 416.368706 -281.373653) (xy 416.414722 -281.356201) (xy 416.462941 -281.346357) (xy 416.512116 -281.344376)
			(xy 416.560971 -281.350308) (xy 416.608242 -281.364) (xy 416.652704 -281.385098) (xy 416.693207 -281.413054)
			(xy 416.7287 -281.447146) (xy 416.758265 -281.48649) (xy 416.781136 -281.530067) (xy 416.79672 -281.576748)
			(xy 416.804615 -281.625325) (xy 416.80511 -281.649932) (xy 417.144212 -281.649932) (xy 417.148172 -281.600878)
			(xy 417.159949 -281.553094) (xy 417.17924 -281.507818) (xy 417.205543 -281.466222) (xy 417.238178 -281.429385)
			(xy 417.276299 -281.39826) (xy 417.31892 -281.373653) (xy 417.364936 -281.356201) (xy 417.413155 -281.346357)
			(xy 417.46233 -281.344376) (xy 417.511185 -281.350308) (xy 417.558456 -281.364) (xy 417.602918 -281.385098)
			(xy 417.643421 -281.413054) (xy 417.678914 -281.447146) (xy 417.708479 -281.48649) (xy 417.73135 -281.530067)
			(xy 417.746934 -281.576748) (xy 417.754829 -281.625325) (xy 417.755324 -281.649932) (xy 418.094172 -281.649932)
			(xy 418.098132 -281.600878) (xy 418.109909 -281.553094) (xy 418.1292 -281.507818) (xy 418.155503 -281.466222)
			(xy 418.188138 -281.429385) (xy 418.226259 -281.39826) (xy 418.26888 -281.373653) (xy 418.314896 -281.356201)
			(xy 418.363115 -281.346357) (xy 418.41229 -281.344376) (xy 418.461145 -281.350308) (xy 418.508416 -281.364)
			(xy 418.552878 -281.385098) (xy 418.593381 -281.413054) (xy 418.628874 -281.447146) (xy 418.658439 -281.48649)
			(xy 418.68131 -281.530067) (xy 418.696894 -281.576748) (xy 418.704789 -281.625325) (xy 418.705284 -281.649932)
			(xy 419.044132 -281.649932) (xy 419.048092 -281.600878) (xy 419.059869 -281.553094) (xy 419.07916 -281.507818)
			(xy 419.105463 -281.466222) (xy 419.138098 -281.429385) (xy 419.176219 -281.39826) (xy 419.21884 -281.373653)
			(xy 419.264856 -281.356201) (xy 419.313075 -281.346357) (xy 419.36225 -281.344376) (xy 419.411105 -281.350308)
			(xy 419.458376 -281.364) (xy 419.502838 -281.385098) (xy 419.543341 -281.413054) (xy 419.578834 -281.447146)
			(xy 419.608399 -281.48649) (xy 419.63127 -281.530067) (xy 419.646854 -281.576748) (xy 419.654749 -281.625325)
			(xy 419.655244 -281.649932) (xy 419.994092 -281.649932) (xy 419.998052 -281.600878) (xy 420.009829 -281.553094)
			(xy 420.02912 -281.507818) (xy 420.055423 -281.466222) (xy 420.088058 -281.429385) (xy 420.126179 -281.39826)
			(xy 420.1688 -281.373653) (xy 420.214816 -281.356201) (xy 420.263035 -281.346357) (xy 420.31221 -281.344376)
			(xy 420.361065 -281.350308) (xy 420.408336 -281.364) (xy 420.452798 -281.385098) (xy 420.493301 -281.413054)
			(xy 420.528794 -281.447146) (xy 420.558359 -281.48649) (xy 420.58123 -281.530067) (xy 420.596814 -281.576748)
			(xy 420.604709 -281.625325) (xy 420.605204 -281.649932) (xy 420.944052 -281.649932) (xy 420.948012 -281.600878)
			(xy 420.959789 -281.553094) (xy 420.97908 -281.507818) (xy 421.005383 -281.466222) (xy 421.038018 -281.429385)
			(xy 421.076139 -281.39826) (xy 421.11876 -281.373653) (xy 421.164776 -281.356201) (xy 421.212995 -281.346357)
			(xy 421.26217 -281.344376) (xy 421.311025 -281.350308) (xy 421.358296 -281.364) (xy 421.402758 -281.385098)
			(xy 421.443261 -281.413054) (xy 421.478754 -281.447146) (xy 421.508319 -281.48649) (xy 421.53119 -281.530067)
			(xy 421.546774 -281.576748) (xy 421.554669 -281.625325) (xy 421.555164 -281.649932) (xy 421.894012 -281.649932)
			(xy 421.897972 -281.600878) (xy 421.909749 -281.553094) (xy 421.92904 -281.507818) (xy 421.955343 -281.466222)
			(xy 421.987978 -281.429385) (xy 422.026099 -281.39826) (xy 422.06872 -281.373653) (xy 422.114736 -281.356201)
			(xy 422.162955 -281.346357) (xy 422.21213 -281.344376) (xy 422.260985 -281.350308) (xy 422.308256 -281.364)
			(xy 422.352718 -281.385098) (xy 422.393221 -281.413054) (xy 422.428714 -281.447146) (xy 422.458279 -281.48649)
			(xy 422.48115 -281.530067) (xy 422.496734 -281.576748) (xy 422.504629 -281.625325) (xy 422.505124 -281.649932)
			(xy 422.844226 -281.649932) (xy 422.848186 -281.600878) (xy 422.859963 -281.553094) (xy 422.879254 -281.507818)
			(xy 422.905557 -281.466222) (xy 422.938192 -281.429385) (xy 422.976313 -281.39826) (xy 423.018934 -281.373653)
			(xy 423.06495 -281.356201) (xy 423.113169 -281.346357) (xy 423.162344 -281.344376) (xy 423.211199 -281.350308)
			(xy 423.25847 -281.364) (xy 423.302932 -281.385098) (xy 423.343435 -281.413054) (xy 423.378928 -281.447146)
			(xy 423.408493 -281.48649) (xy 423.431364 -281.530067) (xy 423.446948 -281.576748) (xy 423.454843 -281.625325)
			(xy 423.455338 -281.649932) (xy 423.794186 -281.649932) (xy 423.798146 -281.600878) (xy 423.809923 -281.553094)
			(xy 423.829214 -281.507818) (xy 423.855517 -281.466222) (xy 423.888152 -281.429385) (xy 423.926273 -281.39826)
			(xy 423.968894 -281.373653) (xy 424.01491 -281.356201) (xy 424.063129 -281.346357) (xy 424.112304 -281.344376)
			(xy 424.161159 -281.350308) (xy 424.20843 -281.364) (xy 424.252892 -281.385098) (xy 424.293395 -281.413054)
			(xy 424.328888 -281.447146) (xy 424.358453 -281.48649) (xy 424.381324 -281.530067) (xy 424.396908 -281.576748)
			(xy 424.404803 -281.625325) (xy 424.405298 -281.649932) (xy 424.744146 -281.649932) (xy 424.748106 -281.600878)
			(xy 424.759883 -281.553094) (xy 424.779174 -281.507818) (xy 424.805477 -281.466222) (xy 424.838112 -281.429385)
			(xy 424.876233 -281.39826) (xy 424.918854 -281.373653) (xy 424.96487 -281.356201) (xy 425.013089 -281.346357)
			(xy 425.062264 -281.344376) (xy 425.111119 -281.350308) (xy 425.15839 -281.364) (xy 425.202852 -281.385098)
			(xy 425.243355 -281.413054) (xy 425.278848 -281.447146) (xy 425.308413 -281.48649) (xy 425.331284 -281.530067)
			(xy 425.346868 -281.576748) (xy 425.354763 -281.625325) (xy 425.355253 -281.649678) (xy 425.693852 -281.649678)
			(xy 425.697812 -281.600624) (xy 425.709589 -281.55284) (xy 425.72888 -281.507564) (xy 425.755183 -281.465968)
			(xy 425.787818 -281.429131) (xy 425.825939 -281.398006) (xy 425.86856 -281.373399) (xy 425.914576 -281.355947)
			(xy 425.962795 -281.346103) (xy 426.01197 -281.344122) (xy 426.060825 -281.350054) (xy 426.108096 -281.363746)
			(xy 426.152558 -281.384844) (xy 426.193061 -281.4128) (xy 426.228554 -281.446892) (xy 426.258119 -281.486236)
			(xy 426.28099 -281.529813) (xy 426.296574 -281.576494) (xy 426.304469 -281.625071) (xy 426.304964 -281.649678)
			(xy 426.304959 -281.649932) (xy 426.643812 -281.649932) (xy 426.647772 -281.600878) (xy 426.659549 -281.553094)
			(xy 426.67884 -281.507818) (xy 426.705143 -281.466222) (xy 426.737778 -281.429385) (xy 426.775899 -281.39826)
			(xy 426.81852 -281.373653) (xy 426.864536 -281.356201) (xy 426.912755 -281.346357) (xy 426.96193 -281.344376)
			(xy 427.010785 -281.350308) (xy 427.058056 -281.364) (xy 427.102518 -281.385098) (xy 427.143021 -281.413054)
			(xy 427.178514 -281.447146) (xy 427.208079 -281.48649) (xy 427.23095 -281.530067) (xy 427.246534 -281.576748)
			(xy 427.254429 -281.625325) (xy 427.254924 -281.649932) (xy 427.594026 -281.649932) (xy 427.597986 -281.600878)
			(xy 427.609763 -281.553094) (xy 427.629054 -281.507818) (xy 427.655357 -281.466222) (xy 427.687992 -281.429385)
			(xy 427.726113 -281.39826) (xy 427.768734 -281.373653) (xy 427.81475 -281.356201) (xy 427.862969 -281.346357)
			(xy 427.912144 -281.344376) (xy 427.960999 -281.350308) (xy 428.00827 -281.364) (xy 428.052732 -281.385098)
			(xy 428.093235 -281.413054) (xy 428.128728 -281.447146) (xy 428.158293 -281.48649) (xy 428.181164 -281.530067)
			(xy 428.196748 -281.576748) (xy 428.204643 -281.625325) (xy 428.205138 -281.649932) (xy 428.543986 -281.649932)
			(xy 428.547946 -281.600878) (xy 428.559723 -281.553094) (xy 428.579014 -281.507818) (xy 428.605317 -281.466222)
			(xy 428.637952 -281.429385) (xy 428.676073 -281.39826) (xy 428.718694 -281.373653) (xy 428.76471 -281.356201)
			(xy 428.812929 -281.346357) (xy 428.862104 -281.344376) (xy 428.910959 -281.350308) (xy 428.95823 -281.364)
			(xy 429.002692 -281.385098) (xy 429.043195 -281.413054) (xy 429.078688 -281.447146) (xy 429.108253 -281.48649)
			(xy 429.131124 -281.530067) (xy 429.146708 -281.576748) (xy 429.154603 -281.625325) (xy 429.155098 -281.649932)
			(xy 429.154603 -281.674539) (xy 429.154424 -281.67564) (xy 429.473356 -281.67564) (xy 429.473356 -281.624224)
			(xy 429.481399 -281.573442) (xy 429.497287 -281.524543) (xy 429.52063 -281.478731) (xy 429.550851 -281.437135)
			(xy 429.587207 -281.400779) (xy 429.628803 -281.370558) (xy 429.674615 -281.347215) (xy 429.723514 -281.331327)
			(xy 429.774296 -281.323284) (xy 429.825712 -281.323284) (xy 429.876494 -281.331327) (xy 429.925393 -281.347215)
			(xy 429.971205 -281.370558) (xy 430.012801 -281.400779) (xy 430.049157 -281.437135) (xy 430.079378 -281.478731)
			(xy 430.102721 -281.524543) (xy 430.118609 -281.573442) (xy 430.126652 -281.624224) (xy 430.127156 -281.649932)
			(xy 430.126652 -281.67564) (xy 430.423316 -281.67564) (xy 430.423316 -281.624224) (xy 430.431359 -281.573442)
			(xy 430.447247 -281.524543) (xy 430.47059 -281.478731) (xy 430.500811 -281.437135) (xy 430.537167 -281.400779)
			(xy 430.578763 -281.370558) (xy 430.624575 -281.347215) (xy 430.673474 -281.331327) (xy 430.724256 -281.323284)
			(xy 430.775672 -281.323284) (xy 430.826454 -281.331327) (xy 430.875353 -281.347215) (xy 430.921165 -281.370558)
			(xy 430.962761 -281.400779) (xy 430.999117 -281.437135) (xy 431.029338 -281.478731) (xy 431.052681 -281.524543)
			(xy 431.068569 -281.573442) (xy 431.076612 -281.624224) (xy 431.077116 -281.649932) (xy 431.077111 -281.650186)
			(xy 431.394374 -281.650186) (xy 431.398334 -281.601132) (xy 431.410111 -281.553348) (xy 431.429402 -281.508072)
			(xy 431.455705 -281.466476) (xy 431.48834 -281.429639) (xy 431.526461 -281.398514) (xy 431.569082 -281.373907)
			(xy 431.615098 -281.356455) (xy 431.663317 -281.346611) (xy 431.712492 -281.34463) (xy 431.761347 -281.350562)
			(xy 431.808618 -281.364254) (xy 431.85308 -281.385352) (xy 431.893583 -281.413308) (xy 431.929076 -281.4474)
			(xy 431.958641 -281.486744) (xy 431.981512 -281.530321) (xy 431.997096 -281.577002) (xy 432.004991 -281.625579)
			(xy 432.005486 -281.650186) (xy 432.004991 -281.674793) (xy 431.997096 -281.72337) (xy 431.981512 -281.770051)
			(xy 431.958641 -281.813628) (xy 431.929076 -281.852972) (xy 431.893583 -281.887064) (xy 431.85308 -281.91502)
			(xy 431.808618 -281.936118) (xy 431.761347 -281.94981) (xy 431.712492 -281.955742) (xy 431.663317 -281.953761)
			(xy 431.615098 -281.943917) (xy 431.569082 -281.926465) (xy 431.526461 -281.901858) (xy 431.48834 -281.870733)
			(xy 431.455705 -281.833896) (xy 431.429402 -281.7923) (xy 431.410111 -281.747024) (xy 431.398334 -281.69924)
			(xy 431.394374 -281.650186) (xy 431.077111 -281.650186) (xy 431.076612 -281.67564) (xy 431.068569 -281.726422)
			(xy 431.052681 -281.775321) (xy 431.029338 -281.821133) (xy 430.999117 -281.862729) (xy 430.962761 -281.899085)
			(xy 430.921165 -281.929306) (xy 430.875353 -281.952649) (xy 430.826454 -281.968537) (xy 430.775672 -281.97658)
			(xy 430.724256 -281.97658) (xy 430.673474 -281.968537) (xy 430.624575 -281.952649) (xy 430.578763 -281.929306)
			(xy 430.537167 -281.899085) (xy 430.500811 -281.862729) (xy 430.47059 -281.821133) (xy 430.447247 -281.775321)
			(xy 430.431359 -281.726422) (xy 430.423316 -281.67564) (xy 430.126652 -281.67564) (xy 430.118609 -281.726422)
			(xy 430.102721 -281.775321) (xy 430.079378 -281.821133) (xy 430.049157 -281.862729) (xy 430.012801 -281.899085)
			(xy 429.971205 -281.929306) (xy 429.925393 -281.952649) (xy 429.876494 -281.968537) (xy 429.825712 -281.97658)
			(xy 429.774296 -281.97658) (xy 429.723514 -281.968537) (xy 429.674615 -281.952649) (xy 429.628803 -281.929306)
			(xy 429.587207 -281.899085) (xy 429.550851 -281.862729) (xy 429.52063 -281.821133) (xy 429.497287 -281.775321)
			(xy 429.481399 -281.726422) (xy 429.473356 -281.67564) (xy 429.154424 -281.67564) (xy 429.146708 -281.723116)
			(xy 429.131124 -281.769797) (xy 429.108253 -281.813374) (xy 429.078688 -281.852718) (xy 429.043195 -281.88681)
			(xy 429.002692 -281.914766) (xy 428.95823 -281.935864) (xy 428.910959 -281.949556) (xy 428.862104 -281.955488)
			(xy 428.812929 -281.953507) (xy 428.76471 -281.943663) (xy 428.718694 -281.926211) (xy 428.676073 -281.901604)
			(xy 428.637952 -281.870479) (xy 428.605317 -281.833642) (xy 428.579014 -281.792046) (xy 428.559723 -281.74677)
			(xy 428.547946 -281.698986) (xy 428.543986 -281.649932) (xy 428.205138 -281.649932) (xy 428.204643 -281.674539)
			(xy 428.196748 -281.723116) (xy 428.181164 -281.769797) (xy 428.158293 -281.813374) (xy 428.128728 -281.852718)
			(xy 428.093235 -281.88681) (xy 428.052732 -281.914766) (xy 428.00827 -281.935864) (xy 427.960999 -281.949556)
			(xy 427.912144 -281.955488) (xy 427.862969 -281.953507) (xy 427.81475 -281.943663) (xy 427.768734 -281.926211)
			(xy 427.726113 -281.901604) (xy 427.687992 -281.870479) (xy 427.655357 -281.833642) (xy 427.629054 -281.792046)
			(xy 427.609763 -281.74677) (xy 427.597986 -281.698986) (xy 427.594026 -281.649932) (xy 427.254924 -281.649932)
			(xy 427.254429 -281.674539) (xy 427.246534 -281.723116) (xy 427.23095 -281.769797) (xy 427.208079 -281.813374)
			(xy 427.178514 -281.852718) (xy 427.143021 -281.88681) (xy 427.102518 -281.914766) (xy 427.058056 -281.935864)
			(xy 427.010785 -281.949556) (xy 426.96193 -281.955488) (xy 426.912755 -281.953507) (xy 426.864536 -281.943663)
			(xy 426.81852 -281.926211) (xy 426.775899 -281.901604) (xy 426.737778 -281.870479) (xy 426.705143 -281.833642)
			(xy 426.67884 -281.792046) (xy 426.659549 -281.74677) (xy 426.647772 -281.698986) (xy 426.643812 -281.649932)
			(xy 426.304959 -281.649932) (xy 426.304469 -281.674285) (xy 426.296574 -281.722862) (xy 426.28099 -281.769543)
			(xy 426.258119 -281.81312) (xy 426.228554 -281.852464) (xy 426.193061 -281.886556) (xy 426.152558 -281.914512)
			(xy 426.108096 -281.93561) (xy 426.060825 -281.949302) (xy 426.01197 -281.955234) (xy 425.962795 -281.953253)
			(xy 425.914576 -281.943409) (xy 425.86856 -281.925957) (xy 425.825939 -281.90135) (xy 425.787818 -281.870225)
			(xy 425.755183 -281.833388) (xy 425.72888 -281.791792) (xy 425.709589 -281.746516) (xy 425.697812 -281.698732)
			(xy 425.693852 -281.649678) (xy 425.355253 -281.649678) (xy 425.355258 -281.649932) (xy 425.354763 -281.674539)
			(xy 425.346868 -281.723116) (xy 425.331284 -281.769797) (xy 425.308413 -281.813374) (xy 425.278848 -281.852718)
			(xy 425.243355 -281.88681) (xy 425.202852 -281.914766) (xy 425.15839 -281.935864) (xy 425.111119 -281.949556)
			(xy 425.062264 -281.955488) (xy 425.013089 -281.953507) (xy 424.96487 -281.943663) (xy 424.918854 -281.926211)
			(xy 424.876233 -281.901604) (xy 424.838112 -281.870479) (xy 424.805477 -281.833642) (xy 424.779174 -281.792046)
			(xy 424.759883 -281.74677) (xy 424.748106 -281.698986) (xy 424.744146 -281.649932) (xy 424.405298 -281.649932)
			(xy 424.404803 -281.674539) (xy 424.396908 -281.723116) (xy 424.381324 -281.769797) (xy 424.358453 -281.813374)
			(xy 424.328888 -281.852718) (xy 424.293395 -281.88681) (xy 424.252892 -281.914766) (xy 424.20843 -281.935864)
			(xy 424.161159 -281.949556) (xy 424.112304 -281.955488) (xy 424.063129 -281.953507) (xy 424.01491 -281.943663)
			(xy 423.968894 -281.926211) (xy 423.926273 -281.901604) (xy 423.888152 -281.870479) (xy 423.855517 -281.833642)
			(xy 423.829214 -281.792046) (xy 423.809923 -281.74677) (xy 423.798146 -281.698986) (xy 423.794186 -281.649932)
			(xy 423.455338 -281.649932) (xy 423.454843 -281.674539) (xy 423.446948 -281.723116) (xy 423.431364 -281.769797)
			(xy 423.408493 -281.813374) (xy 423.378928 -281.852718) (xy 423.343435 -281.88681) (xy 423.302932 -281.914766)
			(xy 423.25847 -281.935864) (xy 423.211199 -281.949556) (xy 423.162344 -281.955488) (xy 423.113169 -281.953507)
			(xy 423.06495 -281.943663) (xy 423.018934 -281.926211) (xy 422.976313 -281.901604) (xy 422.938192 -281.870479)
			(xy 422.905557 -281.833642) (xy 422.879254 -281.792046) (xy 422.859963 -281.74677) (xy 422.848186 -281.698986)
			(xy 422.844226 -281.649932) (xy 422.505124 -281.649932) (xy 422.504629 -281.674539) (xy 422.496734 -281.723116)
			(xy 422.48115 -281.769797) (xy 422.458279 -281.813374) (xy 422.428714 -281.852718) (xy 422.393221 -281.88681)
			(xy 422.352718 -281.914766) (xy 422.308256 -281.935864) (xy 422.260985 -281.949556) (xy 422.21213 -281.955488)
			(xy 422.162955 -281.953507) (xy 422.114736 -281.943663) (xy 422.06872 -281.926211) (xy 422.026099 -281.901604)
			(xy 421.987978 -281.870479) (xy 421.955343 -281.833642) (xy 421.92904 -281.792046) (xy 421.909749 -281.74677)
			(xy 421.897972 -281.698986) (xy 421.894012 -281.649932) (xy 421.555164 -281.649932) (xy 421.554669 -281.674539)
			(xy 421.546774 -281.723116) (xy 421.53119 -281.769797) (xy 421.508319 -281.813374) (xy 421.478754 -281.852718)
			(xy 421.443261 -281.88681) (xy 421.402758 -281.914766) (xy 421.358296 -281.935864) (xy 421.311025 -281.949556)
			(xy 421.26217 -281.955488) (xy 421.212995 -281.953507) (xy 421.164776 -281.943663) (xy 421.11876 -281.926211)
			(xy 421.076139 -281.901604) (xy 421.038018 -281.870479) (xy 421.005383 -281.833642) (xy 420.97908 -281.792046)
			(xy 420.959789 -281.74677) (xy 420.948012 -281.698986) (xy 420.944052 -281.649932) (xy 420.605204 -281.649932)
			(xy 420.604709 -281.674539) (xy 420.596814 -281.723116) (xy 420.58123 -281.769797) (xy 420.558359 -281.813374)
			(xy 420.528794 -281.852718) (xy 420.493301 -281.88681) (xy 420.452798 -281.914766) (xy 420.408336 -281.935864)
			(xy 420.361065 -281.949556) (xy 420.31221 -281.955488) (xy 420.263035 -281.953507) (xy 420.214816 -281.943663)
			(xy 420.1688 -281.926211) (xy 420.126179 -281.901604) (xy 420.088058 -281.870479) (xy 420.055423 -281.833642)
			(xy 420.02912 -281.792046) (xy 420.009829 -281.74677) (xy 419.998052 -281.698986) (xy 419.994092 -281.649932)
			(xy 419.655244 -281.649932) (xy 419.654749 -281.674539) (xy 419.646854 -281.723116) (xy 419.63127 -281.769797)
			(xy 419.608399 -281.813374) (xy 419.578834 -281.852718) (xy 419.543341 -281.88681) (xy 419.502838 -281.914766)
			(xy 419.458376 -281.935864) (xy 419.411105 -281.949556) (xy 419.36225 -281.955488) (xy 419.313075 -281.953507)
			(xy 419.264856 -281.943663) (xy 419.21884 -281.926211) (xy 419.176219 -281.901604) (xy 419.138098 -281.870479)
			(xy 419.105463 -281.833642) (xy 419.07916 -281.792046) (xy 419.059869 -281.74677) (xy 419.048092 -281.698986)
			(xy 419.044132 -281.649932) (xy 418.705284 -281.649932) (xy 418.704789 -281.674539) (xy 418.696894 -281.723116)
			(xy 418.68131 -281.769797) (xy 418.658439 -281.813374) (xy 418.628874 -281.852718) (xy 418.593381 -281.88681)
			(xy 418.552878 -281.914766) (xy 418.508416 -281.935864) (xy 418.461145 -281.949556) (xy 418.41229 -281.955488)
			(xy 418.363115 -281.953507) (xy 418.314896 -281.943663) (xy 418.26888 -281.926211) (xy 418.226259 -281.901604)
			(xy 418.188138 -281.870479) (xy 418.155503 -281.833642) (xy 418.1292 -281.792046) (xy 418.109909 -281.74677)
			(xy 418.098132 -281.698986) (xy 418.094172 -281.649932) (xy 417.755324 -281.649932) (xy 417.754829 -281.674539)
			(xy 417.746934 -281.723116) (xy 417.73135 -281.769797) (xy 417.708479 -281.813374) (xy 417.678914 -281.852718)
			(xy 417.643421 -281.88681) (xy 417.602918 -281.914766) (xy 417.558456 -281.935864) (xy 417.511185 -281.949556)
			(xy 417.46233 -281.955488) (xy 417.413155 -281.953507) (xy 417.364936 -281.943663) (xy 417.31892 -281.926211)
			(xy 417.276299 -281.901604) (xy 417.238178 -281.870479) (xy 417.205543 -281.833642) (xy 417.17924 -281.792046)
			(xy 417.159949 -281.74677) (xy 417.148172 -281.698986) (xy 417.144212 -281.649932) (xy 416.80511 -281.649932)
			(xy 416.804615 -281.674539) (xy 416.79672 -281.723116) (xy 416.781136 -281.769797) (xy 416.758265 -281.813374)
			(xy 416.7287 -281.852718) (xy 416.693207 -281.88681) (xy 416.652704 -281.914766) (xy 416.608242 -281.935864)
			(xy 416.560971 -281.949556) (xy 416.512116 -281.955488) (xy 416.462941 -281.953507) (xy 416.414722 -281.943663)
			(xy 416.368706 -281.926211) (xy 416.326085 -281.901604) (xy 416.287964 -281.870479) (xy 416.255329 -281.833642)
			(xy 416.229026 -281.792046) (xy 416.209735 -281.74677) (xy 416.197958 -281.698986) (xy 416.193998 -281.649932)
			(xy 415.85515 -281.649932) (xy 415.854655 -281.674539) (xy 415.84676 -281.723116) (xy 415.831176 -281.769797)
			(xy 415.808305 -281.813374) (xy 415.77874 -281.852718) (xy 415.743247 -281.88681) (xy 415.702744 -281.914766)
			(xy 415.658282 -281.935864) (xy 415.611011 -281.949556) (xy 415.562156 -281.955488) (xy 415.512981 -281.953507)
			(xy 415.464762 -281.943663) (xy 415.418746 -281.926211) (xy 415.376125 -281.901604) (xy 415.338004 -281.870479)
			(xy 415.305369 -281.833642) (xy 415.279066 -281.792046) (xy 415.259775 -281.74677) (xy 415.247998 -281.698986)
			(xy 415.244038 -281.649932) (xy 414.90519 -281.649932) (xy 414.904695 -281.674539) (xy 414.8968 -281.723116)
			(xy 414.881216 -281.769797) (xy 414.858345 -281.813374) (xy 414.82878 -281.852718) (xy 414.793287 -281.88681)
			(xy 414.752784 -281.914766) (xy 414.708322 -281.935864) (xy 414.661051 -281.949556) (xy 414.612196 -281.955488)
			(xy 414.563021 -281.953507) (xy 414.514802 -281.943663) (xy 414.468786 -281.926211) (xy 414.426165 -281.901604)
			(xy 414.388044 -281.870479) (xy 414.355409 -281.833642) (xy 414.329106 -281.792046) (xy 414.309815 -281.74677)
			(xy 414.298038 -281.698986) (xy 414.294078 -281.649932) (xy 413.95523 -281.649932) (xy 413.954735 -281.674539)
			(xy 413.94684 -281.723116) (xy 413.931256 -281.769797) (xy 413.908385 -281.813374) (xy 413.87882 -281.852718)
			(xy 413.843327 -281.88681) (xy 413.802824 -281.914766) (xy 413.758362 -281.935864) (xy 413.711091 -281.949556)
			(xy 413.662236 -281.955488) (xy 413.613061 -281.953507) (xy 413.564842 -281.943663) (xy 413.518826 -281.926211)
			(xy 413.476205 -281.901604) (xy 413.438084 -281.870479) (xy 413.405449 -281.833642) (xy 413.379146 -281.792046)
			(xy 413.359855 -281.74677) (xy 413.348078 -281.698986) (xy 413.344118 -281.649932) (xy 413.00527 -281.649932)
			(xy 413.004775 -281.674539) (xy 412.99688 -281.723116) (xy 412.981296 -281.769797) (xy 412.958425 -281.813374)
			(xy 412.92886 -281.852718) (xy 412.893367 -281.88681) (xy 412.852864 -281.914766) (xy 412.808402 -281.935864)
			(xy 412.761131 -281.949556) (xy 412.712276 -281.955488) (xy 412.663101 -281.953507) (xy 412.614882 -281.943663)
			(xy 412.568866 -281.926211) (xy 412.526245 -281.901604) (xy 412.488124 -281.870479) (xy 412.455489 -281.833642)
			(xy 412.429186 -281.792046) (xy 412.409895 -281.74677) (xy 412.398118 -281.698986) (xy 412.394158 -281.649932)
			(xy 412.05531 -281.649932) (xy 412.054815 -281.674539) (xy 412.04692 -281.723116) (xy 412.031336 -281.769797)
			(xy 412.008465 -281.813374) (xy 411.9789 -281.852718) (xy 411.943407 -281.88681) (xy 411.902904 -281.914766)
			(xy 411.858442 -281.935864) (xy 411.811171 -281.949556) (xy 411.762316 -281.955488) (xy 411.713141 -281.953507)
			(xy 411.664922 -281.943663) (xy 411.618906 -281.926211) (xy 411.576285 -281.901604) (xy 411.538164 -281.870479)
			(xy 411.505529 -281.833642) (xy 411.479226 -281.792046) (xy 411.459935 -281.74677) (xy 411.448158 -281.698986)
			(xy 411.444198 -281.649932) (xy 411.105096 -281.649932) (xy 411.104601 -281.674539) (xy 411.096706 -281.723116)
			(xy 411.081122 -281.769797) (xy 411.058251 -281.813374) (xy 411.028686 -281.852718) (xy 410.993193 -281.88681)
			(xy 410.95269 -281.914766) (xy 410.908228 -281.935864) (xy 410.860957 -281.949556) (xy 410.812102 -281.955488)
			(xy 410.762927 -281.953507) (xy 410.714708 -281.943663) (xy 410.668692 -281.926211) (xy 410.626071 -281.901604)
			(xy 410.58795 -281.870479) (xy 410.555315 -281.833642) (xy 410.529012 -281.792046) (xy 410.509721 -281.74677)
			(xy 410.497944 -281.698986) (xy 410.493984 -281.649932) (xy 410.155136 -281.649932) (xy 410.154641 -281.674539)
			(xy 410.146746 -281.723116) (xy 410.131162 -281.769797) (xy 410.108291 -281.813374) (xy 410.078726 -281.852718)
			(xy 410.043233 -281.88681) (xy 410.00273 -281.914766) (xy 409.958268 -281.935864) (xy 409.910997 -281.949556)
			(xy 409.862142 -281.955488) (xy 409.812967 -281.953507) (xy 409.764748 -281.943663) (xy 409.718732 -281.926211)
			(xy 409.676111 -281.901604) (xy 409.63799 -281.870479) (xy 409.605355 -281.833642) (xy 409.579052 -281.792046)
			(xy 409.559761 -281.74677) (xy 409.547984 -281.698986) (xy 409.544024 -281.649932) (xy 409.205176 -281.649932)
			(xy 409.204681 -281.674539) (xy 409.196786 -281.723116) (xy 409.181202 -281.769797) (xy 409.158331 -281.813374)
			(xy 409.128766 -281.852718) (xy 409.093273 -281.88681) (xy 409.05277 -281.914766) (xy 409.008308 -281.935864)
			(xy 408.961037 -281.949556) (xy 408.912182 -281.955488) (xy 408.863007 -281.953507) (xy 408.814788 -281.943663)
			(xy 408.768772 -281.926211) (xy 408.726151 -281.901604) (xy 408.68803 -281.870479) (xy 408.655395 -281.833642)
			(xy 408.629092 -281.792046) (xy 408.609801 -281.74677) (xy 408.598024 -281.698986) (xy 408.594064 -281.649932)
			(xy 408.255216 -281.649932) (xy 408.254721 -281.674539) (xy 408.246826 -281.723116) (xy 408.231242 -281.769797)
			(xy 408.208371 -281.813374) (xy 408.178806 -281.852718) (xy 408.143313 -281.88681) (xy 408.10281 -281.914766)
			(xy 408.058348 -281.935864) (xy 408.011077 -281.949556) (xy 407.962222 -281.955488) (xy 407.913047 -281.953507)
			(xy 407.864828 -281.943663) (xy 407.818812 -281.926211) (xy 407.776191 -281.901604) (xy 407.73807 -281.870479)
			(xy 407.705435 -281.833642) (xy 407.679132 -281.792046) (xy 407.659841 -281.74677) (xy 407.648064 -281.698986)
			(xy 407.644104 -281.649932) (xy 407.305256 -281.649932) (xy 407.304761 -281.674539) (xy 407.296866 -281.723116)
			(xy 407.281282 -281.769797) (xy 407.258411 -281.813374) (xy 407.228846 -281.852718) (xy 407.193353 -281.88681)
			(xy 407.15285 -281.914766) (xy 407.108388 -281.935864) (xy 407.061117 -281.949556) (xy 407.012262 -281.955488)
			(xy 406.963087 -281.953507) (xy 406.914868 -281.943663) (xy 406.868852 -281.926211) (xy 406.826231 -281.901604)
			(xy 406.78811 -281.870479) (xy 406.755475 -281.833642) (xy 406.729172 -281.792046) (xy 406.709881 -281.74677)
			(xy 406.698104 -281.698986) (xy 406.694144 -281.649932) (xy 406.355296 -281.649932) (xy 406.354801 -281.674539)
			(xy 406.346906 -281.723116) (xy 406.331322 -281.769797) (xy 406.308451 -281.813374) (xy 406.278886 -281.852718)
			(xy 406.243393 -281.88681) (xy 406.20289 -281.914766) (xy 406.158428 -281.935864) (xy 406.111157 -281.949556)
			(xy 406.062302 -281.955488) (xy 406.013127 -281.953507) (xy 405.964908 -281.943663) (xy 405.918892 -281.926211)
			(xy 405.876271 -281.901604) (xy 405.83815 -281.870479) (xy 405.805515 -281.833642) (xy 405.779212 -281.792046)
			(xy 405.759921 -281.74677) (xy 405.748144 -281.698986) (xy 405.744184 -281.649932) (xy 405.405336 -281.649932)
			(xy 405.404841 -281.674539) (xy 405.396946 -281.723116) (xy 405.381362 -281.769797) (xy 405.358491 -281.813374)
			(xy 405.328926 -281.852718) (xy 405.293433 -281.88681) (xy 405.25293 -281.914766) (xy 405.208468 -281.935864)
			(xy 405.161197 -281.949556) (xy 405.112342 -281.955488) (xy 405.063167 -281.953507) (xy 405.014948 -281.943663)
			(xy 404.968932 -281.926211) (xy 404.926311 -281.901604) (xy 404.88819 -281.870479) (xy 404.855555 -281.833642)
			(xy 404.829252 -281.792046) (xy 404.809961 -281.74677) (xy 404.798184 -281.698986) (xy 404.794224 -281.649932)
			(xy 404.455122 -281.649932) (xy 404.454627 -281.674539) (xy 404.446732 -281.723116) (xy 404.431148 -281.769797)
			(xy 404.408277 -281.813374) (xy 404.378712 -281.852718) (xy 404.343219 -281.88681) (xy 404.302716 -281.914766)
			(xy 404.258254 -281.935864) (xy 404.210983 -281.949556) (xy 404.162128 -281.955488) (xy 404.112953 -281.953507)
			(xy 404.064734 -281.943663) (xy 404.018718 -281.926211) (xy 403.976097 -281.901604) (xy 403.937976 -281.870479)
			(xy 403.905341 -281.833642) (xy 403.879038 -281.792046) (xy 403.859747 -281.74677) (xy 403.84797 -281.698986)
			(xy 403.84401 -281.649932) (xy 403.505162 -281.649932) (xy 403.504667 -281.674539) (xy 403.496772 -281.723116)
			(xy 403.481188 -281.769797) (xy 403.458317 -281.813374) (xy 403.428752 -281.852718) (xy 403.393259 -281.88681)
			(xy 403.352756 -281.914766) (xy 403.308294 -281.935864) (xy 403.261023 -281.949556) (xy 403.212168 -281.955488)
			(xy 403.162993 -281.953507) (xy 403.114774 -281.943663) (xy 403.068758 -281.926211) (xy 403.026137 -281.901604)
			(xy 402.988016 -281.870479) (xy 402.955381 -281.833642) (xy 402.929078 -281.792046) (xy 402.909787 -281.74677)
			(xy 402.89801 -281.698986) (xy 402.89405 -281.649932) (xy 402.555202 -281.649932) (xy 402.554707 -281.674539)
			(xy 402.546812 -281.723116) (xy 402.531228 -281.769797) (xy 402.508357 -281.813374) (xy 402.478792 -281.852718)
			(xy 402.443299 -281.88681) (xy 402.402796 -281.914766) (xy 402.358334 -281.935864) (xy 402.311063 -281.949556)
			(xy 402.262208 -281.955488) (xy 402.213033 -281.953507) (xy 402.164814 -281.943663) (xy 402.118798 -281.926211)
			(xy 402.076177 -281.901604) (xy 402.038056 -281.870479) (xy 402.005421 -281.833642) (xy 401.979118 -281.792046)
			(xy 401.959827 -281.74677) (xy 401.94805 -281.698986) (xy 401.94409 -281.649932) (xy 401.605242 -281.649932)
			(xy 401.604747 -281.674539) (xy 401.596852 -281.723116) (xy 401.581268 -281.769797) (xy 401.558397 -281.813374)
			(xy 401.528832 -281.852718) (xy 401.493339 -281.88681) (xy 401.452836 -281.914766) (xy 401.408374 -281.935864)
			(xy 401.361103 -281.949556) (xy 401.312248 -281.955488) (xy 401.263073 -281.953507) (xy 401.214854 -281.943663)
			(xy 401.168838 -281.926211) (xy 401.126217 -281.901604) (xy 401.088096 -281.870479) (xy 401.055461 -281.833642)
			(xy 401.029158 -281.792046) (xy 401.009867 -281.74677) (xy 400.99809 -281.698986) (xy 400.99413 -281.649932)
			(xy 400.655282 -281.649932) (xy 400.654787 -281.674539) (xy 400.646892 -281.723116) (xy 400.631308 -281.769797)
			(xy 400.608437 -281.813374) (xy 400.578872 -281.852718) (xy 400.543379 -281.88681) (xy 400.502876 -281.914766)
			(xy 400.458414 -281.935864) (xy 400.411143 -281.949556) (xy 400.362288 -281.955488) (xy 400.313113 -281.953507)
			(xy 400.264894 -281.943663) (xy 400.218878 -281.926211) (xy 400.176257 -281.901604) (xy 400.138136 -281.870479)
			(xy 400.105501 -281.833642) (xy 400.079198 -281.792046) (xy 400.059907 -281.74677) (xy 400.04813 -281.698986)
			(xy 400.04417 -281.649932) (xy 399.705322 -281.649932) (xy 399.704827 -281.674539) (xy 399.696932 -281.723116)
			(xy 399.681348 -281.769797) (xy 399.658477 -281.813374) (xy 399.628912 -281.852718) (xy 399.593419 -281.88681)
			(xy 399.552916 -281.914766) (xy 399.508454 -281.935864) (xy 399.461183 -281.949556) (xy 399.412328 -281.955488)
			(xy 399.363153 -281.953507) (xy 399.314934 -281.943663) (xy 399.268918 -281.926211) (xy 399.226297 -281.901604)
			(xy 399.188176 -281.870479) (xy 399.155541 -281.833642) (xy 399.129238 -281.792046) (xy 399.109947 -281.74677)
			(xy 399.09817 -281.698986) (xy 399.09421 -281.649932) (xy 398.755108 -281.649932) (xy 398.754613 -281.674539)
			(xy 398.746718 -281.723116) (xy 398.731134 -281.769797) (xy 398.708263 -281.813374) (xy 398.678698 -281.852718)
			(xy 398.643205 -281.88681) (xy 398.602702 -281.914766) (xy 398.55824 -281.935864) (xy 398.510969 -281.949556)
			(xy 398.462114 -281.955488) (xy 398.412939 -281.953507) (xy 398.36472 -281.943663) (xy 398.318704 -281.926211)
			(xy 398.276083 -281.901604) (xy 398.237962 -281.870479) (xy 398.205327 -281.833642) (xy 398.179024 -281.792046)
			(xy 398.159733 -281.74677) (xy 398.147956 -281.698986) (xy 398.143996 -281.649932) (xy 397.805148 -281.649932)
			(xy 397.804653 -281.674539) (xy 397.796758 -281.723116) (xy 397.781174 -281.769797) (xy 397.758303 -281.813374)
			(xy 397.728738 -281.852718) (xy 397.693245 -281.88681) (xy 397.652742 -281.914766) (xy 397.60828 -281.935864)
			(xy 397.561009 -281.949556) (xy 397.512154 -281.955488) (xy 397.462979 -281.953507) (xy 397.41476 -281.943663)
			(xy 397.368744 -281.926211) (xy 397.326123 -281.901604) (xy 397.288002 -281.870479) (xy 397.255367 -281.833642)
			(xy 397.229064 -281.792046) (xy 397.209773 -281.74677) (xy 397.197996 -281.698986) (xy 397.194036 -281.649932)
			(xy 396.854764 -281.649932) (xy 396.854764 -281.673958) (xy 396.847219 -281.721468) (xy 396.832318 -281.767207)
			(xy 396.810428 -281.810043) (xy 396.782092 -281.848917) (xy 396.74801 -281.882866) (xy 396.709026 -281.911051)
			(xy 396.666104 -281.932773) (xy 396.620307 -281.947496) (xy 396.596616 -281.951684) (xy 396.578074 -281.954478)
			(xy 396.55369 -281.982926) (xy 396.55369 -282.203652) (xy 450.561456 -282.203652) (xy 450.561883 -282.178253)
			(xy 450.568618 -282.127905) (xy 450.581977 -282.078896) (xy 450.601722 -282.032094) (xy 450.627505 -281.988326)
			(xy 450.658869 -281.948369) (xy 450.676772 -281.930348) (xy 450.683884 -281.92349) (xy 450.691758 -281.90571)
			(xy 450.69506 -281.815794) (xy 450.688456 -281.79776) (xy 450.681852 -281.79014) (xy 450.663878 -281.769091)
			(xy 450.633518 -281.722813) (xy 450.610173 -281.672629) (xy 450.594333 -281.619596) (xy 450.586332 -281.56483)
			(xy 450.58584 -281.537156) (xy 450.58584 -281.536902) (xy 450.586257 -281.509647) (xy 450.594015 -281.455692)
			(xy 450.609373 -281.40339) (xy 450.632019 -281.353807) (xy 450.661492 -281.307952) (xy 450.69719 -281.266758)
			(xy 450.738388 -281.231064) (xy 450.784247 -281.201597) (xy 450.833833 -281.178957) (xy 450.886137 -281.163605)
			(xy 450.940093 -281.155854) (xy 450.967348 -281.155394) (xy 450.996088 -281.15589) (xy 451.052916 -281.16452)
			(xy 451.107807 -281.181576) (xy 451.159519 -281.206674) (xy 451.20688 -281.239245) (xy 451.228206 -281.258518)
			(xy 451.22846 -281.258772) (xy 451.235767 -281.264876) (xy 451.253493 -281.27178) (xy 451.263004 -281.272234)
			(xy 451.332092 -281.272234) (xy 451.341618 -281.27184) (xy 451.359373 -281.264945) (xy 451.366636 -281.258772)
			(xy 451.36689 -281.258518) (xy 451.388217 -281.239248) (xy 451.43558 -281.206683) (xy 451.487291 -281.181592)
			(xy 451.542182 -281.164542) (xy 451.599009 -281.15592) (xy 451.656487 -281.15592) (xy 451.713314 -281.164542)
			(xy 451.768205 -281.181592) (xy 451.819916 -281.206683) (xy 451.867279 -281.239248) (xy 451.888606 -281.258518)
			(xy 451.88886 -281.258772) (xy 451.896167 -281.264876) (xy 451.913893 -281.27178) (xy 451.923404 -281.272234)
			(xy 451.992492 -281.272234) (xy 452.002018 -281.27184) (xy 452.019773 -281.264945) (xy 452.027036 -281.258772)
			(xy 452.02729 -281.258518) (xy 452.048617 -281.239248) (xy 452.09598 -281.206683) (xy 452.147691 -281.181592)
			(xy 452.202582 -281.164542) (xy 452.259409 -281.15592) (xy 452.316887 -281.15592) (xy 452.373714 -281.164542)
			(xy 452.428605 -281.181592) (xy 452.480316 -281.206683) (xy 452.527679 -281.239248) (xy 452.549006 -281.258518)
			(xy 452.54926 -281.258772) (xy 452.556567 -281.264876) (xy 452.574293 -281.27178) (xy 452.583804 -281.272234)
			(xy 452.652892 -281.272234) (xy 452.662418 -281.27184) (xy 452.680173 -281.264945) (xy 452.687436 -281.258772)
			(xy 452.68769 -281.258518) (xy 452.708994 -281.239221) (xy 452.756363 -281.206659) (xy 452.80808 -281.181572)
			(xy 452.862976 -281.164528) (xy 452.919807 -281.155911) (xy 452.948548 -281.155394) (xy 452.975801 -281.155833)
			(xy 453.02975 -281.163596) (xy 453.082046 -281.178958) (xy 453.131623 -281.201604) (xy 453.177474 -281.231076)
			(xy 453.218663 -281.266772) (xy 453.254354 -281.307967) (xy 453.28382 -281.353821) (xy 453.30646 -281.403401)
			(xy 453.321814 -281.455699) (xy 453.32957 -281.509649) (xy 453.330056 -281.536902) (xy 453.329661 -281.562302)
			(xy 453.322919 -281.612651) (xy 453.309553 -281.661661) (xy 453.289802 -281.708463) (xy 453.281187 -281.723084)
			(xy 464.670392 -281.723084) (xy 464.674463 -281.667462) (xy 464.686589 -281.613025) (xy 464.706512 -281.560934)
			(xy 464.733808 -281.512299) (xy 464.767894 -281.468156) (xy 464.808043 -281.429447) (xy 464.853401 -281.396996)
			(xy 464.903001 -281.371495) (xy 464.955785 -281.353488) (xy 465.010628 -281.343358) (xy 465.066362 -281.341321)
			(xy 465.121799 -281.347421) (xy 465.175756 -281.361527) (xy 465.227085 -281.383339) (xy 465.274691 -281.412393)
			(xy 465.317559 -281.448068) (xy 465.354776 -281.489605) (xy 465.385549 -281.536118) (xy 465.409221 -281.586615)
			(xy 465.425289 -281.640022) (xy 465.433409 -281.695198) (xy 465.433918 -281.723084) (xy 465.433409 -281.75097)
			(xy 465.425289 -281.806146) (xy 465.409221 -281.859553) (xy 465.385549 -281.91005) (xy 465.354776 -281.956563)
			(xy 465.317559 -281.9981) (xy 465.274691 -282.033775) (xy 465.227085 -282.062829) (xy 465.175756 -282.084641)
			(xy 465.121799 -282.098747) (xy 465.066362 -282.104847) (xy 465.010628 -282.10281) (xy 464.955785 -282.09268)
			(xy 464.903001 -282.074673) (xy 464.853401 -282.049172) (xy 464.808043 -282.016721) (xy 464.767894 -281.978012)
			(xy 464.733808 -281.933869) (xy 464.706512 -281.885234) (xy 464.686589 -281.833143) (xy 464.674463 -281.778706)
			(xy 464.670392 -281.723084) (xy 453.281187 -281.723084) (xy 453.264014 -281.752229) (xy 453.232645 -281.792186)
			(xy 453.21474 -281.810206) (xy 453.207628 -281.817064) (xy 453.199754 -281.834844) (xy 453.196452 -281.92476)
			(xy 453.203056 -281.942794) (xy 453.20966 -281.950414) (xy 453.227661 -281.971441) (xy 453.258016 -282.017725)
			(xy 453.281356 -282.067914) (xy 453.29719 -282.120952) (xy 453.305184 -282.175723) (xy 453.305672 -282.203398)
			(xy 453.305672 -282.203652) (xy 453.3052 -282.230905) (xy 453.297449 -282.284858) (xy 453.282097 -282.337158)
			(xy 453.259457 -282.38674) (xy 453.229991 -282.432595) (xy 453.194298 -282.473789) (xy 453.153105 -282.509484)
			(xy 453.107251 -282.538951) (xy 453.057669 -282.561593) (xy 453.00537 -282.576946) (xy 452.951417 -282.584699)
			(xy 452.924164 -282.58516) (xy 452.895425 -282.584642) (xy 452.838598 -282.576016) (xy 452.783708 -282.558963)
			(xy 452.731996 -282.533871) (xy 452.684633 -282.501306) (xy 452.663306 -282.482036) (xy 452.663052 -282.481782)
			(xy 452.655767 -282.47564) (xy 452.638028 -282.46872) (xy 452.628508 -282.46832) (xy 452.55942 -282.46832)
			(xy 452.549888 -282.468656) (xy 452.532132 -282.47559) (xy 452.524876 -282.481782) (xy 452.524622 -282.482036)
			(xy 452.503295 -282.501306) (xy 452.455932 -282.533871) (xy 452.404221 -282.558962) (xy 452.34933 -282.576012)
			(xy 452.292503 -282.584634) (xy 452.235025 -282.584634) (xy 452.178198 -282.576012) (xy 452.123307 -282.558962)
			(xy 452.071596 -282.533871) (xy 452.024233 -282.501306) (xy 452.002906 -282.482036) (xy 452.002652 -282.481782)
			(xy 451.995367 -282.47564) (xy 451.977628 -282.46872) (xy 451.968108 -282.46832) (xy 451.89902 -282.46832)
			(xy 451.889488 -282.468656) (xy 451.871732 -282.47559) (xy 451.864476 -282.481782) (xy 451.864222 -282.482036)
			(xy 451.842895 -282.501306) (xy 451.795532 -282.533871) (xy 451.743821 -282.558962) (xy 451.68893 -282.576012)
			(xy 451.632103 -282.584634) (xy 451.574625 -282.584634) (xy 451.517798 -282.576012) (xy 451.462907 -282.558962)
			(xy 451.411196 -282.533871) (xy 451.363833 -282.501306) (xy 451.342506 -282.482036) (xy 451.342252 -282.481782)
			(xy 451.334967 -282.47564) (xy 451.317228 -282.46872) (xy 451.307708 -282.46832) (xy 451.23862 -282.46832)
			(xy 451.229088 -282.468656) (xy 451.211332 -282.47559) (xy 451.204076 -282.481782) (xy 451.203822 -282.482036)
			(xy 451.182506 -282.501319) (xy 451.135141 -282.533885) (xy 451.083427 -282.558975) (xy 451.028534 -282.576023)
			(xy 450.971704 -282.584642) (xy 450.942964 -282.58516) (xy 450.915708 -282.584778) (xy 450.861752 -282.577015)
			(xy 450.809449 -282.561652) (xy 450.759866 -282.539002) (xy 450.71401 -282.509526) (xy 450.672817 -282.473824)
			(xy 450.637124 -282.432622) (xy 450.607658 -282.38676) (xy 450.585018 -282.337172) (xy 450.569667 -282.284866)
			(xy 450.561916 -282.230908) (xy 450.561456 -282.203652) (xy 396.55369 -282.203652) (xy 396.55369 -283.074872)
			(xy 396.719056 -283.074872) (xy 396.723016 -283.025818) (xy 396.734793 -282.978034) (xy 396.754084 -282.932758)
			(xy 396.780387 -282.891162) (xy 396.813022 -282.854325) (xy 396.851143 -282.8232) (xy 396.893764 -282.798593)
			(xy 396.93978 -282.781141) (xy 396.987999 -282.771297) (xy 397.037174 -282.769316) (xy 397.086029 -282.775248)
			(xy 397.1333 -282.78894) (xy 397.177762 -282.810038) (xy 397.218265 -282.837994) (xy 397.253758 -282.872086)
			(xy 397.283323 -282.91143) (xy 397.306194 -282.955007) (xy 397.321778 -283.001688) (xy 397.329673 -283.050265)
			(xy 397.330168 -283.074872) (xy 397.669016 -283.074872) (xy 397.672976 -283.025818) (xy 397.684753 -282.978034)
			(xy 397.704044 -282.932758) (xy 397.730347 -282.891162) (xy 397.762982 -282.854325) (xy 397.801103 -282.8232)
			(xy 397.843724 -282.798593) (xy 397.88974 -282.781141) (xy 397.937959 -282.771297) (xy 397.987134 -282.769316)
			(xy 398.035989 -282.775248) (xy 398.08326 -282.78894) (xy 398.127722 -282.810038) (xy 398.168225 -282.837994)
			(xy 398.203718 -282.872086) (xy 398.233283 -282.91143) (xy 398.256154 -282.955007) (xy 398.271738 -283.001688)
			(xy 398.279633 -283.050265) (xy 398.280128 -283.074872) (xy 398.61923 -283.074872) (xy 398.62319 -283.025818)
			(xy 398.634967 -282.978034) (xy 398.654258 -282.932758) (xy 398.680561 -282.891162) (xy 398.713196 -282.854325)
			(xy 398.751317 -282.8232) (xy 398.793938 -282.798593) (xy 398.839954 -282.781141) (xy 398.888173 -282.771297)
			(xy 398.937348 -282.769316) (xy 398.986203 -282.775248) (xy 399.033474 -282.78894) (xy 399.077936 -282.810038)
			(xy 399.118439 -282.837994) (xy 399.153932 -282.872086) (xy 399.183497 -282.91143) (xy 399.206368 -282.955007)
			(xy 399.221952 -283.001688) (xy 399.229847 -283.050265) (xy 399.230342 -283.074872) (xy 399.56919 -283.074872)
			(xy 399.57315 -283.025818) (xy 399.584927 -282.978034) (xy 399.604218 -282.932758) (xy 399.630521 -282.891162)
			(xy 399.663156 -282.854325) (xy 399.701277 -282.8232) (xy 399.743898 -282.798593) (xy 399.789914 -282.781141)
			(xy 399.838133 -282.771297) (xy 399.887308 -282.769316) (xy 399.936163 -282.775248) (xy 399.983434 -282.78894)
			(xy 400.027896 -282.810038) (xy 400.068399 -282.837994) (xy 400.103892 -282.872086) (xy 400.133457 -282.91143)
			(xy 400.156328 -282.955007) (xy 400.171912 -283.001688) (xy 400.179807 -283.050265) (xy 400.180302 -283.074872)
			(xy 400.51915 -283.074872) (xy 400.52311 -283.025818) (xy 400.534887 -282.978034) (xy 400.554178 -282.932758)
			(xy 400.580481 -282.891162) (xy 400.613116 -282.854325) (xy 400.651237 -282.8232) (xy 400.693858 -282.798593)
			(xy 400.739874 -282.781141) (xy 400.788093 -282.771297) (xy 400.837268 -282.769316) (xy 400.886123 -282.775248)
			(xy 400.933394 -282.78894) (xy 400.977856 -282.810038) (xy 401.018359 -282.837994) (xy 401.053852 -282.872086)
			(xy 401.083417 -282.91143) (xy 401.106288 -282.955007) (xy 401.121872 -283.001688) (xy 401.129767 -283.050265)
			(xy 401.130262 -283.074872) (xy 401.46911 -283.074872) (xy 401.47307 -283.025818) (xy 401.484847 -282.978034)
			(xy 401.504138 -282.932758) (xy 401.530441 -282.891162) (xy 401.563076 -282.854325) (xy 401.601197 -282.8232)
			(xy 401.643818 -282.798593) (xy 401.689834 -282.781141) (xy 401.738053 -282.771297) (xy 401.787228 -282.769316)
			(xy 401.836083 -282.775248) (xy 401.883354 -282.78894) (xy 401.927816 -282.810038) (xy 401.968319 -282.837994)
			(xy 402.003812 -282.872086) (xy 402.033377 -282.91143) (xy 402.056248 -282.955007) (xy 402.071832 -283.001688)
			(xy 402.079727 -283.050265) (xy 402.080056 -283.066644) (xy 402.419152 -283.066644) (xy 402.424516 -283.017288)
			(xy 402.437793 -282.969451) (xy 402.458636 -282.924391) (xy 402.486493 -282.883297) (xy 402.520631 -282.847251)
			(xy 402.560152 -282.817203) (xy 402.604013 -282.793944) (xy 402.651059 -282.778088) (xy 402.700051 -282.770052)
			(xy 402.724874 -282.769564) (xy 402.738993 -282.769747) (xy 402.767106 -282.772421) (xy 402.781008 -282.774898)
			(xy 402.793454 -282.777184) (xy 402.81733 -282.769818) (xy 402.8948 -282.692348) (xy 402.902166 -282.668472)
			(xy 402.89988 -282.656026) (xy 402.89741 -282.642123) (xy 402.894743 -282.614011) (xy 402.894546 -282.599892)
			(xy 402.895068 -282.574637) (xy 402.903381 -282.524815) (xy 402.919782 -282.477041) (xy 402.943823 -282.432618)
			(xy 402.974847 -282.392758) (xy 403.012009 -282.358548) (xy 403.054295 -282.330922) (xy 403.100551 -282.310632)
			(xy 403.149516 -282.298232) (xy 403.199854 -282.294061) (xy 403.250192 -282.298232) (xy 403.299157 -282.310632)
			(xy 403.345413 -282.330922) (xy 403.387699 -282.358548) (xy 403.424861 -282.392758) (xy 403.455885 -282.432618)
			(xy 403.479926 -282.477041) (xy 403.496327 -282.524815) (xy 403.50464 -282.574637) (xy 403.505162 -282.599892)
			(xy 422.843972 -282.599892) (xy 422.847932 -282.550838) (xy 422.859709 -282.503054) (xy 422.879 -282.457778)
			(xy 422.905303 -282.416182) (xy 422.937938 -282.379345) (xy 422.976059 -282.34822) (xy 423.01868 -282.323613)
			(xy 423.064696 -282.306161) (xy 423.112915 -282.296317) (xy 423.16209 -282.294336) (xy 423.210945 -282.300268)
			(xy 423.258216 -282.31396) (xy 423.302678 -282.335058) (xy 423.343181 -282.363014) (xy 423.378674 -282.397106)
			(xy 423.408239 -282.43645) (xy 423.43111 -282.480027) (xy 423.446694 -282.526708) (xy 423.454589 -282.575285)
			(xy 423.455084 -282.599892) (xy 423.794186 -282.599892) (xy 423.798146 -282.550838) (xy 423.809923 -282.503054)
			(xy 423.829214 -282.457778) (xy 423.855517 -282.416182) (xy 423.888152 -282.379345) (xy 423.926273 -282.34822)
			(xy 423.968894 -282.323613) (xy 424.01491 -282.306161) (xy 424.063129 -282.296317) (xy 424.112304 -282.294336)
			(xy 424.161159 -282.300268) (xy 424.20843 -282.31396) (xy 424.252892 -282.335058) (xy 424.293395 -282.363014)
			(xy 424.328888 -282.397106) (xy 424.358453 -282.43645) (xy 424.381324 -282.480027) (xy 424.396908 -282.526708)
			(xy 424.404803 -282.575285) (xy 424.405298 -282.599892) (xy 424.744146 -282.599892) (xy 424.748106 -282.550838)
			(xy 424.759883 -282.503054) (xy 424.779174 -282.457778) (xy 424.805477 -282.416182) (xy 424.838112 -282.379345)
			(xy 424.876233 -282.34822) (xy 424.918854 -282.323613) (xy 424.96487 -282.306161) (xy 425.013089 -282.296317)
			(xy 425.062264 -282.294336) (xy 425.111119 -282.300268) (xy 425.15839 -282.31396) (xy 425.202852 -282.335058)
			(xy 425.243355 -282.363014) (xy 425.278848 -282.397106) (xy 425.308413 -282.43645) (xy 425.331284 -282.480027)
			(xy 425.346868 -282.526708) (xy 425.354763 -282.575285) (xy 425.355258 -282.599892) (xy 425.694106 -282.599892)
			(xy 425.698066 -282.550838) (xy 425.709843 -282.503054) (xy 425.729134 -282.457778) (xy 425.755437 -282.416182)
			(xy 425.788072 -282.379345) (xy 425.826193 -282.34822) (xy 425.868814 -282.323613) (xy 425.91483 -282.306161)
			(xy 425.963049 -282.296317) (xy 426.012224 -282.294336) (xy 426.061079 -282.300268) (xy 426.10835 -282.31396)
			(xy 426.152812 -282.335058) (xy 426.193315 -282.363014) (xy 426.228808 -282.397106) (xy 426.258373 -282.43645)
			(xy 426.281244 -282.480027) (xy 426.296828 -282.526708) (xy 426.304723 -282.575285) (xy 426.305218 -282.599892)
			(xy 426.644066 -282.599892) (xy 426.648026 -282.550838) (xy 426.659803 -282.503054) (xy 426.679094 -282.457778)
			(xy 426.705397 -282.416182) (xy 426.738032 -282.379345) (xy 426.776153 -282.34822) (xy 426.818774 -282.323613)
			(xy 426.86479 -282.306161) (xy 426.913009 -282.296317) (xy 426.962184 -282.294336) (xy 427.011039 -282.300268)
			(xy 427.05831 -282.31396) (xy 427.102772 -282.335058) (xy 427.143275 -282.363014) (xy 427.178768 -282.397106)
			(xy 427.208333 -282.43645) (xy 427.231204 -282.480027) (xy 427.246788 -282.526708) (xy 427.254683 -282.575285)
			(xy 427.255178 -282.599892) (xy 427.254683 -282.624499) (xy 427.254504 -282.6256) (xy 427.573182 -282.6256)
			(xy 427.573182 -282.574184) (xy 427.581225 -282.523402) (xy 427.597113 -282.474503) (xy 427.620456 -282.428691)
			(xy 427.650677 -282.387095) (xy 427.687033 -282.350739) (xy 427.728629 -282.320518) (xy 427.774441 -282.297175)
			(xy 427.82334 -282.281287) (xy 427.874122 -282.273244) (xy 427.925538 -282.273244) (xy 427.97632 -282.281287)
			(xy 428.025219 -282.297175) (xy 428.071031 -282.320518) (xy 428.112627 -282.350739) (xy 428.148983 -282.387095)
			(xy 428.179204 -282.428691) (xy 428.202547 -282.474503) (xy 428.218435 -282.523402) (xy 428.226478 -282.574184)
			(xy 428.226982 -282.599892) (xy 428.226478 -282.6256) (xy 428.523142 -282.6256) (xy 428.523142 -282.574184)
			(xy 428.531185 -282.523402) (xy 428.547073 -282.474503) (xy 428.570416 -282.428691) (xy 428.600637 -282.387095)
			(xy 428.636993 -282.350739) (xy 428.678589 -282.320518) (xy 428.724401 -282.297175) (xy 428.7733 -282.281287)
			(xy 428.824082 -282.273244) (xy 428.875498 -282.273244) (xy 428.92628 -282.281287) (xy 428.975179 -282.297175)
			(xy 429.020991 -282.320518) (xy 429.062587 -282.350739) (xy 429.098943 -282.387095) (xy 429.129164 -282.428691)
			(xy 429.152507 -282.474503) (xy 429.168395 -282.523402) (xy 429.176438 -282.574184) (xy 429.176942 -282.599892)
			(xy 429.4942 -282.599892) (xy 429.49816 -282.550838) (xy 429.509937 -282.503054) (xy 429.529228 -282.457778)
			(xy 429.555531 -282.416182) (xy 429.588166 -282.379345) (xy 429.626287 -282.34822) (xy 429.668908 -282.323613)
			(xy 429.714924 -282.306161) (xy 429.763143 -282.296317) (xy 429.812318 -282.294336) (xy 429.861173 -282.300268)
			(xy 429.908444 -282.31396) (xy 429.952906 -282.335058) (xy 429.993409 -282.363014) (xy 430.028902 -282.397106)
			(xy 430.058467 -282.43645) (xy 430.081338 -282.480027) (xy 430.096922 -282.526708) (xy 430.104817 -282.575285)
			(xy 430.105312 -282.599892) (xy 430.44416 -282.599892) (xy 430.44812 -282.550838) (xy 430.459897 -282.503054)
			(xy 430.479188 -282.457778) (xy 430.505491 -282.416182) (xy 430.538126 -282.379345) (xy 430.576247 -282.34822)
			(xy 430.618868 -282.323613) (xy 430.664884 -282.306161) (xy 430.713103 -282.296317) (xy 430.762278 -282.294336)
			(xy 430.811133 -282.300268) (xy 430.858404 -282.31396) (xy 430.902866 -282.335058) (xy 430.943369 -282.363014)
			(xy 430.978862 -282.397106) (xy 431.008427 -282.43645) (xy 431.031298 -282.480027) (xy 431.046882 -282.526708)
			(xy 431.054777 -282.575285) (xy 431.055272 -282.599892) (xy 431.054777 -282.624499) (xy 431.046882 -282.673076)
			(xy 431.031298 -282.719757) (xy 431.008427 -282.763334) (xy 430.978862 -282.802678) (xy 430.943369 -282.83677)
			(xy 430.902866 -282.864726) (xy 430.858404 -282.885824) (xy 430.811133 -282.899516) (xy 430.762278 -282.905448)
			(xy 430.713103 -282.903467) (xy 430.664884 -282.893623) (xy 430.618868 -282.876171) (xy 430.576247 -282.851564)
			(xy 430.538126 -282.820439) (xy 430.505491 -282.783602) (xy 430.479188 -282.742006) (xy 430.459897 -282.69673)
			(xy 430.44812 -282.648946) (xy 430.44416 -282.599892) (xy 430.105312 -282.599892) (xy 430.104817 -282.624499)
			(xy 430.096922 -282.673076) (xy 430.081338 -282.719757) (xy 430.058467 -282.763334) (xy 430.028902 -282.802678)
			(xy 429.993409 -282.83677) (xy 429.952906 -282.864726) (xy 429.908444 -282.885824) (xy 429.861173 -282.899516)
			(xy 429.812318 -282.905448) (xy 429.763143 -282.903467) (xy 429.714924 -282.893623) (xy 429.668908 -282.876171)
			(xy 429.626287 -282.851564) (xy 429.588166 -282.820439) (xy 429.555531 -282.783602) (xy 429.529228 -282.742006)
			(xy 429.509937 -282.69673) (xy 429.49816 -282.648946) (xy 429.4942 -282.599892) (xy 429.176942 -282.599892)
			(xy 429.176438 -282.6256) (xy 429.168395 -282.676382) (xy 429.152507 -282.725281) (xy 429.129164 -282.771093)
			(xy 429.098943 -282.812689) (xy 429.062587 -282.849045) (xy 429.020991 -282.879266) (xy 428.975179 -282.902609)
			(xy 428.92628 -282.918497) (xy 428.875498 -282.92654) (xy 428.824082 -282.92654) (xy 428.7733 -282.918497)
			(xy 428.724401 -282.902609) (xy 428.678589 -282.879266) (xy 428.636993 -282.849045) (xy 428.600637 -282.812689)
			(xy 428.570416 -282.771093) (xy 428.547073 -282.725281) (xy 428.531185 -282.676382) (xy 428.523142 -282.6256)
			(xy 428.226478 -282.6256) (xy 428.218435 -282.676382) (xy 428.202547 -282.725281) (xy 428.179204 -282.771093)
			(xy 428.148983 -282.812689) (xy 428.112627 -282.849045) (xy 428.071031 -282.879266) (xy 428.025219 -282.902609)
			(xy 427.97632 -282.918497) (xy 427.925538 -282.92654) (xy 427.874122 -282.92654) (xy 427.82334 -282.918497)
			(xy 427.774441 -282.902609) (xy 427.728629 -282.879266) (xy 427.687033 -282.849045) (xy 427.650677 -282.812689)
			(xy 427.620456 -282.771093) (xy 427.597113 -282.725281) (xy 427.581225 -282.676382) (xy 427.573182 -282.6256)
			(xy 427.254504 -282.6256) (xy 427.246788 -282.673076) (xy 427.231204 -282.719757) (xy 427.208333 -282.763334)
			(xy 427.178768 -282.802678) (xy 427.143275 -282.83677) (xy 427.102772 -282.864726) (xy 427.05831 -282.885824)
			(xy 427.011039 -282.899516) (xy 426.962184 -282.905448) (xy 426.913009 -282.903467) (xy 426.86479 -282.893623)
			(xy 426.818774 -282.876171) (xy 426.776153 -282.851564) (xy 426.738032 -282.820439) (xy 426.705397 -282.783602)
			(xy 426.679094 -282.742006) (xy 426.659803 -282.69673) (xy 426.648026 -282.648946) (xy 426.644066 -282.599892)
			(xy 426.305218 -282.599892) (xy 426.304723 -282.624499) (xy 426.296828 -282.673076) (xy 426.281244 -282.719757)
			(xy 426.258373 -282.763334) (xy 426.228808 -282.802678) (xy 426.193315 -282.83677) (xy 426.152812 -282.864726)
			(xy 426.10835 -282.885824) (xy 426.061079 -282.899516) (xy 426.012224 -282.905448) (xy 425.963049 -282.903467)
			(xy 425.91483 -282.893623) (xy 425.868814 -282.876171) (xy 425.826193 -282.851564) (xy 425.788072 -282.820439)
			(xy 425.755437 -282.783602) (xy 425.729134 -282.742006) (xy 425.709843 -282.69673) (xy 425.698066 -282.648946)
			(xy 425.694106 -282.599892) (xy 425.355258 -282.599892) (xy 425.354763 -282.624499) (xy 425.346868 -282.673076)
			(xy 425.331284 -282.719757) (xy 425.308413 -282.763334) (xy 425.278848 -282.802678) (xy 425.243355 -282.83677)
			(xy 425.202852 -282.864726) (xy 425.15839 -282.885824) (xy 425.111119 -282.899516) (xy 425.062264 -282.905448)
			(xy 425.013089 -282.903467) (xy 424.96487 -282.893623) (xy 424.918854 -282.876171) (xy 424.876233 -282.851564)
			(xy 424.838112 -282.820439) (xy 424.805477 -282.783602) (xy 424.779174 -282.742006) (xy 424.759883 -282.69673)
			(xy 424.748106 -282.648946) (xy 424.744146 -282.599892) (xy 424.405298 -282.599892) (xy 424.404803 -282.624499)
			(xy 424.396908 -282.673076) (xy 424.381324 -282.719757) (xy 424.358453 -282.763334) (xy 424.328888 -282.802678)
			(xy 424.293395 -282.83677) (xy 424.252892 -282.864726) (xy 424.20843 -282.885824) (xy 424.161159 -282.899516)
			(xy 424.112304 -282.905448) (xy 424.063129 -282.903467) (xy 424.01491 -282.893623) (xy 423.968894 -282.876171)
			(xy 423.926273 -282.851564) (xy 423.888152 -282.820439) (xy 423.855517 -282.783602) (xy 423.829214 -282.742006)
			(xy 423.809923 -282.69673) (xy 423.798146 -282.648946) (xy 423.794186 -282.599892) (xy 423.455084 -282.599892)
			(xy 423.454589 -282.624499) (xy 423.446694 -282.673076) (xy 423.43111 -282.719757) (xy 423.408239 -282.763334)
			(xy 423.378674 -282.802678) (xy 423.343181 -282.83677) (xy 423.302678 -282.864726) (xy 423.258216 -282.885824)
			(xy 423.210945 -282.899516) (xy 423.16209 -282.905448) (xy 423.112915 -282.903467) (xy 423.064696 -282.893623)
			(xy 423.01868 -282.876171) (xy 422.976059 -282.851564) (xy 422.937938 -282.820439) (xy 422.905303 -282.783602)
			(xy 422.879 -282.742006) (xy 422.859709 -282.69673) (xy 422.847932 -282.648946) (xy 422.843972 -282.599892)
			(xy 403.505162 -282.599892) (xy 403.504981 -282.614012) (xy 403.502306 -282.642124) (xy 403.499828 -282.656026)
			(xy 403.497542 -282.668472) (xy 403.504908 -282.692348) (xy 403.582378 -282.769818) (xy 403.606254 -282.777184)
			(xy 403.6187 -282.774898) (xy 403.632604 -282.772438) (xy 403.660715 -282.769765) (xy 403.674834 -282.769564)
			(xy 403.699652 -282.770115) (xy 403.748633 -282.77815) (xy 403.795669 -282.794004) (xy 403.839521 -282.817259)
			(xy 403.879032 -282.847302) (xy 403.913163 -282.883341) (xy 403.941014 -282.924427) (xy 403.96185 -282.969478)
			(xy 403.975124 -283.017306) (xy 403.980486 -283.066651) (xy 403.980039 -283.074872) (xy 404.319244 -283.074872)
			(xy 404.323204 -283.025818) (xy 404.334981 -282.978034) (xy 404.354272 -282.932758) (xy 404.380575 -282.891162)
			(xy 404.41321 -282.854325) (xy 404.451331 -282.8232) (xy 404.493952 -282.798593) (xy 404.539968 -282.781141)
			(xy 404.588187 -282.771297) (xy 404.637362 -282.769316) (xy 404.686217 -282.775248) (xy 404.733488 -282.78894)
			(xy 404.77795 -282.810038) (xy 404.818453 -282.837994) (xy 404.853946 -282.872086) (xy 404.883511 -282.91143)
			(xy 404.906382 -282.955007) (xy 404.921966 -283.001688) (xy 404.929861 -283.050265) (xy 404.930356 -283.074872)
			(xy 405.269204 -283.074872) (xy 405.273164 -283.025818) (xy 405.284941 -282.978034) (xy 405.304232 -282.932758)
			(xy 405.330535 -282.891162) (xy 405.36317 -282.854325) (xy 405.401291 -282.8232) (xy 405.443912 -282.798593)
			(xy 405.489928 -282.781141) (xy 405.538147 -282.771297) (xy 405.587322 -282.769316) (xy 405.636177 -282.775248)
			(xy 405.683448 -282.78894) (xy 405.72791 -282.810038) (xy 405.768413 -282.837994) (xy 405.803906 -282.872086)
			(xy 405.833471 -282.91143) (xy 405.856342 -282.955007) (xy 405.871926 -283.001688) (xy 405.879821 -283.050265)
			(xy 405.880316 -283.074872) (xy 406.219164 -283.074872) (xy 406.223124 -283.025818) (xy 406.234901 -282.978034)
			(xy 406.254192 -282.932758) (xy 406.280495 -282.891162) (xy 406.31313 -282.854325) (xy 406.351251 -282.8232)
			(xy 406.393872 -282.798593) (xy 406.439888 -282.781141) (xy 406.488107 -282.771297) (xy 406.537282 -282.769316)
			(xy 406.586137 -282.775248) (xy 406.633408 -282.78894) (xy 406.67787 -282.810038) (xy 406.718373 -282.837994)
			(xy 406.753866 -282.872086) (xy 406.783431 -282.91143) (xy 406.806302 -282.955007) (xy 406.821886 -283.001688)
			(xy 406.829781 -283.050265) (xy 406.830276 -283.074872) (xy 408.119084 -283.074872) (xy 408.123044 -283.025818)
			(xy 408.134821 -282.978034) (xy 408.154112 -282.932758) (xy 408.180415 -282.891162) (xy 408.21305 -282.854325)
			(xy 408.251171 -282.8232) (xy 408.293792 -282.798593) (xy 408.339808 -282.781141) (xy 408.388027 -282.771297)
			(xy 408.437202 -282.769316) (xy 408.486057 -282.775248) (xy 408.533328 -282.78894) (xy 408.57779 -282.810038)
			(xy 408.618293 -282.837994) (xy 408.653786 -282.872086) (xy 408.683351 -282.91143) (xy 408.706222 -282.955007)
			(xy 408.721806 -283.001688) (xy 408.729701 -283.050265) (xy 408.730196 -283.074872) (xy 409.069044 -283.074872)
			(xy 409.073004 -283.025818) (xy 409.084781 -282.978034) (xy 409.104072 -282.932758) (xy 409.130375 -282.891162)
			(xy 409.16301 -282.854325) (xy 409.201131 -282.8232) (xy 409.243752 -282.798593) (xy 409.289768 -282.781141)
			(xy 409.337987 -282.771297) (xy 409.387162 -282.769316) (xy 409.436017 -282.775248) (xy 409.483288 -282.78894)
			(xy 409.52775 -282.810038) (xy 409.568253 -282.837994) (xy 409.603746 -282.872086) (xy 409.633311 -282.91143)
			(xy 409.656182 -282.955007) (xy 409.671766 -283.001688) (xy 409.679661 -283.050265) (xy 409.680156 -283.074872)
			(xy 410.019004 -283.074872) (xy 410.022964 -283.025818) (xy 410.034741 -282.978034) (xy 410.054032 -282.932758)
			(xy 410.080335 -282.891162) (xy 410.11297 -282.854325) (xy 410.151091 -282.8232) (xy 410.193712 -282.798593)
			(xy 410.239728 -282.781141) (xy 410.287947 -282.771297) (xy 410.337122 -282.769316) (xy 410.385977 -282.775248)
			(xy 410.433248 -282.78894) (xy 410.47771 -282.810038) (xy 410.518213 -282.837994) (xy 410.553706 -282.872086)
			(xy 410.583271 -282.91143) (xy 410.606142 -282.955007) (xy 410.621726 -283.001688) (xy 410.629621 -283.050265)
			(xy 410.630116 -283.074872) (xy 410.969218 -283.074872) (xy 410.973178 -283.025818) (xy 410.984955 -282.978034)
			(xy 411.004246 -282.932758) (xy 411.030549 -282.891162) (xy 411.063184 -282.854325) (xy 411.101305 -282.8232)
			(xy 411.143926 -282.798593) (xy 411.189942 -282.781141) (xy 411.238161 -282.771297) (xy 411.287336 -282.769316)
			(xy 411.336191 -282.775248) (xy 411.383462 -282.78894) (xy 411.427924 -282.810038) (xy 411.468427 -282.837994)
			(xy 411.50392 -282.872086) (xy 411.533485 -282.91143) (xy 411.556356 -282.955007) (xy 411.57194 -283.001688)
			(xy 411.579835 -283.050265) (xy 411.58033 -283.074872) (xy 411.919178 -283.074872) (xy 411.923138 -283.025818)
			(xy 411.934915 -282.978034) (xy 411.954206 -282.932758) (xy 411.980509 -282.891162) (xy 412.013144 -282.854325)
			(xy 412.051265 -282.8232) (xy 412.093886 -282.798593) (xy 412.139902 -282.781141) (xy 412.188121 -282.771297)
			(xy 412.237296 -282.769316) (xy 412.286151 -282.775248) (xy 412.333422 -282.78894) (xy 412.377884 -282.810038)
			(xy 412.418387 -282.837994) (xy 412.45388 -282.872086) (xy 412.483445 -282.91143) (xy 412.506316 -282.955007)
			(xy 412.5219 -283.001688) (xy 412.529795 -283.050265) (xy 412.53029 -283.074872) (xy 412.869138 -283.074872)
			(xy 412.873098 -283.025818) (xy 412.884875 -282.978034) (xy 412.904166 -282.932758) (xy 412.930469 -282.891162)
			(xy 412.963104 -282.854325) (xy 413.001225 -282.8232) (xy 413.043846 -282.798593) (xy 413.089862 -282.781141)
			(xy 413.138081 -282.771297) (xy 413.187256 -282.769316) (xy 413.236111 -282.775248) (xy 413.283382 -282.78894)
			(xy 413.327844 -282.810038) (xy 413.368347 -282.837994) (xy 413.40384 -282.872086) (xy 413.433405 -282.91143)
			(xy 413.456276 -282.955007) (xy 413.47186 -283.001688) (xy 413.479755 -283.050265) (xy 413.48025 -283.074872)
			(xy 413.819098 -283.074872) (xy 413.823058 -283.025818) (xy 413.834835 -282.978034) (xy 413.854126 -282.932758)
			(xy 413.880429 -282.891162) (xy 413.913064 -282.854325) (xy 413.951185 -282.8232) (xy 413.993806 -282.798593)
			(xy 414.039822 -282.781141) (xy 414.088041 -282.771297) (xy 414.137216 -282.769316) (xy 414.186071 -282.775248)
			(xy 414.233342 -282.78894) (xy 414.277804 -282.810038) (xy 414.318307 -282.837994) (xy 414.3538 -282.872086)
			(xy 414.383365 -282.91143) (xy 414.406236 -282.955007) (xy 414.42182 -283.001688) (xy 414.429715 -283.050265)
			(xy 414.43021 -283.074872) (xy 414.769058 -283.074872) (xy 414.773018 -283.025818) (xy 414.784795 -282.978034)
			(xy 414.804086 -282.932758) (xy 414.830389 -282.891162) (xy 414.863024 -282.854325) (xy 414.901145 -282.8232)
			(xy 414.943766 -282.798593) (xy 414.989782 -282.781141) (xy 415.038001 -282.771297) (xy 415.087176 -282.769316)
			(xy 415.136031 -282.775248) (xy 415.183302 -282.78894) (xy 415.227764 -282.810038) (xy 415.268267 -282.837994)
			(xy 415.30376 -282.872086) (xy 415.333325 -282.91143) (xy 415.356196 -282.955007) (xy 415.37178 -283.001688)
			(xy 415.379675 -283.050265) (xy 415.38017 -283.074872) (xy 415.719018 -283.074872) (xy 415.722978 -283.025818)
			(xy 415.734755 -282.978034) (xy 415.754046 -282.932758) (xy 415.780349 -282.891162) (xy 415.812984 -282.854325)
			(xy 415.851105 -282.8232) (xy 415.893726 -282.798593) (xy 415.939742 -282.781141) (xy 415.987961 -282.771297)
			(xy 416.037136 -282.769316) (xy 416.085991 -282.775248) (xy 416.133262 -282.78894) (xy 416.177724 -282.810038)
			(xy 416.218227 -282.837994) (xy 416.25372 -282.872086) (xy 416.283285 -282.91143) (xy 416.306156 -282.955007)
			(xy 416.32174 -283.001688) (xy 416.329635 -283.050265) (xy 416.33013 -283.074872) (xy 416.668978 -283.074872)
			(xy 416.672938 -283.025818) (xy 416.684715 -282.978034) (xy 416.704006 -282.932758) (xy 416.730309 -282.891162)
			(xy 416.762944 -282.854325) (xy 416.801065 -282.8232) (xy 416.843686 -282.798593) (xy 416.889702 -282.781141)
			(xy 416.937921 -282.771297) (xy 416.987096 -282.769316) (xy 417.035951 -282.775248) (xy 417.083222 -282.78894)
			(xy 417.127684 -282.810038) (xy 417.168187 -282.837994) (xy 417.20368 -282.872086) (xy 417.233245 -282.91143)
			(xy 417.256116 -282.955007) (xy 417.2717 -283.001688) (xy 417.279595 -283.050265) (xy 417.28009 -283.074872)
			(xy 417.619192 -283.074872) (xy 417.623152 -283.025818) (xy 417.634929 -282.978034) (xy 417.65422 -282.932758)
			(xy 417.680523 -282.891162) (xy 417.713158 -282.854325) (xy 417.751279 -282.8232) (xy 417.7939 -282.798593)
			(xy 417.839916 -282.781141) (xy 417.888135 -282.771297) (xy 417.93731 -282.769316) (xy 417.986165 -282.775248)
			(xy 418.033436 -282.78894) (xy 418.077898 -282.810038) (xy 418.118401 -282.837994) (xy 418.153894 -282.872086)
			(xy 418.183459 -282.91143) (xy 418.20633 -282.955007) (xy 418.221914 -283.001688) (xy 418.229809 -283.050265)
			(xy 418.230304 -283.074872) (xy 418.569152 -283.074872) (xy 418.573112 -283.025818) (xy 418.584889 -282.978034)
			(xy 418.60418 -282.932758) (xy 418.630483 -282.891162) (xy 418.663118 -282.854325) (xy 418.701239 -282.8232)
			(xy 418.74386 -282.798593) (xy 418.789876 -282.781141) (xy 418.838095 -282.771297) (xy 418.88727 -282.769316)
			(xy 418.936125 -282.775248) (xy 418.983396 -282.78894) (xy 419.027858 -282.810038) (xy 419.068361 -282.837994)
			(xy 419.103854 -282.872086) (xy 419.133419 -282.91143) (xy 419.15629 -282.955007) (xy 419.171874 -283.001688)
			(xy 419.179769 -283.050265) (xy 419.180264 -283.074872) (xy 419.519112 -283.074872) (xy 419.523072 -283.025818)
			(xy 419.534849 -282.978034) (xy 419.55414 -282.932758) (xy 419.580443 -282.891162) (xy 419.613078 -282.854325)
			(xy 419.651199 -282.8232) (xy 419.69382 -282.798593) (xy 419.739836 -282.781141) (xy 419.788055 -282.771297)
			(xy 419.83723 -282.769316) (xy 419.886085 -282.775248) (xy 419.933356 -282.78894) (xy 419.977818 -282.810038)
			(xy 420.018321 -282.837994) (xy 420.053814 -282.872086) (xy 420.083379 -282.91143) (xy 420.10625 -282.955007)
			(xy 420.121834 -283.001688) (xy 420.129729 -283.050265) (xy 420.130224 -283.074872) (xy 420.469072 -283.074872)
			(xy 420.473032 -283.025818) (xy 420.484809 -282.978034) (xy 420.5041 -282.932758) (xy 420.530403 -282.891162)
			(xy 420.563038 -282.854325) (xy 420.601159 -282.8232) (xy 420.64378 -282.798593) (xy 420.689796 -282.781141)
			(xy 420.738015 -282.771297) (xy 420.78719 -282.769316) (xy 420.836045 -282.775248) (xy 420.883316 -282.78894)
			(xy 420.927778 -282.810038) (xy 420.968281 -282.837994) (xy 421.003774 -282.872086) (xy 421.033339 -282.91143)
			(xy 421.05621 -282.955007) (xy 421.071794 -283.001688) (xy 421.079689 -283.050265) (xy 421.080184 -283.074872)
			(xy 421.079689 -283.099479) (xy 421.074265 -283.132854) (xy 456.388661 -283.132854) (xy 456.388661 -283.078346)
			(xy 456.396419 -283.024394) (xy 456.411776 -282.972095) (xy 456.43442 -282.922514) (xy 456.46389 -282.876661)
			(xy 456.499585 -282.835468) (xy 456.54078 -282.799775) (xy 456.586636 -282.770308) (xy 456.636218 -282.747667)
			(xy 456.688518 -282.732314) (xy 456.74247 -282.72456) (xy 456.769724 -282.724098) (xy 456.798463 -282.724608)
			(xy 456.855291 -282.733234) (xy 456.910182 -282.750287) (xy 456.961894 -282.775382) (xy 457.009256 -282.80795)
			(xy 457.030582 -282.827222) (xy 457.030836 -282.827476) (xy 457.038129 -282.833607) (xy 457.055862 -282.840535)
			(xy 457.06538 -282.840938) (xy 457.134468 -282.840938) (xy 457.144001 -282.840606) (xy 457.161757 -282.83367)
			(xy 457.169012 -282.827476) (xy 457.169266 -282.827222) (xy 457.190593 -282.807952) (xy 457.237956 -282.775387)
			(xy 457.289667 -282.750296) (xy 457.344558 -282.733246) (xy 457.401385 -282.724624) (xy 457.458863 -282.724624)
			(xy 457.51569 -282.733246) (xy 457.570581 -282.750296) (xy 457.622292 -282.775387) (xy 457.669655 -282.807952)
			(xy 457.690982 -282.827222) (xy 457.691236 -282.827476) (xy 457.698529 -282.833607) (xy 457.716262 -282.840535)
			(xy 457.72578 -282.840938) (xy 457.794868 -282.840938) (xy 457.804401 -282.840606) (xy 457.822157 -282.83367)
			(xy 457.829412 -282.827476) (xy 457.829666 -282.827222) (xy 457.850981 -282.807937) (xy 457.898346 -282.775373)
			(xy 457.950061 -282.750284) (xy 458.004955 -282.733237) (xy 458.061784 -282.724617) (xy 458.090524 -282.724098)
			(xy 458.120649 -282.724639) (xy 458.180147 -282.734126) (xy 458.237416 -282.752843) (xy 458.291033 -282.780325)
			(xy 458.339665 -282.815891) (xy 458.361288 -282.836874) (xy 458.3684 -282.843986) (xy 458.387196 -282.85186)
			(xy 458.479652 -282.85186) (xy 458.498448 -282.843986) (xy 458.50556 -282.836874) (xy 458.527192 -282.815901)
			(xy 458.575817 -282.780329) (xy 458.629432 -282.752846) (xy 458.686701 -282.734137) (xy 458.7462 -282.724666)
			(xy 458.776324 -282.724098) (xy 458.803575 -282.724573) (xy 458.857521 -282.732333) (xy 458.909813 -282.74769)
			(xy 458.959388 -282.770333) (xy 459.005236 -282.799801) (xy 459.046424 -282.835493) (xy 459.082114 -282.876683)
			(xy 459.111578 -282.922533) (xy 459.134218 -282.972109) (xy 459.149572 -283.024403) (xy 459.157328 -283.078349)
			(xy 459.157328 -283.132851) (xy 459.157328 -283.132853) (xy 460.636061 -283.132853) (xy 460.636061 -283.078347)
			(xy 460.643819 -283.024396) (xy 460.659175 -282.972098) (xy 460.681818 -282.922518) (xy 460.711287 -282.876665)
			(xy 460.746981 -282.835472) (xy 460.788174 -282.799779) (xy 460.834028 -282.770312) (xy 460.883609 -282.747671)
			(xy 460.935908 -282.732316) (xy 460.989859 -282.724561) (xy 461.017112 -282.724098) (xy 461.045851 -282.724615)
			(xy 461.102679 -282.733239) (xy 461.15757 -282.750291) (xy 461.209281 -282.775384) (xy 461.256643 -282.807951)
			(xy 461.27797 -282.827222) (xy 461.278224 -282.827476) (xy 461.285521 -282.833602) (xy 461.303251 -282.840532)
			(xy 461.312768 -282.840938) (xy 461.381856 -282.840938) (xy 461.391388 -282.8406) (xy 461.409144 -282.833669)
			(xy 461.4164 -282.827476) (xy 461.416654 -282.827222) (xy 461.437981 -282.807952) (xy 461.485344 -282.775387)
			(xy 461.537055 -282.750296) (xy 461.591946 -282.733246) (xy 461.648773 -282.724624) (xy 461.706251 -282.724624)
			(xy 461.763078 -282.733246) (xy 461.817969 -282.750296) (xy 461.86968 -282.775387) (xy 461.917043 -282.807952)
			(xy 461.93837 -282.827222) (xy 461.938624 -282.827476) (xy 461.945921 -282.833602) (xy 461.963651 -282.840532)
			(xy 461.973168 -282.840938) (xy 462.042256 -282.840938) (xy 462.051788 -282.8406) (xy 462.069544 -282.833669)
			(xy 462.0768 -282.827476) (xy 462.077054 -282.827222) (xy 462.098374 -282.807943) (xy 462.145738 -282.775378)
			(xy 462.197452 -282.750288) (xy 462.252344 -282.733239) (xy 462.309173 -282.724618) (xy 462.337912 -282.724098)
			(xy 462.368036 -282.724647) (xy 462.427534 -282.734131) (xy 462.484803 -282.752846) (xy 462.53842 -282.780328)
			(xy 462.587053 -282.815892) (xy 462.608676 -282.836874) (xy 462.615788 -282.843986) (xy 462.634584 -282.85186)
			(xy 462.72704 -282.85186) (xy 462.745836 -282.843986) (xy 462.752948 -282.836874) (xy 462.774585 -282.815907)
			(xy 462.823209 -282.780334) (xy 462.876822 -282.75285) (xy 462.93409 -282.734139) (xy 462.993588 -282.724667)
			(xy 463.023712 -282.724098) (xy 463.050963 -282.724573) (xy 463.10491 -282.732331) (xy 463.157205 -282.747687)
			(xy 463.206781 -282.770329) (xy 463.252631 -282.799796) (xy 463.29382 -282.835488) (xy 463.329511 -282.876679)
			(xy 463.358977 -282.92253) (xy 463.381617 -282.972107) (xy 463.396972 -283.024401) (xy 463.404728 -283.078349)
			(xy 463.404728 -283.132851) (xy 463.396972 -283.186799) (xy 463.381617 -283.239093) (xy 463.358977 -283.28867)
			(xy 463.329511 -283.334521) (xy 463.29382 -283.375712) (xy 463.252631 -283.411404) (xy 463.206781 -283.440871)
			(xy 463.157205 -283.463513) (xy 463.10491 -283.478869) (xy 463.050963 -283.486627) (xy 463.023712 -283.487114)
			(xy 462.993588 -283.486546) (xy 462.934091 -283.477066) (xy 462.876823 -283.458355) (xy 462.823206 -283.430878)
			(xy 462.774572 -283.395318) (xy 462.752948 -283.374338) (xy 462.745836 -283.367226) (xy 462.72704 -283.359352)
			(xy 462.634584 -283.359352) (xy 462.615788 -283.367226) (xy 462.608676 -283.374338) (xy 462.58703 -283.395296)
			(xy 462.538408 -283.43087) (xy 462.484797 -283.458355) (xy 462.427531 -283.477068) (xy 462.368035 -283.486544)
			(xy 462.337912 -283.487114) (xy 462.309174 -283.486579) (xy 462.252347 -283.477959) (xy 462.197456 -283.460911)
			(xy 462.145744 -283.435822) (xy 462.098381 -283.403259) (xy 462.077054 -283.38399) (xy 462.0768 -283.383736)
			(xy 462.069536 -283.377566) (xy 462.05178 -283.370664) (xy 462.042256 -283.370274) (xy 461.973168 -283.370274)
			(xy 461.96364 -283.370645) (xy 461.945885 -283.377556) (xy 461.938624 -283.383736) (xy 461.93837 -283.38399)
			(xy 461.917043 -283.40326) (xy 461.86968 -283.435825) (xy 461.817969 -283.460916) (xy 461.763078 -283.477966)
			(xy 461.706251 -283.486588) (xy 461.648773 -283.486588) (xy 461.591946 -283.477966) (xy 461.537055 -283.460916)
			(xy 461.485344 -283.435825) (xy 461.437981 -283.40326) (xy 461.416654 -283.38399) (xy 461.4164 -283.383736)
			(xy 461.409136 -283.377566) (xy 461.39138 -283.370664) (xy 461.381856 -283.370274) (xy 461.312768 -283.370274)
			(xy 461.30324 -283.370645) (xy 461.285485 -283.377556) (xy 461.278224 -283.383736) (xy 461.27797 -283.38399)
			(xy 461.256642 -283.40326) (xy 461.20928 -283.435825) (xy 461.157568 -283.460917) (xy 461.102678 -283.477968)
			(xy 461.045851 -283.486592) (xy 461.017112 -283.487114) (xy 460.989859 -283.486639) (xy 460.935908 -283.478884)
			(xy 460.883609 -283.463529) (xy 460.834028 -283.440888) (xy 460.788174 -283.411421) (xy 460.746981 -283.375728)
			(xy 460.711287 -283.334535) (xy 460.681818 -283.288682) (xy 460.659175 -283.239102) (xy 460.643819 -283.186804)
			(xy 460.636061 -283.132853) (xy 459.157328 -283.132853) (xy 459.149572 -283.186797) (xy 459.134218 -283.239091)
			(xy 459.111578 -283.288667) (xy 459.082114 -283.334517) (xy 459.046424 -283.375707) (xy 459.005236 -283.411399)
			(xy 458.959388 -283.440867) (xy 458.909813 -283.46351) (xy 458.857521 -283.478867) (xy 458.803575 -283.486627)
			(xy 458.776324 -283.487114) (xy 458.746201 -283.486538) (xy 458.686704 -283.47706) (xy 458.629436 -283.458351)
			(xy 458.575819 -283.430876) (xy 458.527185 -283.395317) (xy 458.50556 -283.374338) (xy 458.498448 -283.367226)
			(xy 458.479652 -283.359352) (xy 458.387196 -283.359352) (xy 458.3684 -283.367226) (xy 458.361288 -283.374338)
			(xy 458.339681 -283.395338) (xy 458.291049 -283.430906) (xy 458.237428 -283.458384) (xy 458.180153 -283.477087)
			(xy 458.12065 -283.486551) (xy 458.090524 -283.487114) (xy 458.061786 -283.486572) (xy 458.004959 -283.477953)
			(xy 457.950069 -283.460907) (xy 457.898357 -283.43582) (xy 457.850994 -283.403259) (xy 457.829666 -283.38399)
			(xy 457.829412 -283.383736) (xy 457.822144 -283.377571) (xy 457.804391 -283.370666) (xy 457.794868 -283.370274)
			(xy 457.72578 -283.370274) (xy 457.716252 -283.370652) (xy 457.698498 -283.377558) (xy 457.691236 -283.383736)
			(xy 457.690982 -283.38399) (xy 457.669655 -283.40326) (xy 457.622292 -283.435825) (xy 457.570581 -283.460916)
			(xy 457.51569 -283.477966) (xy 457.458863 -283.486588) (xy 457.401385 -283.486588) (xy 457.344558 -283.477966)
			(xy 457.289667 -283.460916) (xy 457.237956 -283.435825) (xy 457.190593 -283.40326) (xy 457.169266 -283.38399)
			(xy 457.169012 -283.383736) (xy 457.161744 -283.377571) (xy 457.143991 -283.370666) (xy 457.134468 -283.370274)
			(xy 457.06538 -283.370274) (xy 457.055852 -283.370652) (xy 457.038098 -283.377558) (xy 457.030836 -283.383736)
			(xy 457.030582 -283.38399) (xy 457.009249 -283.403254) (xy 456.961888 -283.43582) (xy 456.910178 -283.460913)
			(xy 456.855289 -283.477966) (xy 456.798463 -283.486591) (xy 456.769724 -283.487114) (xy 456.74247 -283.48664)
			(xy 456.688518 -283.478886) (xy 456.636218 -283.463533) (xy 456.586636 -283.440892) (xy 456.54078 -283.411425)
			(xy 456.499585 -283.375732) (xy 456.46389 -283.334539) (xy 456.43442 -283.288686) (xy 456.411776 -283.239105)
			(xy 456.396419 -283.186806) (xy 456.388661 -283.132854) (xy 421.074265 -283.132854) (xy 421.071794 -283.148056)
			(xy 421.05621 -283.194737) (xy 421.033339 -283.238314) (xy 421.003774 -283.277658) (xy 420.968281 -283.31175)
			(xy 420.927778 -283.339706) (xy 420.883316 -283.360804) (xy 420.836045 -283.374496) (xy 420.78719 -283.380428)
			(xy 420.738015 -283.378447) (xy 420.689796 -283.368603) (xy 420.64378 -283.351151) (xy 420.601159 -283.326544)
			(xy 420.563038 -283.295419) (xy 420.530403 -283.258582) (xy 420.5041 -283.216986) (xy 420.484809 -283.17171)
			(xy 420.473032 -283.123926) (xy 420.469072 -283.074872) (xy 420.130224 -283.074872) (xy 420.129729 -283.099479)
			(xy 420.121834 -283.148056) (xy 420.10625 -283.194737) (xy 420.083379 -283.238314) (xy 420.053814 -283.277658)
			(xy 420.018321 -283.31175) (xy 419.977818 -283.339706) (xy 419.933356 -283.360804) (xy 419.886085 -283.374496)
			(xy 419.83723 -283.380428) (xy 419.788055 -283.378447) (xy 419.739836 -283.368603) (xy 419.69382 -283.351151)
			(xy 419.651199 -283.326544) (xy 419.613078 -283.295419) (xy 419.580443 -283.258582) (xy 419.55414 -283.216986)
			(xy 419.534849 -283.17171) (xy 419.523072 -283.123926) (xy 419.519112 -283.074872) (xy 419.180264 -283.074872)
			(xy 419.179769 -283.099479) (xy 419.171874 -283.148056) (xy 419.15629 -283.194737) (xy 419.133419 -283.238314)
			(xy 419.103854 -283.277658) (xy 419.068361 -283.31175) (xy 419.027858 -283.339706) (xy 418.983396 -283.360804)
			(xy 418.936125 -283.374496) (xy 418.88727 -283.380428) (xy 418.838095 -283.378447) (xy 418.789876 -283.368603)
			(xy 418.74386 -283.351151) (xy 418.701239 -283.326544) (xy 418.663118 -283.295419) (xy 418.630483 -283.258582)
			(xy 418.60418 -283.216986) (xy 418.584889 -283.17171) (xy 418.573112 -283.123926) (xy 418.569152 -283.074872)
			(xy 418.230304 -283.074872) (xy 418.229809 -283.099479) (xy 418.221914 -283.148056) (xy 418.20633 -283.194737)
			(xy 418.183459 -283.238314) (xy 418.153894 -283.277658) (xy 418.118401 -283.31175) (xy 418.077898 -283.339706)
			(xy 418.033436 -283.360804) (xy 417.986165 -283.374496) (xy 417.93731 -283.380428) (xy 417.888135 -283.378447)
			(xy 417.839916 -283.368603) (xy 417.7939 -283.351151) (xy 417.751279 -283.326544) (xy 417.713158 -283.295419)
			(xy 417.680523 -283.258582) (xy 417.65422 -283.216986) (xy 417.634929 -283.17171) (xy 417.623152 -283.123926)
			(xy 417.619192 -283.074872) (xy 417.28009 -283.074872) (xy 417.279595 -283.099479) (xy 417.2717 -283.148056)
			(xy 417.256116 -283.194737) (xy 417.233245 -283.238314) (xy 417.20368 -283.277658) (xy 417.168187 -283.31175)
			(xy 417.127684 -283.339706) (xy 417.083222 -283.360804) (xy 417.035951 -283.374496) (xy 416.987096 -283.380428)
			(xy 416.937921 -283.378447) (xy 416.889702 -283.368603) (xy 416.843686 -283.351151) (xy 416.801065 -283.326544)
			(xy 416.762944 -283.295419) (xy 416.730309 -283.258582) (xy 416.704006 -283.216986) (xy 416.684715 -283.17171)
			(xy 416.672938 -283.123926) (xy 416.668978 -283.074872) (xy 416.33013 -283.074872) (xy 416.329635 -283.099479)
			(xy 416.32174 -283.148056) (xy 416.306156 -283.194737) (xy 416.283285 -283.238314) (xy 416.25372 -283.277658)
			(xy 416.218227 -283.31175) (xy 416.177724 -283.339706) (xy 416.133262 -283.360804) (xy 416.085991 -283.374496)
			(xy 416.037136 -283.380428) (xy 415.987961 -283.378447) (xy 415.939742 -283.368603) (xy 415.893726 -283.351151)
			(xy 415.851105 -283.326544) (xy 415.812984 -283.295419) (xy 415.780349 -283.258582) (xy 415.754046 -283.216986)
			(xy 415.734755 -283.17171) (xy 415.722978 -283.123926) (xy 415.719018 -283.074872) (xy 415.38017 -283.074872)
			(xy 415.379675 -283.099479) (xy 415.37178 -283.148056) (xy 415.356196 -283.194737) (xy 415.333325 -283.238314)
			(xy 415.30376 -283.277658) (xy 415.268267 -283.31175) (xy 415.227764 -283.339706) (xy 415.183302 -283.360804)
			(xy 415.136031 -283.374496) (xy 415.087176 -283.380428) (xy 415.038001 -283.378447) (xy 414.989782 -283.368603)
			(xy 414.943766 -283.351151) (xy 414.901145 -283.326544) (xy 414.863024 -283.295419) (xy 414.830389 -283.258582)
			(xy 414.804086 -283.216986) (xy 414.784795 -283.17171) (xy 414.773018 -283.123926) (xy 414.769058 -283.074872)
			(xy 414.43021 -283.074872) (xy 414.429715 -283.099479) (xy 414.42182 -283.148056) (xy 414.406236 -283.194737)
			(xy 414.383365 -283.238314) (xy 414.3538 -283.277658) (xy 414.318307 -283.31175) (xy 414.277804 -283.339706)
			(xy 414.233342 -283.360804) (xy 414.186071 -283.374496) (xy 414.137216 -283.380428) (xy 414.088041 -283.378447)
			(xy 414.039822 -283.368603) (xy 413.993806 -283.351151) (xy 413.951185 -283.326544) (xy 413.913064 -283.295419)
			(xy 413.880429 -283.258582) (xy 413.854126 -283.216986) (xy 413.834835 -283.17171) (xy 413.823058 -283.123926)
			(xy 413.819098 -283.074872) (xy 413.48025 -283.074872) (xy 413.479755 -283.099479) (xy 413.47186 -283.148056)
			(xy 413.456276 -283.194737) (xy 413.433405 -283.238314) (xy 413.40384 -283.277658) (xy 413.368347 -283.31175)
			(xy 413.327844 -283.339706) (xy 413.283382 -283.360804) (xy 413.236111 -283.374496) (xy 413.187256 -283.380428)
			(xy 413.138081 -283.378447) (xy 413.089862 -283.368603) (xy 413.043846 -283.351151) (xy 413.001225 -283.326544)
			(xy 412.963104 -283.295419) (xy 412.930469 -283.258582) (xy 412.904166 -283.216986) (xy 412.884875 -283.17171)
			(xy 412.873098 -283.123926) (xy 412.869138 -283.074872) (xy 412.53029 -283.074872) (xy 412.529795 -283.099479)
			(xy 412.5219 -283.148056) (xy 412.506316 -283.194737) (xy 412.483445 -283.238314) (xy 412.45388 -283.277658)
			(xy 412.418387 -283.31175) (xy 412.377884 -283.339706) (xy 412.333422 -283.360804) (xy 412.286151 -283.374496)
			(xy 412.237296 -283.380428) (xy 412.188121 -283.378447) (xy 412.139902 -283.368603) (xy 412.093886 -283.351151)
			(xy 412.051265 -283.326544) (xy 412.013144 -283.295419) (xy 411.980509 -283.258582) (xy 411.954206 -283.216986)
			(xy 411.934915 -283.17171) (xy 411.923138 -283.123926) (xy 411.919178 -283.074872) (xy 411.58033 -283.074872)
			(xy 411.579835 -283.099479) (xy 411.57194 -283.148056) (xy 411.556356 -283.194737) (xy 411.533485 -283.238314)
			(xy 411.50392 -283.277658) (xy 411.468427 -283.31175) (xy 411.427924 -283.339706) (xy 411.383462 -283.360804)
			(xy 411.336191 -283.374496) (xy 411.287336 -283.380428) (xy 411.238161 -283.378447) (xy 411.189942 -283.368603)
			(xy 411.143926 -283.351151) (xy 411.101305 -283.326544) (xy 411.063184 -283.295419) (xy 411.030549 -283.258582)
			(xy 411.004246 -283.216986) (xy 410.984955 -283.17171) (xy 410.973178 -283.123926) (xy 410.969218 -283.074872)
			(xy 410.630116 -283.074872) (xy 410.629621 -283.099479) (xy 410.621726 -283.148056) (xy 410.606142 -283.194737)
			(xy 410.583271 -283.238314) (xy 410.553706 -283.277658) (xy 410.518213 -283.31175) (xy 410.47771 -283.339706)
			(xy 410.433248 -283.360804) (xy 410.385977 -283.374496) (xy 410.337122 -283.380428) (xy 410.287947 -283.378447)
			(xy 410.239728 -283.368603) (xy 410.193712 -283.351151) (xy 410.151091 -283.326544) (xy 410.11297 -283.295419)
			(xy 410.080335 -283.258582) (xy 410.054032 -283.216986) (xy 410.034741 -283.17171) (xy 410.022964 -283.123926)
			(xy 410.019004 -283.074872) (xy 409.680156 -283.074872) (xy 409.679661 -283.099479) (xy 409.671766 -283.148056)
			(xy 409.656182 -283.194737) (xy 409.633311 -283.238314) (xy 409.603746 -283.277658) (xy 409.568253 -283.31175)
			(xy 409.52775 -283.339706) (xy 409.483288 -283.360804) (xy 409.436017 -283.374496) (xy 409.387162 -283.380428)
			(xy 409.337987 -283.378447) (xy 409.289768 -283.368603) (xy 409.243752 -283.351151) (xy 409.201131 -283.326544)
			(xy 409.16301 -283.295419) (xy 409.130375 -283.258582) (xy 409.104072 -283.216986) (xy 409.084781 -283.17171)
			(xy 409.073004 -283.123926) (xy 409.069044 -283.074872) (xy 408.730196 -283.074872) (xy 408.729701 -283.099479)
			(xy 408.721806 -283.148056) (xy 408.706222 -283.194737) (xy 408.683351 -283.238314) (xy 408.653786 -283.277658)
			(xy 408.618293 -283.31175) (xy 408.57779 -283.339706) (xy 408.533328 -283.360804) (xy 408.486057 -283.374496)
			(xy 408.437202 -283.380428) (xy 408.388027 -283.378447) (xy 408.339808 -283.368603) (xy 408.293792 -283.351151)
			(xy 408.251171 -283.326544) (xy 408.21305 -283.295419) (xy 408.180415 -283.258582) (xy 408.154112 -283.216986)
			(xy 408.134821 -283.17171) (xy 408.123044 -283.123926) (xy 408.119084 -283.074872) (xy 406.830276 -283.074872)
			(xy 406.829781 -283.099479) (xy 406.821886 -283.148056) (xy 406.806302 -283.194737) (xy 406.783431 -283.238314)
			(xy 406.753866 -283.277658) (xy 406.718373 -283.31175) (xy 406.67787 -283.339706) (xy 406.633408 -283.360804)
			(xy 406.586137 -283.374496) (xy 406.537282 -283.380428) (xy 406.488107 -283.378447) (xy 406.439888 -283.368603)
			(xy 406.393872 -283.351151) (xy 406.351251 -283.326544) (xy 406.31313 -283.295419) (xy 406.280495 -283.258582)
			(xy 406.254192 -283.216986) (xy 406.234901 -283.17171) (xy 406.223124 -283.123926) (xy 406.219164 -283.074872)
			(xy 405.880316 -283.074872) (xy 405.879821 -283.099479) (xy 405.871926 -283.148056) (xy 405.856342 -283.194737)
			(xy 405.833471 -283.238314) (xy 405.803906 -283.277658) (xy 405.768413 -283.31175) (xy 405.72791 -283.339706)
			(xy 405.683448 -283.360804) (xy 405.636177 -283.374496) (xy 405.587322 -283.380428) (xy 405.538147 -283.378447)
			(xy 405.489928 -283.368603) (xy 405.443912 -283.351151) (xy 405.401291 -283.326544) (xy 405.36317 -283.295419)
			(xy 405.330535 -283.258582) (xy 405.304232 -283.216986) (xy 405.284941 -283.17171) (xy 405.273164 -283.123926)
			(xy 405.269204 -283.074872) (xy 404.930356 -283.074872) (xy 404.929861 -283.099479) (xy 404.921966 -283.148056)
			(xy 404.906382 -283.194737) (xy 404.883511 -283.238314) (xy 404.853946 -283.277658) (xy 404.818453 -283.31175)
			(xy 404.77795 -283.339706) (xy 404.733488 -283.360804) (xy 404.686217 -283.374496) (xy 404.637362 -283.380428)
			(xy 404.588187 -283.378447) (xy 404.539968 -283.368603) (xy 404.493952 -283.351151) (xy 404.451331 -283.326544)
			(xy 404.41321 -283.295419) (xy 404.380575 -283.258582) (xy 404.354272 -283.216986) (xy 404.334981 -283.17171)
			(xy 404.323204 -283.123926) (xy 404.319244 -283.074872) (xy 403.980039 -283.074872) (xy 403.977793 -283.116214)
			(xy 403.967118 -283.164689) (xy 403.948741 -283.210797) (xy 403.923147 -283.253326) (xy 403.891009 -283.291153)
			(xy 403.853175 -283.323283) (xy 403.810642 -283.348869) (xy 403.764529 -283.367236) (xy 403.716053 -283.377902)
			(xy 403.666489 -283.380584) (xy 403.617145 -283.375213) (xy 403.569319 -283.361929) (xy 403.524273 -283.341083)
			(xy 403.483192 -283.313224) (xy 403.44716 -283.279086) (xy 403.417125 -283.239568) (xy 403.39388 -283.195712)
			(xy 403.378035 -283.148673) (xy 403.370009 -283.09969) (xy 403.369526 -283.074872) (xy 403.369716 -283.060753)
			(xy 403.372385 -283.03264) (xy 403.37486 -283.018738) (xy 403.377146 -283.006292) (xy 403.36978 -282.982416)
			(xy 403.29231 -282.904946) (xy 403.268434 -282.89758) (xy 403.255988 -282.899866) (xy 403.242084 -282.902328)
			(xy 403.213973 -282.905) (xy 403.199854 -282.9052) (xy 403.185735 -282.905013) (xy 403.157622 -282.902342)
			(xy 403.14372 -282.899866) (xy 403.131274 -282.89758) (xy 403.107398 -282.904946) (xy 403.029928 -282.982416)
			(xy 403.022562 -283.006292) (xy 403.024848 -283.018738) (xy 403.027313 -283.032641) (xy 403.029983 -283.060753)
			(xy 403.030182 -283.074872) (xy 403.029752 -283.099695) (xy 403.021725 -283.148688) (xy 403.005877 -283.195737)
			(xy 402.982626 -283.239602) (xy 402.952585 -283.279128) (xy 402.916545 -283.313273) (xy 402.875456 -283.341138)
			(xy 402.8304 -283.361988) (xy 402.782565 -283.375274) (xy 402.73321 -283.380646) (xy 402.683636 -283.377963)
			(xy 402.63515 -283.367295) (xy 402.589028 -283.348923) (xy 402.546486 -283.323331) (xy 402.508644 -283.291194)
			(xy 402.4765 -283.253358) (xy 402.450901 -283.210821) (xy 402.432521 -283.164702) (xy 402.421845 -283.116217)
			(xy 402.419152 -283.066644) (xy 402.080056 -283.066644) (xy 402.080222 -283.074872) (xy 402.079727 -283.099479)
			(xy 402.071832 -283.148056) (xy 402.056248 -283.194737) (xy 402.033377 -283.238314) (xy 402.003812 -283.277658)
			(xy 401.968319 -283.31175) (xy 401.927816 -283.339706) (xy 401.883354 -283.360804) (xy 401.836083 -283.374496)
			(xy 401.787228 -283.380428) (xy 401.738053 -283.378447) (xy 401.689834 -283.368603) (xy 401.643818 -283.351151)
			(xy 401.601197 -283.326544) (xy 401.563076 -283.295419) (xy 401.530441 -283.258582) (xy 401.504138 -283.216986)
			(xy 401.484847 -283.17171) (xy 401.47307 -283.123926) (xy 401.46911 -283.074872) (xy 401.130262 -283.074872)
			(xy 401.129767 -283.099479) (xy 401.121872 -283.148056) (xy 401.106288 -283.194737) (xy 401.083417 -283.238314)
			(xy 401.053852 -283.277658) (xy 401.018359 -283.31175) (xy 400.977856 -283.339706) (xy 400.933394 -283.360804)
			(xy 400.886123 -283.374496) (xy 400.837268 -283.380428) (xy 400.788093 -283.378447) (xy 400.739874 -283.368603)
			(xy 400.693858 -283.351151) (xy 400.651237 -283.326544) (xy 400.613116 -283.295419) (xy 400.580481 -283.258582)
			(xy 400.554178 -283.216986) (xy 400.534887 -283.17171) (xy 400.52311 -283.123926) (xy 400.51915 -283.074872)
			(xy 400.180302 -283.074872) (xy 400.179807 -283.099479) (xy 400.171912 -283.148056) (xy 400.156328 -283.194737)
			(xy 400.133457 -283.238314) (xy 400.103892 -283.277658) (xy 400.068399 -283.31175) (xy 400.027896 -283.339706)
			(xy 399.983434 -283.360804) (xy 399.936163 -283.374496) (xy 399.887308 -283.380428) (xy 399.838133 -283.378447)
			(xy 399.789914 -283.368603) (xy 399.743898 -283.351151) (xy 399.701277 -283.326544) (xy 399.663156 -283.295419)
			(xy 399.630521 -283.258582) (xy 399.604218 -283.216986) (xy 399.584927 -283.17171) (xy 399.57315 -283.123926)
			(xy 399.56919 -283.074872) (xy 399.230342 -283.074872) (xy 399.229847 -283.099479) (xy 399.221952 -283.148056)
			(xy 399.206368 -283.194737) (xy 399.183497 -283.238314) (xy 399.153932 -283.277658) (xy 399.118439 -283.31175)
			(xy 399.077936 -283.339706) (xy 399.033474 -283.360804) (xy 398.986203 -283.374496) (xy 398.937348 -283.380428)
			(xy 398.888173 -283.378447) (xy 398.839954 -283.368603) (xy 398.793938 -283.351151) (xy 398.751317 -283.326544)
			(xy 398.713196 -283.295419) (xy 398.680561 -283.258582) (xy 398.654258 -283.216986) (xy 398.634967 -283.17171)
			(xy 398.62319 -283.123926) (xy 398.61923 -283.074872) (xy 398.280128 -283.074872) (xy 398.279633 -283.099479)
			(xy 398.271738 -283.148056) (xy 398.256154 -283.194737) (xy 398.233283 -283.238314) (xy 398.203718 -283.277658)
			(xy 398.168225 -283.31175) (xy 398.127722 -283.339706) (xy 398.08326 -283.360804) (xy 398.035989 -283.374496)
			(xy 397.987134 -283.380428) (xy 397.937959 -283.378447) (xy 397.88974 -283.368603) (xy 397.843724 -283.351151)
			(xy 397.801103 -283.326544) (xy 397.762982 -283.295419) (xy 397.730347 -283.258582) (xy 397.704044 -283.216986)
			(xy 397.684753 -283.17171) (xy 397.672976 -283.123926) (xy 397.669016 -283.074872) (xy 397.330168 -283.074872)
			(xy 397.329673 -283.099479) (xy 397.321778 -283.148056) (xy 397.306194 -283.194737) (xy 397.283323 -283.238314)
			(xy 397.253758 -283.277658) (xy 397.218265 -283.31175) (xy 397.177762 -283.339706) (xy 397.1333 -283.360804)
			(xy 397.086029 -283.374496) (xy 397.037174 -283.380428) (xy 396.987999 -283.378447) (xy 396.93978 -283.368603)
			(xy 396.893764 -283.351151) (xy 396.851143 -283.326544) (xy 396.813022 -283.295419) (xy 396.780387 -283.258582)
			(xy 396.754084 -283.216986) (xy 396.734793 -283.17171) (xy 396.723016 -283.123926) (xy 396.719056 -283.074872)
			(xy 396.55369 -283.074872) (xy 396.55369 -283.549852) (xy 421.894012 -283.549852) (xy 421.897972 -283.500798)
			(xy 421.909749 -283.453014) (xy 421.92904 -283.407738) (xy 421.955343 -283.366142) (xy 421.987978 -283.329305)
			(xy 422.026099 -283.29818) (xy 422.06872 -283.273573) (xy 422.114736 -283.256121) (xy 422.162955 -283.246277)
			(xy 422.21213 -283.244296) (xy 422.260985 -283.250228) (xy 422.308256 -283.26392) (xy 422.352718 -283.285018)
			(xy 422.393221 -283.312974) (xy 422.428714 -283.347066) (xy 422.458279 -283.38641) (xy 422.48115 -283.429987)
			(xy 422.496734 -283.476668) (xy 422.504629 -283.525245) (xy 422.505124 -283.549852) (xy 422.843972 -283.549852)
			(xy 422.847932 -283.500798) (xy 422.859709 -283.453014) (xy 422.879 -283.407738) (xy 422.905303 -283.366142)
			(xy 422.937938 -283.329305) (xy 422.976059 -283.29818) (xy 423.01868 -283.273573) (xy 423.064696 -283.256121)
			(xy 423.112915 -283.246277) (xy 423.16209 -283.244296) (xy 423.210945 -283.250228) (xy 423.258216 -283.26392)
			(xy 423.302678 -283.285018) (xy 423.343181 -283.312974) (xy 423.378674 -283.347066) (xy 423.408239 -283.38641)
			(xy 423.43111 -283.429987) (xy 423.446694 -283.476668) (xy 423.454589 -283.525245) (xy 423.455084 -283.549852)
			(xy 423.794186 -283.549852) (xy 423.798146 -283.500798) (xy 423.809923 -283.453014) (xy 423.829214 -283.407738)
			(xy 423.855517 -283.366142) (xy 423.888152 -283.329305) (xy 423.926273 -283.29818) (xy 423.968894 -283.273573)
			(xy 424.01491 -283.256121) (xy 424.063129 -283.246277) (xy 424.112304 -283.244296) (xy 424.161159 -283.250228)
			(xy 424.20843 -283.26392) (xy 424.252892 -283.285018) (xy 424.293395 -283.312974) (xy 424.328888 -283.347066)
			(xy 424.358453 -283.38641) (xy 424.381324 -283.429987) (xy 424.396908 -283.476668) (xy 424.404803 -283.525245)
			(xy 424.405298 -283.549852) (xy 424.744146 -283.549852) (xy 424.748106 -283.500798) (xy 424.759883 -283.453014)
			(xy 424.779174 -283.407738) (xy 424.805477 -283.366142) (xy 424.838112 -283.329305) (xy 424.876233 -283.29818)
			(xy 424.918854 -283.273573) (xy 424.96487 -283.256121) (xy 425.013089 -283.246277) (xy 425.062264 -283.244296)
			(xy 425.111119 -283.250228) (xy 425.15839 -283.26392) (xy 425.202852 -283.285018) (xy 425.243355 -283.312974)
			(xy 425.278848 -283.347066) (xy 425.308413 -283.38641) (xy 425.331284 -283.429987) (xy 425.346868 -283.476668)
			(xy 425.354763 -283.525245) (xy 425.355258 -283.549852) (xy 425.694106 -283.549852) (xy 425.698066 -283.500798)
			(xy 425.709843 -283.453014) (xy 425.729134 -283.407738) (xy 425.755437 -283.366142) (xy 425.788072 -283.329305)
			(xy 425.826193 -283.29818) (xy 425.868814 -283.273573) (xy 425.91483 -283.256121) (xy 425.963049 -283.246277)
			(xy 426.012224 -283.244296) (xy 426.061079 -283.250228) (xy 426.10835 -283.26392) (xy 426.152812 -283.285018)
			(xy 426.193315 -283.312974) (xy 426.228808 -283.347066) (xy 426.258373 -283.38641) (xy 426.281244 -283.429987)
			(xy 426.296828 -283.476668) (xy 426.304723 -283.525245) (xy 426.305218 -283.549852) (xy 426.644066 -283.549852)
			(xy 426.648026 -283.500798) (xy 426.659803 -283.453014) (xy 426.679094 -283.407738) (xy 426.705397 -283.366142)
			(xy 426.738032 -283.329305) (xy 426.776153 -283.29818) (xy 426.818774 -283.273573) (xy 426.86479 -283.256121)
			(xy 426.913009 -283.246277) (xy 426.962184 -283.244296) (xy 427.011039 -283.250228) (xy 427.05831 -283.26392)
			(xy 427.102772 -283.285018) (xy 427.143275 -283.312974) (xy 427.178768 -283.347066) (xy 427.208333 -283.38641)
			(xy 427.231204 -283.429987) (xy 427.246788 -283.476668) (xy 427.254683 -283.525245) (xy 427.255178 -283.549852)
			(xy 427.594026 -283.549852) (xy 427.597986 -283.500798) (xy 427.609763 -283.453014) (xy 427.629054 -283.407738)
			(xy 427.655357 -283.366142) (xy 427.687992 -283.329305) (xy 427.726113 -283.29818) (xy 427.768734 -283.273573)
			(xy 427.81475 -283.256121) (xy 427.862969 -283.246277) (xy 427.912144 -283.244296) (xy 427.960999 -283.250228)
			(xy 428.00827 -283.26392) (xy 428.052732 -283.285018) (xy 428.093235 -283.312974) (xy 428.128728 -283.347066)
			(xy 428.158293 -283.38641) (xy 428.181164 -283.429987) (xy 428.196748 -283.476668) (xy 428.204643 -283.525245)
			(xy 428.205138 -283.549852) (xy 428.543986 -283.549852) (xy 428.547946 -283.500798) (xy 428.559723 -283.453014)
			(xy 428.579014 -283.407738) (xy 428.605317 -283.366142) (xy 428.637952 -283.329305) (xy 428.676073 -283.29818)
			(xy 428.718694 -283.273573) (xy 428.76471 -283.256121) (xy 428.812929 -283.246277) (xy 428.862104 -283.244296)
			(xy 428.910959 -283.250228) (xy 428.95823 -283.26392) (xy 429.002692 -283.285018) (xy 429.043195 -283.312974)
			(xy 429.078688 -283.347066) (xy 429.108253 -283.38641) (xy 429.131124 -283.429987) (xy 429.146708 -283.476668)
			(xy 429.154603 -283.525245) (xy 429.155098 -283.549852) (xy 429.154603 -283.574459) (xy 429.154424 -283.57556)
			(xy 429.473356 -283.57556) (xy 429.473356 -283.524144) (xy 429.481399 -283.473362) (xy 429.497287 -283.424463)
			(xy 429.52063 -283.378651) (xy 429.550851 -283.337055) (xy 429.587207 -283.300699) (xy 429.628803 -283.270478)
			(xy 429.674615 -283.247135) (xy 429.723514 -283.231247) (xy 429.774296 -283.223204) (xy 429.825712 -283.223204)
			(xy 429.876494 -283.231247) (xy 429.925393 -283.247135) (xy 429.971205 -283.270478) (xy 430.012801 -283.300699)
			(xy 430.049157 -283.337055) (xy 430.079378 -283.378651) (xy 430.102721 -283.424463) (xy 430.118609 -283.473362)
			(xy 430.126652 -283.524144) (xy 430.127156 -283.549852) (xy 430.126652 -283.57556) (xy 430.423316 -283.57556)
			(xy 430.423316 -283.524144) (xy 430.431359 -283.473362) (xy 430.447247 -283.424463) (xy 430.47059 -283.378651)
			(xy 430.500811 -283.337055) (xy 430.537167 -283.300699) (xy 430.578763 -283.270478) (xy 430.624575 -283.247135)
			(xy 430.673474 -283.231247) (xy 430.724256 -283.223204) (xy 430.775672 -283.223204) (xy 430.826454 -283.231247)
			(xy 430.875353 -283.247135) (xy 430.921165 -283.270478) (xy 430.962761 -283.300699) (xy 430.999117 -283.337055)
			(xy 431.029338 -283.378651) (xy 431.052681 -283.424463) (xy 431.068569 -283.473362) (xy 431.076612 -283.524144)
			(xy 431.077116 -283.549852) (xy 431.077111 -283.550106) (xy 431.394374 -283.550106) (xy 431.398334 -283.501052)
			(xy 431.410111 -283.453268) (xy 431.429402 -283.407992) (xy 431.455705 -283.366396) (xy 431.48834 -283.329559)
			(xy 431.526461 -283.298434) (xy 431.569082 -283.273827) (xy 431.615098 -283.256375) (xy 431.663317 -283.246531)
			(xy 431.712492 -283.24455) (xy 431.761347 -283.250482) (xy 431.808618 -283.264174) (xy 431.85308 -283.285272)
			(xy 431.893583 -283.313228) (xy 431.929076 -283.34732) (xy 431.958641 -283.386664) (xy 431.981512 -283.430241)
			(xy 431.997096 -283.476922) (xy 432.004991 -283.525499) (xy 432.005036 -283.527754) (xy 442.093858 -283.527754)
			(xy 442.094335 -283.500503) (xy 442.102097 -283.446557) (xy 442.117456 -283.394264) (xy 442.1401 -283.344689)
			(xy 442.169568 -283.29884) (xy 442.20526 -283.257652) (xy 442.24645 -283.221961) (xy 442.292299 -283.192494)
			(xy 442.341875 -283.169852) (xy 442.394169 -283.154494) (xy 442.448115 -283.146734) (xy 442.475366 -283.146246)
			(xy 442.502736 -283.146721) (xy 442.556915 -283.154535) (xy 442.609419 -283.170021) (xy 442.659166 -283.192861)
			(xy 442.705132 -283.222585) (xy 442.726064 -283.240226) (xy 442.726318 -283.24048) (xy 442.733388 -283.24609)
			(xy 442.750318 -283.25232) (xy 442.759338 -283.252672) (xy 442.826394 -283.252672) (xy 442.835411 -283.252318)
			(xy 442.852329 -283.246069) (xy 442.859414 -283.24048) (xy 442.859922 -283.239972) (xy 442.880863 -283.222398)
			(xy 442.926796 -283.192758) (xy 442.97649 -283.169979) (xy 443.028927 -283.154526) (xy 443.083033 -283.146718)
			(xy 443.110366 -283.146246) (xy 443.137614 -283.14681) (xy 443.191557 -283.15456) (xy 443.243847 -283.169909)
			(xy 443.293421 -283.192543) (xy 443.33927 -283.222001) (xy 443.380459 -283.257684) (xy 443.416151 -283.298866)
			(xy 443.445619 -283.344709) (xy 443.468263 -283.394278) (xy 443.483623 -283.446565) (xy 443.491385 -283.500506)
			(xy 443.491874 -283.527754) (xy 443.49149 -283.554179) (xy 443.484188 -283.606523) (xy 443.469732 -283.657358)
			(xy 443.448398 -283.705712) (xy 443.420594 -283.750658) (xy 443.386853 -283.791337) (xy 443.34782 -283.826969)
			(xy 443.304244 -283.856874) (xy 443.256957 -283.880477) (xy 443.206864 -283.897328) (xy 443.180978 -283.902658)
			(xy 443.169161 -283.905551) (xy 443.149938 -283.920406) (xy 443.144148 -283.931106) (xy 443.10935 -284.006036)
			(xy 443.104836 -284.017252) (xy 443.105616 -284.041379) (xy 443.110874 -284.052264) (xy 443.111128 -284.052518)
			(xy 443.122831 -284.074052) (xy 443.14127 -284.119461) (xy 443.153736 -284.166859) (xy 443.160023 -284.215465)
			(xy 443.160404 -284.23997) (xy 443.159918 -284.267221) (xy 443.152162 -284.321169) (xy 443.136807 -284.373464)
			(xy 443.114165 -284.423041) (xy 443.084699 -284.468891) (xy 443.049008 -284.510082) (xy 443.007817 -284.545773)
			(xy 442.961967 -284.575239) (xy 442.91239 -284.597881) (xy 442.860095 -284.613236) (xy 442.806147 -284.620992)
			(xy 442.751645 -284.620992) (xy 442.697697 -284.613236) (xy 442.645402 -284.597881) (xy 442.595825 -284.575239)
			(xy 442.549975 -284.545773) (xy 442.508784 -284.510082) (xy 442.473093 -284.468891) (xy 442.443627 -284.423041)
			(xy 442.420985 -284.373464) (xy 442.40563 -284.321169) (xy 442.397874 -284.267221) (xy 442.397388 -284.23997)
			(xy 442.397388 -284.239462) (xy 442.397785 -284.214404) (xy 442.404389 -284.164723) (xy 442.41744 -284.116334)
			(xy 442.436711 -284.07007) (xy 442.44895 -284.0482) (xy 442.455046 -284.037786) (xy 442.45657 -284.014164)
			(xy 442.419994 -283.927804) (xy 442.414803 -283.917263) (xy 442.396937 -283.902042) (xy 442.385704 -283.898594)
			(xy 442.385196 -283.89834) (xy 442.384942 -283.89834) (xy 442.35764 -283.891131) (xy 442.305349 -283.869824)
			(xy 442.256771 -283.841039) (xy 442.212969 -283.805405) (xy 442.174901 -283.763702) (xy 442.143398 -283.716842)
			(xy 442.119149 -283.665848) (xy 442.102685 -283.611836) (xy 442.094365 -283.555987) (xy 442.093858 -283.527754)
			(xy 432.005036 -283.527754) (xy 432.005486 -283.550106) (xy 432.004991 -283.574713) (xy 431.997096 -283.62329)
			(xy 431.981512 -283.669971) (xy 431.958641 -283.713548) (xy 431.929076 -283.752892) (xy 431.893583 -283.786984)
			(xy 431.85308 -283.81494) (xy 431.808618 -283.836038) (xy 431.761347 -283.84973) (xy 431.712492 -283.855662)
			(xy 431.663317 -283.853681) (xy 431.615098 -283.843837) (xy 431.569082 -283.826385) (xy 431.526461 -283.801778)
			(xy 431.48834 -283.770653) (xy 431.455705 -283.733816) (xy 431.429402 -283.69222) (xy 431.410111 -283.646944)
			(xy 431.398334 -283.59916) (xy 431.394374 -283.550106) (xy 431.077111 -283.550106) (xy 431.076612 -283.57556)
			(xy 431.068569 -283.626342) (xy 431.052681 -283.675241) (xy 431.029338 -283.721053) (xy 430.999117 -283.762649)
			(xy 430.962761 -283.799005) (xy 430.921165 -283.829226) (xy 430.875353 -283.852569) (xy 430.826454 -283.868457)
			(xy 430.775672 -283.8765) (xy 430.724256 -283.8765) (xy 430.673474 -283.868457) (xy 430.624575 -283.852569)
			(xy 430.578763 -283.829226) (xy 430.537167 -283.799005) (xy 430.500811 -283.762649) (xy 430.47059 -283.721053)
			(xy 430.447247 -283.675241) (xy 430.431359 -283.626342) (xy 430.423316 -283.57556) (xy 430.126652 -283.57556)
			(xy 430.118609 -283.626342) (xy 430.102721 -283.675241) (xy 430.079378 -283.721053) (xy 430.049157 -283.762649)
			(xy 430.012801 -283.799005) (xy 429.971205 -283.829226) (xy 429.925393 -283.852569) (xy 429.876494 -283.868457)
			(xy 429.825712 -283.8765) (xy 429.774296 -283.8765) (xy 429.723514 -283.868457) (xy 429.674615 -283.852569)
			(xy 429.628803 -283.829226) (xy 429.587207 -283.799005) (xy 429.550851 -283.762649) (xy 429.52063 -283.721053)
			(xy 429.497287 -283.675241) (xy 429.481399 -283.626342) (xy 429.473356 -283.57556) (xy 429.154424 -283.57556)
			(xy 429.146708 -283.623036) (xy 429.131124 -283.669717) (xy 429.108253 -283.713294) (xy 429.078688 -283.752638)
			(xy 429.043195 -283.78673) (xy 429.002692 -283.814686) (xy 428.95823 -283.835784) (xy 428.910959 -283.849476)
			(xy 428.862104 -283.855408) (xy 428.812929 -283.853427) (xy 428.76471 -283.843583) (xy 428.718694 -283.826131)
			(xy 428.676073 -283.801524) (xy 428.637952 -283.770399) (xy 428.605317 -283.733562) (xy 428.579014 -283.691966)
			(xy 428.559723 -283.64669) (xy 428.547946 -283.598906) (xy 428.543986 -283.549852) (xy 428.205138 -283.549852)
			(xy 428.204643 -283.574459) (xy 428.196748 -283.623036) (xy 428.181164 -283.669717) (xy 428.158293 -283.713294)
			(xy 428.128728 -283.752638) (xy 428.093235 -283.78673) (xy 428.052732 -283.814686) (xy 428.00827 -283.835784)
			(xy 427.960999 -283.849476) (xy 427.912144 -283.855408) (xy 427.862969 -283.853427) (xy 427.81475 -283.843583)
			(xy 427.768734 -283.826131) (xy 427.726113 -283.801524) (xy 427.687992 -283.770399) (xy 427.655357 -283.733562)
			(xy 427.629054 -283.691966) (xy 427.609763 -283.64669) (xy 427.597986 -283.598906) (xy 427.594026 -283.549852)
			(xy 427.255178 -283.549852) (xy 427.254683 -283.574459) (xy 427.246788 -283.623036) (xy 427.231204 -283.669717)
			(xy 427.208333 -283.713294) (xy 427.178768 -283.752638) (xy 427.143275 -283.78673) (xy 427.102772 -283.814686)
			(xy 427.05831 -283.835784) (xy 427.011039 -283.849476) (xy 426.962184 -283.855408) (xy 426.913009 -283.853427)
			(xy 426.86479 -283.843583) (xy 426.818774 -283.826131) (xy 426.776153 -283.801524) (xy 426.738032 -283.770399)
			(xy 426.705397 -283.733562) (xy 426.679094 -283.691966) (xy 426.659803 -283.64669) (xy 426.648026 -283.598906)
			(xy 426.644066 -283.549852) (xy 426.305218 -283.549852) (xy 426.304723 -283.574459) (xy 426.296828 -283.623036)
			(xy 426.281244 -283.669717) (xy 426.258373 -283.713294) (xy 426.228808 -283.752638) (xy 426.193315 -283.78673)
			(xy 426.152812 -283.814686) (xy 426.10835 -283.835784) (xy 426.061079 -283.849476) (xy 426.012224 -283.855408)
			(xy 425.963049 -283.853427) (xy 425.91483 -283.843583) (xy 425.868814 -283.826131) (xy 425.826193 -283.801524)
			(xy 425.788072 -283.770399) (xy 425.755437 -283.733562) (xy 425.729134 -283.691966) (xy 425.709843 -283.64669)
			(xy 425.698066 -283.598906) (xy 425.694106 -283.549852) (xy 425.355258 -283.549852) (xy 425.354763 -283.574459)
			(xy 425.346868 -283.623036) (xy 425.331284 -283.669717) (xy 425.308413 -283.713294) (xy 425.278848 -283.752638)
			(xy 425.243355 -283.78673) (xy 425.202852 -283.814686) (xy 425.15839 -283.835784) (xy 425.111119 -283.849476)
			(xy 425.062264 -283.855408) (xy 425.013089 -283.853427) (xy 424.96487 -283.843583) (xy 424.918854 -283.826131)
			(xy 424.876233 -283.801524) (xy 424.838112 -283.770399) (xy 424.805477 -283.733562) (xy 424.779174 -283.691966)
			(xy 424.759883 -283.64669) (xy 424.748106 -283.598906) (xy 424.744146 -283.549852) (xy 424.405298 -283.549852)
			(xy 424.404803 -283.574459) (xy 424.396908 -283.623036) (xy 424.381324 -283.669717) (xy 424.358453 -283.713294)
			(xy 424.328888 -283.752638) (xy 424.293395 -283.78673) (xy 424.252892 -283.814686) (xy 424.20843 -283.835784)
			(xy 424.161159 -283.849476) (xy 424.112304 -283.855408) (xy 424.063129 -283.853427) (xy 424.01491 -283.843583)
			(xy 423.968894 -283.826131) (xy 423.926273 -283.801524) (xy 423.888152 -283.770399) (xy 423.855517 -283.733562)
			(xy 423.829214 -283.691966) (xy 423.809923 -283.64669) (xy 423.798146 -283.598906) (xy 423.794186 -283.549852)
			(xy 423.455084 -283.549852) (xy 423.454589 -283.574459) (xy 423.446694 -283.623036) (xy 423.43111 -283.669717)
			(xy 423.408239 -283.713294) (xy 423.378674 -283.752638) (xy 423.343181 -283.78673) (xy 423.302678 -283.814686)
			(xy 423.258216 -283.835784) (xy 423.210945 -283.849476) (xy 423.16209 -283.855408) (xy 423.112915 -283.853427)
			(xy 423.064696 -283.843583) (xy 423.01868 -283.826131) (xy 422.976059 -283.801524) (xy 422.937938 -283.770399)
			(xy 422.905303 -283.733562) (xy 422.879 -283.691966) (xy 422.859709 -283.64669) (xy 422.847932 -283.598906)
			(xy 422.843972 -283.549852) (xy 422.505124 -283.549852) (xy 422.504629 -283.574459) (xy 422.496734 -283.623036)
			(xy 422.48115 -283.669717) (xy 422.458279 -283.713294) (xy 422.428714 -283.752638) (xy 422.393221 -283.78673)
			(xy 422.352718 -283.814686) (xy 422.308256 -283.835784) (xy 422.260985 -283.849476) (xy 422.21213 -283.855408)
			(xy 422.162955 -283.853427) (xy 422.114736 -283.843583) (xy 422.06872 -283.826131) (xy 422.026099 -283.801524)
			(xy 421.987978 -283.770399) (xy 421.955343 -283.733562) (xy 421.92904 -283.691966) (xy 421.909749 -283.64669)
			(xy 421.897972 -283.598906) (xy 421.894012 -283.549852) (xy 396.55369 -283.549852) (xy 396.55369 -284.024832)
			(xy 396.719056 -284.024832) (xy 396.723016 -283.975778) (xy 396.734793 -283.927994) (xy 396.754084 -283.882718)
			(xy 396.780387 -283.841122) (xy 396.813022 -283.804285) (xy 396.851143 -283.77316) (xy 396.893764 -283.748553)
			(xy 396.93978 -283.731101) (xy 396.987999 -283.721257) (xy 397.037174 -283.719276) (xy 397.086029 -283.725208)
			(xy 397.1333 -283.7389) (xy 397.177762 -283.759998) (xy 397.218265 -283.787954) (xy 397.253758 -283.822046)
			(xy 397.283323 -283.86139) (xy 397.306194 -283.904967) (xy 397.321778 -283.951648) (xy 397.329673 -284.000225)
			(xy 397.330168 -284.024832) (xy 397.669016 -284.024832) (xy 397.672976 -283.975778) (xy 397.684753 -283.927994)
			(xy 397.704044 -283.882718) (xy 397.730347 -283.841122) (xy 397.762982 -283.804285) (xy 397.801103 -283.77316)
			(xy 397.843724 -283.748553) (xy 397.88974 -283.731101) (xy 397.937959 -283.721257) (xy 397.987134 -283.719276)
			(xy 398.035989 -283.725208) (xy 398.08326 -283.7389) (xy 398.127722 -283.759998) (xy 398.168225 -283.787954)
			(xy 398.203718 -283.822046) (xy 398.233283 -283.86139) (xy 398.256154 -283.904967) (xy 398.271738 -283.951648)
			(xy 398.279633 -284.000225) (xy 398.280128 -284.024832) (xy 398.61923 -284.024832) (xy 398.62319 -283.975778)
			(xy 398.634967 -283.927994) (xy 398.654258 -283.882718) (xy 398.680561 -283.841122) (xy 398.713196 -283.804285)
			(xy 398.751317 -283.77316) (xy 398.793938 -283.748553) (xy 398.839954 -283.731101) (xy 398.888173 -283.721257)
			(xy 398.937348 -283.719276) (xy 398.986203 -283.725208) (xy 399.033474 -283.7389) (xy 399.077936 -283.759998)
			(xy 399.118439 -283.787954) (xy 399.153932 -283.822046) (xy 399.183497 -283.86139) (xy 399.206368 -283.904967)
			(xy 399.221952 -283.951648) (xy 399.229847 -284.000225) (xy 399.230342 -284.024832) (xy 399.56919 -284.024832)
			(xy 399.57315 -283.975778) (xy 399.584927 -283.927994) (xy 399.604218 -283.882718) (xy 399.630521 -283.841122)
			(xy 399.663156 -283.804285) (xy 399.701277 -283.77316) (xy 399.743898 -283.748553) (xy 399.789914 -283.731101)
			(xy 399.838133 -283.721257) (xy 399.887308 -283.719276) (xy 399.936163 -283.725208) (xy 399.983434 -283.7389)
			(xy 400.027896 -283.759998) (xy 400.068399 -283.787954) (xy 400.103892 -283.822046) (xy 400.133457 -283.86139)
			(xy 400.156328 -283.904967) (xy 400.171912 -283.951648) (xy 400.179807 -284.000225) (xy 400.180302 -284.024832)
			(xy 400.51915 -284.024832) (xy 400.52311 -283.975778) (xy 400.534887 -283.927994) (xy 400.554178 -283.882718)
			(xy 400.580481 -283.841122) (xy 400.613116 -283.804285) (xy 400.651237 -283.77316) (xy 400.693858 -283.748553)
			(xy 400.739874 -283.731101) (xy 400.788093 -283.721257) (xy 400.837268 -283.719276) (xy 400.886123 -283.725208)
			(xy 400.933394 -283.7389) (xy 400.977856 -283.759998) (xy 401.018359 -283.787954) (xy 401.053852 -283.822046)
			(xy 401.083417 -283.86139) (xy 401.106288 -283.904967) (xy 401.121872 -283.951648) (xy 401.129767 -284.000225)
			(xy 401.130262 -284.024832) (xy 401.46911 -284.024832) (xy 401.47307 -283.975778) (xy 401.484847 -283.927994)
			(xy 401.504138 -283.882718) (xy 401.530441 -283.841122) (xy 401.563076 -283.804285) (xy 401.601197 -283.77316)
			(xy 401.643818 -283.748553) (xy 401.689834 -283.731101) (xy 401.738053 -283.721257) (xy 401.787228 -283.719276)
			(xy 401.836083 -283.725208) (xy 401.883354 -283.7389) (xy 401.927816 -283.759998) (xy 401.968319 -283.787954)
			(xy 402.003812 -283.822046) (xy 402.033377 -283.86139) (xy 402.056248 -283.904967) (xy 402.071832 -283.951648)
			(xy 402.079727 -284.000225) (xy 402.080222 -284.024832) (xy 402.41907 -284.024832) (xy 402.42303 -283.975778)
			(xy 402.434807 -283.927994) (xy 402.454098 -283.882718) (xy 402.480401 -283.841122) (xy 402.513036 -283.804285)
			(xy 402.551157 -283.77316) (xy 402.593778 -283.748553) (xy 402.639794 -283.731101) (xy 402.688013 -283.721257)
			(xy 402.737188 -283.719276) (xy 402.786043 -283.725208) (xy 402.833314 -283.7389) (xy 402.877776 -283.759998)
			(xy 402.918279 -283.787954) (xy 402.953772 -283.822046) (xy 402.983337 -283.86139) (xy 403.006208 -283.904967)
			(xy 403.021792 -283.951648) (xy 403.029687 -284.000225) (xy 403.030182 -284.024832) (xy 403.36903 -284.024832)
			(xy 403.37299 -283.975778) (xy 403.384767 -283.927994) (xy 403.404058 -283.882718) (xy 403.430361 -283.841122)
			(xy 403.462996 -283.804285) (xy 403.501117 -283.77316) (xy 403.543738 -283.748553) (xy 403.589754 -283.731101)
			(xy 403.637973 -283.721257) (xy 403.687148 -283.719276) (xy 403.736003 -283.725208) (xy 403.783274 -283.7389)
			(xy 403.827736 -283.759998) (xy 403.868239 -283.787954) (xy 403.903732 -283.822046) (xy 403.933297 -283.86139)
			(xy 403.956168 -283.904967) (xy 403.971752 -283.951648) (xy 403.979647 -284.000225) (xy 403.980142 -284.024832)
			(xy 404.31899 -284.024832) (xy 404.32295 -283.975778) (xy 404.334727 -283.927994) (xy 404.354018 -283.882718)
			(xy 404.380321 -283.841122) (xy 404.412956 -283.804285) (xy 404.451077 -283.77316) (xy 404.493698 -283.748553)
			(xy 404.539714 -283.731101) (xy 404.587933 -283.721257) (xy 404.637108 -283.719276) (xy 404.685963 -283.725208)
			(xy 404.733234 -283.7389) (xy 404.777696 -283.759998) (xy 404.818199 -283.787954) (xy 404.853692 -283.822046)
			(xy 404.883257 -283.86139) (xy 404.906128 -283.904967) (xy 404.921712 -283.951648) (xy 404.929607 -284.000225)
			(xy 404.930102 -284.024832) (xy 405.269204 -284.024832) (xy 405.273164 -283.975778) (xy 405.284941 -283.927994)
			(xy 405.304232 -283.882718) (xy 405.330535 -283.841122) (xy 405.36317 -283.804285) (xy 405.401291 -283.77316)
			(xy 405.443912 -283.748553) (xy 405.489928 -283.731101) (xy 405.538147 -283.721257) (xy 405.587322 -283.719276)
			(xy 405.636177 -283.725208) (xy 405.683448 -283.7389) (xy 405.72791 -283.759998) (xy 405.768413 -283.787954)
			(xy 405.803906 -283.822046) (xy 405.833471 -283.86139) (xy 405.856342 -283.904967) (xy 405.871926 -283.951648)
			(xy 405.879821 -284.000225) (xy 405.880316 -284.024832) (xy 406.219164 -284.024832) (xy 406.223124 -283.975778)
			(xy 406.234901 -283.927994) (xy 406.254192 -283.882718) (xy 406.280495 -283.841122) (xy 406.31313 -283.804285)
			(xy 406.351251 -283.77316) (xy 406.393872 -283.748553) (xy 406.439888 -283.731101) (xy 406.488107 -283.721257)
			(xy 406.537282 -283.719276) (xy 406.586137 -283.725208) (xy 406.633408 -283.7389) (xy 406.67787 -283.759998)
			(xy 406.718373 -283.787954) (xy 406.753866 -283.822046) (xy 406.783431 -283.86139) (xy 406.806302 -283.904967)
			(xy 406.821886 -283.951648) (xy 406.829781 -284.000225) (xy 406.830276 -284.024832) (xy 408.119084 -284.024832)
			(xy 408.123044 -283.975778) (xy 408.134821 -283.927994) (xy 408.154112 -283.882718) (xy 408.180415 -283.841122)
			(xy 408.21305 -283.804285) (xy 408.251171 -283.77316) (xy 408.293792 -283.748553) (xy 408.339808 -283.731101)
			(xy 408.388027 -283.721257) (xy 408.437202 -283.719276) (xy 408.486057 -283.725208) (xy 408.533328 -283.7389)
			(xy 408.57779 -283.759998) (xy 408.618293 -283.787954) (xy 408.653786 -283.822046) (xy 408.683351 -283.86139)
			(xy 408.706222 -283.904967) (xy 408.721806 -283.951648) (xy 408.729701 -284.000225) (xy 408.730196 -284.024832)
			(xy 409.069044 -284.024832) (xy 409.073004 -283.975778) (xy 409.084781 -283.927994) (xy 409.104072 -283.882718)
			(xy 409.130375 -283.841122) (xy 409.16301 -283.804285) (xy 409.201131 -283.77316) (xy 409.243752 -283.748553)
			(xy 409.289768 -283.731101) (xy 409.337987 -283.721257) (xy 409.387162 -283.719276) (xy 409.436017 -283.725208)
			(xy 409.483288 -283.7389) (xy 409.52775 -283.759998) (xy 409.568253 -283.787954) (xy 409.603746 -283.822046)
			(xy 409.633311 -283.86139) (xy 409.656182 -283.904967) (xy 409.671766 -283.951648) (xy 409.679661 -284.000225)
			(xy 409.680156 -284.024832) (xy 410.019004 -284.024832) (xy 410.022964 -283.975778) (xy 410.034741 -283.927994)
			(xy 410.054032 -283.882718) (xy 410.080335 -283.841122) (xy 410.11297 -283.804285) (xy 410.151091 -283.77316)
			(xy 410.193712 -283.748553) (xy 410.239728 -283.731101) (xy 410.287947 -283.721257) (xy 410.337122 -283.719276)
			(xy 410.385977 -283.725208) (xy 410.433248 -283.7389) (xy 410.47771 -283.759998) (xy 410.518213 -283.787954)
			(xy 410.553706 -283.822046) (xy 410.583271 -283.86139) (xy 410.606142 -283.904967) (xy 410.621726 -283.951648)
			(xy 410.629621 -284.000225) (xy 410.630116 -284.024832) (xy 410.969218 -284.024832) (xy 410.973178 -283.975778)
			(xy 410.984955 -283.927994) (xy 411.004246 -283.882718) (xy 411.030549 -283.841122) (xy 411.063184 -283.804285)
			(xy 411.101305 -283.77316) (xy 411.143926 -283.748553) (xy 411.189942 -283.731101) (xy 411.238161 -283.721257)
			(xy 411.287336 -283.719276) (xy 411.336191 -283.725208) (xy 411.383462 -283.7389) (xy 411.427924 -283.759998)
			(xy 411.468427 -283.787954) (xy 411.50392 -283.822046) (xy 411.533485 -283.86139) (xy 411.556356 -283.904967)
			(xy 411.57194 -283.951648) (xy 411.579835 -284.000225) (xy 411.58033 -284.024832) (xy 411.919178 -284.024832)
			(xy 411.923138 -283.975778) (xy 411.934915 -283.927994) (xy 411.954206 -283.882718) (xy 411.980509 -283.841122)
			(xy 412.013144 -283.804285) (xy 412.051265 -283.77316) (xy 412.093886 -283.748553) (xy 412.139902 -283.731101)
			(xy 412.188121 -283.721257) (xy 412.237296 -283.719276) (xy 412.286151 -283.725208) (xy 412.333422 -283.7389)
			(xy 412.377884 -283.759998) (xy 412.418387 -283.787954) (xy 412.45388 -283.822046) (xy 412.483445 -283.86139)
			(xy 412.506316 -283.904967) (xy 412.5219 -283.951648) (xy 412.529795 -284.000225) (xy 412.53029 -284.024832)
			(xy 412.869138 -284.024832) (xy 412.873098 -283.975778) (xy 412.884875 -283.927994) (xy 412.904166 -283.882718)
			(xy 412.930469 -283.841122) (xy 412.963104 -283.804285) (xy 413.001225 -283.77316) (xy 413.043846 -283.748553)
			(xy 413.089862 -283.731101) (xy 413.138081 -283.721257) (xy 413.187256 -283.719276) (xy 413.236111 -283.725208)
			(xy 413.283382 -283.7389) (xy 413.327844 -283.759998) (xy 413.368347 -283.787954) (xy 413.40384 -283.822046)
			(xy 413.433405 -283.86139) (xy 413.456276 -283.904967) (xy 413.47186 -283.951648) (xy 413.479755 -284.000225)
			(xy 413.48025 -284.024832) (xy 413.819098 -284.024832) (xy 413.823058 -283.975778) (xy 413.834835 -283.927994)
			(xy 413.854126 -283.882718) (xy 413.880429 -283.841122) (xy 413.913064 -283.804285) (xy 413.951185 -283.77316)
			(xy 413.993806 -283.748553) (xy 414.039822 -283.731101) (xy 414.088041 -283.721257) (xy 414.137216 -283.719276)
			(xy 414.186071 -283.725208) (xy 414.233342 -283.7389) (xy 414.277804 -283.759998) (xy 414.318307 -283.787954)
			(xy 414.3538 -283.822046) (xy 414.383365 -283.86139) (xy 414.406236 -283.904967) (xy 414.42182 -283.951648)
			(xy 414.429715 -284.000225) (xy 414.43021 -284.024832) (xy 414.769058 -284.024832) (xy 414.773018 -283.975778)
			(xy 414.784795 -283.927994) (xy 414.804086 -283.882718) (xy 414.830389 -283.841122) (xy 414.863024 -283.804285)
			(xy 414.901145 -283.77316) (xy 414.943766 -283.748553) (xy 414.989782 -283.731101) (xy 415.038001 -283.721257)
			(xy 415.087176 -283.719276) (xy 415.136031 -283.725208) (xy 415.183302 -283.7389) (xy 415.227764 -283.759998)
			(xy 415.268267 -283.787954) (xy 415.30376 -283.822046) (xy 415.333325 -283.86139) (xy 415.356196 -283.904967)
			(xy 415.37178 -283.951648) (xy 415.379675 -284.000225) (xy 415.38017 -284.024832) (xy 415.719018 -284.024832)
			(xy 415.722978 -283.975778) (xy 415.734755 -283.927994) (xy 415.754046 -283.882718) (xy 415.780349 -283.841122)
			(xy 415.812984 -283.804285) (xy 415.851105 -283.77316) (xy 415.893726 -283.748553) (xy 415.939742 -283.731101)
			(xy 415.987961 -283.721257) (xy 416.037136 -283.719276) (xy 416.085991 -283.725208) (xy 416.133262 -283.7389)
			(xy 416.177724 -283.759998) (xy 416.218227 -283.787954) (xy 416.25372 -283.822046) (xy 416.283285 -283.86139)
			(xy 416.306156 -283.904967) (xy 416.32174 -283.951648) (xy 416.329635 -284.000225) (xy 416.33013 -284.024832)
			(xy 416.668978 -284.024832) (xy 416.672938 -283.975778) (xy 416.684715 -283.927994) (xy 416.704006 -283.882718)
			(xy 416.730309 -283.841122) (xy 416.762944 -283.804285) (xy 416.801065 -283.77316) (xy 416.843686 -283.748553)
			(xy 416.889702 -283.731101) (xy 416.937921 -283.721257) (xy 416.987096 -283.719276) (xy 417.035951 -283.725208)
			(xy 417.083222 -283.7389) (xy 417.127684 -283.759998) (xy 417.168187 -283.787954) (xy 417.20368 -283.822046)
			(xy 417.233245 -283.86139) (xy 417.256116 -283.904967) (xy 417.2717 -283.951648) (xy 417.279595 -284.000225)
			(xy 417.28009 -284.024832) (xy 417.619192 -284.024832) (xy 417.623152 -283.975778) (xy 417.634929 -283.927994)
			(xy 417.65422 -283.882718) (xy 417.680523 -283.841122) (xy 417.713158 -283.804285) (xy 417.751279 -283.77316)
			(xy 417.7939 -283.748553) (xy 417.839916 -283.731101) (xy 417.888135 -283.721257) (xy 417.93731 -283.719276)
			(xy 417.986165 -283.725208) (xy 418.033436 -283.7389) (xy 418.077898 -283.759998) (xy 418.118401 -283.787954)
			(xy 418.153894 -283.822046) (xy 418.183459 -283.86139) (xy 418.20633 -283.904967) (xy 418.221914 -283.951648)
			(xy 418.229809 -284.000225) (xy 418.230304 -284.024832) (xy 418.569152 -284.024832) (xy 418.573112 -283.975778)
			(xy 418.584889 -283.927994) (xy 418.60418 -283.882718) (xy 418.630483 -283.841122) (xy 418.663118 -283.804285)
			(xy 418.701239 -283.77316) (xy 418.74386 -283.748553) (xy 418.789876 -283.731101) (xy 418.838095 -283.721257)
			(xy 418.88727 -283.719276) (xy 418.936125 -283.725208) (xy 418.983396 -283.7389) (xy 419.027858 -283.759998)
			(xy 419.068361 -283.787954) (xy 419.103854 -283.822046) (xy 419.133419 -283.86139) (xy 419.15629 -283.904967)
			(xy 419.171874 -283.951648) (xy 419.179769 -284.000225) (xy 419.180264 -284.024832) (xy 419.519112 -284.024832)
			(xy 419.523072 -283.975778) (xy 419.534849 -283.927994) (xy 419.55414 -283.882718) (xy 419.580443 -283.841122)
			(xy 419.613078 -283.804285) (xy 419.651199 -283.77316) (xy 419.69382 -283.748553) (xy 419.739836 -283.731101)
			(xy 419.788055 -283.721257) (xy 419.83723 -283.719276) (xy 419.886085 -283.725208) (xy 419.933356 -283.7389)
			(xy 419.977818 -283.759998) (xy 420.018321 -283.787954) (xy 420.053814 -283.822046) (xy 420.083379 -283.86139)
			(xy 420.10625 -283.904967) (xy 420.121834 -283.951648) (xy 420.129729 -284.000225) (xy 420.130224 -284.024832)
			(xy 420.469072 -284.024832) (xy 420.473032 -283.975778) (xy 420.484809 -283.927994) (xy 420.5041 -283.882718)
			(xy 420.530403 -283.841122) (xy 420.563038 -283.804285) (xy 420.601159 -283.77316) (xy 420.64378 -283.748553)
			(xy 420.689796 -283.731101) (xy 420.738015 -283.721257) (xy 420.78719 -283.719276) (xy 420.836045 -283.725208)
			(xy 420.883316 -283.7389) (xy 420.927778 -283.759998) (xy 420.968281 -283.787954) (xy 421.003774 -283.822046)
			(xy 421.033339 -283.86139) (xy 421.05621 -283.904967) (xy 421.071794 -283.951648) (xy 421.079689 -284.000225)
			(xy 421.080184 -284.024832) (xy 421.079689 -284.049439) (xy 421.071794 -284.098016) (xy 421.05621 -284.144697)
			(xy 421.033339 -284.188274) (xy 421.003774 -284.227618) (xy 420.968281 -284.26171) (xy 420.927778 -284.289666)
			(xy 420.883316 -284.310764) (xy 420.836045 -284.324456) (xy 420.78719 -284.330388) (xy 420.738015 -284.328407)
			(xy 420.689796 -284.318563) (xy 420.64378 -284.301111) (xy 420.601159 -284.276504) (xy 420.563038 -284.245379)
			(xy 420.530403 -284.208542) (xy 420.5041 -284.166946) (xy 420.484809 -284.12167) (xy 420.473032 -284.073886)
			(xy 420.469072 -284.024832) (xy 420.130224 -284.024832) (xy 420.129729 -284.049439) (xy 420.121834 -284.098016)
			(xy 420.10625 -284.144697) (xy 420.083379 -284.188274) (xy 420.053814 -284.227618) (xy 420.018321 -284.26171)
			(xy 419.977818 -284.289666) (xy 419.933356 -284.310764) (xy 419.886085 -284.324456) (xy 419.83723 -284.330388)
			(xy 419.788055 -284.328407) (xy 419.739836 -284.318563) (xy 419.69382 -284.301111) (xy 419.651199 -284.276504)
			(xy 419.613078 -284.245379) (xy 419.580443 -284.208542) (xy 419.55414 -284.166946) (xy 419.534849 -284.12167)
			(xy 419.523072 -284.073886) (xy 419.519112 -284.024832) (xy 419.180264 -284.024832) (xy 419.179769 -284.049439)
			(xy 419.171874 -284.098016) (xy 419.15629 -284.144697) (xy 419.133419 -284.188274) (xy 419.103854 -284.227618)
			(xy 419.068361 -284.26171) (xy 419.027858 -284.289666) (xy 418.983396 -284.310764) (xy 418.936125 -284.324456)
			(xy 418.88727 -284.330388) (xy 418.838095 -284.328407) (xy 418.789876 -284.318563) (xy 418.74386 -284.301111)
			(xy 418.701239 -284.276504) (xy 418.663118 -284.245379) (xy 418.630483 -284.208542) (xy 418.60418 -284.166946)
			(xy 418.584889 -284.12167) (xy 418.573112 -284.073886) (xy 418.569152 -284.024832) (xy 418.230304 -284.024832)
			(xy 418.229809 -284.049439) (xy 418.221914 -284.098016) (xy 418.20633 -284.144697) (xy 418.183459 -284.188274)
			(xy 418.153894 -284.227618) (xy 418.118401 -284.26171) (xy 418.077898 -284.289666) (xy 418.033436 -284.310764)
			(xy 417.986165 -284.324456) (xy 417.93731 -284.330388) (xy 417.888135 -284.328407) (xy 417.839916 -284.318563)
			(xy 417.7939 -284.301111) (xy 417.751279 -284.276504) (xy 417.713158 -284.245379) (xy 417.680523 -284.208542)
			(xy 417.65422 -284.166946) (xy 417.634929 -284.12167) (xy 417.623152 -284.073886) (xy 417.619192 -284.024832)
			(xy 417.28009 -284.024832) (xy 417.279595 -284.049439) (xy 417.2717 -284.098016) (xy 417.256116 -284.144697)
			(xy 417.233245 -284.188274) (xy 417.20368 -284.227618) (xy 417.168187 -284.26171) (xy 417.127684 -284.289666)
			(xy 417.083222 -284.310764) (xy 417.035951 -284.324456) (xy 416.987096 -284.330388) (xy 416.937921 -284.328407)
			(xy 416.889702 -284.318563) (xy 416.843686 -284.301111) (xy 416.801065 -284.276504) (xy 416.762944 -284.245379)
			(xy 416.730309 -284.208542) (xy 416.704006 -284.166946) (xy 416.684715 -284.12167) (xy 416.672938 -284.073886)
			(xy 416.668978 -284.024832) (xy 416.33013 -284.024832) (xy 416.329635 -284.049439) (xy 416.32174 -284.098016)
			(xy 416.306156 -284.144697) (xy 416.283285 -284.188274) (xy 416.25372 -284.227618) (xy 416.218227 -284.26171)
			(xy 416.177724 -284.289666) (xy 416.133262 -284.310764) (xy 416.085991 -284.324456) (xy 416.037136 -284.330388)
			(xy 415.987961 -284.328407) (xy 415.939742 -284.318563) (xy 415.893726 -284.301111) (xy 415.851105 -284.276504)
			(xy 415.812984 -284.245379) (xy 415.780349 -284.208542) (xy 415.754046 -284.166946) (xy 415.734755 -284.12167)
			(xy 415.722978 -284.073886) (xy 415.719018 -284.024832) (xy 415.38017 -284.024832) (xy 415.379675 -284.049439)
			(xy 415.37178 -284.098016) (xy 415.356196 -284.144697) (xy 415.333325 -284.188274) (xy 415.30376 -284.227618)
			(xy 415.268267 -284.26171) (xy 415.227764 -284.289666) (xy 415.183302 -284.310764) (xy 415.136031 -284.324456)
			(xy 415.087176 -284.330388) (xy 415.038001 -284.328407) (xy 414.989782 -284.318563) (xy 414.943766 -284.301111)
			(xy 414.901145 -284.276504) (xy 414.863024 -284.245379) (xy 414.830389 -284.208542) (xy 414.804086 -284.166946)
			(xy 414.784795 -284.12167) (xy 414.773018 -284.073886) (xy 414.769058 -284.024832) (xy 414.43021 -284.024832)
			(xy 414.429715 -284.049439) (xy 414.42182 -284.098016) (xy 414.406236 -284.144697) (xy 414.383365 -284.188274)
			(xy 414.3538 -284.227618) (xy 414.318307 -284.26171) (xy 414.277804 -284.289666) (xy 414.233342 -284.310764)
			(xy 414.186071 -284.324456) (xy 414.137216 -284.330388) (xy 414.088041 -284.328407) (xy 414.039822 -284.318563)
			(xy 413.993806 -284.301111) (xy 413.951185 -284.276504) (xy 413.913064 -284.245379) (xy 413.880429 -284.208542)
			(xy 413.854126 -284.166946) (xy 413.834835 -284.12167) (xy 413.823058 -284.073886) (xy 413.819098 -284.024832)
			(xy 413.48025 -284.024832) (xy 413.479755 -284.049439) (xy 413.47186 -284.098016) (xy 413.456276 -284.144697)
			(xy 413.433405 -284.188274) (xy 413.40384 -284.227618) (xy 413.368347 -284.26171) (xy 413.327844 -284.289666)
			(xy 413.283382 -284.310764) (xy 413.236111 -284.324456) (xy 413.187256 -284.330388) (xy 413.138081 -284.328407)
			(xy 413.089862 -284.318563) (xy 413.043846 -284.301111) (xy 413.001225 -284.276504) (xy 412.963104 -284.245379)
			(xy 412.930469 -284.208542) (xy 412.904166 -284.166946) (xy 412.884875 -284.12167) (xy 412.873098 -284.073886)
			(xy 412.869138 -284.024832) (xy 412.53029 -284.024832) (xy 412.529795 -284.049439) (xy 412.5219 -284.098016)
			(xy 412.506316 -284.144697) (xy 412.483445 -284.188274) (xy 412.45388 -284.227618) (xy 412.418387 -284.26171)
			(xy 412.377884 -284.289666) (xy 412.333422 -284.310764) (xy 412.286151 -284.324456) (xy 412.237296 -284.330388)
			(xy 412.188121 -284.328407) (xy 412.139902 -284.318563) (xy 412.093886 -284.301111) (xy 412.051265 -284.276504)
			(xy 412.013144 -284.245379) (xy 411.980509 -284.208542) (xy 411.954206 -284.166946) (xy 411.934915 -284.12167)
			(xy 411.923138 -284.073886) (xy 411.919178 -284.024832) (xy 411.58033 -284.024832) (xy 411.579835 -284.049439)
			(xy 411.57194 -284.098016) (xy 411.556356 -284.144697) (xy 411.533485 -284.188274) (xy 411.50392 -284.227618)
			(xy 411.468427 -284.26171) (xy 411.427924 -284.289666) (xy 411.383462 -284.310764) (xy 411.336191 -284.324456)
			(xy 411.287336 -284.330388) (xy 411.238161 -284.328407) (xy 411.189942 -284.318563) (xy 411.143926 -284.301111)
			(xy 411.101305 -284.276504) (xy 411.063184 -284.245379) (xy 411.030549 -284.208542) (xy 411.004246 -284.166946)
			(xy 410.984955 -284.12167) (xy 410.973178 -284.073886) (xy 410.969218 -284.024832) (xy 410.630116 -284.024832)
			(xy 410.629621 -284.049439) (xy 410.621726 -284.098016) (xy 410.606142 -284.144697) (xy 410.583271 -284.188274)
			(xy 410.553706 -284.227618) (xy 410.518213 -284.26171) (xy 410.47771 -284.289666) (xy 410.433248 -284.310764)
			(xy 410.385977 -284.324456) (xy 410.337122 -284.330388) (xy 410.287947 -284.328407) (xy 410.239728 -284.318563)
			(xy 410.193712 -284.301111) (xy 410.151091 -284.276504) (xy 410.11297 -284.245379) (xy 410.080335 -284.208542)
			(xy 410.054032 -284.166946) (xy 410.034741 -284.12167) (xy 410.022964 -284.073886) (xy 410.019004 -284.024832)
			(xy 409.680156 -284.024832) (xy 409.679661 -284.049439) (xy 409.671766 -284.098016) (xy 409.656182 -284.144697)
			(xy 409.633311 -284.188274) (xy 409.603746 -284.227618) (xy 409.568253 -284.26171) (xy 409.52775 -284.289666)
			(xy 409.483288 -284.310764) (xy 409.436017 -284.324456) (xy 409.387162 -284.330388) (xy 409.337987 -284.328407)
			(xy 409.289768 -284.318563) (xy 409.243752 -284.301111) (xy 409.201131 -284.276504) (xy 409.16301 -284.245379)
			(xy 409.130375 -284.208542) (xy 409.104072 -284.166946) (xy 409.084781 -284.12167) (xy 409.073004 -284.073886)
			(xy 409.069044 -284.024832) (xy 408.730196 -284.024832) (xy 408.729701 -284.049439) (xy 408.721806 -284.098016)
			(xy 408.706222 -284.144697) (xy 408.683351 -284.188274) (xy 408.653786 -284.227618) (xy 408.618293 -284.26171)
			(xy 408.57779 -284.289666) (xy 408.533328 -284.310764) (xy 408.486057 -284.324456) (xy 408.437202 -284.330388)
			(xy 408.388027 -284.328407) (xy 408.339808 -284.318563) (xy 408.293792 -284.301111) (xy 408.251171 -284.276504)
			(xy 408.21305 -284.245379) (xy 408.180415 -284.208542) (xy 408.154112 -284.166946) (xy 408.134821 -284.12167)
			(xy 408.123044 -284.073886) (xy 408.119084 -284.024832) (xy 406.830276 -284.024832) (xy 406.829781 -284.049439)
			(xy 406.821886 -284.098016) (xy 406.806302 -284.144697) (xy 406.783431 -284.188274) (xy 406.753866 -284.227618)
			(xy 406.718373 -284.26171) (xy 406.67787 -284.289666) (xy 406.633408 -284.310764) (xy 406.586137 -284.324456)
			(xy 406.537282 -284.330388) (xy 406.488107 -284.328407) (xy 406.439888 -284.318563) (xy 406.393872 -284.301111)
			(xy 406.351251 -284.276504) (xy 406.31313 -284.245379) (xy 406.280495 -284.208542) (xy 406.254192 -284.166946)
			(xy 406.234901 -284.12167) (xy 406.223124 -284.073886) (xy 406.219164 -284.024832) (xy 405.880316 -284.024832)
			(xy 405.879821 -284.049439) (xy 405.871926 -284.098016) (xy 405.856342 -284.144697) (xy 405.833471 -284.188274)
			(xy 405.803906 -284.227618) (xy 405.768413 -284.26171) (xy 405.72791 -284.289666) (xy 405.683448 -284.310764)
			(xy 405.636177 -284.324456) (xy 405.587322 -284.330388) (xy 405.538147 -284.328407) (xy 405.489928 -284.318563)
			(xy 405.443912 -284.301111) (xy 405.401291 -284.276504) (xy 405.36317 -284.245379) (xy 405.330535 -284.208542)
			(xy 405.304232 -284.166946) (xy 405.284941 -284.12167) (xy 405.273164 -284.073886) (xy 405.269204 -284.024832)
			(xy 404.930102 -284.024832) (xy 404.929607 -284.049439) (xy 404.921712 -284.098016) (xy 404.906128 -284.144697)
			(xy 404.883257 -284.188274) (xy 404.853692 -284.227618) (xy 404.818199 -284.26171) (xy 404.777696 -284.289666)
			(xy 404.733234 -284.310764) (xy 404.685963 -284.324456) (xy 404.637108 -284.330388) (xy 404.587933 -284.328407)
			(xy 404.539714 -284.318563) (xy 404.493698 -284.301111) (xy 404.451077 -284.276504) (xy 404.412956 -284.245379)
			(xy 404.380321 -284.208542) (xy 404.354018 -284.166946) (xy 404.334727 -284.12167) (xy 404.32295 -284.073886)
			(xy 404.31899 -284.024832) (xy 403.980142 -284.024832) (xy 403.979647 -284.049439) (xy 403.971752 -284.098016)
			(xy 403.956168 -284.144697) (xy 403.933297 -284.188274) (xy 403.903732 -284.227618) (xy 403.868239 -284.26171)
			(xy 403.827736 -284.289666) (xy 403.783274 -284.310764) (xy 403.736003 -284.324456) (xy 403.687148 -284.330388)
			(xy 403.637973 -284.328407) (xy 403.589754 -284.318563) (xy 403.543738 -284.301111) (xy 403.501117 -284.276504)
			(xy 403.462996 -284.245379) (xy 403.430361 -284.208542) (xy 403.404058 -284.166946) (xy 403.384767 -284.12167)
			(xy 403.37299 -284.073886) (xy 403.36903 -284.024832) (xy 403.030182 -284.024832) (xy 403.029687 -284.049439)
			(xy 403.021792 -284.098016) (xy 403.006208 -284.144697) (xy 402.983337 -284.188274) (xy 402.953772 -284.227618)
			(xy 402.918279 -284.26171) (xy 402.877776 -284.289666) (xy 402.833314 -284.310764) (xy 402.786043 -284.324456)
			(xy 402.737188 -284.330388) (xy 402.688013 -284.328407) (xy 402.639794 -284.318563) (xy 402.593778 -284.301111)
			(xy 402.551157 -284.276504) (xy 402.513036 -284.245379) (xy 402.480401 -284.208542) (xy 402.454098 -284.166946)
			(xy 402.434807 -284.12167) (xy 402.42303 -284.073886) (xy 402.41907 -284.024832) (xy 402.080222 -284.024832)
			(xy 402.079727 -284.049439) (xy 402.071832 -284.098016) (xy 402.056248 -284.144697) (xy 402.033377 -284.188274)
			(xy 402.003812 -284.227618) (xy 401.968319 -284.26171) (xy 401.927816 -284.289666) (xy 401.883354 -284.310764)
			(xy 401.836083 -284.324456) (xy 401.787228 -284.330388) (xy 401.738053 -284.328407) (xy 401.689834 -284.318563)
			(xy 401.643818 -284.301111) (xy 401.601197 -284.276504) (xy 401.563076 -284.245379) (xy 401.530441 -284.208542)
			(xy 401.504138 -284.166946) (xy 401.484847 -284.12167) (xy 401.47307 -284.073886) (xy 401.46911 -284.024832)
			(xy 401.130262 -284.024832) (xy 401.129767 -284.049439) (xy 401.121872 -284.098016) (xy 401.106288 -284.144697)
			(xy 401.083417 -284.188274) (xy 401.053852 -284.227618) (xy 401.018359 -284.26171) (xy 400.977856 -284.289666)
			(xy 400.933394 -284.310764) (xy 400.886123 -284.324456) (xy 400.837268 -284.330388) (xy 400.788093 -284.328407)
			(xy 400.739874 -284.318563) (xy 400.693858 -284.301111) (xy 400.651237 -284.276504) (xy 400.613116 -284.245379)
			(xy 400.580481 -284.208542) (xy 400.554178 -284.166946) (xy 400.534887 -284.12167) (xy 400.52311 -284.073886)
			(xy 400.51915 -284.024832) (xy 400.180302 -284.024832) (xy 400.179807 -284.049439) (xy 400.171912 -284.098016)
			(xy 400.156328 -284.144697) (xy 400.133457 -284.188274) (xy 400.103892 -284.227618) (xy 400.068399 -284.26171)
			(xy 400.027896 -284.289666) (xy 399.983434 -284.310764) (xy 399.936163 -284.324456) (xy 399.887308 -284.330388)
			(xy 399.838133 -284.328407) (xy 399.789914 -284.318563) (xy 399.743898 -284.301111) (xy 399.701277 -284.276504)
			(xy 399.663156 -284.245379) (xy 399.630521 -284.208542) (xy 399.604218 -284.166946) (xy 399.584927 -284.12167)
			(xy 399.57315 -284.073886) (xy 399.56919 -284.024832) (xy 399.230342 -284.024832) (xy 399.229847 -284.049439)
			(xy 399.221952 -284.098016) (xy 399.206368 -284.144697) (xy 399.183497 -284.188274) (xy 399.153932 -284.227618)
			(xy 399.118439 -284.26171) (xy 399.077936 -284.289666) (xy 399.033474 -284.310764) (xy 398.986203 -284.324456)
			(xy 398.937348 -284.330388) (xy 398.888173 -284.328407) (xy 398.839954 -284.318563) (xy 398.793938 -284.301111)
			(xy 398.751317 -284.276504) (xy 398.713196 -284.245379) (xy 398.680561 -284.208542) (xy 398.654258 -284.166946)
			(xy 398.634967 -284.12167) (xy 398.62319 -284.073886) (xy 398.61923 -284.024832) (xy 398.280128 -284.024832)
			(xy 398.279633 -284.049439) (xy 398.271738 -284.098016) (xy 398.256154 -284.144697) (xy 398.233283 -284.188274)
			(xy 398.203718 -284.227618) (xy 398.168225 -284.26171) (xy 398.127722 -284.289666) (xy 398.08326 -284.310764)
			(xy 398.035989 -284.324456) (xy 397.987134 -284.330388) (xy 397.937959 -284.328407) (xy 397.88974 -284.318563)
			(xy 397.843724 -284.301111) (xy 397.801103 -284.276504) (xy 397.762982 -284.245379) (xy 397.730347 -284.208542)
			(xy 397.704044 -284.166946) (xy 397.684753 -284.12167) (xy 397.672976 -284.073886) (xy 397.669016 -284.024832)
			(xy 397.330168 -284.024832) (xy 397.329673 -284.049439) (xy 397.321778 -284.098016) (xy 397.306194 -284.144697)
			(xy 397.283323 -284.188274) (xy 397.253758 -284.227618) (xy 397.218265 -284.26171) (xy 397.177762 -284.289666)
			(xy 397.1333 -284.310764) (xy 397.086029 -284.324456) (xy 397.037174 -284.330388) (xy 396.987999 -284.328407)
			(xy 396.93978 -284.318563) (xy 396.893764 -284.301111) (xy 396.851143 -284.276504) (xy 396.813022 -284.245379)
			(xy 396.780387 -284.208542) (xy 396.754084 -284.166946) (xy 396.734793 -284.12167) (xy 396.723016 -284.073886)
			(xy 396.719056 -284.024832) (xy 396.55369 -284.024832) (xy 396.55369 -284.499812) (xy 421.894012 -284.499812)
			(xy 421.897972 -284.450758) (xy 421.909749 -284.402974) (xy 421.92904 -284.357698) (xy 421.955343 -284.316102)
			(xy 421.987978 -284.279265) (xy 422.026099 -284.24814) (xy 422.06872 -284.223533) (xy 422.114736 -284.206081)
			(xy 422.162955 -284.196237) (xy 422.21213 -284.194256) (xy 422.260985 -284.200188) (xy 422.308256 -284.21388)
			(xy 422.352718 -284.234978) (xy 422.393221 -284.262934) (xy 422.428714 -284.297026) (xy 422.458279 -284.33637)
			(xy 422.48115 -284.379947) (xy 422.496734 -284.426628) (xy 422.504629 -284.475205) (xy 422.505124 -284.499812)
			(xy 422.843972 -284.499812) (xy 422.847932 -284.450758) (xy 422.859709 -284.402974) (xy 422.879 -284.357698)
			(xy 422.905303 -284.316102) (xy 422.937938 -284.279265) (xy 422.976059 -284.24814) (xy 423.01868 -284.223533)
			(xy 423.064696 -284.206081) (xy 423.112915 -284.196237) (xy 423.16209 -284.194256) (xy 423.210945 -284.200188)
			(xy 423.258216 -284.21388) (xy 423.302678 -284.234978) (xy 423.343181 -284.262934) (xy 423.378674 -284.297026)
			(xy 423.408239 -284.33637) (xy 423.43111 -284.379947) (xy 423.446694 -284.426628) (xy 423.454589 -284.475205)
			(xy 423.455084 -284.499812) (xy 423.794186 -284.499812) (xy 423.798146 -284.450758) (xy 423.809923 -284.402974)
			(xy 423.829214 -284.357698) (xy 423.855517 -284.316102) (xy 423.888152 -284.279265) (xy 423.926273 -284.24814)
			(xy 423.968894 -284.223533) (xy 424.01491 -284.206081) (xy 424.063129 -284.196237) (xy 424.112304 -284.194256)
			(xy 424.161159 -284.200188) (xy 424.20843 -284.21388) (xy 424.252892 -284.234978) (xy 424.293395 -284.262934)
			(xy 424.328888 -284.297026) (xy 424.358453 -284.33637) (xy 424.381324 -284.379947) (xy 424.396908 -284.426628)
			(xy 424.404803 -284.475205) (xy 424.405298 -284.499812) (xy 424.744146 -284.499812) (xy 424.748106 -284.450758)
			(xy 424.759883 -284.402974) (xy 424.779174 -284.357698) (xy 424.805477 -284.316102) (xy 424.838112 -284.279265)
			(xy 424.876233 -284.24814) (xy 424.918854 -284.223533) (xy 424.96487 -284.206081) (xy 425.013089 -284.196237)
			(xy 425.062264 -284.194256) (xy 425.111119 -284.200188) (xy 425.15839 -284.21388) (xy 425.202852 -284.234978)
			(xy 425.243355 -284.262934) (xy 425.278848 -284.297026) (xy 425.308413 -284.33637) (xy 425.331284 -284.379947)
			(xy 425.346868 -284.426628) (xy 425.354763 -284.475205) (xy 425.355258 -284.499812) (xy 425.694106 -284.499812)
			(xy 425.698066 -284.450758) (xy 425.709843 -284.402974) (xy 425.729134 -284.357698) (xy 425.755437 -284.316102)
			(xy 425.788072 -284.279265) (xy 425.826193 -284.24814) (xy 425.868814 -284.223533) (xy 425.91483 -284.206081)
			(xy 425.963049 -284.196237) (xy 426.012224 -284.194256) (xy 426.061079 -284.200188) (xy 426.10835 -284.21388)
			(xy 426.152812 -284.234978) (xy 426.193315 -284.262934) (xy 426.228808 -284.297026) (xy 426.258373 -284.33637)
			(xy 426.281244 -284.379947) (xy 426.296828 -284.426628) (xy 426.304723 -284.475205) (xy 426.305218 -284.499812)
			(xy 426.644066 -284.499812) (xy 426.648026 -284.450758) (xy 426.659803 -284.402974) (xy 426.679094 -284.357698)
			(xy 426.705397 -284.316102) (xy 426.738032 -284.279265) (xy 426.776153 -284.24814) (xy 426.818774 -284.223533)
			(xy 426.86479 -284.206081) (xy 426.913009 -284.196237) (xy 426.962184 -284.194256) (xy 427.011039 -284.200188)
			(xy 427.05831 -284.21388) (xy 427.102772 -284.234978) (xy 427.143275 -284.262934) (xy 427.178768 -284.297026)
			(xy 427.208333 -284.33637) (xy 427.231204 -284.379947) (xy 427.246788 -284.426628) (xy 427.254683 -284.475205)
			(xy 427.255178 -284.499812) (xy 427.254683 -284.524419) (xy 427.254504 -284.52552) (xy 427.573182 -284.52552)
			(xy 427.573182 -284.474104) (xy 427.581225 -284.423322) (xy 427.597113 -284.374423) (xy 427.620456 -284.328611)
			(xy 427.650677 -284.287015) (xy 427.687033 -284.250659) (xy 427.728629 -284.220438) (xy 427.774441 -284.197095)
			(xy 427.82334 -284.181207) (xy 427.874122 -284.173164) (xy 427.925538 -284.173164) (xy 427.97632 -284.181207)
			(xy 428.025219 -284.197095) (xy 428.071031 -284.220438) (xy 428.112627 -284.250659) (xy 428.148983 -284.287015)
			(xy 428.179204 -284.328611) (xy 428.202547 -284.374423) (xy 428.218435 -284.423322) (xy 428.226478 -284.474104)
			(xy 428.226982 -284.499812) (xy 428.226478 -284.52552) (xy 428.523142 -284.52552) (xy 428.523142 -284.474104)
			(xy 428.531185 -284.423322) (xy 428.547073 -284.374423) (xy 428.570416 -284.328611) (xy 428.600637 -284.287015)
			(xy 428.636993 -284.250659) (xy 428.678589 -284.220438) (xy 428.724401 -284.197095) (xy 428.7733 -284.181207)
			(xy 428.824082 -284.173164) (xy 428.875498 -284.173164) (xy 428.92628 -284.181207) (xy 428.975179 -284.197095)
			(xy 429.020991 -284.220438) (xy 429.062587 -284.250659) (xy 429.098943 -284.287015) (xy 429.129164 -284.328611)
			(xy 429.152507 -284.374423) (xy 429.168395 -284.423322) (xy 429.176438 -284.474104) (xy 429.176942 -284.499812)
			(xy 429.4942 -284.499812) (xy 429.49816 -284.450758) (xy 429.509937 -284.402974) (xy 429.529228 -284.357698)
			(xy 429.555531 -284.316102) (xy 429.588166 -284.279265) (xy 429.626287 -284.24814) (xy 429.668908 -284.223533)
			(xy 429.714924 -284.206081) (xy 429.763143 -284.196237) (xy 429.812318 -284.194256) (xy 429.861173 -284.200188)
			(xy 429.908444 -284.21388) (xy 429.952906 -284.234978) (xy 429.993409 -284.262934) (xy 430.028902 -284.297026)
			(xy 430.058467 -284.33637) (xy 430.081338 -284.379947) (xy 430.096922 -284.426628) (xy 430.104817 -284.475205)
			(xy 430.105312 -284.499812) (xy 430.44416 -284.499812) (xy 430.44812 -284.450758) (xy 430.459897 -284.402974)
			(xy 430.479188 -284.357698) (xy 430.505491 -284.316102) (xy 430.538126 -284.279265) (xy 430.576247 -284.24814)
			(xy 430.618868 -284.223533) (xy 430.664884 -284.206081) (xy 430.713103 -284.196237) (xy 430.762278 -284.194256)
			(xy 430.811133 -284.200188) (xy 430.858404 -284.21388) (xy 430.902866 -284.234978) (xy 430.943369 -284.262934)
			(xy 430.978862 -284.297026) (xy 431.008427 -284.33637) (xy 431.031298 -284.379947) (xy 431.046882 -284.426628)
			(xy 431.054777 -284.475205) (xy 431.055272 -284.499812) (xy 431.054777 -284.524419) (xy 431.046882 -284.572996)
			(xy 431.031298 -284.619677) (xy 431.008427 -284.663254) (xy 430.978862 -284.702598) (xy 430.943369 -284.73669)
			(xy 430.902866 -284.764646) (xy 430.858404 -284.785744) (xy 430.835922 -284.792256) (xy 448.411243 -284.792256)
			(xy 448.411243 -284.737744) (xy 448.419001 -284.683787) (xy 448.43436 -284.631484) (xy 448.457007 -284.581899)
			(xy 448.48648 -284.536043) (xy 448.52218 -284.494847) (xy 448.563379 -284.459153) (xy 448.60924 -284.429685)
			(xy 448.658827 -284.407044) (xy 448.711132 -284.391692) (xy 448.76509 -284.38394) (xy 448.792346 -284.38348)
			(xy 448.821086 -284.383981) (xy 448.877914 -284.39261) (xy 448.932805 -284.409666) (xy 448.984516 -284.434762)
			(xy 449.031878 -284.467331) (xy 449.053204 -284.486604) (xy 449.053458 -284.486858) (xy 449.060767 -284.49296)
			(xy 449.078492 -284.499865) (xy 449.088002 -284.50032) (xy 449.15709 -284.50032) (xy 449.166621 -284.499979)
			(xy 449.184376 -284.493047) (xy 449.191634 -284.486858) (xy 449.191888 -284.486604) (xy 449.213215 -284.467334)
			(xy 449.260578 -284.434769) (xy 449.312289 -284.409678) (xy 449.36718 -284.392628) (xy 449.424007 -284.384006)
			(xy 449.481485 -284.384006) (xy 449.538312 -284.392628) (xy 449.593203 -284.409678) (xy 449.644914 -284.434769)
			(xy 449.692277 -284.467334) (xy 449.713604 -284.486604) (xy 449.713858 -284.486858) (xy 449.721167 -284.49296)
			(xy 449.738892 -284.499865) (xy 449.748402 -284.50032) (xy 449.81749 -284.50032) (xy 449.827021 -284.499979)
			(xy 449.844776 -284.493047) (xy 449.852034 -284.486858) (xy 449.852288 -284.486604) (xy 449.873606 -284.467323)
			(xy 449.920969 -284.434756) (xy 449.972683 -284.409664) (xy 450.027576 -284.392616) (xy 450.084406 -284.383998)
			(xy 450.113146 -284.38348) (xy 450.143268 -284.384076) (xy 450.202764 -284.39355) (xy 450.260032 -284.412254)
			(xy 450.31365 -284.439725) (xy 450.362285 -284.475279) (xy 450.38391 -284.496256) (xy 450.391022 -284.503368)
			(xy 450.409818 -284.511242) (xy 450.502274 -284.511242) (xy 450.52107 -284.503368) (xy 450.528182 -284.496256)
			(xy 450.549801 -284.475269) (xy 450.59843 -284.439699) (xy 450.652048 -284.412219) (xy 450.70932 -284.393513)
			(xy 450.768821 -284.384046) (xy 450.798946 -284.38348) (xy 450.826194 -284.383993) (xy 450.880135 -284.391755)
			(xy 450.932423 -284.407114) (xy 450.981993 -284.429757) (xy 451.027836 -284.459223) (xy 451.069019 -284.494914)
			(xy 451.104704 -284.536101) (xy 451.134165 -284.581948) (xy 451.156803 -284.63152) (xy 451.172155 -284.68381)
			(xy 451.17991 -284.737752) (xy 451.17991 -284.792248) (xy 451.179909 -284.792255) (xy 453.090443 -284.792255)
			(xy 453.090443 -284.737745) (xy 453.098201 -284.683789) (xy 453.113559 -284.631487) (xy 453.136205 -284.581903)
			(xy 453.165677 -284.536047) (xy 453.201376 -284.494852) (xy 453.242574 -284.459157) (xy 453.288433 -284.429689)
			(xy 453.338019 -284.407047) (xy 453.390322 -284.391694) (xy 453.444279 -284.383941) (xy 453.471534 -284.38348)
			(xy 453.500273 -284.383988) (xy 453.557101 -284.392616) (xy 453.611992 -284.409669) (xy 453.663703 -284.434764)
			(xy 453.711065 -284.467332) (xy 453.732392 -284.486604) (xy 453.732646 -284.486858) (xy 453.739958 -284.492955)
			(xy 453.757681 -284.499863) (xy 453.76719 -284.50032) (xy 453.836278 -284.50032) (xy 453.845809 -284.499973)
			(xy 453.863564 -284.493045) (xy 453.870822 -284.486858) (xy 453.871076 -284.486604) (xy 453.892403 -284.467334)
			(xy 453.939766 -284.434769) (xy 453.991477 -284.409678) (xy 454.046368 -284.392628) (xy 454.103195 -284.384006)
			(xy 454.160673 -284.384006) (xy 454.2175 -284.392628) (xy 454.272391 -284.409678) (xy 454.324102 -284.434769)
			(xy 454.371465 -284.467334) (xy 454.392792 -284.486604) (xy 454.393046 -284.486858) (xy 454.400358 -284.492955)
			(xy 454.418081 -284.499863) (xy 454.42759 -284.50032) (xy 454.496678 -284.50032) (xy 454.506209 -284.499973)
			(xy 454.523964 -284.493045) (xy 454.531222 -284.486858) (xy 454.531476 -284.486604) (xy 454.552799 -284.467328)
			(xy 454.600161 -284.43476) (xy 454.651873 -284.409668) (xy 454.706766 -284.392619) (xy 454.763595 -284.383999)
			(xy 454.792334 -284.38348) (xy 454.822459 -284.38402) (xy 454.881957 -284.393508) (xy 454.939226 -284.412225)
			(xy 454.992842 -284.439708) (xy 455.041475 -284.475274) (xy 455.063098 -284.496256) (xy 455.07021 -284.503368)
			(xy 455.089006 -284.511242) (xy 455.181462 -284.511242) (xy 455.200258 -284.503368) (xy 455.20737 -284.496256)
			(xy 455.228994 -284.475275) (xy 455.277622 -284.439704) (xy 455.331239 -284.412223) (xy 455.388509 -284.393516)
			(xy 455.44801 -284.384047) (xy 455.478134 -284.38348) (xy 455.505383 -284.383993) (xy 455.559325 -284.391753)
			(xy 455.611614 -284.40711) (xy 455.661185 -284.429753) (xy 455.70703 -284.459219) (xy 455.748215 -284.494909)
			(xy 455.783901 -284.536097) (xy 455.813364 -284.581945) (xy 455.836002 -284.631518) (xy 455.851354 -284.683808)
			(xy 455.85911 -284.737751) (xy 455.85911 -284.792249) (xy 455.851354 -284.846192) (xy 455.836002 -284.898482)
			(xy 455.813364 -284.948055) (xy 455.783901 -284.993903) (xy 455.748215 -285.035091) (xy 455.70703 -285.070781)
			(xy 455.661185 -285.100247) (xy 455.611614 -285.12289) (xy 455.559325 -285.138247) (xy 455.505383 -285.146007)
			(xy 455.478134 -285.146496) (xy 455.448011 -285.145919) (xy 455.388514 -285.136442) (xy 455.331245 -285.117733)
			(xy 455.277628 -285.090258) (xy 455.228994 -285.054699) (xy 455.20737 -285.03372) (xy 455.200258 -285.026608)
			(xy 455.181462 -285.018734) (xy 455.089006 -285.018734) (xy 455.07021 -285.026608) (xy 455.063098 -285.03372)
			(xy 455.041501 -285.05473) (xy 454.992864 -285.090293) (xy 454.939241 -285.117768) (xy 454.881964 -285.136469)
			(xy 454.82246 -285.145932) (xy 454.792334 -285.146496) (xy 454.763594 -285.146013) (xy 454.706764 -285.137381)
			(xy 454.651873 -285.120321) (xy 454.600162 -285.095221) (xy 454.552801 -285.062647) (xy 454.531476 -285.043372)
			(xy 454.531222 -285.043118) (xy 454.523943 -285.036968) (xy 454.506199 -285.030052) (xy 454.496678 -285.029656)
			(xy 454.42759 -285.029656) (xy 454.41806 -285.030019) (xy 454.400305 -285.036933) (xy 454.393046 -285.043118)
			(xy 454.392792 -285.043372) (xy 454.371465 -285.062642) (xy 454.324102 -285.095207) (xy 454.272391 -285.120298)
			(xy 454.2175 -285.137348) (xy 454.160673 -285.14597) (xy 454.103195 -285.14597) (xy 454.046368 -285.137348)
			(xy 453.991477 -285.120298) (xy 453.939766 -285.095207) (xy 453.892403 -285.062642) (xy 453.871076 -285.043372)
			(xy 453.870822 -285.043118) (xy 453.863543 -285.036968) (xy 453.845799 -285.030052) (xy 453.836278 -285.029656)
			(xy 453.76719 -285.029656) (xy 453.75766 -285.030019) (xy 453.739905 -285.036933) (xy 453.732646 -285.043118)
			(xy 453.732392 -285.043372) (xy 453.711052 -285.062628) (xy 453.663694 -285.095196) (xy 453.611985 -285.120291)
			(xy 453.557097 -285.137345) (xy 453.500272 -285.145973) (xy 453.471534 -285.146496) (xy 453.444279 -285.146059)
			(xy 453.390322 -285.138306) (xy 453.338019 -285.122953) (xy 453.288433 -285.100311) (xy 453.242574 -285.070843)
			(xy 453.201376 -285.035148) (xy 453.165677 -284.993953) (xy 453.136205 -284.948097) (xy 453.113559 -284.898513)
			(xy 453.098201 -284.846211) (xy 453.090443 -284.792255) (xy 451.179909 -284.792255) (xy 451.172155 -284.84619)
			(xy 451.156803 -284.89848) (xy 451.134165 -284.948052) (xy 451.104704 -284.993899) (xy 451.069019 -285.035086)
			(xy 451.027836 -285.070777) (xy 450.981993 -285.100243) (xy 450.932423 -285.122886) (xy 450.880135 -285.138245)
			(xy 450.826194 -285.146007) (xy 450.798946 -285.146496) (xy 450.768823 -285.145912) (xy 450.709327 -285.136436)
			(xy 450.652058 -285.117729) (xy 450.598441 -285.090256) (xy 450.549807 -285.054699) (xy 450.528182 -285.03372)
			(xy 450.52107 -285.026608) (xy 450.502274 -285.018734) (xy 450.409818 -285.018734) (xy 450.391022 -285.026608)
			(xy 450.38391 -285.03372) (xy 450.362307 -285.054724) (xy 450.313672 -285.090288) (xy 450.26005 -285.117764)
			(xy 450.202775 -285.136466) (xy 450.143272 -285.145931) (xy 450.113146 -285.146496) (xy 450.084406 -285.146006)
			(xy 450.027577 -285.137375) (xy 449.972686 -285.120318) (xy 449.920975 -285.095218) (xy 449.873614 -285.062646)
			(xy 449.852288 -285.043372) (xy 449.852034 -285.043118) (xy 449.844751 -285.036973) (xy 449.82701 -285.030054)
			(xy 449.81749 -285.029656) (xy 449.748402 -285.029656) (xy 449.738873 -285.030025) (xy 449.721117 -285.036935)
			(xy 449.713858 -285.043118) (xy 449.713604 -285.043372) (xy 449.692277 -285.062642) (xy 449.644914 -285.095207)
			(xy 449.593203 -285.120298) (xy 449.538312 -285.137348) (xy 449.481485 -285.14597) (xy 449.424007 -285.14597)
			(xy 449.36718 -285.137348) (xy 449.312289 -285.120298) (xy 449.260578 -285.095207) (xy 449.213215 -285.062642)
			(xy 449.191888 -285.043372) (xy 449.191634 -285.043118) (xy 449.184351 -285.036973) (xy 449.16661 -285.030054)
			(xy 449.15709 -285.029656) (xy 449.088002 -285.029656) (xy 449.078473 -285.030025) (xy 449.060717 -285.036935)
			(xy 449.053458 -285.043118) (xy 449.053204 -285.043372) (xy 449.031901 -285.06267) (xy 448.984532 -285.095232)
			(xy 448.932814 -285.120319) (xy 448.877918 -285.137363) (xy 448.821087 -285.145979) (xy 448.792346 -285.146496)
			(xy 448.76509 -285.14606) (xy 448.711132 -285.138308) (xy 448.658827 -285.122956) (xy 448.60924 -285.100315)
			(xy 448.563379 -285.070847) (xy 448.52218 -285.035153) (xy 448.48648 -284.993957) (xy 448.457007 -284.948101)
			(xy 448.43436 -284.898516) (xy 448.419001 -284.846213) (xy 448.411243 -284.792256) (xy 430.835922 -284.792256)
			(xy 430.811133 -284.799436) (xy 430.762278 -284.805368) (xy 430.713103 -284.803387) (xy 430.664884 -284.793543)
			(xy 430.618868 -284.776091) (xy 430.576247 -284.751484) (xy 430.538126 -284.720359) (xy 430.505491 -284.683522)
			(xy 430.479188 -284.641926) (xy 430.459897 -284.59665) (xy 430.44812 -284.548866) (xy 430.44416 -284.499812)
			(xy 430.105312 -284.499812) (xy 430.104817 -284.524419) (xy 430.096922 -284.572996) (xy 430.081338 -284.619677)
			(xy 430.058467 -284.663254) (xy 430.028902 -284.702598) (xy 429.993409 -284.73669) (xy 429.952906 -284.764646)
			(xy 429.908444 -284.785744) (xy 429.861173 -284.799436) (xy 429.812318 -284.805368) (xy 429.763143 -284.803387)
			(xy 429.714924 -284.793543) (xy 429.668908 -284.776091) (xy 429.626287 -284.751484) (xy 429.588166 -284.720359)
			(xy 429.555531 -284.683522) (xy 429.529228 -284.641926) (xy 429.509937 -284.59665) (xy 429.49816 -284.548866)
			(xy 429.4942 -284.499812) (xy 429.176942 -284.499812) (xy 429.176438 -284.52552) (xy 429.168395 -284.576302)
			(xy 429.152507 -284.625201) (xy 429.129164 -284.671013) (xy 429.098943 -284.712609) (xy 429.062587 -284.748965)
			(xy 429.020991 -284.779186) (xy 428.975179 -284.802529) (xy 428.92628 -284.818417) (xy 428.875498 -284.82646)
			(xy 428.824082 -284.82646) (xy 428.7733 -284.818417) (xy 428.724401 -284.802529) (xy 428.678589 -284.779186)
			(xy 428.636993 -284.748965) (xy 428.600637 -284.712609) (xy 428.570416 -284.671013) (xy 428.547073 -284.625201)
			(xy 428.531185 -284.576302) (xy 428.523142 -284.52552) (xy 428.226478 -284.52552) (xy 428.218435 -284.576302)
			(xy 428.202547 -284.625201) (xy 428.179204 -284.671013) (xy 428.148983 -284.712609) (xy 428.112627 -284.748965)
			(xy 428.071031 -284.779186) (xy 428.025219 -284.802529) (xy 427.97632 -284.818417) (xy 427.925538 -284.82646)
			(xy 427.874122 -284.82646) (xy 427.82334 -284.818417) (xy 427.774441 -284.802529) (xy 427.728629 -284.779186)
			(xy 427.687033 -284.748965) (xy 427.650677 -284.712609) (xy 427.620456 -284.671013) (xy 427.597113 -284.625201)
			(xy 427.581225 -284.576302) (xy 427.573182 -284.52552) (xy 427.254504 -284.52552) (xy 427.246788 -284.572996)
			(xy 427.231204 -284.619677) (xy 427.208333 -284.663254) (xy 427.178768 -284.702598) (xy 427.143275 -284.73669)
			(xy 427.102772 -284.764646) (xy 427.05831 -284.785744) (xy 427.011039 -284.799436) (xy 426.962184 -284.805368)
			(xy 426.913009 -284.803387) (xy 426.86479 -284.793543) (xy 426.818774 -284.776091) (xy 426.776153 -284.751484)
			(xy 426.738032 -284.720359) (xy 426.705397 -284.683522) (xy 426.679094 -284.641926) (xy 426.659803 -284.59665)
			(xy 426.648026 -284.548866) (xy 426.644066 -284.499812) (xy 426.305218 -284.499812) (xy 426.304723 -284.524419)
			(xy 426.296828 -284.572996) (xy 426.281244 -284.619677) (xy 426.258373 -284.663254) (xy 426.228808 -284.702598)
			(xy 426.193315 -284.73669) (xy 426.152812 -284.764646) (xy 426.10835 -284.785744) (xy 426.061079 -284.799436)
			(xy 426.012224 -284.805368) (xy 425.963049 -284.803387) (xy 425.91483 -284.793543) (xy 425.868814 -284.776091)
			(xy 425.826193 -284.751484) (xy 425.788072 -284.720359) (xy 425.755437 -284.683522) (xy 425.729134 -284.641926)
			(xy 425.709843 -284.59665) (xy 425.698066 -284.548866) (xy 425.694106 -284.499812) (xy 425.355258 -284.499812)
			(xy 425.354763 -284.524419) (xy 425.346868 -284.572996) (xy 425.331284 -284.619677) (xy 425.308413 -284.663254)
			(xy 425.278848 -284.702598) (xy 425.243355 -284.73669) (xy 425.202852 -284.764646) (xy 425.15839 -284.785744)
			(xy 425.111119 -284.799436) (xy 425.062264 -284.805368) (xy 425.013089 -284.803387) (xy 424.96487 -284.793543)
			(xy 424.918854 -284.776091) (xy 424.876233 -284.751484) (xy 424.838112 -284.720359) (xy 424.805477 -284.683522)
			(xy 424.779174 -284.641926) (xy 424.759883 -284.59665) (xy 424.748106 -284.548866) (xy 424.744146 -284.499812)
			(xy 424.405298 -284.499812) (xy 424.404803 -284.524419) (xy 424.396908 -284.572996) (xy 424.381324 -284.619677)
			(xy 424.358453 -284.663254) (xy 424.328888 -284.702598) (xy 424.293395 -284.73669) (xy 424.252892 -284.764646)
			(xy 424.20843 -284.785744) (xy 424.161159 -284.799436) (xy 424.112304 -284.805368) (xy 424.063129 -284.803387)
			(xy 424.01491 -284.793543) (xy 423.968894 -284.776091) (xy 423.926273 -284.751484) (xy 423.888152 -284.720359)
			(xy 423.855517 -284.683522) (xy 423.829214 -284.641926) (xy 423.809923 -284.59665) (xy 423.798146 -284.548866)
			(xy 423.794186 -284.499812) (xy 423.455084 -284.499812) (xy 423.454589 -284.524419) (xy 423.446694 -284.572996)
			(xy 423.43111 -284.619677) (xy 423.408239 -284.663254) (xy 423.378674 -284.702598) (xy 423.343181 -284.73669)
			(xy 423.302678 -284.764646) (xy 423.258216 -284.785744) (xy 423.210945 -284.799436) (xy 423.16209 -284.805368)
			(xy 423.112915 -284.803387) (xy 423.064696 -284.793543) (xy 423.01868 -284.776091) (xy 422.976059 -284.751484)
			(xy 422.937938 -284.720359) (xy 422.905303 -284.683522) (xy 422.879 -284.641926) (xy 422.859709 -284.59665)
			(xy 422.847932 -284.548866) (xy 422.843972 -284.499812) (xy 422.505124 -284.499812) (xy 422.504629 -284.524419)
			(xy 422.496734 -284.572996) (xy 422.48115 -284.619677) (xy 422.458279 -284.663254) (xy 422.428714 -284.702598)
			(xy 422.393221 -284.73669) (xy 422.352718 -284.764646) (xy 422.308256 -284.785744) (xy 422.260985 -284.799436)
			(xy 422.21213 -284.805368) (xy 422.162955 -284.803387) (xy 422.114736 -284.793543) (xy 422.06872 -284.776091)
			(xy 422.026099 -284.751484) (xy 421.987978 -284.720359) (xy 421.955343 -284.683522) (xy 421.92904 -284.641926)
			(xy 421.909749 -284.59665) (xy 421.897972 -284.548866) (xy 421.894012 -284.499812) (xy 396.55369 -284.499812)
			(xy 396.55369 -284.974792) (xy 396.719056 -284.974792) (xy 396.723016 -284.925738) (xy 396.734793 -284.877954)
			(xy 396.754084 -284.832678) (xy 396.780387 -284.791082) (xy 396.813022 -284.754245) (xy 396.851143 -284.72312)
			(xy 396.893764 -284.698513) (xy 396.93978 -284.681061) (xy 396.987999 -284.671217) (xy 397.037174 -284.669236)
			(xy 397.086029 -284.675168) (xy 397.1333 -284.68886) (xy 397.177762 -284.709958) (xy 397.218265 -284.737914)
			(xy 397.253758 -284.772006) (xy 397.283323 -284.81135) (xy 397.306194 -284.854927) (xy 397.321778 -284.901608)
			(xy 397.329673 -284.950185) (xy 397.330168 -284.974792) (xy 397.669016 -284.974792) (xy 397.672976 -284.925738)
			(xy 397.684753 -284.877954) (xy 397.704044 -284.832678) (xy 397.730347 -284.791082) (xy 397.762982 -284.754245)
			(xy 397.801103 -284.72312) (xy 397.843724 -284.698513) (xy 397.88974 -284.681061) (xy 397.937959 -284.671217)
			(xy 397.987134 -284.669236) (xy 398.035989 -284.675168) (xy 398.08326 -284.68886) (xy 398.127722 -284.709958)
			(xy 398.168225 -284.737914) (xy 398.203718 -284.772006) (xy 398.233283 -284.81135) (xy 398.256154 -284.854927)
			(xy 398.271738 -284.901608) (xy 398.279633 -284.950185) (xy 398.280128 -284.974792) (xy 398.61923 -284.974792)
			(xy 398.62319 -284.925738) (xy 398.634967 -284.877954) (xy 398.654258 -284.832678) (xy 398.680561 -284.791082)
			(xy 398.713196 -284.754245) (xy 398.751317 -284.72312) (xy 398.793938 -284.698513) (xy 398.839954 -284.681061)
			(xy 398.888173 -284.671217) (xy 398.937348 -284.669236) (xy 398.986203 -284.675168) (xy 399.033474 -284.68886)
			(xy 399.077936 -284.709958) (xy 399.118439 -284.737914) (xy 399.153932 -284.772006) (xy 399.183497 -284.81135)
			(xy 399.206368 -284.854927) (xy 399.221952 -284.901608) (xy 399.229847 -284.950185) (xy 399.230342 -284.974792)
			(xy 399.56919 -284.974792) (xy 399.57315 -284.925738) (xy 399.584927 -284.877954) (xy 399.604218 -284.832678)
			(xy 399.630521 -284.791082) (xy 399.663156 -284.754245) (xy 399.701277 -284.72312) (xy 399.743898 -284.698513)
			(xy 399.789914 -284.681061) (xy 399.838133 -284.671217) (xy 399.887308 -284.669236) (xy 399.936163 -284.675168)
			(xy 399.983434 -284.68886) (xy 400.027896 -284.709958) (xy 400.068399 -284.737914) (xy 400.103892 -284.772006)
			(xy 400.133457 -284.81135) (xy 400.156328 -284.854927) (xy 400.171912 -284.901608) (xy 400.179807 -284.950185)
			(xy 400.180302 -284.974792) (xy 400.51915 -284.974792) (xy 400.52311 -284.925738) (xy 400.534887 -284.877954)
			(xy 400.554178 -284.832678) (xy 400.580481 -284.791082) (xy 400.613116 -284.754245) (xy 400.651237 -284.72312)
			(xy 400.693858 -284.698513) (xy 400.739874 -284.681061) (xy 400.788093 -284.671217) (xy 400.837268 -284.669236)
			(xy 400.886123 -284.675168) (xy 400.933394 -284.68886) (xy 400.977856 -284.709958) (xy 401.018359 -284.737914)
			(xy 401.053852 -284.772006) (xy 401.083417 -284.81135) (xy 401.106288 -284.854927) (xy 401.121872 -284.901608)
			(xy 401.129767 -284.950185) (xy 401.130262 -284.974792) (xy 401.46911 -284.974792) (xy 401.47307 -284.925738)
			(xy 401.484847 -284.877954) (xy 401.504138 -284.832678) (xy 401.530441 -284.791082) (xy 401.563076 -284.754245)
			(xy 401.601197 -284.72312) (xy 401.643818 -284.698513) (xy 401.689834 -284.681061) (xy 401.738053 -284.671217)
			(xy 401.787228 -284.669236) (xy 401.836083 -284.675168) (xy 401.883354 -284.68886) (xy 401.927816 -284.709958)
			(xy 401.968319 -284.737914) (xy 402.003812 -284.772006) (xy 402.033377 -284.81135) (xy 402.056248 -284.854927)
			(xy 402.071832 -284.901608) (xy 402.079727 -284.950185) (xy 402.080222 -284.974792) (xy 402.41907 -284.974792)
			(xy 402.42303 -284.925738) (xy 402.434807 -284.877954) (xy 402.454098 -284.832678) (xy 402.480401 -284.791082)
			(xy 402.513036 -284.754245) (xy 402.551157 -284.72312) (xy 402.593778 -284.698513) (xy 402.639794 -284.681061)
			(xy 402.688013 -284.671217) (xy 402.737188 -284.669236) (xy 402.786043 -284.675168) (xy 402.833314 -284.68886)
			(xy 402.877776 -284.709958) (xy 402.918279 -284.737914) (xy 402.953772 -284.772006) (xy 402.983337 -284.81135)
			(xy 403.006208 -284.854927) (xy 403.021792 -284.901608) (xy 403.029687 -284.950185) (xy 403.030182 -284.974792)
			(xy 403.36903 -284.974792) (xy 403.37299 -284.925738) (xy 403.384767 -284.877954) (xy 403.404058 -284.832678)
			(xy 403.430361 -284.791082) (xy 403.462996 -284.754245) (xy 403.501117 -284.72312) (xy 403.543738 -284.698513)
			(xy 403.589754 -284.681061) (xy 403.637973 -284.671217) (xy 403.687148 -284.669236) (xy 403.736003 -284.675168)
			(xy 403.783274 -284.68886) (xy 403.827736 -284.709958) (xy 403.868239 -284.737914) (xy 403.903732 -284.772006)
			(xy 403.933297 -284.81135) (xy 403.956168 -284.854927) (xy 403.971752 -284.901608) (xy 403.979647 -284.950185)
			(xy 403.980142 -284.974792) (xy 404.31899 -284.974792) (xy 404.32295 -284.925738) (xy 404.334727 -284.877954)
			(xy 404.354018 -284.832678) (xy 404.380321 -284.791082) (xy 404.412956 -284.754245) (xy 404.451077 -284.72312)
			(xy 404.493698 -284.698513) (xy 404.539714 -284.681061) (xy 404.587933 -284.671217) (xy 404.637108 -284.669236)
			(xy 404.685963 -284.675168) (xy 404.733234 -284.68886) (xy 404.777696 -284.709958) (xy 404.818199 -284.737914)
			(xy 404.853692 -284.772006) (xy 404.883257 -284.81135) (xy 404.906128 -284.854927) (xy 404.921712 -284.901608)
			(xy 404.929607 -284.950185) (xy 404.930102 -284.974792) (xy 405.269204 -284.974792) (xy 405.273164 -284.925738)
			(xy 405.284941 -284.877954) (xy 405.304232 -284.832678) (xy 405.330535 -284.791082) (xy 405.36317 -284.754245)
			(xy 405.401291 -284.72312) (xy 405.443912 -284.698513) (xy 405.489928 -284.681061) (xy 405.538147 -284.671217)
			(xy 405.587322 -284.669236) (xy 405.636177 -284.675168) (xy 405.683448 -284.68886) (xy 405.72791 -284.709958)
			(xy 405.768413 -284.737914) (xy 405.803906 -284.772006) (xy 405.833471 -284.81135) (xy 405.856342 -284.854927)
			(xy 405.871926 -284.901608) (xy 405.879821 -284.950185) (xy 405.880316 -284.974792) (xy 406.219164 -284.974792)
			(xy 406.223124 -284.925738) (xy 406.234901 -284.877954) (xy 406.254192 -284.832678) (xy 406.280495 -284.791082)
			(xy 406.31313 -284.754245) (xy 406.351251 -284.72312) (xy 406.393872 -284.698513) (xy 406.439888 -284.681061)
			(xy 406.488107 -284.671217) (xy 406.537282 -284.669236) (xy 406.586137 -284.675168) (xy 406.633408 -284.68886)
			(xy 406.67787 -284.709958) (xy 406.718373 -284.737914) (xy 406.753866 -284.772006) (xy 406.783431 -284.81135)
			(xy 406.806302 -284.854927) (xy 406.821886 -284.901608) (xy 406.829781 -284.950185) (xy 406.830276 -284.974792)
			(xy 408.119084 -284.974792) (xy 408.123044 -284.925738) (xy 408.134821 -284.877954) (xy 408.154112 -284.832678)
			(xy 408.180415 -284.791082) (xy 408.21305 -284.754245) (xy 408.251171 -284.72312) (xy 408.293792 -284.698513)
			(xy 408.339808 -284.681061) (xy 408.388027 -284.671217) (xy 408.437202 -284.669236) (xy 408.486057 -284.675168)
			(xy 408.533328 -284.68886) (xy 408.57779 -284.709958) (xy 408.618293 -284.737914) (xy 408.653786 -284.772006)
			(xy 408.683351 -284.81135) (xy 408.706222 -284.854927) (xy 408.721806 -284.901608) (xy 408.729701 -284.950185)
			(xy 408.730196 -284.974792) (xy 409.069044 -284.974792) (xy 409.073004 -284.925738) (xy 409.084781 -284.877954)
			(xy 409.104072 -284.832678) (xy 409.130375 -284.791082) (xy 409.16301 -284.754245) (xy 409.201131 -284.72312)
			(xy 409.243752 -284.698513) (xy 409.289768 -284.681061) (xy 409.337987 -284.671217) (xy 409.387162 -284.669236)
			(xy 409.436017 -284.675168) (xy 409.483288 -284.68886) (xy 409.52775 -284.709958) (xy 409.568253 -284.737914)
			(xy 409.603746 -284.772006) (xy 409.633311 -284.81135) (xy 409.656182 -284.854927) (xy 409.671766 -284.901608)
			(xy 409.679661 -284.950185) (xy 409.680156 -284.974792) (xy 410.019004 -284.974792) (xy 410.022964 -284.925738)
			(xy 410.034741 -284.877954) (xy 410.054032 -284.832678) (xy 410.080335 -284.791082) (xy 410.11297 -284.754245)
			(xy 410.151091 -284.72312) (xy 410.193712 -284.698513) (xy 410.239728 -284.681061) (xy 410.287947 -284.671217)
			(xy 410.337122 -284.669236) (xy 410.385977 -284.675168) (xy 410.433248 -284.68886) (xy 410.47771 -284.709958)
			(xy 410.518213 -284.737914) (xy 410.553706 -284.772006) (xy 410.583271 -284.81135) (xy 410.606142 -284.854927)
			(xy 410.621726 -284.901608) (xy 410.629621 -284.950185) (xy 410.630116 -284.974792) (xy 410.969218 -284.974792)
			(xy 410.973178 -284.925738) (xy 410.984955 -284.877954) (xy 411.004246 -284.832678) (xy 411.030549 -284.791082)
			(xy 411.063184 -284.754245) (xy 411.101305 -284.72312) (xy 411.143926 -284.698513) (xy 411.189942 -284.681061)
			(xy 411.238161 -284.671217) (xy 411.287336 -284.669236) (xy 411.336191 -284.675168) (xy 411.383462 -284.68886)
			(xy 411.427924 -284.709958) (xy 411.468427 -284.737914) (xy 411.50392 -284.772006) (xy 411.533485 -284.81135)
			(xy 411.556356 -284.854927) (xy 411.57194 -284.901608) (xy 411.579835 -284.950185) (xy 411.58033 -284.974792)
			(xy 411.919178 -284.974792) (xy 411.923138 -284.925738) (xy 411.934915 -284.877954) (xy 411.954206 -284.832678)
			(xy 411.980509 -284.791082) (xy 412.013144 -284.754245) (xy 412.051265 -284.72312) (xy 412.093886 -284.698513)
			(xy 412.139902 -284.681061) (xy 412.188121 -284.671217) (xy 412.237296 -284.669236) (xy 412.286151 -284.675168)
			(xy 412.333422 -284.68886) (xy 412.377884 -284.709958) (xy 412.418387 -284.737914) (xy 412.45388 -284.772006)
			(xy 412.483445 -284.81135) (xy 412.506316 -284.854927) (xy 412.5219 -284.901608) (xy 412.529795 -284.950185)
			(xy 412.53029 -284.974792) (xy 412.869138 -284.974792) (xy 412.873098 -284.925738) (xy 412.884875 -284.877954)
			(xy 412.904166 -284.832678) (xy 412.930469 -284.791082) (xy 412.963104 -284.754245) (xy 413.001225 -284.72312)
			(xy 413.043846 -284.698513) (xy 413.089862 -284.681061) (xy 413.138081 -284.671217) (xy 413.187256 -284.669236)
			(xy 413.236111 -284.675168) (xy 413.283382 -284.68886) (xy 413.327844 -284.709958) (xy 413.368347 -284.737914)
			(xy 413.40384 -284.772006) (xy 413.433405 -284.81135) (xy 413.456276 -284.854927) (xy 413.47186 -284.901608)
			(xy 413.479755 -284.950185) (xy 413.48025 -284.974792) (xy 413.819098 -284.974792) (xy 413.823058 -284.925738)
			(xy 413.834835 -284.877954) (xy 413.854126 -284.832678) (xy 413.880429 -284.791082) (xy 413.913064 -284.754245)
			(xy 413.951185 -284.72312) (xy 413.993806 -284.698513) (xy 414.039822 -284.681061) (xy 414.088041 -284.671217)
			(xy 414.137216 -284.669236) (xy 414.186071 -284.675168) (xy 414.233342 -284.68886) (xy 414.277804 -284.709958)
			(xy 414.318307 -284.737914) (xy 414.3538 -284.772006) (xy 414.383365 -284.81135) (xy 414.406236 -284.854927)
			(xy 414.42182 -284.901608) (xy 414.429715 -284.950185) (xy 414.43021 -284.974792) (xy 414.769058 -284.974792)
			(xy 414.773018 -284.925738) (xy 414.784795 -284.877954) (xy 414.804086 -284.832678) (xy 414.830389 -284.791082)
			(xy 414.863024 -284.754245) (xy 414.901145 -284.72312) (xy 414.943766 -284.698513) (xy 414.989782 -284.681061)
			(xy 415.038001 -284.671217) (xy 415.087176 -284.669236) (xy 415.136031 -284.675168) (xy 415.183302 -284.68886)
			(xy 415.227764 -284.709958) (xy 415.268267 -284.737914) (xy 415.30376 -284.772006) (xy 415.333325 -284.81135)
			(xy 415.356196 -284.854927) (xy 415.37178 -284.901608) (xy 415.379675 -284.950185) (xy 415.38017 -284.974792)
			(xy 415.719018 -284.974792) (xy 415.722978 -284.925738) (xy 415.734755 -284.877954) (xy 415.754046 -284.832678)
			(xy 415.780349 -284.791082) (xy 415.812984 -284.754245) (xy 415.851105 -284.72312) (xy 415.893726 -284.698513)
			(xy 415.939742 -284.681061) (xy 415.987961 -284.671217) (xy 416.037136 -284.669236) (xy 416.085991 -284.675168)
			(xy 416.133262 -284.68886) (xy 416.177724 -284.709958) (xy 416.218227 -284.737914) (xy 416.25372 -284.772006)
			(xy 416.283285 -284.81135) (xy 416.306156 -284.854927) (xy 416.32174 -284.901608) (xy 416.329635 -284.950185)
			(xy 416.33013 -284.974792) (xy 416.668978 -284.974792) (xy 416.672938 -284.925738) (xy 416.684715 -284.877954)
			(xy 416.704006 -284.832678) (xy 416.730309 -284.791082) (xy 416.762944 -284.754245) (xy 416.801065 -284.72312)
			(xy 416.843686 -284.698513) (xy 416.889702 -284.681061) (xy 416.937921 -284.671217) (xy 416.987096 -284.669236)
			(xy 417.035951 -284.675168) (xy 417.083222 -284.68886) (xy 417.127684 -284.709958) (xy 417.168187 -284.737914)
			(xy 417.20368 -284.772006) (xy 417.233245 -284.81135) (xy 417.256116 -284.854927) (xy 417.2717 -284.901608)
			(xy 417.279595 -284.950185) (xy 417.28009 -284.974792) (xy 417.619192 -284.974792) (xy 417.623152 -284.925738)
			(xy 417.634929 -284.877954) (xy 417.65422 -284.832678) (xy 417.680523 -284.791082) (xy 417.713158 -284.754245)
			(xy 417.751279 -284.72312) (xy 417.7939 -284.698513) (xy 417.839916 -284.681061) (xy 417.888135 -284.671217)
			(xy 417.93731 -284.669236) (xy 417.986165 -284.675168) (xy 418.033436 -284.68886) (xy 418.077898 -284.709958)
			(xy 418.118401 -284.737914) (xy 418.153894 -284.772006) (xy 418.183459 -284.81135) (xy 418.20633 -284.854927)
			(xy 418.221914 -284.901608) (xy 418.229809 -284.950185) (xy 418.230304 -284.974792) (xy 418.569152 -284.974792)
			(xy 418.573112 -284.925738) (xy 418.584889 -284.877954) (xy 418.60418 -284.832678) (xy 418.630483 -284.791082)
			(xy 418.663118 -284.754245) (xy 418.701239 -284.72312) (xy 418.74386 -284.698513) (xy 418.789876 -284.681061)
			(xy 418.838095 -284.671217) (xy 418.88727 -284.669236) (xy 418.936125 -284.675168) (xy 418.983396 -284.68886)
			(xy 419.027858 -284.709958) (xy 419.068361 -284.737914) (xy 419.103854 -284.772006) (xy 419.133419 -284.81135)
			(xy 419.15629 -284.854927) (xy 419.171874 -284.901608) (xy 419.179769 -284.950185) (xy 419.180264 -284.974792)
			(xy 419.179769 -284.999399) (xy 419.171874 -285.047976) (xy 419.15629 -285.094657) (xy 419.133419 -285.138234)
			(xy 419.103854 -285.177578) (xy 419.068361 -285.21167) (xy 419.027858 -285.239626) (xy 418.983396 -285.260724)
			(xy 418.936125 -285.274416) (xy 418.88727 -285.280348) (xy 418.838095 -285.278367) (xy 418.789876 -285.268523)
			(xy 418.74386 -285.251071) (xy 418.701239 -285.226464) (xy 418.663118 -285.195339) (xy 418.630483 -285.158502)
			(xy 418.60418 -285.116906) (xy 418.584889 -285.07163) (xy 418.573112 -285.023846) (xy 418.569152 -284.974792)
			(xy 418.230304 -284.974792) (xy 418.229809 -284.999399) (xy 418.221914 -285.047976) (xy 418.20633 -285.094657)
			(xy 418.183459 -285.138234) (xy 418.153894 -285.177578) (xy 418.118401 -285.21167) (xy 418.077898 -285.239626)
			(xy 418.033436 -285.260724) (xy 417.986165 -285.274416) (xy 417.93731 -285.280348) (xy 417.888135 -285.278367)
			(xy 417.839916 -285.268523) (xy 417.7939 -285.251071) (xy 417.751279 -285.226464) (xy 417.713158 -285.195339)
			(xy 417.680523 -285.158502) (xy 417.65422 -285.116906) (xy 417.634929 -285.07163) (xy 417.623152 -285.023846)
			(xy 417.619192 -284.974792) (xy 417.28009 -284.974792) (xy 417.279595 -284.999399) (xy 417.2717 -285.047976)
			(xy 417.256116 -285.094657) (xy 417.233245 -285.138234) (xy 417.20368 -285.177578) (xy 417.168187 -285.21167)
			(xy 417.127684 -285.239626) (xy 417.083222 -285.260724) (xy 417.035951 -285.274416) (xy 416.987096 -285.280348)
			(xy 416.937921 -285.278367) (xy 416.889702 -285.268523) (xy 416.843686 -285.251071) (xy 416.801065 -285.226464)
			(xy 416.762944 -285.195339) (xy 416.730309 -285.158502) (xy 416.704006 -285.116906) (xy 416.684715 -285.07163)
			(xy 416.672938 -285.023846) (xy 416.668978 -284.974792) (xy 416.33013 -284.974792) (xy 416.329635 -284.999399)
			(xy 416.32174 -285.047976) (xy 416.306156 -285.094657) (xy 416.283285 -285.138234) (xy 416.25372 -285.177578)
			(xy 416.218227 -285.21167) (xy 416.177724 -285.239626) (xy 416.133262 -285.260724) (xy 416.085991 -285.274416)
			(xy 416.037136 -285.280348) (xy 415.987961 -285.278367) (xy 415.939742 -285.268523) (xy 415.893726 -285.251071)
			(xy 415.851105 -285.226464) (xy 415.812984 -285.195339) (xy 415.780349 -285.158502) (xy 415.754046 -285.116906)
			(xy 415.734755 -285.07163) (xy 415.722978 -285.023846) (xy 415.719018 -284.974792) (xy 415.38017 -284.974792)
			(xy 415.379675 -284.999399) (xy 415.37178 -285.047976) (xy 415.356196 -285.094657) (xy 415.333325 -285.138234)
			(xy 415.30376 -285.177578) (xy 415.268267 -285.21167) (xy 415.227764 -285.239626) (xy 415.183302 -285.260724)
			(xy 415.136031 -285.274416) (xy 415.087176 -285.280348) (xy 415.038001 -285.278367) (xy 414.989782 -285.268523)
			(xy 414.943766 -285.251071) (xy 414.901145 -285.226464) (xy 414.863024 -285.195339) (xy 414.830389 -285.158502)
			(xy 414.804086 -285.116906) (xy 414.784795 -285.07163) (xy 414.773018 -285.023846) (xy 414.769058 -284.974792)
			(xy 414.43021 -284.974792) (xy 414.429715 -284.999399) (xy 414.42182 -285.047976) (xy 414.406236 -285.094657)
			(xy 414.383365 -285.138234) (xy 414.3538 -285.177578) (xy 414.318307 -285.21167) (xy 414.277804 -285.239626)
			(xy 414.233342 -285.260724) (xy 414.186071 -285.274416) (xy 414.137216 -285.280348) (xy 414.088041 -285.278367)
			(xy 414.039822 -285.268523) (xy 413.993806 -285.251071) (xy 413.951185 -285.226464) (xy 413.913064 -285.195339)
			(xy 413.880429 -285.158502) (xy 413.854126 -285.116906) (xy 413.834835 -285.07163) (xy 413.823058 -285.023846)
			(xy 413.819098 -284.974792) (xy 413.48025 -284.974792) (xy 413.479755 -284.999399) (xy 413.47186 -285.047976)
			(xy 413.456276 -285.094657) (xy 413.433405 -285.138234) (xy 413.40384 -285.177578) (xy 413.368347 -285.21167)
			(xy 413.327844 -285.239626) (xy 413.283382 -285.260724) (xy 413.236111 -285.274416) (xy 413.187256 -285.280348)
			(xy 413.138081 -285.278367) (xy 413.089862 -285.268523) (xy 413.043846 -285.251071) (xy 413.001225 -285.226464)
			(xy 412.963104 -285.195339) (xy 412.930469 -285.158502) (xy 412.904166 -285.116906) (xy 412.884875 -285.07163)
			(xy 412.873098 -285.023846) (xy 412.869138 -284.974792) (xy 412.53029 -284.974792) (xy 412.529795 -284.999399)
			(xy 412.5219 -285.047976) (xy 412.506316 -285.094657) (xy 412.483445 -285.138234) (xy 412.45388 -285.177578)
			(xy 412.418387 -285.21167) (xy 412.377884 -285.239626) (xy 412.333422 -285.260724) (xy 412.286151 -285.274416)
			(xy 412.237296 -285.280348) (xy 412.188121 -285.278367) (xy 412.139902 -285.268523) (xy 412.093886 -285.251071)
			(xy 412.051265 -285.226464) (xy 412.013144 -285.195339) (xy 411.980509 -285.158502) (xy 411.954206 -285.116906)
			(xy 411.934915 -285.07163) (xy 411.923138 -285.023846) (xy 411.919178 -284.974792) (xy 411.58033 -284.974792)
			(xy 411.579835 -284.999399) (xy 411.57194 -285.047976) (xy 411.556356 -285.094657) (xy 411.533485 -285.138234)
			(xy 411.50392 -285.177578) (xy 411.468427 -285.21167) (xy 411.427924 -285.239626) (xy 411.383462 -285.260724)
			(xy 411.336191 -285.274416) (xy 411.287336 -285.280348) (xy 411.238161 -285.278367) (xy 411.189942 -285.268523)
			(xy 411.143926 -285.251071) (xy 411.101305 -285.226464) (xy 411.063184 -285.195339) (xy 411.030549 -285.158502)
			(xy 411.004246 -285.116906) (xy 410.984955 -285.07163) (xy 410.973178 -285.023846) (xy 410.969218 -284.974792)
			(xy 410.630116 -284.974792) (xy 410.629621 -284.999399) (xy 410.621726 -285.047976) (xy 410.606142 -285.094657)
			(xy 410.583271 -285.138234) (xy 410.553706 -285.177578) (xy 410.518213 -285.21167) (xy 410.47771 -285.239626)
			(xy 410.433248 -285.260724) (xy 410.385977 -285.274416) (xy 410.337122 -285.280348) (xy 410.287947 -285.278367)
			(xy 410.239728 -285.268523) (xy 410.193712 -285.251071) (xy 410.151091 -285.226464) (xy 410.11297 -285.195339)
			(xy 410.080335 -285.158502) (xy 410.054032 -285.116906) (xy 410.034741 -285.07163) (xy 410.022964 -285.023846)
			(xy 410.019004 -284.974792) (xy 409.680156 -284.974792) (xy 409.679661 -284.999399) (xy 409.671766 -285.047976)
			(xy 409.656182 -285.094657) (xy 409.633311 -285.138234) (xy 409.603746 -285.177578) (xy 409.568253 -285.21167)
			(xy 409.52775 -285.239626) (xy 409.483288 -285.260724) (xy 409.436017 -285.274416) (xy 409.387162 -285.280348)
			(xy 409.337987 -285.278367) (xy 409.289768 -285.268523) (xy 409.243752 -285.251071) (xy 409.201131 -285.226464)
			(xy 409.16301 -285.195339) (xy 409.130375 -285.158502) (xy 409.104072 -285.116906) (xy 409.084781 -285.07163)
			(xy 409.073004 -285.023846) (xy 409.069044 -284.974792) (xy 408.730196 -284.974792) (xy 408.729701 -284.999399)
			(xy 408.721806 -285.047976) (xy 408.706222 -285.094657) (xy 408.683351 -285.138234) (xy 408.653786 -285.177578)
			(xy 408.618293 -285.21167) (xy 408.57779 -285.239626) (xy 408.533328 -285.260724) (xy 408.486057 -285.274416)
			(xy 408.437202 -285.280348) (xy 408.388027 -285.278367) (xy 408.339808 -285.268523) (xy 408.293792 -285.251071)
			(xy 408.251171 -285.226464) (xy 408.21305 -285.195339) (xy 408.180415 -285.158502) (xy 408.154112 -285.116906)
			(xy 408.134821 -285.07163) (xy 408.123044 -285.023846) (xy 408.119084 -284.974792) (xy 406.830276 -284.974792)
			(xy 406.829781 -284.999399) (xy 406.821886 -285.047976) (xy 406.806302 -285.094657) (xy 406.783431 -285.138234)
			(xy 406.753866 -285.177578) (xy 406.718373 -285.21167) (xy 406.67787 -285.239626) (xy 406.633408 -285.260724)
			(xy 406.586137 -285.274416) (xy 406.537282 -285.280348) (xy 406.488107 -285.278367) (xy 406.439888 -285.268523)
			(xy 406.393872 -285.251071) (xy 406.351251 -285.226464) (xy 406.31313 -285.195339) (xy 406.280495 -285.158502)
			(xy 406.254192 -285.116906) (xy 406.234901 -285.07163) (xy 406.223124 -285.023846) (xy 406.219164 -284.974792)
			(xy 405.880316 -284.974792) (xy 405.879821 -284.999399) (xy 405.871926 -285.047976) (xy 405.856342 -285.094657)
			(xy 405.833471 -285.138234) (xy 405.803906 -285.177578) (xy 405.768413 -285.21167) (xy 405.72791 -285.239626)
			(xy 405.683448 -285.260724) (xy 405.636177 -285.274416) (xy 405.587322 -285.280348) (xy 405.538147 -285.278367)
			(xy 405.489928 -285.268523) (xy 405.443912 -285.251071) (xy 405.401291 -285.226464) (xy 405.36317 -285.195339)
			(xy 405.330535 -285.158502) (xy 405.304232 -285.116906) (xy 405.284941 -285.07163) (xy 405.273164 -285.023846)
			(xy 405.269204 -284.974792) (xy 404.930102 -284.974792) (xy 404.929607 -284.999399) (xy 404.921712 -285.047976)
			(xy 404.906128 -285.094657) (xy 404.883257 -285.138234) (xy 404.853692 -285.177578) (xy 404.818199 -285.21167)
			(xy 404.777696 -285.239626) (xy 404.733234 -285.260724) (xy 404.685963 -285.274416) (xy 404.637108 -285.280348)
			(xy 404.587933 -285.278367) (xy 404.539714 -285.268523) (xy 404.493698 -285.251071) (xy 404.451077 -285.226464)
			(xy 404.412956 -285.195339) (xy 404.380321 -285.158502) (xy 404.354018 -285.116906) (xy 404.334727 -285.07163)
			(xy 404.32295 -285.023846) (xy 404.31899 -284.974792) (xy 403.980142 -284.974792) (xy 403.979647 -284.999399)
			(xy 403.971752 -285.047976) (xy 403.956168 -285.094657) (xy 403.933297 -285.138234) (xy 403.903732 -285.177578)
			(xy 403.868239 -285.21167) (xy 403.827736 -285.239626) (xy 403.783274 -285.260724) (xy 403.736003 -285.274416)
			(xy 403.687148 -285.280348) (xy 403.637973 -285.278367) (xy 403.589754 -285.268523) (xy 403.543738 -285.251071)
			(xy 403.501117 -285.226464) (xy 403.462996 -285.195339) (xy 403.430361 -285.158502) (xy 403.404058 -285.116906)
			(xy 403.384767 -285.07163) (xy 403.37299 -285.023846) (xy 403.36903 -284.974792) (xy 403.030182 -284.974792)
			(xy 403.029687 -284.999399) (xy 403.021792 -285.047976) (xy 403.006208 -285.094657) (xy 402.983337 -285.138234)
			(xy 402.953772 -285.177578) (xy 402.918279 -285.21167) (xy 402.877776 -285.239626) (xy 402.833314 -285.260724)
			(xy 402.786043 -285.274416) (xy 402.737188 -285.280348) (xy 402.688013 -285.278367) (xy 402.639794 -285.268523)
			(xy 402.593778 -285.251071) (xy 402.551157 -285.226464) (xy 402.513036 -285.195339) (xy 402.480401 -285.158502)
			(xy 402.454098 -285.116906) (xy 402.434807 -285.07163) (xy 402.42303 -285.023846) (xy 402.41907 -284.974792)
			(xy 402.080222 -284.974792) (xy 402.079727 -284.999399) (xy 402.071832 -285.047976) (xy 402.056248 -285.094657)
			(xy 402.033377 -285.138234) (xy 402.003812 -285.177578) (xy 401.968319 -285.21167) (xy 401.927816 -285.239626)
			(xy 401.883354 -285.260724) (xy 401.836083 -285.274416) (xy 401.787228 -285.280348) (xy 401.738053 -285.278367)
			(xy 401.689834 -285.268523) (xy 401.643818 -285.251071) (xy 401.601197 -285.226464) (xy 401.563076 -285.195339)
			(xy 401.530441 -285.158502) (xy 401.504138 -285.116906) (xy 401.484847 -285.07163) (xy 401.47307 -285.023846)
			(xy 401.46911 -284.974792) (xy 401.130262 -284.974792) (xy 401.129767 -284.999399) (xy 401.121872 -285.047976)
			(xy 401.106288 -285.094657) (xy 401.083417 -285.138234) (xy 401.053852 -285.177578) (xy 401.018359 -285.21167)
			(xy 400.977856 -285.239626) (xy 400.933394 -285.260724) (xy 400.886123 -285.274416) (xy 400.837268 -285.280348)
			(xy 400.788093 -285.278367) (xy 400.739874 -285.268523) (xy 400.693858 -285.251071) (xy 400.651237 -285.226464)
			(xy 400.613116 -285.195339) (xy 400.580481 -285.158502) (xy 400.554178 -285.116906) (xy 400.534887 -285.07163)
			(xy 400.52311 -285.023846) (xy 400.51915 -284.974792) (xy 400.180302 -284.974792) (xy 400.179807 -284.999399)
			(xy 400.171912 -285.047976) (xy 400.156328 -285.094657) (xy 400.133457 -285.138234) (xy 400.103892 -285.177578)
			(xy 400.068399 -285.21167) (xy 400.027896 -285.239626) (xy 399.983434 -285.260724) (xy 399.936163 -285.274416)
			(xy 399.887308 -285.280348) (xy 399.838133 -285.278367) (xy 399.789914 -285.268523) (xy 399.743898 -285.251071)
			(xy 399.701277 -285.226464) (xy 399.663156 -285.195339) (xy 399.630521 -285.158502) (xy 399.604218 -285.116906)
			(xy 399.584927 -285.07163) (xy 399.57315 -285.023846) (xy 399.56919 -284.974792) (xy 399.230342 -284.974792)
			(xy 399.229847 -284.999399) (xy 399.221952 -285.047976) (xy 399.206368 -285.094657) (xy 399.183497 -285.138234)
			(xy 399.153932 -285.177578) (xy 399.118439 -285.21167) (xy 399.077936 -285.239626) (xy 399.033474 -285.260724)
			(xy 398.986203 -285.274416) (xy 398.937348 -285.280348) (xy 398.888173 -285.278367) (xy 398.839954 -285.268523)
			(xy 398.793938 -285.251071) (xy 398.751317 -285.226464) (xy 398.713196 -285.195339) (xy 398.680561 -285.158502)
			(xy 398.654258 -285.116906) (xy 398.634967 -285.07163) (xy 398.62319 -285.023846) (xy 398.61923 -284.974792)
			(xy 398.280128 -284.974792) (xy 398.279633 -284.999399) (xy 398.271738 -285.047976) (xy 398.256154 -285.094657)
			(xy 398.233283 -285.138234) (xy 398.203718 -285.177578) (xy 398.168225 -285.21167) (xy 398.127722 -285.239626)
			(xy 398.08326 -285.260724) (xy 398.035989 -285.274416) (xy 397.987134 -285.280348) (xy 397.937959 -285.278367)
			(xy 397.88974 -285.268523) (xy 397.843724 -285.251071) (xy 397.801103 -285.226464) (xy 397.762982 -285.195339)
			(xy 397.730347 -285.158502) (xy 397.704044 -285.116906) (xy 397.684753 -285.07163) (xy 397.672976 -285.023846)
			(xy 397.669016 -284.974792) (xy 397.330168 -284.974792) (xy 397.329673 -284.999399) (xy 397.321778 -285.047976)
			(xy 397.306194 -285.094657) (xy 397.283323 -285.138234) (xy 397.253758 -285.177578) (xy 397.218265 -285.21167)
			(xy 397.177762 -285.239626) (xy 397.1333 -285.260724) (xy 397.086029 -285.274416) (xy 397.037174 -285.280348)
			(xy 396.987999 -285.278367) (xy 396.93978 -285.268523) (xy 396.893764 -285.251071) (xy 396.851143 -285.226464)
			(xy 396.813022 -285.195339) (xy 396.780387 -285.158502) (xy 396.754084 -285.116906) (xy 396.734793 -285.07163)
			(xy 396.723016 -285.023846) (xy 396.719056 -284.974792) (xy 396.55369 -284.974792) (xy 396.55369 -285.449772)
			(xy 421.894012 -285.449772) (xy 421.897972 -285.400718) (xy 421.909749 -285.352934) (xy 421.92904 -285.307658)
			(xy 421.955343 -285.266062) (xy 421.987978 -285.229225) (xy 422.026099 -285.1981) (xy 422.06872 -285.173493)
			(xy 422.114736 -285.156041) (xy 422.162955 -285.146197) (xy 422.21213 -285.144216) (xy 422.260985 -285.150148)
			(xy 422.308256 -285.16384) (xy 422.352718 -285.184938) (xy 422.393221 -285.212894) (xy 422.428714 -285.246986)
			(xy 422.458279 -285.28633) (xy 422.48115 -285.329907) (xy 422.496734 -285.376588) (xy 422.504629 -285.425165)
			(xy 422.505124 -285.449772) (xy 422.843972 -285.449772) (xy 422.847932 -285.400718) (xy 422.859709 -285.352934)
			(xy 422.879 -285.307658) (xy 422.905303 -285.266062) (xy 422.937938 -285.229225) (xy 422.976059 -285.1981)
			(xy 423.01868 -285.173493) (xy 423.064696 -285.156041) (xy 423.112915 -285.146197) (xy 423.16209 -285.144216)
			(xy 423.210945 -285.150148) (xy 423.258216 -285.16384) (xy 423.302678 -285.184938) (xy 423.343181 -285.212894)
			(xy 423.378674 -285.246986) (xy 423.408239 -285.28633) (xy 423.43111 -285.329907) (xy 423.446694 -285.376588)
			(xy 423.454589 -285.425165) (xy 423.455084 -285.449772) (xy 423.794186 -285.449772) (xy 423.798146 -285.400718)
			(xy 423.809923 -285.352934) (xy 423.829214 -285.307658) (xy 423.855517 -285.266062) (xy 423.888152 -285.229225)
			(xy 423.926273 -285.1981) (xy 423.968894 -285.173493) (xy 424.01491 -285.156041) (xy 424.063129 -285.146197)
			(xy 424.112304 -285.144216) (xy 424.161159 -285.150148) (xy 424.20843 -285.16384) (xy 424.252892 -285.184938)
			(xy 424.293395 -285.212894) (xy 424.328888 -285.246986) (xy 424.358453 -285.28633) (xy 424.381324 -285.329907)
			(xy 424.396908 -285.376588) (xy 424.404803 -285.425165) (xy 424.405298 -285.449772) (xy 424.744146 -285.449772)
			(xy 424.748106 -285.400718) (xy 424.759883 -285.352934) (xy 424.779174 -285.307658) (xy 424.805477 -285.266062)
			(xy 424.838112 -285.229225) (xy 424.876233 -285.1981) (xy 424.918854 -285.173493) (xy 424.96487 -285.156041)
			(xy 425.013089 -285.146197) (xy 425.062264 -285.144216) (xy 425.111119 -285.150148) (xy 425.15839 -285.16384)
			(xy 425.202852 -285.184938) (xy 425.243355 -285.212894) (xy 425.278848 -285.246986) (xy 425.308413 -285.28633)
			(xy 425.331284 -285.329907) (xy 425.346868 -285.376588) (xy 425.354763 -285.425165) (xy 425.355258 -285.449772)
			(xy 425.694106 -285.449772) (xy 425.698066 -285.400718) (xy 425.709843 -285.352934) (xy 425.729134 -285.307658)
			(xy 425.755437 -285.266062) (xy 425.788072 -285.229225) (xy 425.826193 -285.1981) (xy 425.868814 -285.173493)
			(xy 425.91483 -285.156041) (xy 425.963049 -285.146197) (xy 426.012224 -285.144216) (xy 426.061079 -285.150148)
			(xy 426.10835 -285.16384) (xy 426.152812 -285.184938) (xy 426.193315 -285.212894) (xy 426.228808 -285.246986)
			(xy 426.258373 -285.28633) (xy 426.281244 -285.329907) (xy 426.296828 -285.376588) (xy 426.304723 -285.425165)
			(xy 426.305218 -285.449772) (xy 426.644066 -285.449772) (xy 426.648026 -285.400718) (xy 426.659803 -285.352934)
			(xy 426.679094 -285.307658) (xy 426.705397 -285.266062) (xy 426.738032 -285.229225) (xy 426.776153 -285.1981)
			(xy 426.818774 -285.173493) (xy 426.86479 -285.156041) (xy 426.913009 -285.146197) (xy 426.962184 -285.144216)
			(xy 427.011039 -285.150148) (xy 427.05831 -285.16384) (xy 427.102772 -285.184938) (xy 427.143275 -285.212894)
			(xy 427.178768 -285.246986) (xy 427.208333 -285.28633) (xy 427.231204 -285.329907) (xy 427.246788 -285.376588)
			(xy 427.254683 -285.425165) (xy 427.255178 -285.449772) (xy 427.594026 -285.449772) (xy 427.597986 -285.400718)
			(xy 427.609763 -285.352934) (xy 427.629054 -285.307658) (xy 427.655357 -285.266062) (xy 427.687992 -285.229225)
			(xy 427.726113 -285.1981) (xy 427.768734 -285.173493) (xy 427.81475 -285.156041) (xy 427.862969 -285.146197)
			(xy 427.912144 -285.144216) (xy 427.960999 -285.150148) (xy 428.00827 -285.16384) (xy 428.052732 -285.184938)
			(xy 428.093235 -285.212894) (xy 428.128728 -285.246986) (xy 428.158293 -285.28633) (xy 428.181164 -285.329907)
			(xy 428.196748 -285.376588) (xy 428.204643 -285.425165) (xy 428.205138 -285.449772) (xy 428.543986 -285.449772)
			(xy 428.547946 -285.400718) (xy 428.559723 -285.352934) (xy 428.579014 -285.307658) (xy 428.605317 -285.266062)
			(xy 428.637952 -285.229225) (xy 428.676073 -285.1981) (xy 428.718694 -285.173493) (xy 428.76471 -285.156041)
			(xy 428.812929 -285.146197) (xy 428.862104 -285.144216) (xy 428.910959 -285.150148) (xy 428.95823 -285.16384)
			(xy 429.002692 -285.184938) (xy 429.043195 -285.212894) (xy 429.078688 -285.246986) (xy 429.108253 -285.28633)
			(xy 429.131124 -285.329907) (xy 429.146708 -285.376588) (xy 429.154603 -285.425165) (xy 429.155098 -285.449772)
			(xy 429.154603 -285.474379) (xy 429.154424 -285.47548) (xy 429.473356 -285.47548) (xy 429.473356 -285.424064)
			(xy 429.481399 -285.373282) (xy 429.497287 -285.324383) (xy 429.52063 -285.278571) (xy 429.550851 -285.236975)
			(xy 429.587207 -285.200619) (xy 429.628803 -285.170398) (xy 429.674615 -285.147055) (xy 429.723514 -285.131167)
			(xy 429.774296 -285.123124) (xy 429.825712 -285.123124) (xy 429.876494 -285.131167) (xy 429.925393 -285.147055)
			(xy 429.971205 -285.170398) (xy 430.012801 -285.200619) (xy 430.049157 -285.236975) (xy 430.079378 -285.278571)
			(xy 430.102721 -285.324383) (xy 430.118609 -285.373282) (xy 430.126652 -285.424064) (xy 430.127156 -285.449772)
			(xy 430.126652 -285.47548) (xy 430.423316 -285.47548) (xy 430.423316 -285.424064) (xy 430.431359 -285.373282)
			(xy 430.447247 -285.324383) (xy 430.47059 -285.278571) (xy 430.500811 -285.236975) (xy 430.537167 -285.200619)
			(xy 430.578763 -285.170398) (xy 430.624575 -285.147055) (xy 430.673474 -285.131167) (xy 430.724256 -285.123124)
			(xy 430.775672 -285.123124) (xy 430.826454 -285.131167) (xy 430.875353 -285.147055) (xy 430.921165 -285.170398)
			(xy 430.962761 -285.200619) (xy 430.999117 -285.236975) (xy 431.029338 -285.278571) (xy 431.052681 -285.324383)
			(xy 431.068569 -285.373282) (xy 431.076612 -285.424064) (xy 431.077116 -285.449772) (xy 431.077111 -285.450026)
			(xy 431.394374 -285.450026) (xy 431.398334 -285.400972) (xy 431.410111 -285.353188) (xy 431.429402 -285.307912)
			(xy 431.455705 -285.266316) (xy 431.48834 -285.229479) (xy 431.526461 -285.198354) (xy 431.569082 -285.173747)
			(xy 431.615098 -285.156295) (xy 431.663317 -285.146451) (xy 431.712492 -285.14447) (xy 431.761347 -285.150402)
			(xy 431.808618 -285.164094) (xy 431.85308 -285.185192) (xy 431.893583 -285.213148) (xy 431.929076 -285.24724)
			(xy 431.958641 -285.286584) (xy 431.981512 -285.330161) (xy 431.997096 -285.376842) (xy 432.004991 -285.425419)
			(xy 432.005486 -285.450026) (xy 432.004991 -285.474633) (xy 431.997096 -285.52321) (xy 431.981512 -285.569891)
			(xy 431.962271 -285.606552) (xy 456.489267 -285.606552) (xy 456.489267 -285.552048) (xy 456.497024 -285.498098)
			(xy 456.51238 -285.445801) (xy 456.535023 -285.396222) (xy 456.56449 -285.35037) (xy 456.600184 -285.309178)
			(xy 456.641376 -285.273486) (xy 456.687229 -285.244019) (xy 456.736808 -285.221377) (xy 456.789106 -285.206023)
			(xy 456.843056 -285.198267) (xy 456.870308 -285.197804) (xy 456.899047 -285.198322) (xy 456.955875 -285.206946)
			(xy 457.010766 -285.223997) (xy 457.062477 -285.24909) (xy 457.109839 -285.281657) (xy 457.131166 -285.300928)
			(xy 457.13142 -285.301182) (xy 457.138717 -285.307307) (xy 457.156447 -285.314238) (xy 457.165964 -285.314644)
			(xy 457.235052 -285.314644) (xy 457.244584 -285.314303) (xy 457.26234 -285.307373) (xy 457.269596 -285.301182)
			(xy 457.26985 -285.300928) (xy 457.291177 -285.281658) (xy 457.33854 -285.249093) (xy 457.390251 -285.224002)
			(xy 457.445142 -285.206952) (xy 457.501969 -285.19833) (xy 457.559447 -285.19833) (xy 457.616274 -285.206952)
			(xy 457.671165 -285.224002) (xy 457.722876 -285.249093) (xy 457.770239 -285.281658) (xy 457.791566 -285.300928)
			(xy 457.79182 -285.301182) (xy 457.799117 -285.307307) (xy 457.816847 -285.314238) (xy 457.826364 -285.314644)
			(xy 457.895452 -285.314644) (xy 457.904984 -285.314303) (xy 457.92274 -285.307373) (xy 457.929996 -285.301182)
			(xy 457.93025 -285.300928) (xy 457.951572 -285.281652) (xy 457.998936 -285.249087) (xy 458.050649 -285.223995)
			(xy 458.10554 -285.206946) (xy 458.162369 -285.198324) (xy 458.191108 -285.197804) (xy 458.221232 -285.198354)
			(xy 458.280731 -285.207838) (xy 458.337999 -285.226552) (xy 458.391616 -285.254033) (xy 458.440249 -285.289598)
			(xy 458.461872 -285.31058) (xy 458.468984 -285.317692) (xy 458.48778 -285.325566) (xy 458.580236 -285.325566)
			(xy 458.599032 -285.317692) (xy 458.606144 -285.31058) (xy 458.627767 -285.289598) (xy 458.676397 -285.254031)
			(xy 458.730014 -285.226551) (xy 458.787284 -285.207844) (xy 458.846784 -285.198372) (xy 458.876908 -285.197804)
			(xy 458.90416 -285.198266) (xy 458.958108 -285.206024) (xy 459.010404 -285.22138) (xy 459.059982 -285.244023)
			(xy 459.105832 -285.27349) (xy 459.147023 -285.309183) (xy 459.182715 -285.350374) (xy 459.212181 -285.396226)
			(xy 459.234822 -285.445804) (xy 459.250178 -285.4981) (xy 459.257934 -285.552048) (xy 459.257934 -285.596653)
			(xy 460.661461 -285.596653) (xy 460.661461 -285.542147) (xy 460.669219 -285.488196) (xy 460.684575 -285.435898)
			(xy 460.707218 -285.386318) (xy 460.736687 -285.340465) (xy 460.772381 -285.299272) (xy 460.813574 -285.263579)
			(xy 460.859428 -285.234112) (xy 460.909009 -285.211471) (xy 460.961308 -285.196116) (xy 461.015259 -285.188361)
			(xy 461.042512 -285.187898) (xy 461.071251 -285.188415) (xy 461.128079 -285.197039) (xy 461.18297 -285.214091)
			(xy 461.234681 -285.239184) (xy 461.282043 -285.271751) (xy 461.30337 -285.291022) (xy 461.303624 -285.291276)
			(xy 461.310921 -285.297402) (xy 461.328651 -285.304332) (xy 461.338168 -285.304738) (xy 461.407256 -285.304738)
			(xy 461.416788 -285.3044) (xy 461.434544 -285.297469) (xy 461.4418 -285.291276) (xy 461.442054 -285.291022)
			(xy 461.463381 -285.271752) (xy 461.510744 -285.239187) (xy 461.562455 -285.214096) (xy 461.617346 -285.197046)
			(xy 461.674173 -285.188424) (xy 461.731651 -285.188424) (xy 461.788478 -285.197046) (xy 461.843369 -285.214096)
			(xy 461.89508 -285.239187) (xy 461.942443 -285.271752) (xy 461.96377 -285.291022) (xy 461.964024 -285.291276)
			(xy 461.971321 -285.297402) (xy 461.989051 -285.304332) (xy 461.998568 -285.304738) (xy 462.067656 -285.304738)
			(xy 462.077188 -285.3044) (xy 462.094944 -285.297469) (xy 462.1022 -285.291276) (xy 462.102454 -285.291022)
			(xy 462.123774 -285.271743) (xy 462.171138 -285.239178) (xy 462.222852 -285.214088) (xy 462.277744 -285.197039)
			(xy 462.334573 -285.188418) (xy 462.363312 -285.187898) (xy 462.393436 -285.188447) (xy 462.452934 -285.197931)
			(xy 462.510203 -285.216646) (xy 462.56382 -285.244128) (xy 462.612453 -285.279692) (xy 462.634076 -285.300674)
			(xy 462.641188 -285.307786) (xy 462.659984 -285.31566) (xy 462.75244 -285.31566) (xy 462.771236 -285.307786)
			(xy 462.778348 -285.300674) (xy 462.799985 -285.279707) (xy 462.848609 -285.244134) (xy 462.902222 -285.21665)
			(xy 462.95949 -285.197939) (xy 463.018988 -285.188467) (xy 463.049112 -285.187898) (xy 463.076363 -285.188373)
			(xy 463.13031 -285.196131) (xy 463.182605 -285.211487) (xy 463.232181 -285.234129) (xy 463.278031 -285.263596)
			(xy 463.31922 -285.299288) (xy 463.354911 -285.340479) (xy 463.384377 -285.38633) (xy 463.407017 -285.435907)
			(xy 463.422372 -285.488201) (xy 463.430128 -285.542149) (xy 463.430128 -285.596651) (xy 463.422372 -285.650599)
			(xy 463.407017 -285.702893) (xy 463.384377 -285.75247) (xy 463.354911 -285.798321) (xy 463.31922 -285.839512)
			(xy 463.278031 -285.875204) (xy 463.232181 -285.904671) (xy 463.182605 -285.927313) (xy 463.13031 -285.942669)
			(xy 463.076363 -285.950427) (xy 463.049112 -285.950914) (xy 463.018988 -285.950346) (xy 462.959491 -285.940866)
			(xy 462.902223 -285.922155) (xy 462.848606 -285.894678) (xy 462.799972 -285.859118) (xy 462.778348 -285.838138)
			(xy 462.771236 -285.831026) (xy 462.75244 -285.823152) (xy 462.659984 -285.823152) (xy 462.641188 -285.831026)
			(xy 462.634076 -285.838138) (xy 462.61243 -285.859096) (xy 462.563808 -285.89467) (xy 462.510197 -285.922155)
			(xy 462.452931 -285.940868) (xy 462.393435 -285.950344) (xy 462.363312 -285.950914) (xy 462.334574 -285.950379)
			(xy 462.277747 -285.941759) (xy 462.222856 -285.924711) (xy 462.171144 -285.899622) (xy 462.123781 -285.867059)
			(xy 462.102454 -285.84779) (xy 462.1022 -285.847536) (xy 462.094936 -285.841366) (xy 462.07718 -285.834464)
			(xy 462.067656 -285.834074) (xy 461.998568 -285.834074) (xy 461.98904 -285.834445) (xy 461.971285 -285.841356)
			(xy 461.964024 -285.847536) (xy 461.96377 -285.84779) (xy 461.942443 -285.86706) (xy 461.89508 -285.899625)
			(xy 461.843369 -285.924716) (xy 461.788478 -285.941766) (xy 461.731651 -285.950388) (xy 461.674173 -285.950388)
			(xy 461.617346 -285.941766) (xy 461.562455 -285.924716) (xy 461.510744 -285.899625) (xy 461.463381 -285.86706)
			(xy 461.442054 -285.84779) (xy 461.4418 -285.847536) (xy 461.434536 -285.841366) (xy 461.41678 -285.834464)
			(xy 461.407256 -285.834074) (xy 461.338168 -285.834074) (xy 461.32864 -285.834445) (xy 461.310885 -285.841356)
			(xy 461.303624 -285.847536) (xy 461.30337 -285.84779) (xy 461.282042 -285.86706) (xy 461.23468 -285.899625)
			(xy 461.182968 -285.924717) (xy 461.128078 -285.941768) (xy 461.071251 -285.950392) (xy 461.042512 -285.950914)
			(xy 461.015259 -285.950439) (xy 460.961308 -285.942684) (xy 460.909009 -285.927329) (xy 460.859428 -285.904688)
			(xy 460.813574 -285.875221) (xy 460.772381 -285.839528) (xy 460.736687 -285.798335) (xy 460.707218 -285.752482)
			(xy 460.684575 -285.702902) (xy 460.669219 -285.650604) (xy 460.661461 -285.596653) (xy 459.257934 -285.596653)
			(xy 459.257934 -285.606552) (xy 459.250178 -285.6605) (xy 459.234822 -285.712796) (xy 459.212181 -285.762374)
			(xy 459.182715 -285.808226) (xy 459.147023 -285.849417) (xy 459.105832 -285.88511) (xy 459.059982 -285.914577)
			(xy 459.010404 -285.93722) (xy 458.958108 -285.952576) (xy 458.90416 -285.960334) (xy 458.876908 -285.96082)
			(xy 458.846784 -285.960253) (xy 458.787287 -285.950772) (xy 458.730019 -285.932061) (xy 458.676402 -285.904584)
			(xy 458.627768 -285.869024) (xy 458.606144 -285.848044) (xy 458.599032 -285.840932) (xy 458.580236 -285.833058)
			(xy 458.48778 -285.833058) (xy 458.468984 -285.840932) (xy 458.461872 -285.848044) (xy 458.440229 -285.869005)
			(xy 458.391606 -285.904578) (xy 458.337995 -285.932063) (xy 458.280728 -285.950775) (xy 458.221231 -285.96025)
			(xy 458.191108 -285.96082) (xy 458.16237 -285.960286) (xy 458.105543 -285.951665) (xy 458.050652 -285.934617)
			(xy 457.998941 -285.909528) (xy 457.951577 -285.876965) (xy 457.93025 -285.857696) (xy 457.929996 -285.857442)
			(xy 457.922732 -285.851271) (xy 457.904976 -285.84437) (xy 457.895452 -285.84398) (xy 457.826364 -285.84398)
			(xy 457.816835 -285.844348) (xy 457.79908 -285.851261) (xy 457.79182 -285.857442) (xy 457.791566 -285.857696)
			(xy 457.770239 -285.876966) (xy 457.722876 -285.909531) (xy 457.671165 -285.934622) (xy 457.616274 -285.951672)
			(xy 457.559447 -285.960294) (xy 457.501969 -285.960294) (xy 457.445142 -285.951672) (xy 457.390251 -285.934622)
			(xy 457.33854 -285.909531) (xy 457.291177 -285.876966) (xy 457.26985 -285.857696) (xy 457.269596 -285.857442)
			(xy 457.262332 -285.851271) (xy 457.244576 -285.84437) (xy 457.235052 -285.84398) (xy 457.165964 -285.84398)
			(xy 457.156435 -285.844348) (xy 457.13868 -285.851261) (xy 457.13142 -285.857442) (xy 457.131166 -285.857696)
			(xy 457.109826 -285.876952) (xy 457.062468 -285.909522) (xy 457.01076 -285.934619) (xy 456.955872 -285.951673)
			(xy 456.899046 -285.960298) (xy 456.870308 -285.96082) (xy 456.843056 -285.960333) (xy 456.789106 -285.952577)
			(xy 456.736808 -285.937223) (xy 456.687229 -285.914581) (xy 456.641376 -285.885114) (xy 456.600184 -285.849422)
			(xy 456.56449 -285.80823) (xy 456.535023 -285.762378) (xy 456.51238 -285.712799) (xy 456.497024 -285.660502)
			(xy 456.489267 -285.606552) (xy 431.962271 -285.606552) (xy 431.958641 -285.613468) (xy 431.929076 -285.652812)
			(xy 431.893583 -285.686904) (xy 431.85308 -285.71486) (xy 431.808618 -285.735958) (xy 431.761347 -285.74965)
			(xy 431.712492 -285.755582) (xy 431.663317 -285.753601) (xy 431.615098 -285.743757) (xy 431.569082 -285.726305)
			(xy 431.526461 -285.701698) (xy 431.48834 -285.670573) (xy 431.455705 -285.633736) (xy 431.429402 -285.59214)
			(xy 431.410111 -285.546864) (xy 431.398334 -285.49908) (xy 431.394374 -285.450026) (xy 431.077111 -285.450026)
			(xy 431.076612 -285.47548) (xy 431.068569 -285.526262) (xy 431.052681 -285.575161) (xy 431.029338 -285.620973)
			(xy 430.999117 -285.662569) (xy 430.962761 -285.698925) (xy 430.921165 -285.729146) (xy 430.875353 -285.752489)
			(xy 430.826454 -285.768377) (xy 430.775672 -285.77642) (xy 430.724256 -285.77642) (xy 430.673474 -285.768377)
			(xy 430.624575 -285.752489) (xy 430.578763 -285.729146) (xy 430.537167 -285.698925) (xy 430.500811 -285.662569)
			(xy 430.47059 -285.620973) (xy 430.447247 -285.575161) (xy 430.431359 -285.526262) (xy 430.423316 -285.47548)
			(xy 430.126652 -285.47548) (xy 430.118609 -285.526262) (xy 430.102721 -285.575161) (xy 430.079378 -285.620973)
			(xy 430.049157 -285.662569) (xy 430.012801 -285.698925) (xy 429.971205 -285.729146) (xy 429.925393 -285.752489)
			(xy 429.876494 -285.768377) (xy 429.825712 -285.77642) (xy 429.774296 -285.77642) (xy 429.723514 -285.768377)
			(xy 429.674615 -285.752489) (xy 429.628803 -285.729146) (xy 429.587207 -285.698925) (xy 429.550851 -285.662569)
			(xy 429.52063 -285.620973) (xy 429.497287 -285.575161) (xy 429.481399 -285.526262) (xy 429.473356 -285.47548)
			(xy 429.154424 -285.47548) (xy 429.146708 -285.522956) (xy 429.131124 -285.569637) (xy 429.108253 -285.613214)
			(xy 429.078688 -285.652558) (xy 429.043195 -285.68665) (xy 429.002692 -285.714606) (xy 428.95823 -285.735704)
			(xy 428.910959 -285.749396) (xy 428.862104 -285.755328) (xy 428.812929 -285.753347) (xy 428.76471 -285.743503)
			(xy 428.718694 -285.726051) (xy 428.676073 -285.701444) (xy 428.637952 -285.670319) (xy 428.605317 -285.633482)
			(xy 428.579014 -285.591886) (xy 428.559723 -285.54661) (xy 428.547946 -285.498826) (xy 428.543986 -285.449772)
			(xy 428.205138 -285.449772) (xy 428.204643 -285.474379) (xy 428.196748 -285.522956) (xy 428.181164 -285.569637)
			(xy 428.158293 -285.613214) (xy 428.128728 -285.652558) (xy 428.093235 -285.68665) (xy 428.052732 -285.714606)
			(xy 428.00827 -285.735704) (xy 427.960999 -285.749396) (xy 427.912144 -285.755328) (xy 427.862969 -285.753347)
			(xy 427.81475 -285.743503) (xy 427.768734 -285.726051) (xy 427.726113 -285.701444) (xy 427.687992 -285.670319)
			(xy 427.655357 -285.633482) (xy 427.629054 -285.591886) (xy 427.609763 -285.54661) (xy 427.597986 -285.498826)
			(xy 427.594026 -285.449772) (xy 427.255178 -285.449772) (xy 427.254683 -285.474379) (xy 427.246788 -285.522956)
			(xy 427.231204 -285.569637) (xy 427.208333 -285.613214) (xy 427.178768 -285.652558) (xy 427.143275 -285.68665)
			(xy 427.102772 -285.714606) (xy 427.05831 -285.735704) (xy 427.011039 -285.749396) (xy 426.962184 -285.755328)
			(xy 426.913009 -285.753347) (xy 426.86479 -285.743503) (xy 426.818774 -285.726051) (xy 426.776153 -285.701444)
			(xy 426.738032 -285.670319) (xy 426.705397 -285.633482) (xy 426.679094 -285.591886) (xy 426.659803 -285.54661)
			(xy 426.648026 -285.498826) (xy 426.644066 -285.449772) (xy 426.305218 -285.449772) (xy 426.304723 -285.474379)
			(xy 426.296828 -285.522956) (xy 426.281244 -285.569637) (xy 426.258373 -285.613214) (xy 426.228808 -285.652558)
			(xy 426.193315 -285.68665) (xy 426.152812 -285.714606) (xy 426.10835 -285.735704) (xy 426.061079 -285.749396)
			(xy 426.012224 -285.755328) (xy 425.963049 -285.753347) (xy 425.91483 -285.743503) (xy 425.868814 -285.726051)
			(xy 425.826193 -285.701444) (xy 425.788072 -285.670319) (xy 425.755437 -285.633482) (xy 425.729134 -285.591886)
			(xy 425.709843 -285.54661) (xy 425.698066 -285.498826) (xy 425.694106 -285.449772) (xy 425.355258 -285.449772)
			(xy 425.354763 -285.474379) (xy 425.346868 -285.522956) (xy 425.331284 -285.569637) (xy 425.308413 -285.613214)
			(xy 425.278848 -285.652558) (xy 425.243355 -285.68665) (xy 425.202852 -285.714606) (xy 425.15839 -285.735704)
			(xy 425.111119 -285.749396) (xy 425.062264 -285.755328) (xy 425.013089 -285.753347) (xy 424.96487 -285.743503)
			(xy 424.918854 -285.726051) (xy 424.876233 -285.701444) (xy 424.838112 -285.670319) (xy 424.805477 -285.633482)
			(xy 424.779174 -285.591886) (xy 424.759883 -285.54661) (xy 424.748106 -285.498826) (xy 424.744146 -285.449772)
			(xy 424.405298 -285.449772) (xy 424.404803 -285.474379) (xy 424.396908 -285.522956) (xy 424.381324 -285.569637)
			(xy 424.358453 -285.613214) (xy 424.328888 -285.652558) (xy 424.293395 -285.68665) (xy 424.252892 -285.714606)
			(xy 424.20843 -285.735704) (xy 424.161159 -285.749396) (xy 424.112304 -285.755328) (xy 424.063129 -285.753347)
			(xy 424.01491 -285.743503) (xy 423.968894 -285.726051) (xy 423.926273 -285.701444) (xy 423.888152 -285.670319)
			(xy 423.855517 -285.633482) (xy 423.829214 -285.591886) (xy 423.809923 -285.54661) (xy 423.798146 -285.498826)
			(xy 423.794186 -285.449772) (xy 423.455084 -285.449772) (xy 423.454589 -285.474379) (xy 423.446694 -285.522956)
			(xy 423.43111 -285.569637) (xy 423.408239 -285.613214) (xy 423.378674 -285.652558) (xy 423.343181 -285.68665)
			(xy 423.302678 -285.714606) (xy 423.258216 -285.735704) (xy 423.210945 -285.749396) (xy 423.16209 -285.755328)
			(xy 423.112915 -285.753347) (xy 423.064696 -285.743503) (xy 423.01868 -285.726051) (xy 422.976059 -285.701444)
			(xy 422.937938 -285.670319) (xy 422.905303 -285.633482) (xy 422.879 -285.591886) (xy 422.859709 -285.54661)
			(xy 422.847932 -285.498826) (xy 422.843972 -285.449772) (xy 422.505124 -285.449772) (xy 422.504629 -285.474379)
			(xy 422.496734 -285.522956) (xy 422.48115 -285.569637) (xy 422.458279 -285.613214) (xy 422.428714 -285.652558)
			(xy 422.393221 -285.68665) (xy 422.352718 -285.714606) (xy 422.308256 -285.735704) (xy 422.260985 -285.749396)
			(xy 422.21213 -285.755328) (xy 422.162955 -285.753347) (xy 422.114736 -285.743503) (xy 422.06872 -285.726051)
			(xy 422.026099 -285.701444) (xy 421.987978 -285.670319) (xy 421.955343 -285.633482) (xy 421.92904 -285.591886)
			(xy 421.909749 -285.54661) (xy 421.897972 -285.498826) (xy 421.894012 -285.449772) (xy 396.55369 -285.449772)
			(xy 396.55369 -285.924752) (xy 396.719056 -285.924752) (xy 396.723016 -285.875698) (xy 396.734793 -285.827914)
			(xy 396.754084 -285.782638) (xy 396.780387 -285.741042) (xy 396.813022 -285.704205) (xy 396.851143 -285.67308)
			(xy 396.893764 -285.648473) (xy 396.93978 -285.631021) (xy 396.987999 -285.621177) (xy 397.037174 -285.619196)
			(xy 397.086029 -285.625128) (xy 397.1333 -285.63882) (xy 397.177762 -285.659918) (xy 397.218265 -285.687874)
			(xy 397.253758 -285.721966) (xy 397.283323 -285.76131) (xy 397.306194 -285.804887) (xy 397.321778 -285.851568)
			(xy 397.329673 -285.900145) (xy 397.330168 -285.924752) (xy 397.669016 -285.924752) (xy 397.672976 -285.875698)
			(xy 397.684753 -285.827914) (xy 397.704044 -285.782638) (xy 397.730347 -285.741042) (xy 397.762982 -285.704205)
			(xy 397.801103 -285.67308) (xy 397.843724 -285.648473) (xy 397.88974 -285.631021) (xy 397.937959 -285.621177)
			(xy 397.987134 -285.619196) (xy 398.035989 -285.625128) (xy 398.08326 -285.63882) (xy 398.127722 -285.659918)
			(xy 398.168225 -285.687874) (xy 398.203718 -285.721966) (xy 398.233283 -285.76131) (xy 398.256154 -285.804887)
			(xy 398.271738 -285.851568) (xy 398.279633 -285.900145) (xy 398.280128 -285.924752) (xy 398.61923 -285.924752)
			(xy 398.62319 -285.875698) (xy 398.634967 -285.827914) (xy 398.654258 -285.782638) (xy 398.680561 -285.741042)
			(xy 398.713196 -285.704205) (xy 398.751317 -285.67308) (xy 398.793938 -285.648473) (xy 398.839954 -285.631021)
			(xy 398.888173 -285.621177) (xy 398.937348 -285.619196) (xy 398.986203 -285.625128) (xy 399.033474 -285.63882)
			(xy 399.077936 -285.659918) (xy 399.118439 -285.687874) (xy 399.153932 -285.721966) (xy 399.183497 -285.76131)
			(xy 399.206368 -285.804887) (xy 399.221952 -285.851568) (xy 399.229847 -285.900145) (xy 399.230342 -285.924752)
			(xy 399.56919 -285.924752) (xy 399.57315 -285.875698) (xy 399.584927 -285.827914) (xy 399.604218 -285.782638)
			(xy 399.630521 -285.741042) (xy 399.663156 -285.704205) (xy 399.701277 -285.67308) (xy 399.743898 -285.648473)
			(xy 399.789914 -285.631021) (xy 399.838133 -285.621177) (xy 399.887308 -285.619196) (xy 399.936163 -285.625128)
			(xy 399.983434 -285.63882) (xy 400.027896 -285.659918) (xy 400.068399 -285.687874) (xy 400.103892 -285.721966)
			(xy 400.133457 -285.76131) (xy 400.156328 -285.804887) (xy 400.171912 -285.851568) (xy 400.179807 -285.900145)
			(xy 400.180302 -285.924752) (xy 400.51915 -285.924752) (xy 400.52311 -285.875698) (xy 400.534887 -285.827914)
			(xy 400.554178 -285.782638) (xy 400.580481 -285.741042) (xy 400.613116 -285.704205) (xy 400.651237 -285.67308)
			(xy 400.693858 -285.648473) (xy 400.739874 -285.631021) (xy 400.788093 -285.621177) (xy 400.837268 -285.619196)
			(xy 400.886123 -285.625128) (xy 400.933394 -285.63882) (xy 400.977856 -285.659918) (xy 401.018359 -285.687874)
			(xy 401.053852 -285.721966) (xy 401.083417 -285.76131) (xy 401.106288 -285.804887) (xy 401.121872 -285.851568)
			(xy 401.129767 -285.900145) (xy 401.130262 -285.924752) (xy 401.46911 -285.924752) (xy 401.47307 -285.875698)
			(xy 401.484847 -285.827914) (xy 401.504138 -285.782638) (xy 401.530441 -285.741042) (xy 401.563076 -285.704205)
			(xy 401.601197 -285.67308) (xy 401.643818 -285.648473) (xy 401.689834 -285.631021) (xy 401.738053 -285.621177)
			(xy 401.787228 -285.619196) (xy 401.836083 -285.625128) (xy 401.883354 -285.63882) (xy 401.927816 -285.659918)
			(xy 401.968319 -285.687874) (xy 402.003812 -285.721966) (xy 402.033377 -285.76131) (xy 402.056248 -285.804887)
			(xy 402.071832 -285.851568) (xy 402.079727 -285.900145) (xy 402.080222 -285.924752) (xy 402.41907 -285.924752)
			(xy 402.42303 -285.875698) (xy 402.434807 -285.827914) (xy 402.454098 -285.782638) (xy 402.480401 -285.741042)
			(xy 402.513036 -285.704205) (xy 402.551157 -285.67308) (xy 402.593778 -285.648473) (xy 402.639794 -285.631021)
			(xy 402.688013 -285.621177) (xy 402.737188 -285.619196) (xy 402.786043 -285.625128) (xy 402.833314 -285.63882)
			(xy 402.877776 -285.659918) (xy 402.918279 -285.687874) (xy 402.953772 -285.721966) (xy 402.983337 -285.76131)
			(xy 403.006208 -285.804887) (xy 403.021792 -285.851568) (xy 403.029687 -285.900145) (xy 403.030182 -285.924752)
			(xy 403.36903 -285.924752) (xy 403.37299 -285.875698) (xy 403.384767 -285.827914) (xy 403.404058 -285.782638)
			(xy 403.430361 -285.741042) (xy 403.462996 -285.704205) (xy 403.501117 -285.67308) (xy 403.543738 -285.648473)
			(xy 403.589754 -285.631021) (xy 403.637973 -285.621177) (xy 403.687148 -285.619196) (xy 403.736003 -285.625128)
			(xy 403.783274 -285.63882) (xy 403.827736 -285.659918) (xy 403.868239 -285.687874) (xy 403.903732 -285.721966)
			(xy 403.933297 -285.76131) (xy 403.956168 -285.804887) (xy 403.971752 -285.851568) (xy 403.979647 -285.900145)
			(xy 403.980142 -285.924752) (xy 404.31899 -285.924752) (xy 404.32295 -285.875698) (xy 404.334727 -285.827914)
			(xy 404.354018 -285.782638) (xy 404.380321 -285.741042) (xy 404.412956 -285.704205) (xy 404.451077 -285.67308)
			(xy 404.493698 -285.648473) (xy 404.539714 -285.631021) (xy 404.587933 -285.621177) (xy 404.637108 -285.619196)
			(xy 404.685963 -285.625128) (xy 404.733234 -285.63882) (xy 404.777696 -285.659918) (xy 404.818199 -285.687874)
			(xy 404.853692 -285.721966) (xy 404.883257 -285.76131) (xy 404.906128 -285.804887) (xy 404.921712 -285.851568)
			(xy 404.929607 -285.900145) (xy 404.930102 -285.924752) (xy 405.269204 -285.924752) (xy 405.273164 -285.875698)
			(xy 405.284941 -285.827914) (xy 405.304232 -285.782638) (xy 405.330535 -285.741042) (xy 405.36317 -285.704205)
			(xy 405.401291 -285.67308) (xy 405.443912 -285.648473) (xy 405.489928 -285.631021) (xy 405.538147 -285.621177)
			(xy 405.587322 -285.619196) (xy 405.636177 -285.625128) (xy 405.683448 -285.63882) (xy 405.72791 -285.659918)
			(xy 405.768413 -285.687874) (xy 405.803906 -285.721966) (xy 405.833471 -285.76131) (xy 405.856342 -285.804887)
			(xy 405.871926 -285.851568) (xy 405.879821 -285.900145) (xy 405.880316 -285.924752) (xy 406.219164 -285.924752)
			(xy 406.223124 -285.875698) (xy 406.234901 -285.827914) (xy 406.254192 -285.782638) (xy 406.280495 -285.741042)
			(xy 406.31313 -285.704205) (xy 406.351251 -285.67308) (xy 406.393872 -285.648473) (xy 406.439888 -285.631021)
			(xy 406.488107 -285.621177) (xy 406.537282 -285.619196) (xy 406.586137 -285.625128) (xy 406.633408 -285.63882)
			(xy 406.67787 -285.659918) (xy 406.718373 -285.687874) (xy 406.753866 -285.721966) (xy 406.783431 -285.76131)
			(xy 406.806302 -285.804887) (xy 406.821886 -285.851568) (xy 406.829781 -285.900145) (xy 406.830276 -285.924752)
			(xy 408.119084 -285.924752) (xy 408.123044 -285.875698) (xy 408.134821 -285.827914) (xy 408.154112 -285.782638)
			(xy 408.180415 -285.741042) (xy 408.21305 -285.704205) (xy 408.251171 -285.67308) (xy 408.293792 -285.648473)
			(xy 408.339808 -285.631021) (xy 408.388027 -285.621177) (xy 408.437202 -285.619196) (xy 408.486057 -285.625128)
			(xy 408.533328 -285.63882) (xy 408.57779 -285.659918) (xy 408.618293 -285.687874) (xy 408.653786 -285.721966)
			(xy 408.683351 -285.76131) (xy 408.706222 -285.804887) (xy 408.721806 -285.851568) (xy 408.729701 -285.900145)
			(xy 408.730196 -285.924752) (xy 409.069044 -285.924752) (xy 409.073004 -285.875698) (xy 409.084781 -285.827914)
			(xy 409.104072 -285.782638) (xy 409.130375 -285.741042) (xy 409.16301 -285.704205) (xy 409.201131 -285.67308)
			(xy 409.243752 -285.648473) (xy 409.289768 -285.631021) (xy 409.337987 -285.621177) (xy 409.387162 -285.619196)
			(xy 409.436017 -285.625128) (xy 409.483288 -285.63882) (xy 409.52775 -285.659918) (xy 409.568253 -285.687874)
			(xy 409.603746 -285.721966) (xy 409.633311 -285.76131) (xy 409.656182 -285.804887) (xy 409.671766 -285.851568)
			(xy 409.679661 -285.900145) (xy 409.680156 -285.924752) (xy 410.019004 -285.924752) (xy 410.022964 -285.875698)
			(xy 410.034741 -285.827914) (xy 410.054032 -285.782638) (xy 410.080335 -285.741042) (xy 410.11297 -285.704205)
			(xy 410.151091 -285.67308) (xy 410.193712 -285.648473) (xy 410.239728 -285.631021) (xy 410.287947 -285.621177)
			(xy 410.337122 -285.619196) (xy 410.385977 -285.625128) (xy 410.433248 -285.63882) (xy 410.47771 -285.659918)
			(xy 410.518213 -285.687874) (xy 410.553706 -285.721966) (xy 410.583271 -285.76131) (xy 410.606142 -285.804887)
			(xy 410.621726 -285.851568) (xy 410.629621 -285.900145) (xy 410.630116 -285.924752) (xy 410.969218 -285.924752)
			(xy 410.973178 -285.875698) (xy 410.984955 -285.827914) (xy 411.004246 -285.782638) (xy 411.030549 -285.741042)
			(xy 411.063184 -285.704205) (xy 411.101305 -285.67308) (xy 411.143926 -285.648473) (xy 411.189942 -285.631021)
			(xy 411.238161 -285.621177) (xy 411.287336 -285.619196) (xy 411.336191 -285.625128) (xy 411.383462 -285.63882)
			(xy 411.427924 -285.659918) (xy 411.468427 -285.687874) (xy 411.50392 -285.721966) (xy 411.533485 -285.76131)
			(xy 411.556356 -285.804887) (xy 411.57194 -285.851568) (xy 411.579835 -285.900145) (xy 411.58033 -285.924752)
			(xy 411.919178 -285.924752) (xy 411.923138 -285.875698) (xy 411.934915 -285.827914) (xy 411.954206 -285.782638)
			(xy 411.980509 -285.741042) (xy 412.013144 -285.704205) (xy 412.051265 -285.67308) (xy 412.093886 -285.648473)
			(xy 412.139902 -285.631021) (xy 412.188121 -285.621177) (xy 412.237296 -285.619196) (xy 412.286151 -285.625128)
			(xy 412.333422 -285.63882) (xy 412.377884 -285.659918) (xy 412.418387 -285.687874) (xy 412.45388 -285.721966)
			(xy 412.483445 -285.76131) (xy 412.506316 -285.804887) (xy 412.5219 -285.851568) (xy 412.529795 -285.900145)
			(xy 412.53029 -285.924752) (xy 412.869138 -285.924752) (xy 412.873098 -285.875698) (xy 412.884875 -285.827914)
			(xy 412.904166 -285.782638) (xy 412.930469 -285.741042) (xy 412.963104 -285.704205) (xy 413.001225 -285.67308)
			(xy 413.043846 -285.648473) (xy 413.089862 -285.631021) (xy 413.138081 -285.621177) (xy 413.187256 -285.619196)
			(xy 413.236111 -285.625128) (xy 413.283382 -285.63882) (xy 413.327844 -285.659918) (xy 413.368347 -285.687874)
			(xy 413.40384 -285.721966) (xy 413.433405 -285.76131) (xy 413.456276 -285.804887) (xy 413.47186 -285.851568)
			(xy 413.479755 -285.900145) (xy 413.48025 -285.924752) (xy 413.819098 -285.924752) (xy 413.823058 -285.875698)
			(xy 413.834835 -285.827914) (xy 413.854126 -285.782638) (xy 413.880429 -285.741042) (xy 413.913064 -285.704205)
			(xy 413.951185 -285.67308) (xy 413.993806 -285.648473) (xy 414.039822 -285.631021) (xy 414.088041 -285.621177)
			(xy 414.137216 -285.619196) (xy 414.186071 -285.625128) (xy 414.233342 -285.63882) (xy 414.277804 -285.659918)
			(xy 414.318307 -285.687874) (xy 414.3538 -285.721966) (xy 414.383365 -285.76131) (xy 414.406236 -285.804887)
			(xy 414.42182 -285.851568) (xy 414.429715 -285.900145) (xy 414.43021 -285.924752) (xy 414.769058 -285.924752)
			(xy 414.773018 -285.875698) (xy 414.784795 -285.827914) (xy 414.804086 -285.782638) (xy 414.830389 -285.741042)
			(xy 414.863024 -285.704205) (xy 414.901145 -285.67308) (xy 414.943766 -285.648473) (xy 414.989782 -285.631021)
			(xy 415.038001 -285.621177) (xy 415.087176 -285.619196) (xy 415.136031 -285.625128) (xy 415.183302 -285.63882)
			(xy 415.227764 -285.659918) (xy 415.268267 -285.687874) (xy 415.30376 -285.721966) (xy 415.333325 -285.76131)
			(xy 415.356196 -285.804887) (xy 415.37178 -285.851568) (xy 415.379675 -285.900145) (xy 415.38017 -285.924752)
			(xy 415.719018 -285.924752) (xy 415.722978 -285.875698) (xy 415.734755 -285.827914) (xy 415.754046 -285.782638)
			(xy 415.780349 -285.741042) (xy 415.812984 -285.704205) (xy 415.851105 -285.67308) (xy 415.893726 -285.648473)
			(xy 415.939742 -285.631021) (xy 415.987961 -285.621177) (xy 416.037136 -285.619196) (xy 416.085991 -285.625128)
			(xy 416.133262 -285.63882) (xy 416.177724 -285.659918) (xy 416.218227 -285.687874) (xy 416.25372 -285.721966)
			(xy 416.283285 -285.76131) (xy 416.306156 -285.804887) (xy 416.32174 -285.851568) (xy 416.329635 -285.900145)
			(xy 416.33013 -285.924752) (xy 416.668978 -285.924752) (xy 416.672938 -285.875698) (xy 416.684715 -285.827914)
			(xy 416.704006 -285.782638) (xy 416.730309 -285.741042) (xy 416.762944 -285.704205) (xy 416.801065 -285.67308)
			(xy 416.843686 -285.648473) (xy 416.889702 -285.631021) (xy 416.937921 -285.621177) (xy 416.987096 -285.619196)
			(xy 417.035951 -285.625128) (xy 417.083222 -285.63882) (xy 417.127684 -285.659918) (xy 417.168187 -285.687874)
			(xy 417.20368 -285.721966) (xy 417.233245 -285.76131) (xy 417.256116 -285.804887) (xy 417.2717 -285.851568)
			(xy 417.279595 -285.900145) (xy 417.28009 -285.924752) (xy 417.619192 -285.924752) (xy 417.623152 -285.875698)
			(xy 417.634929 -285.827914) (xy 417.65422 -285.782638) (xy 417.680523 -285.741042) (xy 417.713158 -285.704205)
			(xy 417.751279 -285.67308) (xy 417.7939 -285.648473) (xy 417.839916 -285.631021) (xy 417.888135 -285.621177)
			(xy 417.93731 -285.619196) (xy 417.986165 -285.625128) (xy 418.033436 -285.63882) (xy 418.077898 -285.659918)
			(xy 418.118401 -285.687874) (xy 418.153894 -285.721966) (xy 418.183459 -285.76131) (xy 418.20633 -285.804887)
			(xy 418.221914 -285.851568) (xy 418.229809 -285.900145) (xy 418.230304 -285.924752) (xy 418.569152 -285.924752)
			(xy 418.573112 -285.875698) (xy 418.584889 -285.827914) (xy 418.60418 -285.782638) (xy 418.630483 -285.741042)
			(xy 418.663118 -285.704205) (xy 418.701239 -285.67308) (xy 418.74386 -285.648473) (xy 418.789876 -285.631021)
			(xy 418.838095 -285.621177) (xy 418.88727 -285.619196) (xy 418.936125 -285.625128) (xy 418.983396 -285.63882)
			(xy 419.027858 -285.659918) (xy 419.068361 -285.687874) (xy 419.103854 -285.721966) (xy 419.133419 -285.76131)
			(xy 419.15629 -285.804887) (xy 419.171874 -285.851568) (xy 419.179769 -285.900145) (xy 419.180264 -285.924752)
			(xy 419.179769 -285.949359) (xy 419.171874 -285.997936) (xy 419.15629 -286.044617) (xy 419.133419 -286.088194)
			(xy 419.103854 -286.127538) (xy 419.068361 -286.16163) (xy 419.027858 -286.189586) (xy 418.983396 -286.210684)
			(xy 418.936125 -286.224376) (xy 418.88727 -286.230308) (xy 418.838095 -286.228327) (xy 418.789876 -286.218483)
			(xy 418.74386 -286.201031) (xy 418.701239 -286.176424) (xy 418.663118 -286.145299) (xy 418.630483 -286.108462)
			(xy 418.60418 -286.066866) (xy 418.584889 -286.02159) (xy 418.573112 -285.973806) (xy 418.569152 -285.924752)
			(xy 418.230304 -285.924752) (xy 418.229809 -285.949359) (xy 418.221914 -285.997936) (xy 418.20633 -286.044617)
			(xy 418.183459 -286.088194) (xy 418.153894 -286.127538) (xy 418.118401 -286.16163) (xy 418.077898 -286.189586)
			(xy 418.033436 -286.210684) (xy 417.986165 -286.224376) (xy 417.93731 -286.230308) (xy 417.888135 -286.228327)
			(xy 417.839916 -286.218483) (xy 417.7939 -286.201031) (xy 417.751279 -286.176424) (xy 417.713158 -286.145299)
			(xy 417.680523 -286.108462) (xy 417.65422 -286.066866) (xy 417.634929 -286.02159) (xy 417.623152 -285.973806)
			(xy 417.619192 -285.924752) (xy 417.28009 -285.924752) (xy 417.279595 -285.949359) (xy 417.2717 -285.997936)
			(xy 417.256116 -286.044617) (xy 417.233245 -286.088194) (xy 417.20368 -286.127538) (xy 417.168187 -286.16163)
			(xy 417.127684 -286.189586) (xy 417.083222 -286.210684) (xy 417.035951 -286.224376) (xy 416.987096 -286.230308)
			(xy 416.937921 -286.228327) (xy 416.889702 -286.218483) (xy 416.843686 -286.201031) (xy 416.801065 -286.176424)
			(xy 416.762944 -286.145299) (xy 416.730309 -286.108462) (xy 416.704006 -286.066866) (xy 416.684715 -286.02159)
			(xy 416.672938 -285.973806) (xy 416.668978 -285.924752) (xy 416.33013 -285.924752) (xy 416.329635 -285.949359)
			(xy 416.32174 -285.997936) (xy 416.306156 -286.044617) (xy 416.283285 -286.088194) (xy 416.25372 -286.127538)
			(xy 416.218227 -286.16163) (xy 416.177724 -286.189586) (xy 416.133262 -286.210684) (xy 416.085991 -286.224376)
			(xy 416.037136 -286.230308) (xy 415.987961 -286.228327) (xy 415.939742 -286.218483) (xy 415.893726 -286.201031)
			(xy 415.851105 -286.176424) (xy 415.812984 -286.145299) (xy 415.780349 -286.108462) (xy 415.754046 -286.066866)
			(xy 415.734755 -286.02159) (xy 415.722978 -285.973806) (xy 415.719018 -285.924752) (xy 415.38017 -285.924752)
			(xy 415.379675 -285.949359) (xy 415.37178 -285.997936) (xy 415.356196 -286.044617) (xy 415.333325 -286.088194)
			(xy 415.30376 -286.127538) (xy 415.268267 -286.16163) (xy 415.227764 -286.189586) (xy 415.183302 -286.210684)
			(xy 415.136031 -286.224376) (xy 415.087176 -286.230308) (xy 415.038001 -286.228327) (xy 414.989782 -286.218483)
			(xy 414.943766 -286.201031) (xy 414.901145 -286.176424) (xy 414.863024 -286.145299) (xy 414.830389 -286.108462)
			(xy 414.804086 -286.066866) (xy 414.784795 -286.02159) (xy 414.773018 -285.973806) (xy 414.769058 -285.924752)
			(xy 414.43021 -285.924752) (xy 414.429715 -285.949359) (xy 414.42182 -285.997936) (xy 414.406236 -286.044617)
			(xy 414.383365 -286.088194) (xy 414.3538 -286.127538) (xy 414.318307 -286.16163) (xy 414.277804 -286.189586)
			(xy 414.233342 -286.210684) (xy 414.186071 -286.224376) (xy 414.137216 -286.230308) (xy 414.088041 -286.228327)
			(xy 414.039822 -286.218483) (xy 413.993806 -286.201031) (xy 413.951185 -286.176424) (xy 413.913064 -286.145299)
			(xy 413.880429 -286.108462) (xy 413.854126 -286.066866) (xy 413.834835 -286.02159) (xy 413.823058 -285.973806)
			(xy 413.819098 -285.924752) (xy 413.48025 -285.924752) (xy 413.479755 -285.949359) (xy 413.47186 -285.997936)
			(xy 413.456276 -286.044617) (xy 413.433405 -286.088194) (xy 413.40384 -286.127538) (xy 413.368347 -286.16163)
			(xy 413.327844 -286.189586) (xy 413.283382 -286.210684) (xy 413.236111 -286.224376) (xy 413.187256 -286.230308)
			(xy 413.138081 -286.228327) (xy 413.089862 -286.218483) (xy 413.043846 -286.201031) (xy 413.001225 -286.176424)
			(xy 412.963104 -286.145299) (xy 412.930469 -286.108462) (xy 412.904166 -286.066866) (xy 412.884875 -286.02159)
			(xy 412.873098 -285.973806) (xy 412.869138 -285.924752) (xy 412.53029 -285.924752) (xy 412.529795 -285.949359)
			(xy 412.5219 -285.997936) (xy 412.506316 -286.044617) (xy 412.483445 -286.088194) (xy 412.45388 -286.127538)
			(xy 412.418387 -286.16163) (xy 412.377884 -286.189586) (xy 412.333422 -286.210684) (xy 412.286151 -286.224376)
			(xy 412.237296 -286.230308) (xy 412.188121 -286.228327) (xy 412.139902 -286.218483) (xy 412.093886 -286.201031)
			(xy 412.051265 -286.176424) (xy 412.013144 -286.145299) (xy 411.980509 -286.108462) (xy 411.954206 -286.066866)
			(xy 411.934915 -286.02159) (xy 411.923138 -285.973806) (xy 411.919178 -285.924752) (xy 411.58033 -285.924752)
			(xy 411.579835 -285.949359) (xy 411.57194 -285.997936) (xy 411.556356 -286.044617) (xy 411.533485 -286.088194)
			(xy 411.50392 -286.127538) (xy 411.468427 -286.16163) (xy 411.427924 -286.189586) (xy 411.383462 -286.210684)
			(xy 411.336191 -286.224376) (xy 411.287336 -286.230308) (xy 411.238161 -286.228327) (xy 411.189942 -286.218483)
			(xy 411.143926 -286.201031) (xy 411.101305 -286.176424) (xy 411.063184 -286.145299) (xy 411.030549 -286.108462)
			(xy 411.004246 -286.066866) (xy 410.984955 -286.02159) (xy 410.973178 -285.973806) (xy 410.969218 -285.924752)
			(xy 410.630116 -285.924752) (xy 410.629621 -285.949359) (xy 410.621726 -285.997936) (xy 410.606142 -286.044617)
			(xy 410.583271 -286.088194) (xy 410.553706 -286.127538) (xy 410.518213 -286.16163) (xy 410.47771 -286.189586)
			(xy 410.433248 -286.210684) (xy 410.385977 -286.224376) (xy 410.337122 -286.230308) (xy 410.287947 -286.228327)
			(xy 410.239728 -286.218483) (xy 410.193712 -286.201031) (xy 410.151091 -286.176424) (xy 410.11297 -286.145299)
			(xy 410.080335 -286.108462) (xy 410.054032 -286.066866) (xy 410.034741 -286.02159) (xy 410.022964 -285.973806)
			(xy 410.019004 -285.924752) (xy 409.680156 -285.924752) (xy 409.679661 -285.949359) (xy 409.671766 -285.997936)
			(xy 409.656182 -286.044617) (xy 409.633311 -286.088194) (xy 409.603746 -286.127538) (xy 409.568253 -286.16163)
			(xy 409.52775 -286.189586) (xy 409.483288 -286.210684) (xy 409.436017 -286.224376) (xy 409.387162 -286.230308)
			(xy 409.337987 -286.228327) (xy 409.289768 -286.218483) (xy 409.243752 -286.201031) (xy 409.201131 -286.176424)
			(xy 409.16301 -286.145299) (xy 409.130375 -286.108462) (xy 409.104072 -286.066866) (xy 409.084781 -286.02159)
			(xy 409.073004 -285.973806) (xy 409.069044 -285.924752) (xy 408.730196 -285.924752) (xy 408.729701 -285.949359)
			(xy 408.721806 -285.997936) (xy 408.706222 -286.044617) (xy 408.683351 -286.088194) (xy 408.653786 -286.127538)
			(xy 408.618293 -286.16163) (xy 408.57779 -286.189586) (xy 408.533328 -286.210684) (xy 408.486057 -286.224376)
			(xy 408.437202 -286.230308) (xy 408.388027 -286.228327) (xy 408.339808 -286.218483) (xy 408.293792 -286.201031)
			(xy 408.251171 -286.176424) (xy 408.21305 -286.145299) (xy 408.180415 -286.108462) (xy 408.154112 -286.066866)
			(xy 408.134821 -286.02159) (xy 408.123044 -285.973806) (xy 408.119084 -285.924752) (xy 406.830276 -285.924752)
			(xy 406.829781 -285.949359) (xy 406.821886 -285.997936) (xy 406.806302 -286.044617) (xy 406.783431 -286.088194)
			(xy 406.753866 -286.127538) (xy 406.718373 -286.16163) (xy 406.67787 -286.189586) (xy 406.633408 -286.210684)
			(xy 406.586137 -286.224376) (xy 406.537282 -286.230308) (xy 406.488107 -286.228327) (xy 406.439888 -286.218483)
			(xy 406.393872 -286.201031) (xy 406.351251 -286.176424) (xy 406.31313 -286.145299) (xy 406.280495 -286.108462)
			(xy 406.254192 -286.066866) (xy 406.234901 -286.02159) (xy 406.223124 -285.973806) (xy 406.219164 -285.924752)
			(xy 405.880316 -285.924752) (xy 405.879821 -285.949359) (xy 405.871926 -285.997936) (xy 405.856342 -286.044617)
			(xy 405.833471 -286.088194) (xy 405.803906 -286.127538) (xy 405.768413 -286.16163) (xy 405.72791 -286.189586)
			(xy 405.683448 -286.210684) (xy 405.636177 -286.224376) (xy 405.587322 -286.230308) (xy 405.538147 -286.228327)
			(xy 405.489928 -286.218483) (xy 405.443912 -286.201031) (xy 405.401291 -286.176424) (xy 405.36317 -286.145299)
			(xy 405.330535 -286.108462) (xy 405.304232 -286.066866) (xy 405.284941 -286.02159) (xy 405.273164 -285.973806)
			(xy 405.269204 -285.924752) (xy 404.930102 -285.924752) (xy 404.929607 -285.949359) (xy 404.921712 -285.997936)
			(xy 404.906128 -286.044617) (xy 404.883257 -286.088194) (xy 404.853692 -286.127538) (xy 404.818199 -286.16163)
			(xy 404.777696 -286.189586) (xy 404.733234 -286.210684) (xy 404.685963 -286.224376) (xy 404.637108 -286.230308)
			(xy 404.587933 -286.228327) (xy 404.539714 -286.218483) (xy 404.493698 -286.201031) (xy 404.451077 -286.176424)
			(xy 404.412956 -286.145299) (xy 404.380321 -286.108462) (xy 404.354018 -286.066866) (xy 404.334727 -286.02159)
			(xy 404.32295 -285.973806) (xy 404.31899 -285.924752) (xy 403.980142 -285.924752) (xy 403.979647 -285.949359)
			(xy 403.971752 -285.997936) (xy 403.956168 -286.044617) (xy 403.933297 -286.088194) (xy 403.903732 -286.127538)
			(xy 403.868239 -286.16163) (xy 403.827736 -286.189586) (xy 403.783274 -286.210684) (xy 403.736003 -286.224376)
			(xy 403.687148 -286.230308) (xy 403.637973 -286.228327) (xy 403.589754 -286.218483) (xy 403.543738 -286.201031)
			(xy 403.501117 -286.176424) (xy 403.462996 -286.145299) (xy 403.430361 -286.108462) (xy 403.404058 -286.066866)
			(xy 403.384767 -286.02159) (xy 403.37299 -285.973806) (xy 403.36903 -285.924752) (xy 403.030182 -285.924752)
			(xy 403.029687 -285.949359) (xy 403.021792 -285.997936) (xy 403.006208 -286.044617) (xy 402.983337 -286.088194)
			(xy 402.953772 -286.127538) (xy 402.918279 -286.16163) (xy 402.877776 -286.189586) (xy 402.833314 -286.210684)
			(xy 402.786043 -286.224376) (xy 402.737188 -286.230308) (xy 402.688013 -286.228327) (xy 402.639794 -286.218483)
			(xy 402.593778 -286.201031) (xy 402.551157 -286.176424) (xy 402.513036 -286.145299) (xy 402.480401 -286.108462)
			(xy 402.454098 -286.066866) (xy 402.434807 -286.02159) (xy 402.42303 -285.973806) (xy 402.41907 -285.924752)
			(xy 402.080222 -285.924752) (xy 402.079727 -285.949359) (xy 402.071832 -285.997936) (xy 402.056248 -286.044617)
			(xy 402.033377 -286.088194) (xy 402.003812 -286.127538) (xy 401.968319 -286.16163) (xy 401.927816 -286.189586)
			(xy 401.883354 -286.210684) (xy 401.836083 -286.224376) (xy 401.787228 -286.230308) (xy 401.738053 -286.228327)
			(xy 401.689834 -286.218483) (xy 401.643818 -286.201031) (xy 401.601197 -286.176424) (xy 401.563076 -286.145299)
			(xy 401.530441 -286.108462) (xy 401.504138 -286.066866) (xy 401.484847 -286.02159) (xy 401.47307 -285.973806)
			(xy 401.46911 -285.924752) (xy 401.130262 -285.924752) (xy 401.129767 -285.949359) (xy 401.121872 -285.997936)
			(xy 401.106288 -286.044617) (xy 401.083417 -286.088194) (xy 401.053852 -286.127538) (xy 401.018359 -286.16163)
			(xy 400.977856 -286.189586) (xy 400.933394 -286.210684) (xy 400.886123 -286.224376) (xy 400.837268 -286.230308)
			(xy 400.788093 -286.228327) (xy 400.739874 -286.218483) (xy 400.693858 -286.201031) (xy 400.651237 -286.176424)
			(xy 400.613116 -286.145299) (xy 400.580481 -286.108462) (xy 400.554178 -286.066866) (xy 400.534887 -286.02159)
			(xy 400.52311 -285.973806) (xy 400.51915 -285.924752) (xy 400.180302 -285.924752) (xy 400.179807 -285.949359)
			(xy 400.171912 -285.997936) (xy 400.156328 -286.044617) (xy 400.133457 -286.088194) (xy 400.103892 -286.127538)
			(xy 400.068399 -286.16163) (xy 400.027896 -286.189586) (xy 399.983434 -286.210684) (xy 399.936163 -286.224376)
			(xy 399.887308 -286.230308) (xy 399.838133 -286.228327) (xy 399.789914 -286.218483) (xy 399.743898 -286.201031)
			(xy 399.701277 -286.176424) (xy 399.663156 -286.145299) (xy 399.630521 -286.108462) (xy 399.604218 -286.066866)
			(xy 399.584927 -286.02159) (xy 399.57315 -285.973806) (xy 399.56919 -285.924752) (xy 399.230342 -285.924752)
			(xy 399.229847 -285.949359) (xy 399.221952 -285.997936) (xy 399.206368 -286.044617) (xy 399.183497 -286.088194)
			(xy 399.153932 -286.127538) (xy 399.118439 -286.16163) (xy 399.077936 -286.189586) (xy 399.033474 -286.210684)
			(xy 398.986203 -286.224376) (xy 398.937348 -286.230308) (xy 398.888173 -286.228327) (xy 398.839954 -286.218483)
			(xy 398.793938 -286.201031) (xy 398.751317 -286.176424) (xy 398.713196 -286.145299) (xy 398.680561 -286.108462)
			(xy 398.654258 -286.066866) (xy 398.634967 -286.02159) (xy 398.62319 -285.973806) (xy 398.61923 -285.924752)
			(xy 398.280128 -285.924752) (xy 398.279633 -285.949359) (xy 398.271738 -285.997936) (xy 398.256154 -286.044617)
			(xy 398.233283 -286.088194) (xy 398.203718 -286.127538) (xy 398.168225 -286.16163) (xy 398.127722 -286.189586)
			(xy 398.08326 -286.210684) (xy 398.035989 -286.224376) (xy 397.987134 -286.230308) (xy 397.937959 -286.228327)
			(xy 397.88974 -286.218483) (xy 397.843724 -286.201031) (xy 397.801103 -286.176424) (xy 397.762982 -286.145299)
			(xy 397.730347 -286.108462) (xy 397.704044 -286.066866) (xy 397.684753 -286.02159) (xy 397.672976 -285.973806)
			(xy 397.669016 -285.924752) (xy 397.330168 -285.924752) (xy 397.329673 -285.949359) (xy 397.321778 -285.997936)
			(xy 397.306194 -286.044617) (xy 397.283323 -286.088194) (xy 397.253758 -286.127538) (xy 397.218265 -286.16163)
			(xy 397.177762 -286.189586) (xy 397.1333 -286.210684) (xy 397.086029 -286.224376) (xy 397.037174 -286.230308)
			(xy 396.987999 -286.228327) (xy 396.93978 -286.218483) (xy 396.893764 -286.201031) (xy 396.851143 -286.176424)
			(xy 396.813022 -286.145299) (xy 396.780387 -286.108462) (xy 396.754084 -286.066866) (xy 396.734793 -286.02159)
			(xy 396.723016 -285.973806) (xy 396.719056 -285.924752) (xy 396.55369 -285.924752) (xy 396.55369 -286.399732)
			(xy 421.894012 -286.399732) (xy 421.897972 -286.350678) (xy 421.909749 -286.302894) (xy 421.92904 -286.257618)
			(xy 421.955343 -286.216022) (xy 421.987978 -286.179185) (xy 422.026099 -286.14806) (xy 422.06872 -286.123453)
			(xy 422.114736 -286.106001) (xy 422.162955 -286.096157) (xy 422.21213 -286.094176) (xy 422.260985 -286.100108)
			(xy 422.308256 -286.1138) (xy 422.352718 -286.134898) (xy 422.393221 -286.162854) (xy 422.428714 -286.196946)
			(xy 422.458279 -286.23629) (xy 422.48115 -286.279867) (xy 422.496734 -286.326548) (xy 422.504629 -286.375125)
			(xy 422.505124 -286.399732) (xy 422.844226 -286.399732) (xy 422.848186 -286.350678) (xy 422.859963 -286.302894)
			(xy 422.879254 -286.257618) (xy 422.905557 -286.216022) (xy 422.938192 -286.179185) (xy 422.976313 -286.14806)
			(xy 423.018934 -286.123453) (xy 423.06495 -286.106001) (xy 423.113169 -286.096157) (xy 423.162344 -286.094176)
			(xy 423.211199 -286.100108) (xy 423.25847 -286.1138) (xy 423.302932 -286.134898) (xy 423.343435 -286.162854)
			(xy 423.378928 -286.196946) (xy 423.408493 -286.23629) (xy 423.431364 -286.279867) (xy 423.446948 -286.326548)
			(xy 423.454843 -286.375125) (xy 423.455338 -286.399732) (xy 423.794186 -286.399732) (xy 423.798146 -286.350678)
			(xy 423.809923 -286.302894) (xy 423.829214 -286.257618) (xy 423.855517 -286.216022) (xy 423.888152 -286.179185)
			(xy 423.926273 -286.14806) (xy 423.968894 -286.123453) (xy 424.01491 -286.106001) (xy 424.063129 -286.096157)
			(xy 424.112304 -286.094176) (xy 424.161159 -286.100108) (xy 424.20843 -286.1138) (xy 424.252892 -286.134898)
			(xy 424.293395 -286.162854) (xy 424.328888 -286.196946) (xy 424.358453 -286.23629) (xy 424.381324 -286.279867)
			(xy 424.396908 -286.326548) (xy 424.404803 -286.375125) (xy 424.405298 -286.399732) (xy 424.405293 -286.399986)
			(xy 424.744146 -286.399986) (xy 424.748106 -286.350932) (xy 424.759883 -286.303148) (xy 424.779174 -286.257872)
			(xy 424.805477 -286.216276) (xy 424.838112 -286.179439) (xy 424.876233 -286.148314) (xy 424.918854 -286.123707)
			(xy 424.96487 -286.106255) (xy 425.013089 -286.096411) (xy 425.062264 -286.09443) (xy 425.111119 -286.100362)
			(xy 425.15839 -286.114054) (xy 425.202852 -286.135152) (xy 425.243355 -286.163108) (xy 425.278848 -286.1972)
			(xy 425.308413 -286.236544) (xy 425.331284 -286.280121) (xy 425.346868 -286.326802) (xy 425.354763 -286.375379)
			(xy 425.355258 -286.399986) (xy 425.694106 -286.399986) (xy 425.698066 -286.350932) (xy 425.709843 -286.303148)
			(xy 425.729134 -286.257872) (xy 425.755437 -286.216276) (xy 425.788072 -286.179439) (xy 425.826193 -286.148314)
			(xy 425.868814 -286.123707) (xy 425.91483 -286.106255) (xy 425.963049 -286.096411) (xy 426.012224 -286.09443)
			(xy 426.061079 -286.100362) (xy 426.10835 -286.114054) (xy 426.152812 -286.135152) (xy 426.193315 -286.163108)
			(xy 426.228808 -286.1972) (xy 426.258373 -286.236544) (xy 426.281244 -286.280121) (xy 426.296828 -286.326802)
			(xy 426.304723 -286.375379) (xy 426.305213 -286.399732) (xy 426.644066 -286.399732) (xy 426.648026 -286.350678)
			(xy 426.659803 -286.302894) (xy 426.679094 -286.257618) (xy 426.705397 -286.216022) (xy 426.738032 -286.179185)
			(xy 426.776153 -286.14806) (xy 426.818774 -286.123453) (xy 426.86479 -286.106001) (xy 426.913009 -286.096157)
			(xy 426.962184 -286.094176) (xy 427.011039 -286.100108) (xy 427.05831 -286.1138) (xy 427.102772 -286.134898)
			(xy 427.143275 -286.162854) (xy 427.178768 -286.196946) (xy 427.208333 -286.23629) (xy 427.231204 -286.279867)
			(xy 427.246788 -286.326548) (xy 427.254683 -286.375125) (xy 427.255178 -286.399732) (xy 427.254683 -286.424339)
			(xy 427.254504 -286.42544) (xy 427.573182 -286.42544) (xy 427.573182 -286.374024) (xy 427.581225 -286.323242)
			(xy 427.597113 -286.274343) (xy 427.620456 -286.228531) (xy 427.650677 -286.186935) (xy 427.687033 -286.150579)
			(xy 427.728629 -286.120358) (xy 427.774441 -286.097015) (xy 427.82334 -286.081127) (xy 427.874122 -286.073084)
			(xy 427.925538 -286.073084) (xy 427.97632 -286.081127) (xy 428.025219 -286.097015) (xy 428.071031 -286.120358)
			(xy 428.112627 -286.150579) (xy 428.148983 -286.186935) (xy 428.179204 -286.228531) (xy 428.202547 -286.274343)
			(xy 428.218435 -286.323242) (xy 428.226478 -286.374024) (xy 428.226982 -286.399732) (xy 428.226478 -286.42544)
			(xy 428.523142 -286.42544) (xy 428.523142 -286.374024) (xy 428.531185 -286.323242) (xy 428.547073 -286.274343)
			(xy 428.570416 -286.228531) (xy 428.600637 -286.186935) (xy 428.636993 -286.150579) (xy 428.678589 -286.120358)
			(xy 428.724401 -286.097015) (xy 428.7733 -286.081127) (xy 428.824082 -286.073084) (xy 428.875498 -286.073084)
			(xy 428.92628 -286.081127) (xy 428.975179 -286.097015) (xy 429.020991 -286.120358) (xy 429.062587 -286.150579)
			(xy 429.098943 -286.186935) (xy 429.129164 -286.228531) (xy 429.152507 -286.274343) (xy 429.168395 -286.323242)
			(xy 429.176438 -286.374024) (xy 429.176942 -286.399732) (xy 429.4942 -286.399732) (xy 429.49816 -286.350678)
			(xy 429.509937 -286.302894) (xy 429.529228 -286.257618) (xy 429.555531 -286.216022) (xy 429.588166 -286.179185)
			(xy 429.626287 -286.14806) (xy 429.668908 -286.123453) (xy 429.714924 -286.106001) (xy 429.763143 -286.096157)
			(xy 429.812318 -286.094176) (xy 429.861173 -286.100108) (xy 429.908444 -286.1138) (xy 429.952906 -286.134898)
			(xy 429.993409 -286.162854) (xy 430.028902 -286.196946) (xy 430.058467 -286.23629) (xy 430.081338 -286.279867)
			(xy 430.096922 -286.326548) (xy 430.104817 -286.375125) (xy 430.105312 -286.399732) (xy 430.44416 -286.399732)
			(xy 430.44812 -286.350678) (xy 430.459897 -286.302894) (xy 430.479188 -286.257618) (xy 430.505491 -286.216022)
			(xy 430.538126 -286.179185) (xy 430.576247 -286.14806) (xy 430.618868 -286.123453) (xy 430.664884 -286.106001)
			(xy 430.713103 -286.096157) (xy 430.762278 -286.094176) (xy 430.811133 -286.100108) (xy 430.858404 -286.1138)
			(xy 430.902866 -286.134898) (xy 430.943369 -286.162854) (xy 430.978862 -286.196946) (xy 431.008427 -286.23629)
			(xy 431.031298 -286.279867) (xy 431.046882 -286.326548) (xy 431.054777 -286.375125) (xy 431.055272 -286.399732)
			(xy 431.054777 -286.424339) (xy 431.046882 -286.472916) (xy 431.031298 -286.519597) (xy 431.008427 -286.563174)
			(xy 430.978862 -286.602518) (xy 430.943369 -286.63661) (xy 430.902866 -286.664566) (xy 430.858404 -286.685664)
			(xy 430.811133 -286.699356) (xy 430.762278 -286.705288) (xy 430.713103 -286.703307) (xy 430.664884 -286.693463)
			(xy 430.618868 -286.676011) (xy 430.576247 -286.651404) (xy 430.538126 -286.620279) (xy 430.505491 -286.583442)
			(xy 430.479188 -286.541846) (xy 430.459897 -286.49657) (xy 430.44812 -286.448786) (xy 430.44416 -286.399732)
			(xy 430.105312 -286.399732) (xy 430.104817 -286.424339) (xy 430.096922 -286.472916) (xy 430.081338 -286.519597)
			(xy 430.058467 -286.563174) (xy 430.028902 -286.602518) (xy 429.993409 -286.63661) (xy 429.952906 -286.664566)
			(xy 429.908444 -286.685664) (xy 429.861173 -286.699356) (xy 429.812318 -286.705288) (xy 429.763143 -286.703307)
			(xy 429.714924 -286.693463) (xy 429.668908 -286.676011) (xy 429.626287 -286.651404) (xy 429.588166 -286.620279)
			(xy 429.555531 -286.583442) (xy 429.529228 -286.541846) (xy 429.509937 -286.49657) (xy 429.49816 -286.448786)
			(xy 429.4942 -286.399732) (xy 429.176942 -286.399732) (xy 429.176438 -286.42544) (xy 429.168395 -286.476222)
			(xy 429.152507 -286.525121) (xy 429.129164 -286.570933) (xy 429.098943 -286.612529) (xy 429.062587 -286.648885)
			(xy 429.020991 -286.679106) (xy 428.975179 -286.702449) (xy 428.92628 -286.718337) (xy 428.875498 -286.72638)
			(xy 428.824082 -286.72638) (xy 428.7733 -286.718337) (xy 428.724401 -286.702449) (xy 428.678589 -286.679106)
			(xy 428.636993 -286.648885) (xy 428.600637 -286.612529) (xy 428.570416 -286.570933) (xy 428.547073 -286.525121)
			(xy 428.531185 -286.476222) (xy 428.523142 -286.42544) (xy 428.226478 -286.42544) (xy 428.218435 -286.476222)
			(xy 428.202547 -286.525121) (xy 428.179204 -286.570933) (xy 428.148983 -286.612529) (xy 428.112627 -286.648885)
			(xy 428.071031 -286.679106) (xy 428.025219 -286.702449) (xy 427.97632 -286.718337) (xy 427.925538 -286.72638)
			(xy 427.874122 -286.72638) (xy 427.82334 -286.718337) (xy 427.774441 -286.702449) (xy 427.728629 -286.679106)
			(xy 427.687033 -286.648885) (xy 427.650677 -286.612529) (xy 427.620456 -286.570933) (xy 427.597113 -286.525121)
			(xy 427.581225 -286.476222) (xy 427.573182 -286.42544) (xy 427.254504 -286.42544) (xy 427.246788 -286.472916)
			(xy 427.231204 -286.519597) (xy 427.208333 -286.563174) (xy 427.178768 -286.602518) (xy 427.143275 -286.63661)
			(xy 427.102772 -286.664566) (xy 427.05831 -286.685664) (xy 427.011039 -286.699356) (xy 426.962184 -286.705288)
			(xy 426.913009 -286.703307) (xy 426.86479 -286.693463) (xy 426.818774 -286.676011) (xy 426.776153 -286.651404)
			(xy 426.738032 -286.620279) (xy 426.705397 -286.583442) (xy 426.679094 -286.541846) (xy 426.659803 -286.49657)
			(xy 426.648026 -286.448786) (xy 426.644066 -286.399732) (xy 426.305213 -286.399732) (xy 426.305218 -286.399986)
			(xy 426.304723 -286.424593) (xy 426.296828 -286.47317) (xy 426.281244 -286.519851) (xy 426.258373 -286.563428)
			(xy 426.228808 -286.602772) (xy 426.193315 -286.636864) (xy 426.152812 -286.66482) (xy 426.10835 -286.685918)
			(xy 426.061079 -286.69961) (xy 426.012224 -286.705542) (xy 425.963049 -286.703561) (xy 425.91483 -286.693717)
			(xy 425.868814 -286.676265) (xy 425.826193 -286.651658) (xy 425.788072 -286.620533) (xy 425.755437 -286.583696)
			(xy 425.729134 -286.5421) (xy 425.709843 -286.496824) (xy 425.698066 -286.44904) (xy 425.694106 -286.399986)
			(xy 425.355258 -286.399986) (xy 425.354763 -286.424593) (xy 425.346868 -286.47317) (xy 425.331284 -286.519851)
			(xy 425.308413 -286.563428) (xy 425.278848 -286.602772) (xy 425.243355 -286.636864) (xy 425.202852 -286.66482)
			(xy 425.15839 -286.685918) (xy 425.111119 -286.69961) (xy 425.062264 -286.705542) (xy 425.013089 -286.703561)
			(xy 424.96487 -286.693717) (xy 424.918854 -286.676265) (xy 424.876233 -286.651658) (xy 424.838112 -286.620533)
			(xy 424.805477 -286.583696) (xy 424.779174 -286.5421) (xy 424.759883 -286.496824) (xy 424.748106 -286.44904)
			(xy 424.744146 -286.399986) (xy 424.405293 -286.399986) (xy 424.404803 -286.424339) (xy 424.396908 -286.472916)
			(xy 424.381324 -286.519597) (xy 424.358453 -286.563174) (xy 424.328888 -286.602518) (xy 424.293395 -286.63661)
			(xy 424.252892 -286.664566) (xy 424.20843 -286.685664) (xy 424.161159 -286.699356) (xy 424.112304 -286.705288)
			(xy 424.063129 -286.703307) (xy 424.01491 -286.693463) (xy 423.968894 -286.676011) (xy 423.926273 -286.651404)
			(xy 423.888152 -286.620279) (xy 423.855517 -286.583442) (xy 423.829214 -286.541846) (xy 423.809923 -286.49657)
			(xy 423.798146 -286.448786) (xy 423.794186 -286.399732) (xy 423.455338 -286.399732) (xy 423.454843 -286.424339)
			(xy 423.446948 -286.472916) (xy 423.431364 -286.519597) (xy 423.408493 -286.563174) (xy 423.378928 -286.602518)
			(xy 423.343435 -286.63661) (xy 423.302932 -286.664566) (xy 423.25847 -286.685664) (xy 423.211199 -286.699356)
			(xy 423.162344 -286.705288) (xy 423.113169 -286.703307) (xy 423.06495 -286.693463) (xy 423.018934 -286.676011)
			(xy 422.976313 -286.651404) (xy 422.938192 -286.620279) (xy 422.905557 -286.583442) (xy 422.879254 -286.541846)
			(xy 422.859963 -286.49657) (xy 422.848186 -286.448786) (xy 422.844226 -286.399732) (xy 422.505124 -286.399732)
			(xy 422.504629 -286.424339) (xy 422.496734 -286.472916) (xy 422.48115 -286.519597) (xy 422.458279 -286.563174)
			(xy 422.428714 -286.602518) (xy 422.393221 -286.63661) (xy 422.352718 -286.664566) (xy 422.308256 -286.685664)
			(xy 422.260985 -286.699356) (xy 422.21213 -286.705288) (xy 422.162955 -286.703307) (xy 422.114736 -286.693463)
			(xy 422.06872 -286.676011) (xy 422.026099 -286.651404) (xy 421.987978 -286.620279) (xy 421.955343 -286.583442)
			(xy 421.92904 -286.541846) (xy 421.909749 -286.49657) (xy 421.897972 -286.448786) (xy 421.894012 -286.399732)
			(xy 396.55369 -286.399732) (xy 396.55369 -287.10001) (xy 396.554114 -287.11008) (xy 396.56183 -287.128682)
			(xy 396.568676 -287.136078) (xy 396.582138 -287.14954) (xy 396.588604 -287.155582) (xy 396.604606 -287.163113)
			(xy 396.61338 -287.164272) (xy 396.620238 -287.16478) (xy 396.6337 -287.16478) (xy 396.64005 -287.164272)
			(xy 396.650051 -287.162938) (xy 396.667868 -287.153505) (xy 396.674594 -287.145984) (xy 396.677896 -287.14192)
			(xy 396.697708 -287.110424) (xy 396.723616 -287.069022) (xy 396.728686 -287.06013) (xy 396.731969 -287.039944)
			(xy 396.729966 -287.029906) (xy 396.727172 -287.018984) (xy 396.724886 -287.014158) (xy 396.715179 -286.992251)
			(xy 396.701481 -286.946336) (xy 396.694562 -286.898923) (xy 396.694152 -286.874966) (xy 396.694662 -286.848979)
			(xy 396.702792 -286.797644) (xy 396.718853 -286.748214) (xy 396.742449 -286.701904) (xy 396.772999 -286.659856)
			(xy 396.80975 -286.623105) (xy 396.851798 -286.592555) (xy 396.898108 -286.568959) (xy 396.947538 -286.552898)
			(xy 396.998873 -286.544768) (xy 397.050847 -286.544768) (xy 397.102182 -286.552898) (xy 397.151612 -286.568959)
			(xy 397.197922 -286.592555) (xy 397.23997 -286.623105) (xy 397.276721 -286.659856) (xy 397.307271 -286.701904)
			(xy 397.330867 -286.748214) (xy 397.346928 -286.797644) (xy 397.355058 -286.848979) (xy 397.355568 -286.874966)
			(xy 397.355568 -286.875474) (xy 397.355139 -286.898969) (xy 397.348442 -286.945481) (xy 397.335208 -286.99057)
			(xy 397.32585 -287.012126) (xy 397.325088 -287.013904) (xy 397.321278 -287.024318) (xy 397.3195 -287.0327)
			(xy 397.317964 -287.042439) (xy 397.321612 -287.061796) (xy 397.326612 -287.070292) (xy 397.378174 -287.151064)
			(xy 397.398494 -287.163256) (xy 397.409924 -287.164272) (xy 397.41475 -287.16478) (xy 397.580358 -287.16478)
			(xy 397.583914 -287.164526) (xy 397.588994 -287.164272) (xy 397.599255 -287.163074) (xy 397.617605 -287.153629)
			(xy 397.624554 -287.145984) (xy 397.627856 -287.14192) (xy 397.647668 -287.110424) (xy 397.673576 -287.069022)
			(xy 397.678642 -287.060129) (xy 397.68192 -287.039945) (xy 397.679926 -287.029906) (xy 397.677132 -287.018984)
			(xy 397.674846 -287.014158) (xy 397.665137 -286.992251) (xy 397.651437 -286.946337) (xy 397.644517 -286.898924)
			(xy 397.644112 -286.874966) (xy 397.644622 -286.848979) (xy 397.652752 -286.797644) (xy 397.668813 -286.748214)
			(xy 397.692409 -286.701904) (xy 397.722959 -286.659856) (xy 397.75971 -286.623105) (xy 397.801758 -286.592555)
			(xy 397.848068 -286.568959) (xy 397.897498 -286.552898) (xy 397.948833 -286.544768) (xy 398.000807 -286.544768)
			(xy 398.052142 -286.552898) (xy 398.101572 -286.568959) (xy 398.147882 -286.592555) (xy 398.18993 -286.623105)
			(xy 398.226681 -286.659856) (xy 398.257231 -286.701904) (xy 398.280827 -286.748214) (xy 398.296888 -286.797644)
			(xy 398.305018 -286.848979) (xy 398.305528 -286.874966) (xy 398.305528 -286.875474) (xy 398.305099 -286.89897)
			(xy 398.298403 -286.945481) (xy 398.285172 -286.990572) (xy 398.27581 -287.012126) (xy 398.275048 -287.013904)
			(xy 398.271238 -287.024318) (xy 398.26946 -287.0327) (xy 398.267924 -287.04244) (xy 398.271569 -287.061797)
			(xy 398.276572 -287.070292) (xy 398.328134 -287.151064) (xy 398.348454 -287.163256) (xy 398.359884 -287.164272)
			(xy 398.36471 -287.16478) (xy 398.5641 -287.16478) (xy 398.572803 -287.16443) (xy 398.58921 -287.158618)
			(xy 398.602734 -287.147662) (xy 398.607534 -287.140396) (xy 398.659858 -287.054798) (xy 398.66062 -287.028128)
			(xy 398.65427 -287.01619) (xy 398.652746 -287.013142) (xy 398.651476 -287.01111) (xy 398.641381 -286.989851)
			(xy 398.627124 -286.945001) (xy 398.619913 -286.898496) (xy 398.619472 -286.874966) (xy 398.619726 -286.868108)
			(xy 398.619726 -286.867854) (xy 398.620715 -286.844229) (xy 398.629083 -286.797691) (xy 398.644526 -286.753)
			(xy 398.666676 -286.711225) (xy 398.695003 -286.673365) (xy 398.728828 -286.640326) (xy 398.767344 -286.612898)
			(xy 398.809628 -286.591736) (xy 398.85467 -286.577348) (xy 398.901392 -286.570078) (xy 398.925034 -286.569658)
			(xy 398.948685 -286.570104) (xy 398.99542 -286.577402) (xy 399.040472 -286.591817) (xy 399.082763 -286.613004)
			(xy 399.121283 -286.640459) (xy 399.155109 -286.673523) (xy 399.183433 -286.711407) (xy 399.205579 -286.753204)
			(xy 399.221017 -286.797916) (xy 399.229377 -286.844473) (xy 399.230342 -286.868108) (xy 399.230596 -286.874966)
			(xy 399.230165 -286.898497) (xy 399.222955 -286.945004) (xy 399.2087 -286.989856) (xy 399.198592 -287.01111)
			(xy 399.197322 -287.013142) (xy 399.195798 -287.01619) (xy 399.189448 -287.028128) (xy 399.19021 -287.054798)
			(xy 399.242534 -287.140396) (xy 399.247352 -287.147655) (xy 399.260854 -287.158649) (xy 399.277262 -287.164472)
			(xy 399.285968 -287.16478) (xy 399.51406 -287.16478) (xy 399.522758 -287.164421) (xy 399.53915 -287.158596)
			(xy 399.552658 -287.147634) (xy 399.557494 -287.140396) (xy 399.609818 -287.054798) (xy 399.61058 -287.028128)
			(xy 399.60423 -287.01619) (xy 399.602706 -287.013142) (xy 399.601436 -287.01111) (xy 399.591339 -286.989851)
			(xy 399.577079 -286.945002) (xy 399.569867 -286.898497) (xy 399.569432 -286.874966) (xy 399.569686 -286.868108)
			(xy 399.569686 -286.867854) (xy 399.570675 -286.84423) (xy 399.579043 -286.797696) (xy 399.594487 -286.753009)
			(xy 399.616638 -286.711239) (xy 399.644966 -286.673384) (xy 399.678793 -286.64035) (xy 399.717309 -286.612929)
			(xy 399.759593 -286.591775) (xy 399.804634 -286.577395) (xy 399.851353 -286.570133) (xy 399.874994 -286.569658)
			(xy 399.898642 -286.570109) (xy 399.94537 -286.577413) (xy 399.990414 -286.591834) (xy 400.032697 -286.613025)
			(xy 400.071208 -286.64048) (xy 400.105027 -286.673544) (xy 400.133345 -286.711425) (xy 400.155486 -286.753219)
			(xy 400.170919 -286.797926) (xy 400.179277 -286.844477) (xy 400.180302 -286.868108) (xy 400.180556 -286.874966)
			(xy 400.180125 -286.898497) (xy 400.172914 -286.945004) (xy 400.158658 -286.989855) (xy 400.148552 -287.01111)
			(xy 400.147282 -287.013142) (xy 400.145758 -287.01619) (xy 400.139408 -287.028128) (xy 400.14017 -287.054798)
			(xy 400.192494 -287.140396) (xy 400.197315 -287.147649) (xy 400.210819 -287.158626) (xy 400.227226 -287.16443)
			(xy 400.235928 -287.16478) (xy 400.46402 -287.16478) (xy 400.472721 -287.164427) (xy 400.489123 -287.158611)
			(xy 400.502642 -287.147652) (xy 400.507454 -287.140396) (xy 400.559778 -287.054798) (xy 400.56054 -287.028128)
			(xy 400.55419 -287.01619) (xy 400.552666 -287.013142) (xy 400.551396 -287.01111) (xy 400.541301 -286.989851)
			(xy 400.527043 -286.945002) (xy 400.519831 -286.898497) (xy 400.519392 -286.874966) (xy 400.519646 -286.868108)
			(xy 400.519646 -286.867854) (xy 400.520635 -286.844229) (xy 400.529003 -286.797693) (xy 400.544446 -286.753003)
			(xy 400.566597 -286.711229) (xy 400.594924 -286.673371) (xy 400.62875 -286.640334) (xy 400.667266 -286.612908)
			(xy 400.70955 -286.591749) (xy 400.754591 -286.577364) (xy 400.801312 -286.570096) (xy 400.824954 -286.569658)
			(xy 400.848604 -286.570106) (xy 400.895337 -286.577406) (xy 400.940386 -286.591822) (xy 400.982675 -286.613011)
			(xy 401.021191 -286.640466) (xy 401.055015 -286.67353) (xy 401.083337 -286.711413) (xy 401.105481 -286.753209)
			(xy 401.120918 -286.797919) (xy 401.129277 -286.844474) (xy 401.130262 -286.868108) (xy 401.130516 -286.874966)
			(xy 401.130085 -286.898497) (xy 401.122876 -286.945005) (xy 401.108622 -286.989857) (xy 401.098512 -287.01111)
			(xy 401.097242 -287.013142) (xy 401.095718 -287.01619) (xy 401.089368 -287.028128) (xy 401.09013 -287.054798)
			(xy 401.142454 -287.140396) (xy 401.147273 -287.147653) (xy 401.160775 -287.158641) (xy 401.177183 -287.164458)
			(xy 401.185888 -287.16478) (xy 401.41398 -287.16478) (xy 401.422676 -287.164418) (xy 401.439063 -287.158588)
			(xy 401.452566 -287.147625) (xy 401.457414 -287.140396) (xy 401.509738 -287.054798) (xy 401.5105 -287.028128)
			(xy 401.50415 -287.01619) (xy 401.502626 -287.013142) (xy 401.501356 -287.01111) (xy 401.491262 -286.98985)
			(xy 401.477006 -286.945001) (xy 401.469795 -286.898496) (xy 401.469352 -286.874966) (xy 401.469606 -286.868108)
			(xy 401.469606 -286.867854) (xy 401.470595 -286.844228) (xy 401.478962 -286.797689) (xy 401.494406 -286.752997)
			(xy 401.516555 -286.71122) (xy 401.544881 -286.673359) (xy 401.578707 -286.640318) (xy 401.617222 -286.612887)
			(xy 401.659507 -286.591724) (xy 401.704549 -286.577333) (xy 401.751271 -286.570059) (xy 401.774914 -286.569658)
			(xy 401.798566 -286.570103) (xy 401.845304 -286.577398) (xy 401.890358 -286.591811) (xy 401.932652 -286.612998)
			(xy 401.971174 -286.640451) (xy 402.005003 -286.673516) (xy 402.03333 -286.7114) (xy 402.055477 -286.753199)
			(xy 402.070916 -286.797913) (xy 402.079277 -286.844472) (xy 402.080222 -286.868108) (xy 402.080476 -286.874966)
			(xy 402.080045 -286.898497) (xy 402.072835 -286.945004) (xy 402.058579 -286.989856) (xy 402.048472 -287.01111)
			(xy 402.047202 -287.013142) (xy 402.045678 -287.01619) (xy 402.039328 -287.028128) (xy 402.04009 -287.054798)
			(xy 402.092414 -287.140396) (xy 402.097236 -287.147647) (xy 402.110741 -287.158619) (xy 402.127147 -287.164416)
			(xy 402.135848 -287.16478) (xy 402.36394 -287.16478) (xy 402.372639 -287.164424) (xy 402.389036 -287.158603)
			(xy 402.40255 -287.147643) (xy 402.407374 -287.140396) (xy 402.459698 -287.054798) (xy 402.46046 -287.028128)
			(xy 402.45411 -287.01619) (xy 402.452586 -287.013142) (xy 402.451316 -287.01111) (xy 402.44122 -286.989851)
			(xy 402.426961 -286.945002) (xy 402.419749 -286.898497) (xy 402.419312 -286.874966) (xy 402.419566 -286.868108)
			(xy 402.419566 -286.867854) (xy 402.420555 -286.84423) (xy 402.428923 -286.797694) (xy 402.444367 -286.753006)
			(xy 402.466518 -286.711234) (xy 402.494845 -286.673377) (xy 402.528671 -286.640342) (xy 402.567187 -286.612918)
			(xy 402.609472 -286.591762) (xy 402.654513 -286.577379) (xy 402.701233 -286.570115) (xy 402.724874 -286.569658)
			(xy 402.748523 -286.570107) (xy 402.795254 -286.577409) (xy 402.8403 -286.591828) (xy 402.882586 -286.613018)
			(xy 402.9211 -286.640473) (xy 402.954921 -286.673537) (xy 402.983241 -286.711419) (xy 403.005384 -286.753214)
			(xy 403.020819 -286.797922) (xy 403.029177 -286.844476) (xy 403.030182 -286.868108) (xy 403.030436 -286.874966)
			(xy 403.030005 -286.898497) (xy 403.022796 -286.945005) (xy 403.008543 -286.989858) (xy 402.998432 -287.01111)
			(xy 402.997162 -287.013142) (xy 402.995638 -287.01619) (xy 402.989288 -287.028128) (xy 402.99005 -287.054798)
			(xy 403.042374 -287.140396) (xy 403.047194 -287.147651) (xy 403.060697 -287.158634) (xy 403.077104 -287.164444)
			(xy 403.085808 -287.16478) (xy 403.3139 -287.16478) (xy 403.322603 -287.16443) (xy 403.33901 -287.158618)
			(xy 403.352534 -287.147662) (xy 403.357334 -287.140396) (xy 403.409658 -287.054798) (xy 403.41042 -287.028128)
			(xy 403.40407 -287.01619) (xy 403.402546 -287.013142) (xy 403.401276 -287.01111) (xy 403.391181 -286.989851)
			(xy 403.376924 -286.945001) (xy 403.369713 -286.898496) (xy 403.369272 -286.874966) (xy 403.369526 -286.868108)
			(xy 403.369526 -286.867854) (xy 403.370515 -286.844229) (xy 403.378883 -286.797691) (xy 403.394326 -286.753)
			(xy 403.416476 -286.711225) (xy 403.444803 -286.673365) (xy 403.478628 -286.640326) (xy 403.517144 -286.612898)
			(xy 403.559428 -286.591736) (xy 403.60447 -286.577348) (xy 403.651192 -286.570078) (xy 403.674834 -286.569658)
			(xy 403.698485 -286.570104) (xy 403.74522 -286.577402) (xy 403.790272 -286.591817) (xy 403.832563 -286.613004)
			(xy 403.871083 -286.640459) (xy 403.904909 -286.673523) (xy 403.933233 -286.711407) (xy 403.955379 -286.753204)
			(xy 403.970817 -286.797916) (xy 403.979177 -286.844473) (xy 403.980142 -286.868108) (xy 403.980396 -286.874966)
			(xy 403.979965 -286.898497) (xy 403.972755 -286.945004) (xy 403.9585 -286.989856) (xy 403.948392 -287.01111)
			(xy 403.947122 -287.013142) (xy 403.945598 -287.01619) (xy 403.939248 -287.028128) (xy 403.94001 -287.054798)
			(xy 403.992334 -287.140396) (xy 403.997152 -287.147655) (xy 404.010654 -287.158649) (xy 404.027062 -287.164472)
			(xy 404.035768 -287.16478) (xy 404.26386 -287.16478) (xy 404.272558 -287.164421) (xy 404.28895 -287.158596)
			(xy 404.302458 -287.147634) (xy 404.307294 -287.140396) (xy 404.359618 -287.054798) (xy 404.36038 -287.028128)
			(xy 404.35403 -287.01619) (xy 404.352506 -287.013142) (xy 404.351236 -287.01111) (xy 404.341139 -286.989851)
			(xy 404.326879 -286.945002) (xy 404.319667 -286.898497) (xy 404.319232 -286.874966) (xy 404.319486 -286.868108)
			(xy 404.319486 -286.867854) (xy 404.320475 -286.84423) (xy 404.328843 -286.797696) (xy 404.344287 -286.753009)
			(xy 404.366438 -286.711239) (xy 404.394766 -286.673384) (xy 404.428593 -286.64035) (xy 404.467109 -286.612929)
			(xy 404.509393 -286.591775) (xy 404.554434 -286.577395) (xy 404.601153 -286.570133) (xy 404.624794 -286.569658)
			(xy 404.648442 -286.570109) (xy 404.69517 -286.577413) (xy 404.740214 -286.591834) (xy 404.782497 -286.613025)
			(xy 404.821008 -286.64048) (xy 404.854827 -286.673544) (xy 404.883145 -286.711425) (xy 404.905286 -286.753219)
			(xy 404.920719 -286.797926) (xy 404.929077 -286.844477) (xy 404.930102 -286.868108) (xy 404.930356 -286.874966)
			(xy 404.929925 -286.898497) (xy 404.922714 -286.945004) (xy 404.908458 -286.989855) (xy 404.898352 -287.01111)
			(xy 404.897082 -287.013142) (xy 404.895558 -287.01619) (xy 404.889208 -287.028128) (xy 404.88997 -287.054798)
			(xy 404.942294 -287.140396) (xy 404.947115 -287.147649) (xy 404.960619 -287.158626) (xy 404.977026 -287.16443)
			(xy 404.985728 -287.16478) (xy 405.214074 -287.16478) (xy 405.222771 -287.164419) (xy 405.239159 -287.158591)
			(xy 405.252664 -287.147628) (xy 405.257508 -287.140396) (xy 405.309832 -287.054798) (xy 405.310594 -287.028128)
			(xy 405.304244 -287.01619) (xy 405.30272 -287.013142) (xy 405.30145 -287.01111) (xy 405.291356 -286.98985)
			(xy 405.2771 -286.945001) (xy 405.269889 -286.898496) (xy 405.269446 -286.874966) (xy 405.2697 -286.868108)
			(xy 405.2697 -286.867854) (xy 405.270689 -286.844228) (xy 405.279056 -286.797689) (xy 405.294499 -286.752996)
			(xy 405.316649 -286.711219) (xy 405.344975 -286.673357) (xy 405.3788 -286.640315) (xy 405.417316 -286.612884)
			(xy 405.4596 -286.59172) (xy 405.504643 -286.577328) (xy 405.551365 -286.570054) (xy 405.575008 -286.569658)
			(xy 405.59866 -286.570102) (xy 405.645399 -286.577396) (xy 405.690454 -286.591809) (xy 405.732749 -286.612996)
			(xy 405.771271 -286.640449) (xy 405.805101 -286.673514) (xy 405.833428 -286.711399) (xy 405.855577 -286.753198)
			(xy 405.871016 -286.797912) (xy 405.879377 -286.844471) (xy 405.880316 -286.868108) (xy 405.88057 -286.874966)
			(xy 405.880139 -286.898497) (xy 405.872929 -286.945004) (xy 405.858673 -286.989856) (xy 405.848566 -287.01111)
			(xy 405.847296 -287.013142) (xy 405.845772 -287.01619) (xy 405.839422 -287.028128) (xy 405.840184 -287.054798)
			(xy 405.892508 -287.140396) (xy 405.89733 -287.147647) (xy 405.910834 -287.158621) (xy 405.92724 -287.16442)
			(xy 405.935942 -287.16478) (xy 406.164034 -287.16478) (xy 406.172734 -287.164425) (xy 406.189132 -287.158606)
			(xy 406.202648 -287.147646) (xy 406.207468 -287.140396) (xy 406.259792 -287.054798) (xy 406.260554 -287.028128)
			(xy 406.254204 -287.01619) (xy 406.25268 -287.013142) (xy 406.25141 -287.01111) (xy 406.241314 -286.989851)
			(xy 406.227055 -286.945002) (xy 406.219843 -286.898497) (xy 406.219406 -286.874966) (xy 406.21966 -286.868108)
			(xy 406.21966 -286.867854) (xy 406.220649 -286.84423) (xy 406.229017 -286.797694) (xy 406.244461 -286.753005)
			(xy 406.266611 -286.711233) (xy 406.294938 -286.673376) (xy 406.328765 -286.64034) (xy 406.367281 -286.612915)
			(xy 406.409565 -286.591758) (xy 406.454606 -286.577375) (xy 406.501327 -286.570109) (xy 406.524968 -286.569658)
			(xy 406.548617 -286.570107) (xy 406.595349 -286.577408) (xy 406.640396 -286.591826) (xy 406.682683 -286.613016)
			(xy 406.721197 -286.640471) (xy 406.755019 -286.673535) (xy 406.78334 -286.711417) (xy 406.805483 -286.753212)
			(xy 406.820918 -286.797921) (xy 406.829277 -286.844475) (xy 406.830276 -286.868108) (xy 406.83053 -286.874966)
			(xy 406.830099 -286.898497) (xy 406.82289 -286.945005) (xy 406.808637 -286.989857) (xy 406.798526 -287.01111)
			(xy 406.797256 -287.013142) (xy 406.795732 -287.01619) (xy 406.789382 -287.028128) (xy 406.790144 -287.054798)
			(xy 406.842468 -287.140396) (xy 406.847288 -287.147652) (xy 406.860791 -287.158636) (xy 406.877198 -287.164448)
			(xy 406.885902 -287.16478) (xy 408.063954 -287.16478) (xy 408.072652 -287.164422) (xy 408.089046 -287.158598)
			(xy 408.102556 -287.147637) (xy 408.107388 -287.140396) (xy 408.159712 -287.054798) (xy 408.160474 -287.028128)
			(xy 408.154124 -287.01619) (xy 408.1526 -287.013142) (xy 408.15133 -287.01111) (xy 408.141234 -286.989851)
			(xy 408.126974 -286.945002) (xy 408.119761 -286.898497) (xy 408.119326 -286.874966) (xy 408.11958 -286.868108)
			(xy 408.11958 -286.867854) (xy 408.120569 -286.84423) (xy 408.128937 -286.797696) (xy 408.144381 -286.753008)
			(xy 408.166532 -286.711237) (xy 408.19486 -286.673382) (xy 408.228686 -286.640348) (xy 408.267202 -286.612925)
			(xy 408.309487 -286.591771) (xy 408.354528 -286.57739) (xy 408.401247 -286.570128) (xy 408.424888 -286.569658)
			(xy 408.448536 -286.570108) (xy 408.495265 -286.577412) (xy 408.54031 -286.591832) (xy 408.582594 -286.613023)
			(xy 408.621106 -286.640478) (xy 408.654925 -286.673542) (xy 408.683244 -286.711423) (xy 408.705385 -286.753217)
			(xy 408.720819 -286.797925) (xy 408.729177 -286.844477) (xy 408.730196 -286.868108) (xy 408.73045 -286.874966)
			(xy 408.730019 -286.898497) (xy 408.722808 -286.945004) (xy 408.708551 -286.989855) (xy 408.698446 -287.01111)
			(xy 408.697176 -287.013142) (xy 408.695652 -287.01619) (xy 408.689302 -287.028128) (xy 408.690064 -287.054798)
			(xy 408.742388 -287.140396) (xy 408.747208 -287.14765) (xy 408.760712 -287.158629) (xy 408.777119 -287.164434)
			(xy 408.785822 -287.16478) (xy 409.013914 -287.16478) (xy 409.022616 -287.164428) (xy 409.039019 -287.158613)
			(xy 409.05254 -287.147655) (xy 409.057348 -287.140396) (xy 409.109672 -287.054798) (xy 409.110434 -287.028128)
			(xy 409.104084 -287.01619) (xy 409.10256 -287.013142) (xy 409.10129 -287.01111) (xy 409.091195 -286.989851)
			(xy 409.076937 -286.945002) (xy 409.069725 -286.898497) (xy 409.069286 -286.874966) (xy 409.06954 -286.868108)
			(xy 409.06954 -286.867854) (xy 409.070529 -286.844229) (xy 409.078897 -286.797692) (xy 409.09434 -286.753002)
			(xy 409.11649 -286.711228) (xy 409.144817 -286.673369) (xy 409.178643 -286.640331) (xy 409.217159 -286.612905)
			(xy 409.259444 -286.591745) (xy 409.304485 -286.577359) (xy 409.351206 -286.570091) (xy 409.374848 -286.569658)
			(xy 409.398498 -286.570105) (xy 409.445232 -286.577404) (xy 409.490282 -286.591821) (xy 409.532571 -286.613009)
			(xy 409.571089 -286.640464) (xy 409.604913 -286.673528) (xy 409.633236 -286.711411) (xy 409.655381 -286.753207)
			(xy 409.670817 -286.797918) (xy 409.679177 -286.844474) (xy 409.680156 -286.868108) (xy 409.68041 -286.874966)
			(xy 409.679979 -286.898497) (xy 409.67277 -286.945005) (xy 409.658515 -286.989857) (xy 409.648406 -287.01111)
			(xy 409.647136 -287.013142) (xy 409.645612 -287.01619) (xy 409.639262 -287.028128) (xy 409.640024 -287.054798)
			(xy 409.692348 -287.140396) (xy 409.697167 -287.147654) (xy 409.710669 -287.158643) (xy 409.727077 -287.164462)
			(xy 409.735782 -287.16478) (xy 409.963874 -287.16478) (xy 409.972571 -287.164419) (xy 409.988959 -287.158591)
			(xy 410.002464 -287.147628) (xy 410.007308 -287.140396) (xy 410.059632 -287.054798) (xy 410.060394 -287.028128)
			(xy 410.054044 -287.01619) (xy 410.05252 -287.013142) (xy 410.05125 -287.01111) (xy 410.041156 -286.98985)
			(xy 410.0269 -286.945001) (xy 410.019689 -286.898496) (xy 410.019246 -286.874966) (xy 410.0195 -286.868108)
			(xy 410.0195 -286.867854) (xy 410.020489 -286.844228) (xy 410.028856 -286.797689) (xy 410.044299 -286.752996)
			(xy 410.066449 -286.711219) (xy 410.094775 -286.673357) (xy 410.1286 -286.640315) (xy 410.167116 -286.612884)
			(xy 410.2094 -286.59172) (xy 410.254443 -286.577328) (xy 410.301165 -286.570054) (xy 410.324808 -286.569658)
			(xy 410.34846 -286.570102) (xy 410.395199 -286.577396) (xy 410.440254 -286.591809) (xy 410.482549 -286.612996)
			(xy 410.521071 -286.640449) (xy 410.554901 -286.673514) (xy 410.583228 -286.711399) (xy 410.605377 -286.753198)
			(xy 410.620816 -286.797912) (xy 410.629177 -286.844471) (xy 410.630116 -286.868108) (xy 410.63037 -286.874966)
			(xy 410.629939 -286.898497) (xy 410.622729 -286.945004) (xy 410.608473 -286.989856) (xy 410.598366 -287.01111)
			(xy 410.597096 -287.013142) (xy 410.595572 -287.01619) (xy 410.589222 -287.028128) (xy 410.589984 -287.054798)
			(xy 410.642308 -287.140396) (xy 410.64713 -287.147647) (xy 410.660634 -287.158621) (xy 410.67704 -287.16442)
			(xy 410.685742 -287.16478) (xy 410.914088 -287.16478) (xy 410.922792 -287.164432) (xy 410.939202 -287.158623)
			(xy 410.952729 -287.147667) (xy 410.957522 -287.140396) (xy 411.009846 -287.054798) (xy 411.010608 -287.028128)
			(xy 411.004258 -287.01619) (xy 411.002734 -287.013142) (xy 411.001464 -287.01111) (xy 410.99137 -286.98985)
			(xy 410.977113 -286.945001) (xy 410.969902 -286.898496) (xy 410.96946 -286.874966) (xy 410.969714 -286.868108)
			(xy 410.969714 -286.867854) (xy 410.970703 -286.844228) (xy 410.97907 -286.79769) (xy 410.994514 -286.752998)
			(xy 411.016663 -286.711222) (xy 411.04499 -286.673361) (xy 411.078815 -286.640321) (xy 411.117331 -286.612891)
			(xy 411.159616 -286.591729) (xy 411.204657 -286.577339) (xy 411.25138 -286.570067) (xy 411.275022 -286.569658)
			(xy 411.298673 -286.570103) (xy 411.34541 -286.577399) (xy 411.390464 -286.591813) (xy 411.432757 -286.613)
			(xy 411.471277 -286.640454) (xy 411.505105 -286.673519) (xy 411.533431 -286.711403) (xy 411.555578 -286.753201)
			(xy 411.571016 -286.797914) (xy 411.579377 -286.844472) (xy 411.58033 -286.868108) (xy 411.580584 -286.874966)
			(xy 411.580153 -286.898497) (xy 411.572943 -286.945004) (xy 411.558688 -286.989856) (xy 411.54858 -287.01111)
			(xy 411.54731 -287.013142) (xy 411.545786 -287.01619) (xy 411.539436 -287.028128) (xy 411.540198 -287.054798)
			(xy 411.592522 -287.140396) (xy 411.597339 -287.147657) (xy 411.61084 -287.158654) (xy 411.627249 -287.16448)
			(xy 411.635956 -287.16478) (xy 411.864048 -287.16478) (xy 411.872747 -287.164423) (xy 411.889142 -287.1586)
			(xy 411.902653 -287.14764) (xy 411.907482 -287.140396) (xy 411.959806 -287.054798) (xy 411.960568 -287.028128)
			(xy 411.954218 -287.01619) (xy 411.952694 -287.013142) (xy 411.951424 -287.01111) (xy 411.941328 -286.989851)
			(xy 411.927068 -286.945002) (xy 411.919856 -286.898497) (xy 411.91942 -286.874966) (xy 411.919674 -286.868108)
			(xy 411.919674 -286.867854) (xy 411.920663 -286.84423) (xy 411.929031 -286.797695) (xy 411.944475 -286.753007)
			(xy 411.966626 -286.711236) (xy 411.994953 -286.67338) (xy 412.02878 -286.640345) (xy 412.067296 -286.612922)
			(xy 412.10958 -286.591767) (xy 412.154621 -286.577386) (xy 412.201341 -286.570122) (xy 412.224982 -286.569658)
			(xy 412.24863 -286.570108) (xy 412.29536 -286.577411) (xy 412.340406 -286.59183) (xy 412.38269 -286.613021)
			(xy 412.421203 -286.640476) (xy 412.455023 -286.67354) (xy 412.483343 -286.711421) (xy 412.505484 -286.753216)
			(xy 412.520919 -286.797924) (xy 412.529277 -286.844476) (xy 412.53029 -286.868108) (xy 412.530544 -286.874966)
			(xy 412.530113 -286.898498) (xy 412.522904 -286.945005) (xy 412.508652 -286.989858) (xy 412.49854 -287.01111)
			(xy 412.49727 -287.013142) (xy 412.495746 -287.01619) (xy 412.489396 -287.028128) (xy 412.490158 -287.054798)
			(xy 412.542482 -287.140396) (xy 412.547302 -287.14765) (xy 412.560806 -287.158631) (xy 412.577213 -287.164439)
			(xy 412.585916 -287.16478) (xy 412.814008 -287.16478) (xy 412.82271 -287.164429) (xy 412.839115 -287.158615)
			(xy 412.852637 -287.147658) (xy 412.857442 -287.140396) (xy 412.909766 -287.054798) (xy 412.910528 -287.028128)
			(xy 412.904178 -287.01619) (xy 412.902654 -287.013142) (xy 412.901384 -287.01111) (xy 412.891289 -286.989851)
			(xy 412.877031 -286.945002) (xy 412.86982 -286.898496) (xy 412.86938 -286.874966) (xy 412.869634 -286.868108)
			(xy 412.869634 -286.867854) (xy 412.870623 -286.844229) (xy 412.878991 -286.797692) (xy 412.894434 -286.753001)
			(xy 412.916584 -286.711227) (xy 412.944911 -286.673368) (xy 412.978737 -286.640329) (xy 413.017253 -286.612902)
			(xy 413.059537 -286.591741) (xy 413.104579 -286.577355) (xy 413.1513 -286.570085) (xy 413.174942 -286.569658)
			(xy 413.198592 -286.570105) (xy 413.245327 -286.577403) (xy 413.290378 -286.591819) (xy 413.332668 -286.613007)
			(xy 413.371186 -286.640462) (xy 413.405011 -286.673526) (xy 413.433335 -286.711409) (xy 413.45548 -286.753206)
			(xy 413.470917 -286.797917) (xy 413.479277 -286.844474) (xy 413.48025 -286.868108) (xy 413.480504 -286.874966)
			(xy 413.480073 -286.898497) (xy 413.472863 -286.945005) (xy 413.458609 -286.989857) (xy 413.4485 -287.01111)
			(xy 413.44723 -287.013142) (xy 413.445706 -287.01619) (xy 413.439356 -287.028128) (xy 413.440118 -287.054798)
			(xy 413.492442 -287.140396) (xy 413.49726 -287.147655) (xy 413.510762 -287.158646) (xy 413.527171 -287.164466)
			(xy 413.535876 -287.16478) (xy 413.763968 -287.16478) (xy 413.772665 -287.16442) (xy 413.789055 -287.158593)
			(xy 413.802561 -287.147631) (xy 413.807402 -287.140396) (xy 413.859726 -287.054798) (xy 413.860488 -287.028128)
			(xy 413.854138 -287.01619) (xy 413.852614 -287.013142) (xy 413.851344 -287.01111) (xy 413.84125 -286.98985)
			(xy 413.826995 -286.945001) (xy 413.819784 -286.898496) (xy 413.81934 -286.874966) (xy 413.819594 -286.868108)
			(xy 413.819594 -286.867854) (xy 413.820583 -286.844228) (xy 413.82895 -286.797688) (xy 413.844393 -286.752995)
			(xy 413.866543 -286.711218) (xy 413.894869 -286.673355) (xy 413.928694 -286.640313) (xy 413.967209 -286.612881)
			(xy 414.009494 -286.591716) (xy 414.054536 -286.577324) (xy 414.101259 -286.570048) (xy 414.124902 -286.569658)
			(xy 414.148549 -286.570109) (xy 414.195277 -286.577415) (xy 414.24032 -286.591836) (xy 414.282602 -286.613028)
			(xy 414.321112 -286.640483) (xy 414.35493 -286.673547) (xy 414.383247 -286.711428) (xy 414.405387 -286.753221)
			(xy 414.42082 -286.797927) (xy 414.429178 -286.844478) (xy 414.43021 -286.868108) (xy 414.430464 -286.874966)
			(xy 414.430033 -286.898497) (xy 414.422822 -286.945004) (xy 414.408566 -286.989855) (xy 414.39846 -287.01111)
			(xy 414.39719 -287.013142) (xy 414.395666 -287.01619) (xy 414.389316 -287.028128) (xy 414.390078 -287.054798)
			(xy 414.442402 -287.140396) (xy 414.447223 -287.147648) (xy 414.460728 -287.158623) (xy 414.477134 -287.164424)
			(xy 414.485836 -287.16478) (xy 414.713928 -287.16478) (xy 414.722628 -287.164426) (xy 414.739028 -287.158608)
			(xy 414.752545 -287.147649) (xy 414.757362 -287.140396) (xy 414.809686 -287.054798) (xy 414.810448 -287.028128)
			(xy 414.804098 -287.01619) (xy 414.802574 -287.013142) (xy 414.801304 -287.01111) (xy 414.791208 -286.989851)
			(xy 414.77695 -286.945002) (xy 414.769738 -286.898497) (xy 414.7693 -286.874966) (xy 414.769554 -286.868108)
			(xy 414.769554 -286.867854) (xy 414.770543 -286.844229) (xy 414.778911 -286.797693) (xy 414.794355 -286.753004)
			(xy 414.816505 -286.711231) (xy 414.844832 -286.673374) (xy 414.878658 -286.640337) (xy 414.917174 -286.612912)
			(xy 414.959459 -286.591754) (xy 415.0045 -286.57737) (xy 415.051221 -286.570104) (xy 415.074862 -286.569658)
			(xy 415.098511 -286.570106) (xy 415.145244 -286.577407) (xy 415.190292 -286.591825) (xy 415.232579 -286.613014)
			(xy 415.271095 -286.640469) (xy 415.304917 -286.673533) (xy 415.333239 -286.711415) (xy 415.355382 -286.753211)
			(xy 415.370818 -286.79792) (xy 415.379177 -286.844475) (xy 415.38017 -286.868108) (xy 415.380424 -286.874966)
			(xy 415.379993 -286.898497) (xy 415.372784 -286.945005) (xy 415.35853 -286.989857) (xy 415.34842 -287.01111)
			(xy 415.34715 -287.013142) (xy 415.345626 -287.01619) (xy 415.339276 -287.028128) (xy 415.340038 -287.054798)
			(xy 415.392362 -287.140396) (xy 415.397181 -287.147652) (xy 415.410684 -287.158638) (xy 415.427092 -287.164452)
			(xy 415.435796 -287.16478) (xy 415.663888 -287.16478) (xy 415.672592 -287.164432) (xy 415.689002 -287.158623)
			(xy 415.702529 -287.147667) (xy 415.707322 -287.140396) (xy 415.759646 -287.054798) (xy 415.760408 -287.028128)
			(xy 415.754058 -287.01619) (xy 415.752534 -287.013142) (xy 415.751264 -287.01111) (xy 415.74117 -286.98985)
			(xy 415.726913 -286.945001) (xy 415.719702 -286.898496) (xy 415.71926 -286.874966) (xy 415.719514 -286.868108)
			(xy 415.719514 -286.867854) (xy 415.720503 -286.844228) (xy 415.72887 -286.79769) (xy 415.744314 -286.752998)
			(xy 415.766463 -286.711222) (xy 415.79479 -286.673361) (xy 415.828615 -286.640321) (xy 415.867131 -286.612891)
			(xy 415.909416 -286.591729) (xy 415.954457 -286.577339) (xy 416.00118 -286.570067) (xy 416.024822 -286.569658)
			(xy 416.048473 -286.570103) (xy 416.09521 -286.577399) (xy 416.140264 -286.591813) (xy 416.182557 -286.613)
			(xy 416.221077 -286.640454) (xy 416.254905 -286.673519) (xy 416.283231 -286.711403) (xy 416.305378 -286.753201)
			(xy 416.320816 -286.797914) (xy 416.329177 -286.844472) (xy 416.33013 -286.868108) (xy 416.330384 -286.874966)
			(xy 416.329953 -286.898497) (xy 416.322743 -286.945004) (xy 416.308488 -286.989856) (xy 416.29838 -287.01111)
			(xy 416.29711 -287.013142) (xy 416.295586 -287.01619) (xy 416.289236 -287.028128) (xy 416.289998 -287.054798)
			(xy 416.342322 -287.140396) (xy 416.347139 -287.147657) (xy 416.36064 -287.158654) (xy 416.377049 -287.16448)
			(xy 416.385756 -287.16478) (xy 416.58032 -287.16478) (xy 416.583876 -287.164526) (xy 416.588956 -287.164272)
			(xy 416.599221 -287.163081) (xy 416.617582 -287.153645) (xy 416.624516 -287.145984) (xy 416.627818 -287.14192)
			(xy 416.64763 -287.110424) (xy 416.673538 -287.069022) (xy 416.678607 -287.060129) (xy 416.681888 -287.039944)
			(xy 416.679888 -287.029906) (xy 416.677094 -287.018984) (xy 416.674808 -287.014158) (xy 416.6651 -286.992251)
			(xy 416.651402 -286.946336) (xy 416.644482 -286.898924) (xy 416.644074 -286.874966) (xy 416.644584 -286.848979)
			(xy 416.652714 -286.797644) (xy 416.668775 -286.748214) (xy 416.692371 -286.701904) (xy 416.722921 -286.659856)
			(xy 416.759672 -286.623105) (xy 416.80172 -286.592555) (xy 416.84803 -286.568959) (xy 416.89746 -286.552898)
			(xy 416.948795 -286.544768) (xy 417.000769 -286.544768) (xy 417.052104 -286.552898) (xy 417.101534 -286.568959)
			(xy 417.147844 -286.592555) (xy 417.189892 -286.623105) (xy 417.226643 -286.659856) (xy 417.257193 -286.701904)
			(xy 417.280789 -286.748214) (xy 417.29685 -286.797644) (xy 417.30498 -286.848979) (xy 417.30549 -286.874966)
			(xy 417.619192 -286.874966) (xy 417.623152 -286.825912) (xy 417.634929 -286.778128) (xy 417.65422 -286.732852)
			(xy 417.680523 -286.691256) (xy 417.713158 -286.654419) (xy 417.751279 -286.623294) (xy 417.7939 -286.598687)
			(xy 417.839916 -286.581235) (xy 417.888135 -286.571391) (xy 417.93731 -286.56941) (xy 417.986165 -286.575342)
			(xy 418.033436 -286.589034) (xy 418.077898 -286.610132) (xy 418.118401 -286.638088) (xy 418.153894 -286.67218)
			(xy 418.183459 -286.711524) (xy 418.20633 -286.755101) (xy 418.221914 -286.801782) (xy 418.229809 -286.850359)
			(xy 418.230304 -286.874966) (xy 418.569152 -286.874966) (xy 418.573112 -286.825912) (xy 418.584889 -286.778128)
			(xy 418.60418 -286.732852) (xy 418.630483 -286.691256) (xy 418.663118 -286.654419) (xy 418.701239 -286.623294)
			(xy 418.74386 -286.598687) (xy 418.789876 -286.581235) (xy 418.838095 -286.571391) (xy 418.88727 -286.56941)
			(xy 418.936125 -286.575342) (xy 418.983396 -286.589034) (xy 419.027858 -286.610132) (xy 419.068361 -286.638088)
			(xy 419.103854 -286.67218) (xy 419.133419 -286.711524) (xy 419.15629 -286.755101) (xy 419.171874 -286.801782)
			(xy 419.179769 -286.850359) (xy 419.180264 -286.874966) (xy 419.179769 -286.899573) (xy 419.171874 -286.94815)
			(xy 419.15629 -286.994831) (xy 419.133419 -287.038408) (xy 419.103854 -287.077752) (xy 419.068361 -287.111844)
			(xy 419.027858 -287.1398) (xy 418.983396 -287.160898) (xy 418.936125 -287.17459) (xy 418.88727 -287.180522)
			(xy 418.838095 -287.178541) (xy 418.789876 -287.168697) (xy 418.74386 -287.151245) (xy 418.701239 -287.126638)
			(xy 418.663118 -287.095513) (xy 418.630483 -287.058676) (xy 418.60418 -287.01708) (xy 418.584889 -286.971804)
			(xy 418.573112 -286.92402) (xy 418.569152 -286.874966) (xy 418.230304 -286.874966) (xy 418.229809 -286.899573)
			(xy 418.221914 -286.94815) (xy 418.20633 -286.994831) (xy 418.183459 -287.038408) (xy 418.153894 -287.077752)
			(xy 418.118401 -287.111844) (xy 418.077898 -287.1398) (xy 418.033436 -287.160898) (xy 417.986165 -287.17459)
			(xy 417.93731 -287.180522) (xy 417.888135 -287.178541) (xy 417.839916 -287.168697) (xy 417.7939 -287.151245)
			(xy 417.751279 -287.126638) (xy 417.713158 -287.095513) (xy 417.680523 -287.058676) (xy 417.65422 -287.01708)
			(xy 417.634929 -286.971804) (xy 417.623152 -286.92402) (xy 417.619192 -286.874966) (xy 417.30549 -286.874966)
			(xy 417.304964 -286.901422) (xy 417.296525 -286.953656) (xy 417.279875 -287.003879) (xy 417.255438 -287.050809)
			(xy 417.223837 -287.093248) (xy 417.18588 -287.130111) (xy 417.16452 -287.14573) (xy 417.155109 -287.152974)
			(xy 417.143716 -287.173777) (xy 417.142676 -287.185608) (xy 417.13912 -287.225232) (xy 417.13912 -287.22574)
			(xy 417.136326 -287.259268) (xy 417.136072 -287.263586) (xy 417.136072 -287.265364) (xy 417.136575 -287.275416)
			(xy 417.144292 -287.293981) (xy 417.151058 -287.301432) (xy 417.199572 -287.349946) (xy 421.894012 -287.349946)
			(xy 421.897972 -287.300892) (xy 421.909749 -287.253108) (xy 421.92904 -287.207832) (xy 421.955343 -287.166236)
			(xy 421.987978 -287.129399) (xy 422.026099 -287.098274) (xy 422.06872 -287.073667) (xy 422.114736 -287.056215)
			(xy 422.162955 -287.046371) (xy 422.21213 -287.04439) (xy 422.260985 -287.050322) (xy 422.308256 -287.064014)
			(xy 422.352718 -287.085112) (xy 422.393221 -287.113068) (xy 422.428714 -287.14716) (xy 422.458279 -287.186504)
			(xy 422.48115 -287.230081) (xy 422.496734 -287.276762) (xy 422.504629 -287.325339) (xy 422.505124 -287.349946)
			(xy 422.843972 -287.349946) (xy 422.847932 -287.300892) (xy 422.859709 -287.253108) (xy 422.879 -287.207832)
			(xy 422.905303 -287.166236) (xy 422.937938 -287.129399) (xy 422.976059 -287.098274) (xy 423.01868 -287.073667)
			(xy 423.064696 -287.056215) (xy 423.112915 -287.046371) (xy 423.16209 -287.04439) (xy 423.210945 -287.050322)
			(xy 423.258216 -287.064014) (xy 423.302678 -287.085112) (xy 423.343181 -287.113068) (xy 423.378674 -287.14716)
			(xy 423.408239 -287.186504) (xy 423.43111 -287.230081) (xy 423.446694 -287.276762) (xy 423.454589 -287.325339)
			(xy 423.455084 -287.349946) (xy 423.794186 -287.349946) (xy 423.798146 -287.300892) (xy 423.809923 -287.253108)
			(xy 423.829214 -287.207832) (xy 423.855517 -287.166236) (xy 423.888152 -287.129399) (xy 423.926273 -287.098274)
			(xy 423.968894 -287.073667) (xy 424.01491 -287.056215) (xy 424.063129 -287.046371) (xy 424.112304 -287.04439)
			(xy 424.161159 -287.050322) (xy 424.20843 -287.064014) (xy 424.252892 -287.085112) (xy 424.293395 -287.113068)
			(xy 424.328888 -287.14716) (xy 424.358453 -287.186504) (xy 424.381324 -287.230081) (xy 424.396908 -287.276762)
			(xy 424.404803 -287.325339) (xy 424.405298 -287.349946) (xy 424.744146 -287.349946) (xy 424.748106 -287.300892)
			(xy 424.759883 -287.253108) (xy 424.779174 -287.207832) (xy 424.805477 -287.166236) (xy 424.838112 -287.129399)
			(xy 424.876233 -287.098274) (xy 424.918854 -287.073667) (xy 424.96487 -287.056215) (xy 425.013089 -287.046371)
			(xy 425.062264 -287.04439) (xy 425.111119 -287.050322) (xy 425.15839 -287.064014) (xy 425.202852 -287.085112)
			(xy 425.243355 -287.113068) (xy 425.278848 -287.14716) (xy 425.308413 -287.186504) (xy 425.331284 -287.230081)
			(xy 425.346868 -287.276762) (xy 425.354763 -287.325339) (xy 425.355258 -287.349946) (xy 425.694106 -287.349946)
			(xy 425.698066 -287.300892) (xy 425.709843 -287.253108) (xy 425.729134 -287.207832) (xy 425.755437 -287.166236)
			(xy 425.788072 -287.129399) (xy 425.826193 -287.098274) (xy 425.868814 -287.073667) (xy 425.91483 -287.056215)
			(xy 425.963049 -287.046371) (xy 426.012224 -287.04439) (xy 426.061079 -287.050322) (xy 426.10835 -287.064014)
			(xy 426.152812 -287.085112) (xy 426.193315 -287.113068) (xy 426.228808 -287.14716) (xy 426.258373 -287.186504)
			(xy 426.281244 -287.230081) (xy 426.296828 -287.276762) (xy 426.304723 -287.325339) (xy 426.305218 -287.349946)
			(xy 426.644066 -287.349946) (xy 426.648026 -287.300892) (xy 426.659803 -287.253108) (xy 426.679094 -287.207832)
			(xy 426.705397 -287.166236) (xy 426.738032 -287.129399) (xy 426.776153 -287.098274) (xy 426.818774 -287.073667)
			(xy 426.86479 -287.056215) (xy 426.913009 -287.046371) (xy 426.962184 -287.04439) (xy 427.011039 -287.050322)
			(xy 427.05831 -287.064014) (xy 427.102772 -287.085112) (xy 427.143275 -287.113068) (xy 427.178768 -287.14716)
			(xy 427.208333 -287.186504) (xy 427.231204 -287.230081) (xy 427.246788 -287.276762) (xy 427.254683 -287.325339)
			(xy 427.255178 -287.349946) (xy 427.593772 -287.349946) (xy 427.597732 -287.300892) (xy 427.609509 -287.253108)
			(xy 427.6288 -287.207832) (xy 427.655103 -287.166236) (xy 427.687738 -287.129399) (xy 427.725859 -287.098274)
			(xy 427.76848 -287.073667) (xy 427.814496 -287.056215) (xy 427.862715 -287.046371) (xy 427.91189 -287.04439)
			(xy 427.960745 -287.050322) (xy 428.008016 -287.064014) (xy 428.052478 -287.085112) (xy 428.092981 -287.113068)
			(xy 428.128474 -287.14716) (xy 428.158039 -287.186504) (xy 428.18091 -287.230081) (xy 428.196494 -287.276762)
			(xy 428.204389 -287.325339) (xy 428.204884 -287.349946) (xy 428.543986 -287.349946) (xy 428.547946 -287.300892)
			(xy 428.559723 -287.253108) (xy 428.579014 -287.207832) (xy 428.605317 -287.166236) (xy 428.637952 -287.129399)
			(xy 428.676073 -287.098274) (xy 428.718694 -287.073667) (xy 428.76471 -287.056215) (xy 428.812929 -287.046371)
			(xy 428.862104 -287.04439) (xy 428.910959 -287.050322) (xy 428.95823 -287.064014) (xy 429.002692 -287.085112)
			(xy 429.043195 -287.113068) (xy 429.078688 -287.14716) (xy 429.108253 -287.186504) (xy 429.131124 -287.230081)
			(xy 429.146708 -287.276762) (xy 429.154603 -287.325339) (xy 429.155098 -287.349946) (xy 429.154603 -287.374553)
			(xy 429.154424 -287.375654) (xy 429.473356 -287.375654) (xy 429.473356 -287.324238) (xy 429.481399 -287.273456)
			(xy 429.497287 -287.224557) (xy 429.52063 -287.178745) (xy 429.550851 -287.137149) (xy 429.587207 -287.100793)
			(xy 429.628803 -287.070572) (xy 429.674615 -287.047229) (xy 429.723514 -287.031341) (xy 429.774296 -287.023298)
			(xy 429.825712 -287.023298) (xy 429.876494 -287.031341) (xy 429.925393 -287.047229) (xy 429.971205 -287.070572)
			(xy 430.012801 -287.100793) (xy 430.049157 -287.137149) (xy 430.079378 -287.178745) (xy 430.102721 -287.224557)
			(xy 430.118609 -287.273456) (xy 430.126652 -287.324238) (xy 430.127156 -287.349946) (xy 430.126652 -287.375654)
			(xy 430.423316 -287.375654) (xy 430.423316 -287.324238) (xy 430.431359 -287.273456) (xy 430.447247 -287.224557)
			(xy 430.47059 -287.178745) (xy 430.500811 -287.137149) (xy 430.537167 -287.100793) (xy 430.578763 -287.070572)
			(xy 430.624575 -287.047229) (xy 430.673474 -287.031341) (xy 430.724256 -287.023298) (xy 430.775672 -287.023298)
			(xy 430.826454 -287.031341) (xy 430.875353 -287.047229) (xy 430.921165 -287.070572) (xy 430.962761 -287.100793)
			(xy 430.999117 -287.137149) (xy 431.029338 -287.178745) (xy 431.052681 -287.224557) (xy 431.068569 -287.273456)
			(xy 431.076612 -287.324238) (xy 431.077116 -287.349946) (xy 431.077111 -287.3502) (xy 431.394374 -287.3502)
			(xy 431.398334 -287.301146) (xy 431.410111 -287.253362) (xy 431.429402 -287.208086) (xy 431.455705 -287.16649)
			(xy 431.48834 -287.129653) (xy 431.526461 -287.098528) (xy 431.569082 -287.073921) (xy 431.615098 -287.056469)
			(xy 431.663317 -287.046625) (xy 431.712492 -287.044644) (xy 431.761347 -287.050576) (xy 431.808618 -287.064268)
			(xy 431.85308 -287.085366) (xy 431.893583 -287.113322) (xy 431.929076 -287.147414) (xy 431.958641 -287.186758)
			(xy 431.981512 -287.230335) (xy 431.997096 -287.277016) (xy 432.004991 -287.325593) (xy 432.005486 -287.3502)
			(xy 432.004991 -287.374807) (xy 431.997096 -287.423384) (xy 431.981512 -287.470065) (xy 431.958641 -287.513642)
			(xy 431.929076 -287.552986) (xy 431.893583 -287.587078) (xy 431.85308 -287.615034) (xy 431.808618 -287.636132)
			(xy 431.761347 -287.649824) (xy 431.712492 -287.655756) (xy 431.663317 -287.653775) (xy 431.615098 -287.643931)
			(xy 431.569082 -287.626479) (xy 431.526461 -287.601872) (xy 431.48834 -287.570747) (xy 431.455705 -287.53391)
			(xy 431.429402 -287.492314) (xy 431.410111 -287.447038) (xy 431.398334 -287.399254) (xy 431.394374 -287.3502)
			(xy 431.077111 -287.3502) (xy 431.076612 -287.375654) (xy 431.068569 -287.426436) (xy 431.052681 -287.475335)
			(xy 431.029338 -287.521147) (xy 430.999117 -287.562743) (xy 430.962761 -287.599099) (xy 430.921165 -287.62932)
			(xy 430.875353 -287.652663) (xy 430.826454 -287.668551) (xy 430.775672 -287.676594) (xy 430.724256 -287.676594)
			(xy 430.673474 -287.668551) (xy 430.624575 -287.652663) (xy 430.578763 -287.62932) (xy 430.537167 -287.599099)
			(xy 430.500811 -287.562743) (xy 430.47059 -287.521147) (xy 430.447247 -287.475335) (xy 430.431359 -287.426436)
			(xy 430.423316 -287.375654) (xy 430.126652 -287.375654) (xy 430.118609 -287.426436) (xy 430.102721 -287.475335)
			(xy 430.079378 -287.521147) (xy 430.049157 -287.562743) (xy 430.012801 -287.599099) (xy 429.971205 -287.62932)
			(xy 429.925393 -287.652663) (xy 429.876494 -287.668551) (xy 429.825712 -287.676594) (xy 429.774296 -287.676594)
			(xy 429.723514 -287.668551) (xy 429.674615 -287.652663) (xy 429.628803 -287.62932) (xy 429.587207 -287.599099)
			(xy 429.550851 -287.562743) (xy 429.52063 -287.521147) (xy 429.497287 -287.475335) (xy 429.481399 -287.426436)
			(xy 429.473356 -287.375654) (xy 429.154424 -287.375654) (xy 429.146708 -287.42313) (xy 429.131124 -287.469811)
			(xy 429.108253 -287.513388) (xy 429.078688 -287.552732) (xy 429.043195 -287.586824) (xy 429.002692 -287.61478)
			(xy 428.95823 -287.635878) (xy 428.910959 -287.64957) (xy 428.862104 -287.655502) (xy 428.812929 -287.653521)
			(xy 428.76471 -287.643677) (xy 428.718694 -287.626225) (xy 428.676073 -287.601618) (xy 428.637952 -287.570493)
			(xy 428.605317 -287.533656) (xy 428.579014 -287.49206) (xy 428.559723 -287.446784) (xy 428.547946 -287.399)
			(xy 428.543986 -287.349946) (xy 428.204884 -287.349946) (xy 428.204389 -287.374553) (xy 428.196494 -287.42313)
			(xy 428.18091 -287.469811) (xy 428.158039 -287.513388) (xy 428.128474 -287.552732) (xy 428.092981 -287.586824)
			(xy 428.052478 -287.61478) (xy 428.008016 -287.635878) (xy 427.960745 -287.64957) (xy 427.91189 -287.655502)
			(xy 427.862715 -287.653521) (xy 427.814496 -287.643677) (xy 427.76848 -287.626225) (xy 427.725859 -287.601618)
			(xy 427.687738 -287.570493) (xy 427.655103 -287.533656) (xy 427.6288 -287.49206) (xy 427.609509 -287.446784)
			(xy 427.597732 -287.399) (xy 427.593772 -287.349946) (xy 427.255178 -287.349946) (xy 427.254683 -287.374553)
			(xy 427.246788 -287.42313) (xy 427.231204 -287.469811) (xy 427.208333 -287.513388) (xy 427.178768 -287.552732)
			(xy 427.143275 -287.586824) (xy 427.102772 -287.61478) (xy 427.05831 -287.635878) (xy 427.011039 -287.64957)
			(xy 426.962184 -287.655502) (xy 426.913009 -287.653521) (xy 426.86479 -287.643677) (xy 426.818774 -287.626225)
			(xy 426.776153 -287.601618) (xy 426.738032 -287.570493) (xy 426.705397 -287.533656) (xy 426.679094 -287.49206)
			(xy 426.659803 -287.446784) (xy 426.648026 -287.399) (xy 426.644066 -287.349946) (xy 426.305218 -287.349946)
			(xy 426.304723 -287.374553) (xy 426.296828 -287.42313) (xy 426.281244 -287.469811) (xy 426.258373 -287.513388)
			(xy 426.228808 -287.552732) (xy 426.193315 -287.586824) (xy 426.152812 -287.61478) (xy 426.10835 -287.635878)
			(xy 426.061079 -287.64957) (xy 426.012224 -287.655502) (xy 425.963049 -287.653521) (xy 425.91483 -287.643677)
			(xy 425.868814 -287.626225) (xy 425.826193 -287.601618) (xy 425.788072 -287.570493) (xy 425.755437 -287.533656)
			(xy 425.729134 -287.49206) (xy 425.709843 -287.446784) (xy 425.698066 -287.399) (xy 425.694106 -287.349946)
			(xy 425.355258 -287.349946) (xy 425.354763 -287.374553) (xy 425.346868 -287.42313) (xy 425.331284 -287.469811)
			(xy 425.308413 -287.513388) (xy 425.278848 -287.552732) (xy 425.243355 -287.586824) (xy 425.202852 -287.61478)
			(xy 425.15839 -287.635878) (xy 425.111119 -287.64957) (xy 425.062264 -287.655502) (xy 425.013089 -287.653521)
			(xy 424.96487 -287.643677) (xy 424.918854 -287.626225) (xy 424.876233 -287.601618) (xy 424.838112 -287.570493)
			(xy 424.805477 -287.533656) (xy 424.779174 -287.49206) (xy 424.759883 -287.446784) (xy 424.748106 -287.399)
			(xy 424.744146 -287.349946) (xy 424.405298 -287.349946) (xy 424.404803 -287.374553) (xy 424.396908 -287.42313)
			(xy 424.381324 -287.469811) (xy 424.358453 -287.513388) (xy 424.328888 -287.552732) (xy 424.293395 -287.586824)
			(xy 424.252892 -287.61478) (xy 424.20843 -287.635878) (xy 424.161159 -287.64957) (xy 424.112304 -287.655502)
			(xy 424.063129 -287.653521) (xy 424.01491 -287.643677) (xy 423.968894 -287.626225) (xy 423.926273 -287.601618)
			(xy 423.888152 -287.570493) (xy 423.855517 -287.533656) (xy 423.829214 -287.49206) (xy 423.809923 -287.446784)
			(xy 423.798146 -287.399) (xy 423.794186 -287.349946) (xy 423.455084 -287.349946) (xy 423.454589 -287.374553)
			(xy 423.446694 -287.42313) (xy 423.43111 -287.469811) (xy 423.408239 -287.513388) (xy 423.378674 -287.552732)
			(xy 423.343181 -287.586824) (xy 423.302678 -287.61478) (xy 423.258216 -287.635878) (xy 423.210945 -287.64957)
			(xy 423.16209 -287.655502) (xy 423.112915 -287.653521) (xy 423.064696 -287.643677) (xy 423.01868 -287.626225)
			(xy 422.976059 -287.601618) (xy 422.937938 -287.570493) (xy 422.905303 -287.533656) (xy 422.879 -287.49206)
			(xy 422.859709 -287.446784) (xy 422.847932 -287.399) (xy 422.843972 -287.349946) (xy 422.505124 -287.349946)
			(xy 422.504629 -287.374553) (xy 422.496734 -287.42313) (xy 422.48115 -287.469811) (xy 422.458279 -287.513388)
			(xy 422.428714 -287.552732) (xy 422.393221 -287.586824) (xy 422.352718 -287.61478) (xy 422.308256 -287.635878)
			(xy 422.260985 -287.64957) (xy 422.21213 -287.655502) (xy 422.162955 -287.653521) (xy 422.114736 -287.643677)
			(xy 422.06872 -287.626225) (xy 422.026099 -287.601618) (xy 421.987978 -287.570493) (xy 421.955343 -287.533656)
			(xy 421.92904 -287.49206) (xy 421.909749 -287.446784) (xy 421.897972 -287.399) (xy 421.894012 -287.349946)
			(xy 417.199572 -287.349946) (xy 417.674552 -287.824926) (xy 418.569152 -287.824926) (xy 418.573112 -287.775872)
			(xy 418.584889 -287.728088) (xy 418.60418 -287.682812) (xy 418.630483 -287.641216) (xy 418.663118 -287.604379)
			(xy 418.701239 -287.573254) (xy 418.74386 -287.548647) (xy 418.789876 -287.531195) (xy 418.838095 -287.521351)
			(xy 418.88727 -287.51937) (xy 418.936125 -287.525302) (xy 418.983396 -287.538994) (xy 419.027858 -287.560092)
			(xy 419.068361 -287.588048) (xy 419.103854 -287.62214) (xy 419.133419 -287.661484) (xy 419.15629 -287.705061)
			(xy 419.171874 -287.751742) (xy 419.179769 -287.800319) (xy 419.180264 -287.824926) (xy 420.469072 -287.824926)
			(xy 420.473032 -287.775872) (xy 420.484809 -287.728088) (xy 420.5041 -287.682812) (xy 420.530403 -287.641216)
			(xy 420.563038 -287.604379) (xy 420.601159 -287.573254) (xy 420.64378 -287.548647) (xy 420.689796 -287.531195)
			(xy 420.738015 -287.521351) (xy 420.78719 -287.51937) (xy 420.836045 -287.525302) (xy 420.883316 -287.538994)
			(xy 420.927778 -287.560092) (xy 420.968281 -287.588048) (xy 421.003774 -287.62214) (xy 421.033339 -287.661484)
			(xy 421.05621 -287.705061) (xy 421.071794 -287.751742) (xy 421.079689 -287.800319) (xy 421.080184 -287.824926)
			(xy 421.079689 -287.849533) (xy 421.071794 -287.89811) (xy 421.05621 -287.944791) (xy 421.033339 -287.988368)
			(xy 421.003774 -288.027712) (xy 420.968281 -288.061804) (xy 420.927778 -288.08976) (xy 420.883316 -288.110858)
			(xy 420.836045 -288.12455) (xy 420.78719 -288.130482) (xy 420.738015 -288.128501) (xy 420.689796 -288.118657)
			(xy 420.64378 -288.101205) (xy 420.601159 -288.076598) (xy 420.563038 -288.045473) (xy 420.530403 -288.008636)
			(xy 420.5041 -287.96704) (xy 420.484809 -287.921764) (xy 420.473032 -287.87398) (xy 420.469072 -287.824926)
			(xy 419.180264 -287.824926) (xy 419.179769 -287.849533) (xy 419.171874 -287.89811) (xy 419.15629 -287.944791)
			(xy 419.133419 -287.988368) (xy 419.103854 -288.027712) (xy 419.068361 -288.061804) (xy 419.027858 -288.08976)
			(xy 418.983396 -288.110858) (xy 418.936125 -288.12455) (xy 418.88727 -288.130482) (xy 418.838095 -288.128501)
			(xy 418.789876 -288.118657) (xy 418.74386 -288.101205) (xy 418.701239 -288.076598) (xy 418.663118 -288.045473)
			(xy 418.630483 -288.008636) (xy 418.60418 -287.96704) (xy 418.584889 -287.921764) (xy 418.573112 -287.87398)
			(xy 418.569152 -287.824926) (xy 417.674552 -287.824926) (xy 417.710112 -287.860486) (xy 417.716955 -287.867885)
			(xy 417.724671 -287.886484) (xy 417.725098 -287.896554) (xy 417.725098 -288.299906) (xy 421.894012 -288.299906)
			(xy 421.897972 -288.250852) (xy 421.909749 -288.203068) (xy 421.92904 -288.157792) (xy 421.955343 -288.116196)
			(xy 421.987978 -288.079359) (xy 422.026099 -288.048234) (xy 422.06872 -288.023627) (xy 422.114736 -288.006175)
			(xy 422.162955 -287.996331) (xy 422.21213 -287.99435) (xy 422.260985 -288.000282) (xy 422.308256 -288.013974)
			(xy 422.352718 -288.035072) (xy 422.393221 -288.063028) (xy 422.428714 -288.09712) (xy 422.458279 -288.136464)
			(xy 422.48115 -288.180041) (xy 422.496734 -288.226722) (xy 422.504629 -288.275299) (xy 422.505124 -288.299906)
			(xy 422.844226 -288.299906) (xy 422.848186 -288.250852) (xy 422.859963 -288.203068) (xy 422.879254 -288.157792)
			(xy 422.905557 -288.116196) (xy 422.938192 -288.079359) (xy 422.976313 -288.048234) (xy 423.018934 -288.023627)
			(xy 423.06495 -288.006175) (xy 423.113169 -287.996331) (xy 423.162344 -287.99435) (xy 423.211199 -288.000282)
			(xy 423.25847 -288.013974) (xy 423.302932 -288.035072) (xy 423.343435 -288.063028) (xy 423.378928 -288.09712)
			(xy 423.408493 -288.136464) (xy 423.431364 -288.180041) (xy 423.446948 -288.226722) (xy 423.454843 -288.275299)
			(xy 423.455338 -288.299906) (xy 423.455172 -288.308173) (xy 423.794291 -288.308173) (xy 423.79698 -288.258606)
			(xy 423.807652 -288.210127) (xy 423.826027 -288.164013) (xy 423.85162 -288.121479) (xy 423.883758 -288.083646)
			(xy 423.921592 -288.051511) (xy 423.964127 -288.02592) (xy 424.010242 -288.007548) (xy 424.058722 -287.996878)
			(xy 424.108289 -287.994191) (xy 424.157638 -287.99956) (xy 424.205468 -288.012841) (xy 424.250519 -288.033685)
			(xy 424.291605 -288.061543) (xy 424.327643 -288.095681) (xy 424.357683 -288.1352) (xy 424.380934 -288.179058)
			(xy 424.396783 -288.2261) (xy 424.404813 -288.275086) (xy 424.405298 -288.299906) (xy 424.405106 -288.314025)
			(xy 424.402438 -288.342138) (xy 424.399964 -288.35604) (xy 424.397678 -288.368486) (xy 424.405044 -288.392362)
			(xy 424.482514 -288.469832) (xy 424.50639 -288.477198) (xy 424.518836 -288.474912) (xy 424.532739 -288.472447)
			(xy 424.560851 -288.469777) (xy 424.57497 -288.469578) (xy 424.589089 -288.469762) (xy 424.617202 -288.472435)
			(xy 424.631104 -288.474912) (xy 424.64355 -288.477198) (xy 424.667426 -288.469832) (xy 424.744896 -288.392362)
			(xy 424.752262 -288.368486) (xy 424.749976 -288.35604) (xy 424.747508 -288.342137) (xy 424.74484 -288.314025)
			(xy 424.744642 -288.299906) (xy 424.745071 -288.275085) (xy 424.753101 -288.226098) (xy 424.76895 -288.179055)
			(xy 424.792201 -288.135196) (xy 424.822241 -288.095675) (xy 424.858279 -288.061536) (xy 424.899365 -288.033676)
			(xy 424.944417 -288.012829) (xy 424.992248 -287.999546) (xy 425.041598 -287.994176) (xy 425.091166 -287.99686)
			(xy 425.139648 -288.007528) (xy 425.185765 -288.025898) (xy 425.228302 -288.051487) (xy 425.26614 -288.083621)
			(xy 425.29828 -288.121452) (xy 425.323877 -288.163985) (xy 425.342256 -288.210099) (xy 425.352933 -288.258578)
			(xy 425.355178 -288.299906) (xy 425.694106 -288.299906) (xy 425.698066 -288.250852) (xy 425.709843 -288.203068)
			(xy 425.729134 -288.157792) (xy 425.755437 -288.116196) (xy 425.788072 -288.079359) (xy 425.826193 -288.048234)
			(xy 425.868814 -288.023627) (xy 425.91483 -288.006175) (xy 425.963049 -287.996331) (xy 426.012224 -287.99435)
			(xy 426.061079 -288.000282) (xy 426.10835 -288.013974) (xy 426.152812 -288.035072) (xy 426.193315 -288.063028)
			(xy 426.228808 -288.09712) (xy 426.258373 -288.136464) (xy 426.281244 -288.180041) (xy 426.296828 -288.226722)
			(xy 426.304723 -288.275299) (xy 426.305218 -288.299906) (xy 426.305052 -288.308159) (xy 426.644211 -288.308159)
			(xy 426.646901 -288.258596) (xy 426.657575 -288.210121) (xy 426.67595 -288.164011) (xy 426.701543 -288.121482)
			(xy 426.733679 -288.083653) (xy 426.771511 -288.051522) (xy 426.814044 -288.025934) (xy 426.860155 -288.007564)
			(xy 426.908631 -287.996896) (xy 426.958195 -287.994212) (xy 427.00754 -287.99958) (xy 427.055366 -288.012861)
			(xy 427.100413 -288.033705) (xy 427.141496 -288.061561) (xy 427.17753 -288.095697) (xy 427.207567 -288.135213)
			(xy 427.230816 -288.179068) (xy 427.246664 -288.226106) (xy 427.254693 -288.275088) (xy 427.255178 -288.299906)
			(xy 427.254984 -288.314025) (xy 427.252318 -288.342138) (xy 427.249844 -288.35604) (xy 427.247558 -288.368486)
			(xy 427.254924 -288.392362) (xy 427.332394 -288.469832) (xy 427.35627 -288.477198) (xy 427.368716 -288.474912)
			(xy 427.38262 -288.47245) (xy 427.410731 -288.469778) (xy 427.42485 -288.469578) (xy 427.425104 -288.469578)
			(xy 427.434911 -288.469662) (xy 427.454485 -288.470931) (xy 427.46422 -288.472118) (xy 427.476158 -288.473642)
			(xy 427.498764 -288.465768) (xy 427.563788 -288.398204) (xy 427.567853 -288.393733) (xy 427.574023 -288.383347)
			(xy 427.57598 -288.37763) (xy 427.579282 -288.366454) (xy 427.577504 -288.354516) (xy 427.577504 -288.354008)
			(xy 427.575389 -288.340646) (xy 427.573103 -288.313687) (xy 427.572932 -288.30016) (xy 427.572932 -288.299906)
			(xy 427.573436 -288.274218) (xy 427.581473 -288.223475) (xy 427.597349 -288.174614) (xy 427.620673 -288.128838)
			(xy 427.65087 -288.087274) (xy 427.687198 -288.050946) (xy 427.728762 -288.020749) (xy 427.774538 -287.997425)
			(xy 427.823399 -287.981549) (xy 427.874142 -287.973512) (xy 427.925518 -287.973512) (xy 427.976261 -287.981549)
			(xy 428.025122 -287.997425) (xy 428.070898 -288.020749) (xy 428.112462 -288.050946) (xy 428.14879 -288.087274)
			(xy 428.178987 -288.128838) (xy 428.202311 -288.174614) (xy 428.218187 -288.223475) (xy 428.226224 -288.274218)
			(xy 428.226728 -288.299906) (xy 428.226728 -288.30016) (xy 428.226568 -288.313688) (xy 428.224281 -288.340647)
			(xy 428.222156 -288.354008) (xy 428.222156 -288.354516) (xy 428.220378 -288.366454) (xy 428.22368 -288.37763)
			(xy 428.225572 -288.383376) (xy 428.231747 -288.393777) (xy 428.235872 -288.398204) (xy 428.300896 -288.465768)
			(xy 428.323502 -288.473642) (xy 428.33544 -288.472118) (xy 428.345239 -288.470931) (xy 428.364939 -288.469659)
			(xy 428.37481 -288.469578) (xy 428.384681 -288.46965) (xy 428.404382 -288.470922) (xy 428.41418 -288.472118)
			(xy 428.426118 -288.473642) (xy 428.448724 -288.465768) (xy 428.513748 -288.398204) (xy 428.517821 -288.393739)
			(xy 428.523985 -288.383348) (xy 428.52594 -288.37763) (xy 428.529242 -288.366454) (xy 428.527464 -288.354516)
			(xy 428.527464 -288.354008) (xy 428.525348 -288.340646) (xy 428.523063 -288.313687) (xy 428.522892 -288.30016)
			(xy 428.522892 -288.299906) (xy 428.523396 -288.274218) (xy 428.531433 -288.223475) (xy 428.547309 -288.174614)
			(xy 428.570633 -288.128838) (xy 428.60083 -288.087274) (xy 428.637158 -288.050946) (xy 428.678722 -288.020749)
			(xy 428.724498 -287.997425) (xy 428.773359 -287.981549) (xy 428.824102 -287.973512) (xy 428.875478 -287.973512)
			(xy 428.926221 -287.981549) (xy 428.975082 -287.997425) (xy 429.020858 -288.020749) (xy 429.062422 -288.050946)
			(xy 429.09875 -288.087274) (xy 429.128947 -288.128838) (xy 429.152271 -288.174614) (xy 429.168147 -288.223475)
			(xy 429.176184 -288.274218) (xy 429.176688 -288.299906) (xy 429.176688 -288.30016) (xy 429.176531 -288.313814)
			(xy 429.174245 -288.341028) (xy 429.172116 -288.354516) (xy 429.170084 -288.366454) (xy 429.177196 -288.389314)
			(xy 429.242474 -288.456878) (xy 429.251129 -288.465046) (xy 429.273531 -288.472988) (xy 429.2854 -288.472118)
			(xy 429.285654 -288.472118) (xy 429.29539 -288.470937) (xy 429.314963 -288.469666) (xy 429.32477 -288.469578)
			(xy 429.325024 -288.469578) (xy 429.339143 -288.469768) (xy 429.367256 -288.472437) (xy 429.381158 -288.474912)
			(xy 429.393604 -288.477198) (xy 429.41748 -288.469832) (xy 429.49495 -288.392362) (xy 429.502316 -288.368486)
			(xy 429.50003 -288.35604) (xy 429.497562 -288.342137) (xy 429.494894 -288.314025) (xy 429.494696 -288.299906)
			(xy 429.495218 -288.274651) (xy 429.503531 -288.224829) (xy 429.519932 -288.177055) (xy 429.543973 -288.132632)
			(xy 429.574997 -288.092772) (xy 429.612159 -288.058562) (xy 429.654445 -288.030936) (xy 429.700701 -288.010646)
			(xy 429.749666 -287.998246) (xy 429.800004 -287.994075) (xy 429.850342 -287.998246) (xy 429.899307 -288.010646)
			(xy 429.945563 -288.030936) (xy 429.987849 -288.058562) (xy 430.025011 -288.092772) (xy 430.056035 -288.132632)
			(xy 430.080076 -288.177055) (xy 430.096477 -288.224829) (xy 430.10479 -288.274651) (xy 430.105312 -288.299906)
			(xy 430.10512 -288.314025) (xy 430.102452 -288.342138) (xy 430.099978 -288.35604) (xy 430.097692 -288.368486)
			(xy 430.105058 -288.392362) (xy 430.182528 -288.469832) (xy 430.206404 -288.477198) (xy 430.21885 -288.474912)
			(xy 430.232753 -288.472445) (xy 430.260865 -288.469776) (xy 430.274984 -288.469578) (xy 430.289104 -288.46976)
			(xy 430.317216 -288.472434) (xy 430.331118 -288.474912) (xy 430.343564 -288.477198) (xy 430.36744 -288.469832)
			(xy 430.44491 -288.392362) (xy 430.452276 -288.368486) (xy 430.44999 -288.35604) (xy 430.447521 -288.342137)
			(xy 430.444854 -288.314025) (xy 430.444656 -288.299906) (xy 430.445178 -288.274651) (xy 430.453491 -288.224829)
			(xy 430.469892 -288.177055) (xy 430.493933 -288.132632) (xy 430.524957 -288.092772) (xy 430.562119 -288.058562)
			(xy 430.604405 -288.030936) (xy 430.650661 -288.010646) (xy 430.699626 -287.998246) (xy 430.749964 -287.994075)
			(xy 430.800302 -287.998246) (xy 430.849267 -288.010646) (xy 430.895523 -288.030936) (xy 430.937809 -288.058562)
			(xy 430.974971 -288.092772) (xy 431.005995 -288.132632) (xy 431.030036 -288.177055) (xy 431.046437 -288.224829)
			(xy 431.050379 -288.248455) (xy 435.895921 -288.248455) (xy 435.895921 -288.193945) (xy 435.903679 -288.139988)
			(xy 435.919036 -288.087685) (xy 435.941681 -288.038101) (xy 435.971152 -287.992243) (xy 436.00685 -287.951047)
			(xy 436.048046 -287.91535) (xy 436.093904 -287.885879) (xy 436.143489 -287.863235) (xy 436.195792 -287.847878)
			(xy 436.249749 -287.840121) (xy 436.277004 -287.839658) (xy 436.30312 -287.84011) (xy 436.354864 -287.847248)
			(xy 436.40515 -287.861376) (xy 436.453039 -287.88223) (xy 436.497637 -287.909421) (xy 436.53811 -287.94244)
			(xy 436.573701 -287.98067) (xy 436.603746 -288.023397) (xy 436.616094 -288.046414) (xy 436.622861 -288.058628)
			(xy 436.641864 -288.079074) (xy 436.66569 -288.093616) (xy 436.692561 -288.101168) (xy 436.720475 -288.101168)
			(xy 436.747346 -288.093616) (xy 436.771172 -288.079074) (xy 436.790175 -288.058628) (xy 436.796942 -288.046414)
			(xy 436.809302 -288.023401) (xy 436.839331 -287.980658) (xy 436.874913 -287.942414) (xy 436.915382 -287.909384)
			(xy 436.95998 -287.882187) (xy 437.007873 -287.861333) (xy 437.058165 -287.84721) (xy 437.109914 -287.840085)
			(xy 437.136032 -287.839658) (xy 437.163279 -287.840214) (xy 437.217219 -287.847974) (xy 437.269505 -287.86333)
			(xy 437.319074 -287.885971) (xy 437.364916 -287.915436) (xy 437.406099 -287.951124) (xy 437.441783 -287.99231)
			(xy 437.471244 -288.038155) (xy 437.493881 -288.087725) (xy 437.509233 -288.140013) (xy 437.516988 -288.193953)
			(xy 437.516988 -288.224712) (xy 437.77102 -288.224712) (xy 437.771025 -288.170216) (xy 437.778785 -288.116276)
			(xy 437.794143 -288.063989) (xy 437.816786 -288.01442) (xy 437.846253 -287.968578) (xy 437.881944 -287.927396)
			(xy 437.923132 -287.891712) (xy 437.96898 -287.862254) (xy 438.018553 -287.83962) (xy 438.070842 -287.824271)
			(xy 438.124784 -287.81652) (xy 438.152032 -287.816036) (xy 438.15254 -287.816036) (xy 438.172098 -287.816544)
			(xy 438.184036 -287.817052) (xy 438.20588 -287.807654) (xy 438.273444 -287.72739) (xy 438.279032 -287.704276)
			(xy 438.276492 -287.692592) (xy 438.272114 -287.671978) (xy 438.267403 -287.630098) (xy 438.267094 -287.609026)
			(xy 438.26758 -287.581775) (xy 438.275336 -287.527827) (xy 438.290691 -287.475532) (xy 438.313333 -287.425955)
			(xy 438.342799 -287.380105) (xy 438.37849 -287.338914) (xy 438.419681 -287.303223) (xy 438.465531 -287.273757)
			(xy 438.515108 -287.251115) (xy 438.567403 -287.23576) (xy 438.621351 -287.228004) (xy 438.675853 -287.228004)
			(xy 438.729801 -287.23576) (xy 438.782096 -287.251115) (xy 438.831673 -287.273757) (xy 438.877523 -287.303223)
			(xy 438.918714 -287.338914) (xy 438.954405 -287.380105) (xy 438.983871 -287.425955) (xy 439.006513 -287.475532)
			(xy 439.021868 -287.527827) (xy 439.029624 -287.581775) (xy 439.03011 -287.609026) (xy 439.03011 -287.609534)
			(xy 439.029653 -287.635851) (xy 439.02239 -287.687982) (xy 439.015632 -287.71342) (xy 439.012076 -287.725866)
			(xy 439.01741 -287.75025) (xy 439.080148 -287.824418) (xy 439.084377 -287.829107) (xy 439.094652 -287.836437)
			(xy 439.100468 -287.838896) (xy 439.100468 -287.83915) (xy 439.106565 -287.841341) (xy 439.119425 -287.842882)
			(xy 439.125868 -287.842198) (xy 439.13298 -287.841182) (xy 439.144156 -287.840166) (xy 439.163206 -287.82899)
			(xy 439.21426 -287.756854) (xy 439.220134 -287.747489) (xy 439.224103 -287.725771) (xy 439.22188 -287.714944)
			(xy 439.22188 -287.71469) (xy 439.216316 -287.691465) (xy 439.210329 -287.644082) (xy 439.209942 -287.620202)
			(xy 439.209942 -287.619694) (xy 439.210428 -287.592443) (xy 439.218184 -287.538495) (xy 439.233539 -287.4862)
			(xy 439.256181 -287.436623) (xy 439.285647 -287.390773) (xy 439.321338 -287.349582) (xy 439.362529 -287.313891)
			(xy 439.408379 -287.284425) (xy 439.457956 -287.261783) (xy 439.510251 -287.246428) (xy 439.564199 -287.238672)
			(xy 439.618701 -287.238672) (xy 439.672649 -287.246428) (xy 439.705439 -287.256056) (xy 448.436643 -287.256056)
			(xy 448.436643 -287.201544) (xy 448.444401 -287.147587) (xy 448.45976 -287.095284) (xy 448.482407 -287.045699)
			(xy 448.51188 -286.999843) (xy 448.54758 -286.958647) (xy 448.588779 -286.922953) (xy 448.63464 -286.893485)
			(xy 448.684227 -286.870844) (xy 448.736532 -286.855492) (xy 448.79049 -286.84774) (xy 448.817746 -286.84728)
			(xy 448.846486 -286.847781) (xy 448.903314 -286.85641) (xy 448.958205 -286.873466) (xy 449.009916 -286.898562)
			(xy 449.057278 -286.931131) (xy 449.078604 -286.950404) (xy 449.078858 -286.950658) (xy 449.086167 -286.95676)
			(xy 449.103892 -286.963665) (xy 449.113402 -286.96412) (xy 449.18249 -286.96412) (xy 449.192021 -286.963779)
			(xy 449.209776 -286.956847) (xy 449.217034 -286.950658) (xy 449.217288 -286.950404) (xy 449.238615 -286.931134)
			(xy 449.285978 -286.898569) (xy 449.337689 -286.873478) (xy 449.39258 -286.856428) (xy 449.449407 -286.847806)
			(xy 449.506885 -286.847806) (xy 449.563712 -286.856428) (xy 449.618603 -286.873478) (xy 449.670314 -286.898569)
			(xy 449.717677 -286.931134) (xy 449.739004 -286.950404) (xy 449.739258 -286.950658) (xy 449.746567 -286.95676)
			(xy 449.764292 -286.963665) (xy 449.773802 -286.96412) (xy 449.84289 -286.96412) (xy 449.852421 -286.963779)
			(xy 449.870176 -286.956847) (xy 449.877434 -286.950658) (xy 449.877688 -286.950404) (xy 449.899006 -286.931123)
			(xy 449.946369 -286.898556) (xy 449.998083 -286.873464) (xy 450.052976 -286.856416) (xy 450.109806 -286.847798)
			(xy 450.138546 -286.84728) (xy 450.168668 -286.847876) (xy 450.228164 -286.85735) (xy 450.285432 -286.876054)
			(xy 450.33905 -286.903525) (xy 450.387685 -286.939079) (xy 450.40931 -286.960056) (xy 450.416422 -286.967168)
			(xy 450.435218 -286.975042) (xy 450.527674 -286.975042) (xy 450.54647 -286.967168) (xy 450.553582 -286.960056)
			(xy 450.575201 -286.939069) (xy 450.62383 -286.903499) (xy 450.677448 -286.876019) (xy 450.73472 -286.857313)
			(xy 450.794221 -286.847846) (xy 450.824346 -286.84728) (xy 450.851594 -286.847793) (xy 450.905535 -286.855555)
			(xy 450.957823 -286.870914) (xy 451.007393 -286.893557) (xy 451.053236 -286.923023) (xy 451.094419 -286.958714)
			(xy 451.130104 -286.999901) (xy 451.159565 -287.045748) (xy 451.182203 -287.09532) (xy 451.197555 -287.14761)
			(xy 451.20531 -287.201552) (xy 451.20531 -287.256048) (xy 451.205309 -287.256055) (xy 453.090443 -287.256055)
			(xy 453.090443 -287.201545) (xy 453.098201 -287.147589) (xy 453.113559 -287.095287) (xy 453.136205 -287.045703)
			(xy 453.165677 -286.999847) (xy 453.201376 -286.958652) (xy 453.242574 -286.922957) (xy 453.288433 -286.893489)
			(xy 453.338019 -286.870847) (xy 453.390322 -286.855494) (xy 453.444279 -286.847741) (xy 453.471534 -286.84728)
			(xy 453.500273 -286.847788) (xy 453.557101 -286.856416) (xy 453.611992 -286.873469) (xy 453.663703 -286.898564)
			(xy 453.711065 -286.931132) (xy 453.732392 -286.950404) (xy 453.732646 -286.950658) (xy 453.739958 -286.956755)
			(xy 453.757681 -286.963663) (xy 453.76719 -286.96412) (xy 453.836278 -286.96412) (xy 453.845809 -286.963773)
			(xy 453.863564 -286.956845) (xy 453.870822 -286.950658) (xy 453.871076 -286.950404) (xy 453.892403 -286.931134)
			(xy 453.939766 -286.898569) (xy 453.991477 -286.873478) (xy 454.046368 -286.856428) (xy 454.103195 -286.847806)
			(xy 454.160673 -286.847806) (xy 454.2175 -286.856428) (xy 454.272391 -286.873478) (xy 454.324102 -286.898569)
			(xy 454.371465 -286.931134) (xy 454.392792 -286.950404) (xy 454.393046 -286.950658) (xy 454.400358 -286.956755)
			(xy 454.418081 -286.963663) (xy 454.42759 -286.96412) (xy 454.496678 -286.96412) (xy 454.506209 -286.963773)
			(xy 454.523964 -286.956845) (xy 454.531222 -286.950658) (xy 454.531476 -286.950404) (xy 454.552799 -286.931128)
			(xy 454.600161 -286.89856) (xy 454.651873 -286.873468) (xy 454.706766 -286.856419) (xy 454.763595 -286.847799)
			(xy 454.792334 -286.84728) (xy 454.822459 -286.84782) (xy 454.881957 -286.857308) (xy 454.939226 -286.876025)
			(xy 454.992842 -286.903508) (xy 455.041475 -286.939074) (xy 455.063098 -286.960056) (xy 455.07021 -286.967168)
			(xy 455.089006 -286.975042) (xy 455.181462 -286.975042) (xy 455.200258 -286.967168) (xy 455.20737 -286.960056)
			(xy 455.228994 -286.939075) (xy 455.277622 -286.903504) (xy 455.331239 -286.876023) (xy 455.388509 -286.857316)
			(xy 455.44801 -286.847847) (xy 455.478134 -286.84728) (xy 455.505383 -286.847793) (xy 455.559325 -286.855553)
			(xy 455.611614 -286.87091) (xy 455.661185 -286.893553) (xy 455.70703 -286.923019) (xy 455.748215 -286.958709)
			(xy 455.783901 -286.999897) (xy 455.813364 -287.045745) (xy 455.836002 -287.095318) (xy 455.851354 -287.147608)
			(xy 455.85911 -287.201551) (xy 455.85911 -287.256049) (xy 455.851354 -287.309992) (xy 455.836002 -287.362282)
			(xy 455.813364 -287.411855) (xy 455.783901 -287.457703) (xy 455.748215 -287.498891) (xy 455.70703 -287.534581)
			(xy 455.661185 -287.564047) (xy 455.611614 -287.58669) (xy 455.559325 -287.602047) (xy 455.505383 -287.609807)
			(xy 455.478134 -287.610296) (xy 455.448011 -287.609719) (xy 455.388514 -287.600242) (xy 455.331245 -287.581533)
			(xy 455.277628 -287.554058) (xy 455.228994 -287.518499) (xy 455.20737 -287.49752) (xy 455.200258 -287.490408)
			(xy 455.181462 -287.482534) (xy 455.089006 -287.482534) (xy 455.07021 -287.490408) (xy 455.063098 -287.49752)
			(xy 455.041501 -287.51853) (xy 454.992864 -287.554093) (xy 454.939241 -287.581568) (xy 454.881964 -287.600269)
			(xy 454.82246 -287.609732) (xy 454.792334 -287.610296) (xy 454.763594 -287.609813) (xy 454.706764 -287.601181)
			(xy 454.651873 -287.584121) (xy 454.600162 -287.559021) (xy 454.552801 -287.526447) (xy 454.531476 -287.507172)
			(xy 454.531222 -287.506918) (xy 454.523943 -287.500768) (xy 454.506199 -287.493852) (xy 454.496678 -287.493456)
			(xy 454.42759 -287.493456) (xy 454.41806 -287.493819) (xy 454.400305 -287.500733) (xy 454.393046 -287.506918)
			(xy 454.392792 -287.507172) (xy 454.371465 -287.526442) (xy 454.324102 -287.559007) (xy 454.272391 -287.584098)
			(xy 454.2175 -287.601148) (xy 454.160673 -287.60977) (xy 454.103195 -287.60977) (xy 454.046368 -287.601148)
			(xy 453.991477 -287.584098) (xy 453.939766 -287.559007) (xy 453.892403 -287.526442) (xy 453.871076 -287.507172)
			(xy 453.870822 -287.506918) (xy 453.863543 -287.500768) (xy 453.845799 -287.493852) (xy 453.836278 -287.493456)
			(xy 453.76719 -287.493456) (xy 453.75766 -287.493819) (xy 453.739905 -287.500733) (xy 453.732646 -287.506918)
			(xy 453.732392 -287.507172) (xy 453.711052 -287.526428) (xy 453.663694 -287.558996) (xy 453.611985 -287.584091)
			(xy 453.557097 -287.601145) (xy 453.500272 -287.609773) (xy 453.471534 -287.610296) (xy 453.444279 -287.609859)
			(xy 453.390322 -287.602106) (xy 453.338019 -287.586753) (xy 453.288433 -287.564111) (xy 453.242574 -287.534643)
			(xy 453.201376 -287.498948) (xy 453.165677 -287.457753) (xy 453.136205 -287.411897) (xy 453.113559 -287.362313)
			(xy 453.098201 -287.310011) (xy 453.090443 -287.256055) (xy 451.205309 -287.256055) (xy 451.197555 -287.30999)
			(xy 451.182203 -287.36228) (xy 451.159565 -287.411852) (xy 451.130104 -287.457699) (xy 451.094419 -287.498886)
			(xy 451.053236 -287.534577) (xy 451.007393 -287.564043) (xy 450.957823 -287.586686) (xy 450.905535 -287.602045)
			(xy 450.851594 -287.609807) (xy 450.824346 -287.610296) (xy 450.794223 -287.609712) (xy 450.734727 -287.600236)
			(xy 450.677458 -287.581529) (xy 450.623841 -287.554056) (xy 450.575207 -287.518499) (xy 450.553582 -287.49752)
			(xy 450.54647 -287.490408) (xy 450.527674 -287.482534) (xy 450.435218 -287.482534) (xy 450.416422 -287.490408)
			(xy 450.40931 -287.49752) (xy 450.387707 -287.518524) (xy 450.339072 -287.554088) (xy 450.28545 -287.581564)
			(xy 450.228175 -287.600266) (xy 450.168672 -287.609731) (xy 450.138546 -287.610296) (xy 450.109806 -287.609806)
			(xy 450.052977 -287.601175) (xy 449.998086 -287.584118) (xy 449.946375 -287.559018) (xy 449.899014 -287.526446)
			(xy 449.877688 -287.507172) (xy 449.877434 -287.506918) (xy 449.870151 -287.500773) (xy 449.85241 -287.493854)
			(xy 449.84289 -287.493456) (xy 449.773802 -287.493456) (xy 449.764273 -287.493825) (xy 449.746517 -287.500735)
			(xy 449.739258 -287.506918) (xy 449.739004 -287.507172) (xy 449.717677 -287.526442) (xy 449.670314 -287.559007)
			(xy 449.618603 -287.584098) (xy 449.563712 -287.601148) (xy 449.506885 -287.60977) (xy 449.449407 -287.60977)
			(xy 449.39258 -287.601148) (xy 449.337689 -287.584098) (xy 449.285978 -287.559007) (xy 449.238615 -287.526442)
			(xy 449.217288 -287.507172) (xy 449.217034 -287.506918) (xy 449.209751 -287.500773) (xy 449.19201 -287.493854)
			(xy 449.18249 -287.493456) (xy 449.113402 -287.493456) (xy 449.103873 -287.493825) (xy 449.086117 -287.500735)
			(xy 449.078858 -287.506918) (xy 449.078604 -287.507172) (xy 449.057301 -287.52647) (xy 449.009932 -287.559032)
			(xy 448.958214 -287.584119) (xy 448.903318 -287.601163) (xy 448.846487 -287.609779) (xy 448.817746 -287.610296)
			(xy 448.79049 -287.60986) (xy 448.736532 -287.602108) (xy 448.684227 -287.586756) (xy 448.63464 -287.564115)
			(xy 448.588779 -287.534647) (xy 448.54758 -287.498953) (xy 448.51188 -287.457757) (xy 448.482407 -287.411901)
			(xy 448.45976 -287.362316) (xy 448.444401 -287.310013) (xy 448.436643 -287.256056) (xy 439.705439 -287.256056)
			(xy 439.724944 -287.261783) (xy 439.774521 -287.284425) (xy 439.820371 -287.313891) (xy 439.861562 -287.349582)
			(xy 439.897253 -287.390773) (xy 439.926719 -287.436623) (xy 439.949361 -287.4862) (xy 439.964716 -287.538495)
			(xy 439.972472 -287.592443) (xy 439.972958 -287.619694) (xy 439.972958 -287.620456) (xy 439.972539 -287.645785)
			(xy 439.965779 -287.695991) (xy 439.959496 -287.720532) (xy 439.959496 -287.720786) (xy 439.95752 -287.729189)
			(xy 439.958716 -287.7464) (xy 439.965567 -287.762233) (xy 439.97118 -287.768792) (xy 440.030108 -287.831784)
			(xy 440.036237 -287.837866) (xy 440.051499 -287.845907) (xy 440.068572 -287.848376) (xy 440.077098 -287.847024)
			(xy 440.095511 -287.843584) (xy 440.13279 -287.839899) (xy 440.15152 -287.839658) (xy 440.151774 -287.839658)
			(xy 440.17903 -287.840127) (xy 440.232987 -287.847881) (xy 440.285291 -287.863236) (xy 440.334877 -287.885878)
			(xy 440.356312 -287.899652) (xy 457.970079 -287.899652) (xy 457.970079 -287.845148) (xy 457.977837 -287.791198)
			(xy 457.993193 -287.738901) (xy 458.015836 -287.689322) (xy 458.045305 -287.64347) (xy 458.080999 -287.60228)
			(xy 458.122193 -287.566588) (xy 458.168047 -287.537123) (xy 458.217627 -287.514483) (xy 458.269925 -287.499131)
			(xy 458.323876 -287.491377) (xy 458.351128 -287.490916) (xy 458.381252 -287.491479) (xy 458.440748 -287.500963)
			(xy 458.498016 -287.519677) (xy 458.551632 -287.547154) (xy 458.600267 -287.582713) (xy 458.621892 -287.603692)
			(xy 458.629004 -287.610804) (xy 458.6478 -287.618678) (xy 458.740256 -287.618678) (xy 458.759052 -287.610804)
			(xy 458.766164 -287.603692) (xy 458.78778 -287.582702) (xy 458.836412 -287.547136) (xy 458.89003 -287.519658)
			(xy 458.947302 -287.500952) (xy 459.006803 -287.491483) (xy 459.036928 -287.490916) (xy 459.06418 -287.491356)
			(xy 459.118128 -287.499116) (xy 459.170422 -287.514475) (xy 459.219999 -287.537119) (xy 459.265849 -287.566588)
			(xy 459.307038 -287.602281) (xy 459.342729 -287.643473) (xy 459.372195 -287.689325) (xy 459.394835 -287.738904)
			(xy 459.41019 -287.7912) (xy 459.417946 -287.845148) (xy 459.417946 -287.872424) (xy 460.847692 -287.872424)
			(xy 460.851763 -287.816802) (xy 460.863889 -287.762365) (xy 460.883812 -287.710274) (xy 460.911108 -287.661639)
			(xy 460.945194 -287.617496) (xy 460.985343 -287.578787) (xy 461.030701 -287.546336) (xy 461.080301 -287.520835)
			(xy 461.133085 -287.502828) (xy 461.187928 -287.492698) (xy 461.243662 -287.490661) (xy 461.299099 -287.496761)
			(xy 461.353056 -287.510867) (xy 461.404385 -287.532679) (xy 461.451991 -287.561733) (xy 461.494859 -287.597408)
			(xy 461.532076 -287.638945) (xy 461.562849 -287.685458) (xy 461.586521 -287.735955) (xy 461.602589 -287.789362)
			(xy 461.610709 -287.844538) (xy 461.611218 -287.872424) (xy 461.610709 -287.90031) (xy 461.602589 -287.955486)
			(xy 461.586521 -288.008893) (xy 461.562849 -288.05939) (xy 461.532076 -288.105903) (xy 461.494859 -288.14744)
			(xy 461.451991 -288.183115) (xy 461.404385 -288.212169) (xy 461.353056 -288.233981) (xy 461.299099 -288.248087)
			(xy 461.243662 -288.254187) (xy 461.187928 -288.25215) (xy 461.133085 -288.24202) (xy 461.080301 -288.224013)
			(xy 461.030701 -288.198512) (xy 460.985343 -288.166061) (xy 460.945194 -288.127352) (xy 460.911108 -288.083209)
			(xy 460.883812 -288.034574) (xy 460.863889 -287.982483) (xy 460.851763 -287.928046) (xy 460.847692 -287.872424)
			(xy 459.417946 -287.872424) (xy 459.417946 -287.899652) (xy 459.41019 -287.9536) (xy 459.394835 -288.005896)
			(xy 459.372195 -288.055475) (xy 459.342729 -288.101327) (xy 459.307038 -288.142519) (xy 459.265849 -288.178212)
			(xy 459.219999 -288.207681) (xy 459.170422 -288.230325) (xy 459.118128 -288.245684) (xy 459.06418 -288.253444)
			(xy 459.036928 -288.253932) (xy 459.006805 -288.253349) (xy 458.947309 -288.243872) (xy 458.890041 -288.225164)
			(xy 458.836424 -288.197691) (xy 458.787789 -288.162134) (xy 458.766164 -288.141156) (xy 458.759052 -288.134044)
			(xy 458.740256 -288.12617) (xy 458.6478 -288.12617) (xy 458.629004 -288.134044) (xy 458.621892 -288.141156)
			(xy 458.600287 -288.162158) (xy 458.551653 -288.197725) (xy 458.498032 -288.225202) (xy 458.440757 -288.243905)
			(xy 458.381254 -288.253368) (xy 458.351128 -288.253932) (xy 458.323876 -288.253423) (xy 458.269925 -288.245669)
			(xy 458.217627 -288.230317) (xy 458.168047 -288.207677) (xy 458.122193 -288.178212) (xy 458.080999 -288.14252)
			(xy 458.045305 -288.10133) (xy 458.015836 -288.055478) (xy 457.993193 -288.005899) (xy 457.977837 -287.953602)
			(xy 457.970079 -287.899652) (xy 440.356312 -287.899652) (xy 440.380736 -287.915347) (xy 440.421935 -287.951042)
			(xy 440.457634 -287.992238) (xy 440.487106 -288.038095) (xy 440.509753 -288.087679) (xy 440.525112 -288.139982)
			(xy 440.532871 -288.193938) (xy 440.532871 -288.24845) (xy 440.525114 -288.302406) (xy 440.509757 -288.35471)
			(xy 440.487112 -288.404295) (xy 440.457641 -288.450152) (xy 440.421943 -288.491349) (xy 440.380746 -288.527046)
			(xy 440.334888 -288.556516) (xy 440.285302 -288.57916) (xy 440.232998 -288.594516) (xy 440.179042 -288.602272)
			(xy 440.12453 -288.60227) (xy 440.070574 -288.59451) (xy 440.018272 -288.57915) (xy 439.968688 -288.556503)
			(xy 439.922831 -288.527029) (xy 439.881637 -288.491329) (xy 439.845942 -288.45013) (xy 439.816474 -288.40427)
			(xy 439.793833 -288.354683) (xy 439.77848 -288.302379) (xy 439.770727 -288.248422) (xy 439.770266 -288.221166)
			(xy 439.770266 -288.220404) (xy 439.770697 -288.195075) (xy 439.777449 -288.14487) (xy 439.783728 -288.120328)
			(xy 439.783728 -288.120074) (xy 439.785729 -288.111676) (xy 439.784521 -288.094461) (xy 439.777661 -288.078627)
			(xy 439.772044 -288.072068) (xy 439.703972 -287.99917) (xy 439.67908 -287.991296) (xy 439.665872 -287.993836)
			(xy 439.6561 -287.995739) (xy 439.636406 -287.998663) (xy 439.626502 -287.999678) (xy 439.615326 -288.000694)
			(xy 439.596022 -288.01187) (xy 439.545222 -288.084006) (xy 439.539313 -288.093352) (xy 439.535366 -288.115086)
			(xy 439.537602 -288.125916) (xy 439.537602 -288.12617) (xy 439.543159 -288.149397) (xy 439.549151 -288.196779)
			(xy 439.54954 -288.220658) (xy 439.54954 -288.221166) (xy 439.549054 -288.248417) (xy 439.541298 -288.302365)
			(xy 439.525943 -288.35466) (xy 439.503301 -288.404237) (xy 439.473835 -288.450087) (xy 439.438144 -288.491278)
			(xy 439.396953 -288.526969) (xy 439.351103 -288.556435) (xy 439.301526 -288.579077) (xy 439.249231 -288.594432)
			(xy 439.195283 -288.602188) (xy 439.140781 -288.602188) (xy 439.086833 -288.594432) (xy 439.034538 -288.579077)
			(xy 438.984961 -288.556435) (xy 438.939111 -288.526969) (xy 438.89792 -288.491278) (xy 438.862229 -288.450087)
			(xy 438.832763 -288.404237) (xy 438.810121 -288.35466) (xy 438.794766 -288.302365) (xy 438.78701 -288.248417)
			(xy 438.786524 -288.221166) (xy 438.786524 -288.220658) (xy 438.786978 -288.194341) (xy 438.794243 -288.14221)
			(xy 438.801002 -288.116772) (xy 438.804558 -288.104326) (xy 438.799224 -288.079942) (xy 438.736486 -288.005774)
			(xy 438.73225 -288.001091) (xy 438.72198 -287.993758) (xy 438.716166 -287.991296) (xy 438.704736 -287.986724)
			(xy 438.691782 -287.987994) (xy 438.691274 -287.987994) (xy 438.680644 -287.989157) (xy 438.659295 -287.990426)
			(xy 438.648602 -287.990534) (xy 438.648348 -287.990534) (xy 438.628536 -287.990026) (xy 438.616598 -287.989518)
			(xy 438.594754 -287.998916) (xy 438.52719 -288.07918) (xy 438.521602 -288.102294) (xy 438.524142 -288.113978)
			(xy 438.528516 -288.134593) (xy 438.53323 -288.176472) (xy 438.53354 -288.197544) (xy 438.532975 -288.224792)
			(xy 438.525213 -288.278732) (xy 438.509854 -288.331019) (xy 438.48721 -288.380587) (xy 438.457742 -288.426429)
			(xy 438.42205 -288.46761) (xy 438.380861 -288.503293) (xy 438.335013 -288.53275) (xy 438.28544 -288.555383)
			(xy 438.23315 -288.570731) (xy 438.179208 -288.578481) (xy 438.124712 -288.578475) (xy 438.070772 -288.570714)
			(xy 438.018485 -288.555355) (xy 437.968916 -288.532712) (xy 437.923075 -288.503245) (xy 437.881893 -288.467553)
			(xy 437.84621 -288.426365) (xy 437.816752 -288.380517) (xy 437.794118 -288.330944) (xy 437.77877 -288.278654)
			(xy 437.77102 -288.224712) (xy 437.516988 -288.224712) (xy 437.516988 -288.248447) (xy 437.509233 -288.302387)
			(xy 437.493881 -288.354675) (xy 437.471244 -288.404245) (xy 437.441783 -288.45009) (xy 437.406099 -288.491276)
			(xy 437.364916 -288.526964) (xy 437.319074 -288.556429) (xy 437.269505 -288.57907) (xy 437.217219 -288.594426)
			(xy 437.163279 -288.602186) (xy 437.136032 -288.602674) (xy 437.109915 -288.602229) (xy 437.05817 -288.595095)
			(xy 437.007882 -288.580969) (xy 436.959991 -288.560115) (xy 436.915392 -288.532923) (xy 436.87492 -288.499901)
			(xy 436.83933 -288.461668) (xy 436.809288 -288.418937) (xy 436.796942 -288.395918) (xy 436.790175 -288.383704)
			(xy 436.771172 -288.363258) (xy 436.747346 -288.348716) (xy 436.720475 -288.341164) (xy 436.692561 -288.341164)
			(xy 436.66569 -288.348716) (xy 436.641864 -288.363258) (xy 436.622861 -288.383704) (xy 436.616094 -288.395918)
			(xy 436.603721 -288.418923) (xy 436.573692 -288.461665) (xy 436.538111 -288.499908) (xy 436.497644 -288.532937)
			(xy 436.453048 -288.560134) (xy 436.405157 -288.58099) (xy 436.354868 -288.595115) (xy 436.303122 -288.602245)
			(xy 436.277004 -288.602674) (xy 436.249749 -288.602279) (xy 436.195792 -288.594522) (xy 436.143489 -288.579165)
			(xy 436.093904 -288.556521) (xy 436.048046 -288.52705) (xy 436.00685 -288.491353) (xy 435.971152 -288.450157)
			(xy 435.941681 -288.404299) (xy 435.919036 -288.354715) (xy 435.903679 -288.302412) (xy 435.895921 -288.248455)
			(xy 431.050379 -288.248455) (xy 431.05475 -288.274651) (xy 431.055272 -288.299906) (xy 431.055079 -288.314025)
			(xy 431.052412 -288.342138) (xy 431.049938 -288.35604) (xy 431.047652 -288.368486) (xy 431.055018 -288.392362)
			(xy 431.132488 -288.469832) (xy 431.156364 -288.477198) (xy 431.16881 -288.474912) (xy 431.182714 -288.47245)
			(xy 431.210825 -288.469778) (xy 431.224944 -288.469578) (xy 431.247727 -288.469994) (xy 431.292784 -288.476778)
			(xy 431.336336 -288.490174) (xy 431.377417 -288.509885) (xy 431.415118 -288.535475) (xy 431.448604 -288.566377)
			(xy 431.463196 -288.583878) (xy 431.470763 -288.592476) (xy 431.491379 -288.6024) (xy 431.50282 -288.602928)
			(xy 431.582068 -288.602928) (xy 431.593481 -288.602268) (xy 431.614058 -288.592386) (xy 431.621692 -288.583878)
			(xy 431.636289 -288.566379) (xy 431.669762 -288.535462) (xy 431.707459 -288.509862) (xy 431.748542 -288.49015)
			(xy 431.792098 -288.476762) (xy 431.83716 -288.469997) (xy 431.859944 -288.469578) (xy 431.885196 -288.470131)
			(xy 431.93501 -288.47845) (xy 431.982775 -288.494854) (xy 432.027189 -288.518895) (xy 432.067041 -288.549919)
			(xy 432.101244 -288.587078) (xy 432.128865 -288.629359) (xy 432.14915 -288.67561) (xy 432.161547 -288.724569)
			(xy 432.165717 -288.7749) (xy 432.161547 -288.825231) (xy 432.14915 -288.87419) (xy 432.128865 -288.920441)
			(xy 432.101244 -288.962722) (xy 432.067041 -288.999881) (xy 432.027189 -289.030905) (xy 431.982775 -289.054946)
			(xy 431.93501 -289.07135) (xy 431.885196 -289.079669) (xy 431.859944 -289.080194) (xy 431.837161 -289.079797)
			(xy 431.792102 -289.07301) (xy 431.748549 -289.059612) (xy 431.707468 -289.039897) (xy 431.669767 -289.014303)
			(xy 431.636283 -288.983397) (xy 431.621692 -288.965894) (xy 431.614135 -288.957286) (xy 431.593511 -288.947368)
			(xy 431.582068 -288.946844) (xy 431.50282 -288.946844) (xy 431.491408 -288.947506) (xy 431.470831 -288.957388)
			(xy 431.463196 -288.965894) (xy 431.448623 -288.983414) (xy 431.415143 -289.014326) (xy 431.37744 -289.039921)
			(xy 431.336353 -289.059629) (xy 431.292793 -289.073013) (xy 431.247729 -289.079776) (xy 431.224944 -289.080194)
			(xy 431.200951 -289.079721) (xy 431.153556 -289.072221) (xy 431.107918 -289.057397) (xy 431.065161 -289.035616)
			(xy 431.026338 -289.007414) (xy 430.992406 -288.973485) (xy 430.9642 -288.934665) (xy 430.942414 -288.89191)
			(xy 430.927586 -288.846273) (xy 430.920081 -288.798879) (xy 430.919636 -288.774886) (xy 430.919828 -288.760767)
			(xy 430.922496 -288.732654) (xy 430.92497 -288.718752) (xy 430.927256 -288.706306) (xy 430.91989 -288.68243)
			(xy 430.84242 -288.60496) (xy 430.818544 -288.597594) (xy 430.806098 -288.59988) (xy 430.792194 -288.60234)
			(xy 430.764083 -288.605013) (xy 430.749964 -288.605214) (xy 430.735845 -288.605026) (xy 430.707732 -288.602355)
			(xy 430.69383 -288.59988) (xy 430.681384 -288.597594) (xy 430.657508 -288.60496) (xy 430.580038 -288.68243)
			(xy 430.572672 -288.706306) (xy 430.574958 -288.718752) (xy 430.577425 -288.732655) (xy 430.580094 -288.760767)
			(xy 430.580292 -288.774886) (xy 430.57977 -288.800141) (xy 430.571457 -288.849963) (xy 430.555056 -288.897737)
			(xy 430.531015 -288.94216) (xy 430.499991 -288.98202) (xy 430.462829 -289.01623) (xy 430.420543 -289.043856)
			(xy 430.374287 -289.064146) (xy 430.325322 -289.076546) (xy 430.274984 -289.080717) (xy 430.224646 -289.076546)
			(xy 430.175681 -289.064146) (xy 430.129425 -289.043856) (xy 430.087139 -289.01623) (xy 430.049977 -288.98202)
			(xy 430.018953 -288.94216) (xy 429.994912 -288.897737) (xy 429.978511 -288.849963) (xy 429.970198 -288.800141)
			(xy 429.969676 -288.774886) (xy 429.969868 -288.760767) (xy 429.972536 -288.732654) (xy 429.97501 -288.718752)
			(xy 429.977296 -288.706306) (xy 429.96993 -288.68243) (xy 429.89246 -288.60496) (xy 429.868584 -288.597594)
			(xy 429.856138 -288.59988) (xy 429.842235 -288.602349) (xy 429.814123 -288.605016) (xy 429.800004 -288.605214)
			(xy 429.785884 -288.605034) (xy 429.757772 -288.602358) (xy 429.74387 -288.59988) (xy 429.731424 -288.597594)
			(xy 429.707548 -288.60496) (xy 429.630078 -288.68243) (xy 429.622712 -288.706306) (xy 429.624998 -288.718752)
			(xy 429.627465 -288.732655) (xy 429.630134 -288.760767) (xy 429.630332 -288.774886) (xy 429.62981 -288.800141)
			(xy 429.621497 -288.849963) (xy 429.605096 -288.897737) (xy 429.581055 -288.94216) (xy 429.550031 -288.98202)
			(xy 429.512869 -289.01623) (xy 429.470583 -289.043856) (xy 429.424327 -289.064146) (xy 429.375362 -289.076546)
			(xy 429.325024 -289.080717) (xy 429.274686 -289.076546) (xy 429.225721 -289.064146) (xy 429.179465 -289.043856)
			(xy 429.137179 -289.01623) (xy 429.100017 -288.98202) (xy 429.068993 -288.94216) (xy 429.044952 -288.897737)
			(xy 429.028551 -288.849963) (xy 429.020238 -288.800141) (xy 429.019716 -288.774886) (xy 429.019716 -288.774632)
			(xy 429.019794 -288.764825) (xy 429.021067 -288.745251) (xy 429.022256 -288.735516) (xy 429.022764 -288.732214)
			(xy 429.022764 -288.728658) (xy 429.022225 -288.718448) (xy 429.014102 -288.699706) (xy 429.007016 -288.692336)
			(xy 428.948088 -288.635694) (xy 428.939132 -288.627887) (xy 428.916459 -288.620875) (xy 428.904654 -288.622232)
			(xy 428.9044 -288.622232) (xy 428.890914 -288.624383) (xy 428.863699 -288.626669) (xy 428.850044 -288.626804)
			(xy 428.849536 -288.626804) (xy 428.836008 -288.626645) (xy 428.809049 -288.624358) (xy 428.795688 -288.622232)
			(xy 428.79518 -288.622232) (xy 428.783242 -288.620454) (xy 428.772066 -288.623756) (xy 428.766321 -288.625651)
			(xy 428.755919 -288.631824) (xy 428.751492 -288.635948) (xy 428.683928 -288.700972) (xy 428.676054 -288.723578)
			(xy 428.677578 -288.735516) (xy 428.678755 -288.745252) (xy 428.680029 -288.764825) (xy 428.680118 -288.774632)
			(xy 428.680118 -288.774886) (xy 428.679596 -288.800141) (xy 428.671283 -288.849963) (xy 428.654882 -288.897737)
			(xy 428.630841 -288.94216) (xy 428.599817 -288.98202) (xy 428.562655 -289.01623) (xy 428.520369 -289.043856)
			(xy 428.474113 -289.064146) (xy 428.425148 -289.076546) (xy 428.37481 -289.080717) (xy 428.324472 -289.076546)
			(xy 428.275507 -289.064146) (xy 428.229251 -289.043856) (xy 428.186965 -289.01623) (xy 428.149803 -288.98202)
			(xy 428.118779 -288.94216) (xy 428.094738 -288.897737) (xy 428.078337 -288.849963) (xy 428.070024 -288.800141)
			(xy 428.069502 -288.774886) (xy 428.069502 -288.774632) (xy 428.06958 -288.764825) (xy 428.070853 -288.745251)
			(xy 428.072042 -288.735516) (xy 428.073566 -288.723578) (xy 428.065692 -288.700972) (xy 427.998128 -288.635948)
			(xy 427.993679 -288.631857) (xy 427.983277 -288.625703) (xy 427.977554 -288.623756) (xy 427.966378 -288.620454)
			(xy 427.95444 -288.622232) (xy 427.953932 -288.622232) (xy 427.94057 -288.624345) (xy 427.913611 -288.626632)
			(xy 427.900084 -288.626804) (xy 427.899576 -288.626804) (xy 427.886048 -288.626653) (xy 427.859089 -288.62436)
			(xy 427.845728 -288.622232) (xy 427.84522 -288.622232) (xy 427.833282 -288.620454) (xy 427.822106 -288.623756)
			(xy 427.816365 -288.625662) (xy 427.805961 -288.631828) (xy 427.801532 -288.635948) (xy 427.733968 -288.700972)
			(xy 427.726094 -288.723578) (xy 427.727618 -288.735516) (xy 427.728795 -288.745252) (xy 427.730069 -288.764825)
			(xy 427.730158 -288.774632) (xy 427.730158 -288.774886) (xy 427.729636 -288.800141) (xy 427.721323 -288.849963)
			(xy 427.704922 -288.897737) (xy 427.680881 -288.94216) (xy 427.649857 -288.98202) (xy 427.612695 -289.01623)
			(xy 427.570409 -289.043856) (xy 427.524153 -289.064146) (xy 427.475188 -289.076546) (xy 427.42485 -289.080717)
			(xy 427.374512 -289.076546) (xy 427.325547 -289.064146) (xy 427.279291 -289.043856) (xy 427.237005 -289.01623)
			(xy 427.199843 -288.98202) (xy 427.168819 -288.94216) (xy 427.144778 -288.897737) (xy 427.128377 -288.849963)
			(xy 427.120064 -288.800141) (xy 427.119542 -288.774886) (xy 427.119734 -288.760767) (xy 427.122402 -288.732654)
			(xy 427.124876 -288.718752) (xy 427.127162 -288.706306) (xy 427.119796 -288.68243) (xy 427.042326 -288.60496)
			(xy 427.01845 -288.597594) (xy 427.006004 -288.59988) (xy 426.9921 -288.60234) (xy 426.963989 -288.605013)
			(xy 426.94987 -288.605214) (xy 426.925052 -288.60469) (xy 426.876071 -288.596655) (xy 426.829034 -288.580802)
			(xy 426.785183 -288.557548) (xy 426.74567 -288.527506) (xy 426.711539 -288.491468) (xy 426.683687 -288.450382)
			(xy 426.662849 -288.405332) (xy 426.649573 -288.357504) (xy 426.644211 -288.308159) (xy 426.305052 -288.308159)
			(xy 426.304723 -288.324513) (xy 426.296828 -288.37309) (xy 426.281244 -288.419771) (xy 426.258373 -288.463348)
			(xy 426.228808 -288.502692) (xy 426.193315 -288.536784) (xy 426.152812 -288.56474) (xy 426.10835 -288.585838)
			(xy 426.061079 -288.59953) (xy 426.012224 -288.605462) (xy 425.963049 -288.603481) (xy 425.91483 -288.593637)
			(xy 425.868814 -288.576185) (xy 425.826193 -288.551578) (xy 425.788072 -288.520453) (xy 425.755437 -288.483616)
			(xy 425.729134 -288.44202) (xy 425.709843 -288.396744) (xy 425.698066 -288.34896) (xy 425.694106 -288.299906)
			(xy 425.355178 -288.299906) (xy 425.355626 -288.308146) (xy 425.350265 -288.357497) (xy 425.33699 -288.40533)
			(xy 425.316152 -288.450386) (xy 425.2883 -288.491477) (xy 425.254166 -288.527521) (xy 425.214652 -288.557569)
			(xy 425.170797 -288.580828) (xy 425.123756 -288.596685) (xy 425.074771 -288.604724) (xy 425.04995 -288.605214)
			(xy 425.035831 -288.605028) (xy 425.007718 -288.602356) (xy 424.993816 -288.59988) (xy 424.98137 -288.597594)
			(xy 424.957494 -288.60496) (xy 424.880024 -288.68243) (xy 424.872658 -288.706306) (xy 424.874944 -288.718752)
			(xy 424.877411 -288.732655) (xy 424.88008 -288.760767) (xy 424.880278 -288.774886) (xy 424.879756 -288.800141)
			(xy 424.871443 -288.849963) (xy 424.855042 -288.897737) (xy 424.831001 -288.94216) (xy 424.799977 -288.98202)
			(xy 424.762815 -289.01623) (xy 424.720529 -289.043856) (xy 424.674273 -289.064146) (xy 424.625308 -289.076546)
			(xy 424.57497 -289.080717) (xy 424.524632 -289.076546) (xy 424.475667 -289.064146) (xy 424.429411 -289.043856)
			(xy 424.387125 -289.01623) (xy 424.349963 -288.98202) (xy 424.318939 -288.94216) (xy 424.294898 -288.897737)
			(xy 424.278497 -288.849963) (xy 424.270184 -288.800141) (xy 424.269662 -288.774886) (xy 424.269854 -288.760767)
			(xy 424.272522 -288.732654) (xy 424.274996 -288.718752) (xy 424.277282 -288.706306) (xy 424.269916 -288.68243)
			(xy 424.192446 -288.60496) (xy 424.16857 -288.597594) (xy 424.156124 -288.59988) (xy 424.142219 -288.602337)
			(xy 424.114108 -288.605012) (xy 424.09999 -288.605214) (xy 424.07517 -288.604711) (xy 424.026184 -288.596679)
			(xy 423.979143 -288.580827) (xy 423.935287 -288.557574) (xy 423.895769 -288.527532) (xy 423.861633 -288.491493)
			(xy 423.833777 -288.450405) (xy 423.812935 -288.405353) (xy 423.799657 -288.357522) (xy 423.794291 -288.308173)
			(xy 423.455172 -288.308173) (xy 423.454843 -288.324513) (xy 423.446948 -288.37309) (xy 423.431364 -288.419771)
			(xy 423.408493 -288.463348) (xy 423.378928 -288.502692) (xy 423.343435 -288.536784) (xy 423.302932 -288.56474)
			(xy 423.25847 -288.585838) (xy 423.211199 -288.59953) (xy 423.162344 -288.605462) (xy 423.113169 -288.603481)
			(xy 423.06495 -288.593637) (xy 423.018934 -288.576185) (xy 422.976313 -288.551578) (xy 422.938192 -288.520453)
			(xy 422.905557 -288.483616) (xy 422.879254 -288.44202) (xy 422.859963 -288.396744) (xy 422.848186 -288.34896)
			(xy 422.844226 -288.299906) (xy 422.505124 -288.299906) (xy 422.504629 -288.324513) (xy 422.496734 -288.37309)
			(xy 422.48115 -288.419771) (xy 422.458279 -288.463348) (xy 422.428714 -288.502692) (xy 422.393221 -288.536784)
			(xy 422.352718 -288.56474) (xy 422.308256 -288.585838) (xy 422.260985 -288.59953) (xy 422.21213 -288.605462)
			(xy 422.162955 -288.603481) (xy 422.114736 -288.593637) (xy 422.06872 -288.576185) (xy 422.026099 -288.551578)
			(xy 421.987978 -288.520453) (xy 421.955343 -288.483616) (xy 421.92904 -288.44202) (xy 421.909749 -288.396744)
			(xy 421.897972 -288.34896) (xy 421.894012 -288.299906) (xy 417.725098 -288.299906) (xy 417.725098 -288.3535)
			(xy 417.725555 -288.363379) (xy 417.732993 -288.381682) (xy 417.739576 -288.38906) (xy 417.73983 -288.389314)
			(xy 417.74364 -288.393124) (xy 417.766754 -288.411412) (xy 417.81603 -288.450528) (xy 417.838382 -288.455608)
			(xy 417.849812 -288.452814) (xy 417.86828 -288.448768) (xy 417.905838 -288.444438) (xy 417.924742 -288.444178)
			(xy 417.924996 -288.444178) (xy 417.950987 -288.444661) (xy 418.002328 -288.452792) (xy 418.051765 -288.468855)
			(xy 418.098081 -288.492453) (xy 418.140134 -288.523006) (xy 418.176891 -288.559762) (xy 418.207445 -288.601816)
			(xy 418.231044 -288.648131) (xy 418.247107 -288.697568) (xy 418.255239 -288.748909) (xy 418.255239 -288.774886)
			(xy 418.569152 -288.774886) (xy 418.573112 -288.725832) (xy 418.584889 -288.678048) (xy 418.60418 -288.632772)
			(xy 418.630483 -288.591176) (xy 418.663118 -288.554339) (xy 418.701239 -288.523214) (xy 418.74386 -288.498607)
			(xy 418.789876 -288.481155) (xy 418.838095 -288.471311) (xy 418.88727 -288.46933) (xy 418.936125 -288.475262)
			(xy 418.983396 -288.488954) (xy 419.027858 -288.510052) (xy 419.068361 -288.538008) (xy 419.103854 -288.5721)
			(xy 419.133419 -288.611444) (xy 419.15629 -288.655021) (xy 419.171874 -288.701702) (xy 419.179769 -288.750279)
			(xy 419.180264 -288.774886) (xy 419.519112 -288.774886) (xy 419.523072 -288.725832) (xy 419.534849 -288.678048)
			(xy 419.55414 -288.632772) (xy 419.580443 -288.591176) (xy 419.613078 -288.554339) (xy 419.651199 -288.523214)
			(xy 419.69382 -288.498607) (xy 419.739836 -288.481155) (xy 419.788055 -288.471311) (xy 419.83723 -288.46933)
			(xy 419.886085 -288.475262) (xy 419.933356 -288.488954) (xy 419.977818 -288.510052) (xy 420.018321 -288.538008)
			(xy 420.053814 -288.5721) (xy 420.083379 -288.611444) (xy 420.10625 -288.655021) (xy 420.121834 -288.701702)
			(xy 420.129729 -288.750279) (xy 420.130224 -288.774886) (xy 420.469072 -288.774886) (xy 420.473032 -288.725832)
			(xy 420.484809 -288.678048) (xy 420.5041 -288.632772) (xy 420.530403 -288.591176) (xy 420.563038 -288.554339)
			(xy 420.601159 -288.523214) (xy 420.64378 -288.498607) (xy 420.689796 -288.481155) (xy 420.738015 -288.471311)
			(xy 420.78719 -288.46933) (xy 420.836045 -288.475262) (xy 420.883316 -288.488954) (xy 420.927778 -288.510052)
			(xy 420.968281 -288.538008) (xy 421.003774 -288.5721) (xy 421.033339 -288.611444) (xy 421.05621 -288.655021)
			(xy 421.071794 -288.701702) (xy 421.079689 -288.750279) (xy 421.080184 -288.774886) (xy 421.079689 -288.799493)
			(xy 421.071794 -288.84807) (xy 421.05621 -288.894751) (xy 421.033339 -288.938328) (xy 421.003774 -288.977672)
			(xy 420.968281 -289.011764) (xy 420.927778 -289.03972) (xy 420.883316 -289.060818) (xy 420.836045 -289.07451)
			(xy 420.78719 -289.080442) (xy 420.738015 -289.078461) (xy 420.689796 -289.068617) (xy 420.64378 -289.051165)
			(xy 420.601159 -289.026558) (xy 420.563038 -288.995433) (xy 420.530403 -288.958596) (xy 420.5041 -288.917)
			(xy 420.484809 -288.871724) (xy 420.473032 -288.82394) (xy 420.469072 -288.774886) (xy 420.130224 -288.774886)
			(xy 420.129729 -288.799493) (xy 420.121834 -288.84807) (xy 420.10625 -288.894751) (xy 420.083379 -288.938328)
			(xy 420.053814 -288.977672) (xy 420.018321 -289.011764) (xy 419.977818 -289.03972) (xy 419.933356 -289.060818)
			(xy 419.886085 -289.07451) (xy 419.83723 -289.080442) (xy 419.788055 -289.078461) (xy 419.739836 -289.068617)
			(xy 419.69382 -289.051165) (xy 419.651199 -289.026558) (xy 419.613078 -288.995433) (xy 419.580443 -288.958596)
			(xy 419.55414 -288.917) (xy 419.534849 -288.871724) (xy 419.523072 -288.82394) (xy 419.519112 -288.774886)
			(xy 419.180264 -288.774886) (xy 419.179769 -288.799493) (xy 419.171874 -288.84807) (xy 419.15629 -288.894751)
			(xy 419.133419 -288.938328) (xy 419.103854 -288.977672) (xy 419.068361 -289.011764) (xy 419.027858 -289.03972)
			(xy 418.983396 -289.060818) (xy 418.936125 -289.07451) (xy 418.88727 -289.080442) (xy 418.838095 -289.078461)
			(xy 418.789876 -289.068617) (xy 418.74386 -289.051165) (xy 418.701239 -289.026558) (xy 418.663118 -288.995433)
			(xy 418.630483 -288.958596) (xy 418.60418 -288.917) (xy 418.584889 -288.871724) (xy 418.573112 -288.82394)
			(xy 418.569152 -288.774886) (xy 418.255239 -288.774886) (xy 418.255239 -288.800891) (xy 418.247107 -288.852232)
			(xy 418.231044 -288.901669) (xy 418.207445 -288.947984) (xy 418.176891 -288.990038) (xy 418.140134 -289.026794)
			(xy 418.098081 -289.057347) (xy 418.051765 -289.080945) (xy 418.002328 -289.097008) (xy 417.950987 -289.105139)
			(xy 417.924996 -289.105594) (xy 417.924742 -289.105594) (xy 417.90584 -289.105308) (xy 417.868284 -289.100979)
			(xy 417.849812 -289.096958) (xy 417.838382 -289.094164) (xy 417.81603 -289.099244) (xy 417.744402 -289.15614)
			(xy 417.735677 -289.163713) (xy 417.725605 -289.184478) (xy 417.725098 -289.196018) (xy 417.725098 -289.30346)
			(xy 417.725566 -289.313334) (xy 417.733019 -289.331622) (xy 417.739576 -289.33902) (xy 417.73983 -289.339274)
			(xy 417.74364 -289.343084) (xy 417.766754 -289.361372) (xy 417.81603 -289.400488) (xy 417.838382 -289.405568)
			(xy 417.849812 -289.402774) (xy 417.86828 -289.398728) (xy 417.905838 -289.394399) (xy 417.924742 -289.394138)
			(xy 417.924996 -289.394138) (xy 417.950982 -289.394621) (xy 418.002314 -289.40275) (xy 418.051742 -289.41881)
			(xy 418.098049 -289.442404) (xy 418.140096 -289.472952) (xy 418.176845 -289.509701) (xy 418.207394 -289.551747)
			(xy 418.230989 -289.598054) (xy 418.247049 -289.647482) (xy 418.255179 -289.698814) (xy 418.255179 -289.724846)
			(xy 418.569152 -289.724846) (xy 418.573112 -289.675792) (xy 418.584889 -289.628008) (xy 418.60418 -289.582732)
			(xy 418.630483 -289.541136) (xy 418.663118 -289.504299) (xy 418.701239 -289.473174) (xy 418.74386 -289.448567)
			(xy 418.789876 -289.431115) (xy 418.838095 -289.421271) (xy 418.88727 -289.41929) (xy 418.936125 -289.425222)
			(xy 418.983396 -289.438914) (xy 419.027858 -289.460012) (xy 419.068361 -289.487968) (xy 419.103854 -289.52206)
			(xy 419.133419 -289.561404) (xy 419.15629 -289.604981) (xy 419.171874 -289.651662) (xy 419.179769 -289.700239)
			(xy 419.180264 -289.724846) (xy 419.519112 -289.724846) (xy 419.523072 -289.675792) (xy 419.534849 -289.628008)
			(xy 419.55414 -289.582732) (xy 419.580443 -289.541136) (xy 419.613078 -289.504299) (xy 419.651199 -289.473174)
			(xy 419.69382 -289.448567) (xy 419.739836 -289.431115) (xy 419.788055 -289.421271) (xy 419.83723 -289.41929)
			(xy 419.886085 -289.425222) (xy 419.933356 -289.438914) (xy 419.977818 -289.460012) (xy 420.018321 -289.487968)
			(xy 420.053814 -289.52206) (xy 420.083379 -289.561404) (xy 420.10625 -289.604981) (xy 420.121834 -289.651662)
			(xy 420.129729 -289.700239) (xy 420.130224 -289.724846) (xy 420.469072 -289.724846) (xy 420.473032 -289.675792)
			(xy 420.484809 -289.628008) (xy 420.5041 -289.582732) (xy 420.530403 -289.541136) (xy 420.563038 -289.504299)
			(xy 420.601159 -289.473174) (xy 420.64378 -289.448567) (xy 420.689796 -289.431115) (xy 420.738015 -289.421271)
			(xy 420.78719 -289.41929) (xy 420.836045 -289.425222) (xy 420.883316 -289.438914) (xy 420.927778 -289.460012)
			(xy 420.968281 -289.487968) (xy 421.003774 -289.52206) (xy 421.033339 -289.561404) (xy 421.05621 -289.604981)
			(xy 421.071794 -289.651662) (xy 421.079689 -289.700239) (xy 421.080016 -289.71648) (xy 421.419128 -289.71648)
			(xy 421.424501 -289.667138) (xy 421.437785 -289.619315) (xy 421.458632 -289.574271) (xy 421.486491 -289.533193)
			(xy 421.520629 -289.497163) (xy 421.560145 -289.467131) (xy 421.604 -289.443887) (xy 421.651038 -289.428045)
			(xy 421.700019 -289.420021) (xy 421.724836 -289.419538) (xy 421.738955 -289.419727) (xy 421.767068 -289.422397)
			(xy 421.78097 -289.424872) (xy 421.793416 -289.427158) (xy 421.817292 -289.419792) (xy 421.894762 -289.342322)
			(xy 421.902128 -289.318446) (xy 421.899842 -289.306) (xy 421.897382 -289.292096) (xy 421.894709 -289.263985)
			(xy 421.894508 -289.249866) (xy 421.89503 -289.224611) (xy 421.903343 -289.174789) (xy 421.919744 -289.127015)
			(xy 421.943785 -289.082592) (xy 421.974809 -289.042732) (xy 422.011971 -289.008522) (xy 422.054257 -288.980896)
			(xy 422.100513 -288.960606) (xy 422.149478 -288.948206) (xy 422.199816 -288.944035) (xy 422.250154 -288.948206)
			(xy 422.299119 -288.960606) (xy 422.345375 -288.980896) (xy 422.387661 -289.008522) (xy 422.424823 -289.042732)
			(xy 422.455847 -289.082592) (xy 422.457161 -289.08502) (xy 434.087776 -289.08502) (xy 434.091847 -289.029398)
			(xy 434.103973 -288.974961) (xy 434.123896 -288.92287) (xy 434.151192 -288.874235) (xy 434.185278 -288.830092)
			(xy 434.225427 -288.791383) (xy 434.270785 -288.758932) (xy 434.320385 -288.733431) (xy 434.373169 -288.715424)
			(xy 434.428012 -288.705294) (xy 434.483746 -288.703257) (xy 434.539183 -288.709357) (xy 434.59314 -288.723463)
			(xy 434.644469 -288.745275) (xy 434.692075 -288.774329) (xy 434.734943 -288.810004) (xy 434.753546 -288.830766)
			(xy 441.453014 -288.830766) (xy 441.457085 -288.775144) (xy 441.469211 -288.720707) (xy 441.489134 -288.668616)
			(xy 441.51643 -288.619981) (xy 441.550516 -288.575838) (xy 441.590665 -288.537129) (xy 441.636023 -288.504678)
			(xy 441.685623 -288.479177) (xy 441.738407 -288.46117) (xy 441.79325 -288.45104) (xy 441.848984 -288.449003)
			(xy 441.904421 -288.455103) (xy 441.958378 -288.469209) (xy 442.009707 -288.491021) (xy 442.057313 -288.520075)
			(xy 442.100181 -288.55575) (xy 442.137398 -288.597287) (xy 442.168171 -288.6438) (xy 442.191843 -288.694297)
			(xy 442.207911 -288.747704) (xy 442.216026 -288.802847) (xy 458.605926 -288.802847) (xy 458.605926 -288.748353)
			(xy 458.613681 -288.694413) (xy 458.629034 -288.642125) (xy 458.651672 -288.592555) (xy 458.681133 -288.546711)
			(xy 458.716819 -288.505526) (xy 458.758003 -288.469839) (xy 458.803846 -288.440376) (xy 458.853416 -288.417738)
			(xy 458.905703 -288.402384) (xy 458.959643 -288.394627) (xy 458.98689 -288.39414) (xy 459.01426 -288.394602)
			(xy 459.06844 -288.402419) (xy 459.120944 -288.417909) (xy 459.17069 -288.440752) (xy 459.216657 -288.470478)
			(xy 459.237588 -288.48812) (xy 459.237842 -288.488374) (xy 459.244935 -288.493951) (xy 459.261847 -288.500202)
			(xy 459.270862 -288.500566) (xy 459.337918 -288.500566) (xy 459.346937 -288.500225) (xy 459.363854 -288.493967)
			(xy 459.370938 -288.488374) (xy 459.371446 -288.487866) (xy 459.392377 -288.47028) (xy 459.438313 -288.440642)
			(xy 459.48801 -288.417865) (xy 459.540449 -288.402415) (xy 459.594556 -288.39461) (xy 459.62189 -288.39414)
			(xy 459.649147 -288.394506) (xy 459.703106 -288.402263) (xy 459.755411 -288.41762) (xy 459.804999 -288.440265)
			(xy 459.850859 -288.469736) (xy 459.892058 -288.505435) (xy 459.927758 -288.546633) (xy 459.95723 -288.592492)
			(xy 459.979876 -288.642079) (xy 459.995235 -288.694385) (xy 460.002993 -288.748343) (xy 460.002993 -288.802847)
			(xy 460.345826 -288.802847) (xy 460.345826 -288.748353) (xy 460.353581 -288.694413) (xy 460.368934 -288.642125)
			(xy 460.391572 -288.592555) (xy 460.421033 -288.546711) (xy 460.456719 -288.505526) (xy 460.497903 -288.469839)
			(xy 460.543746 -288.440376) (xy 460.593316 -288.417738) (xy 460.645603 -288.402384) (xy 460.699543 -288.394627)
			(xy 460.72679 -288.39414) (xy 460.75416 -288.394602) (xy 460.80834 -288.402419) (xy 460.860844 -288.417909)
			(xy 460.91059 -288.440752) (xy 460.956557 -288.470478) (xy 460.977488 -288.48812) (xy 460.977742 -288.488374)
			(xy 460.984835 -288.493951) (xy 461.001747 -288.500202) (xy 461.010762 -288.500566) (xy 461.077818 -288.500566)
			(xy 461.086837 -288.500225) (xy 461.103754 -288.493967) (xy 461.110838 -288.488374) (xy 461.111346 -288.487866)
			(xy 461.132277 -288.47028) (xy 461.178213 -288.440642) (xy 461.22791 -288.417865) (xy 461.280349 -288.402415)
			(xy 461.334456 -288.39461) (xy 461.36179 -288.39414) (xy 461.389047 -288.394506) (xy 461.443006 -288.402263)
			(xy 461.495311 -288.41762) (xy 461.544899 -288.440265) (xy 461.590759 -288.469736) (xy 461.631958 -288.505435)
			(xy 461.667658 -288.546633) (xy 461.69713 -288.592492) (xy 461.719776 -288.642079) (xy 461.735135 -288.694385)
			(xy 461.742893 -288.748343) (xy 461.742893 -288.802857) (xy 461.735135 -288.856815) (xy 461.719776 -288.909121)
			(xy 461.69713 -288.958708) (xy 461.667658 -289.004567) (xy 461.631958 -289.045765) (xy 461.590759 -289.081464)
			(xy 461.544899 -289.110935) (xy 461.495311 -289.13358) (xy 461.443006 -289.148937) (xy 461.389047 -289.156694)
			(xy 461.36179 -289.157156) (xy 461.334457 -289.156671) (xy 461.28035 -289.148868) (xy 461.227911 -289.133422)
			(xy 461.178213 -289.11065) (xy 461.132273 -289.081019) (xy 461.111346 -289.06343) (xy 461.110838 -289.062922)
			(xy 461.103751 -289.057336) (xy 461.086834 -289.051091) (xy 461.077818 -289.05073) (xy 461.010762 -289.05073)
			(xy 461.001742 -289.051062) (xy 460.984825 -289.057326) (xy 460.977742 -289.062922) (xy 460.977234 -289.06343)
			(xy 460.95631 -289.081025) (xy 460.910372 -289.110662) (xy 460.860674 -289.133437) (xy 460.808233 -289.148885)
			(xy 460.754124 -289.156687) (xy 460.72679 -289.157156) (xy 460.699543 -289.156573) (xy 460.645603 -289.148816)
			(xy 460.593316 -289.133462) (xy 460.543746 -289.110824) (xy 460.497903 -289.081361) (xy 460.456719 -289.045674)
			(xy 460.421033 -289.004489) (xy 460.391572 -288.958645) (xy 460.368934 -288.909075) (xy 460.353581 -288.856787)
			(xy 460.345826 -288.802847) (xy 460.002993 -288.802847) (xy 460.002993 -288.802857) (xy 459.995235 -288.856815)
			(xy 459.979876 -288.909121) (xy 459.95723 -288.958708) (xy 459.927758 -289.004567) (xy 459.892058 -289.045765)
			(xy 459.850859 -289.081464) (xy 459.804999 -289.110935) (xy 459.755411 -289.13358) (xy 459.703106 -289.148937)
			(xy 459.649147 -289.156694) (xy 459.62189 -289.157156) (xy 459.594557 -289.156671) (xy 459.54045 -289.148868)
			(xy 459.488011 -289.133422) (xy 459.438313 -289.11065) (xy 459.392373 -289.081019) (xy 459.371446 -289.06343)
			(xy 459.370938 -289.062922) (xy 459.363851 -289.057336) (xy 459.346934 -289.051091) (xy 459.337918 -289.05073)
			(xy 459.270862 -289.05073) (xy 459.261842 -289.051062) (xy 459.244925 -289.057326) (xy 459.237842 -289.062922)
			(xy 459.237334 -289.06343) (xy 459.21641 -289.081025) (xy 459.170472 -289.110662) (xy 459.120774 -289.133437)
			(xy 459.068333 -289.148885) (xy 459.014224 -289.156687) (xy 458.98689 -289.157156) (xy 458.959643 -289.156573)
			(xy 458.905703 -289.148816) (xy 458.853416 -289.133462) (xy 458.803846 -289.110824) (xy 458.758003 -289.081361)
			(xy 458.716819 -289.045674) (xy 458.681133 -289.004489) (xy 458.651672 -288.958645) (xy 458.629034 -288.909075)
			(xy 458.613681 -288.856787) (xy 458.605926 -288.802847) (xy 442.216026 -288.802847) (xy 442.216031 -288.80288)
			(xy 442.21654 -288.830766) (xy 442.216031 -288.858652) (xy 442.207911 -288.913828) (xy 442.191843 -288.967235)
			(xy 442.168171 -289.017732) (xy 442.137398 -289.064245) (xy 442.100181 -289.105782) (xy 442.057313 -289.141457)
			(xy 442.009707 -289.170511) (xy 441.958378 -289.192323) (xy 441.904421 -289.206429) (xy 441.848984 -289.212529)
			(xy 441.79325 -289.210492) (xy 441.738407 -289.200362) (xy 441.685623 -289.182355) (xy 441.636023 -289.156854)
			(xy 441.590665 -289.124403) (xy 441.550516 -289.085694) (xy 441.51643 -289.041551) (xy 441.489134 -288.992916)
			(xy 441.469211 -288.940825) (xy 441.457085 -288.886388) (xy 441.453014 -288.830766) (xy 434.753546 -288.830766)
			(xy 434.77216 -288.851541) (xy 434.802933 -288.898054) (xy 434.826605 -288.948551) (xy 434.842673 -289.001958)
			(xy 434.850793 -289.057134) (xy 434.851302 -289.08502) (xy 434.850793 -289.112906) (xy 434.842673 -289.168082)
			(xy 434.826605 -289.221489) (xy 434.802933 -289.271986) (xy 434.77216 -289.318499) (xy 434.734943 -289.360036)
			(xy 434.692075 -289.395711) (xy 434.644469 -289.424765) (xy 434.59314 -289.446577) (xy 434.539183 -289.460683)
			(xy 434.483746 -289.466783) (xy 434.428012 -289.464746) (xy 434.373169 -289.454616) (xy 434.320385 -289.436609)
			(xy 434.270785 -289.411108) (xy 434.225427 -289.378657) (xy 434.185278 -289.339948) (xy 434.151192 -289.295805)
			(xy 434.123896 -289.24717) (xy 434.103973 -289.195079) (xy 434.091847 -289.140642) (xy 434.087776 -289.08502)
			(xy 422.457161 -289.08502) (xy 422.479888 -289.127015) (xy 422.496289 -289.174789) (xy 422.504602 -289.224611)
			(xy 422.505124 -289.249866) (xy 422.504942 -289.264049) (xy 422.502274 -289.292289) (xy 422.49979 -289.306254)
			(xy 422.498324 -289.318547) (xy 422.505596 -289.342164) (xy 422.51376 -289.351466) (xy 422.573196 -289.410902)
			(xy 422.577734 -289.415161) (xy 422.588392 -289.421579) (xy 422.594278 -289.423602) (xy 422.600233 -289.425242)
			(xy 422.612567 -289.425878) (xy 422.618662 -289.424872) (xy 422.632627 -289.422391) (xy 422.660867 -289.419722)
			(xy 422.67505 -289.419538) (xy 422.699865 -289.420032) (xy 422.74884 -289.428068) (xy 422.79587 -289.443922)
			(xy 422.839716 -289.467175) (xy 422.879223 -289.497215) (xy 422.91335 -289.53325) (xy 422.941198 -289.574331)
			(xy 422.962033 -289.619376) (xy 422.975307 -289.667199) (xy 422.980669 -289.716538) (xy 422.980218 -289.724846)
			(xy 424.269166 -289.724846) (xy 424.273126 -289.675792) (xy 424.284903 -289.628008) (xy 424.304194 -289.582732)
			(xy 424.330497 -289.541136) (xy 424.363132 -289.504299) (xy 424.401253 -289.473174) (xy 424.443874 -289.448567)
			(xy 424.48989 -289.431115) (xy 424.538109 -289.421271) (xy 424.587284 -289.41929) (xy 424.636139 -289.425222)
			(xy 424.68341 -289.438914) (xy 424.727872 -289.460012) (xy 424.768375 -289.487968) (xy 424.803868 -289.52206)
			(xy 424.833433 -289.561404) (xy 424.856304 -289.604981) (xy 424.871888 -289.651662) (xy 424.879783 -289.700239)
			(xy 424.880278 -289.724846) (xy 425.219126 -289.724846) (xy 425.223086 -289.675792) (xy 425.234863 -289.628008)
			(xy 425.254154 -289.582732) (xy 425.280457 -289.541136) (xy 425.313092 -289.504299) (xy 425.351213 -289.473174)
			(xy 425.393834 -289.448567) (xy 425.43985 -289.431115) (xy 425.488069 -289.421271) (xy 425.537244 -289.41929)
			(xy 425.586099 -289.425222) (xy 425.63337 -289.438914) (xy 425.677832 -289.460012) (xy 425.718335 -289.487968)
			(xy 425.753828 -289.52206) (xy 425.783393 -289.561404) (xy 425.806264 -289.604981) (xy 425.821848 -289.651662)
			(xy 425.829743 -289.700239) (xy 425.830238 -289.724846) (xy 426.169086 -289.724846) (xy 426.173046 -289.675792)
			(xy 426.184823 -289.628008) (xy 426.204114 -289.582732) (xy 426.230417 -289.541136) (xy 426.263052 -289.504299)
			(xy 426.301173 -289.473174) (xy 426.343794 -289.448567) (xy 426.38981 -289.431115) (xy 426.438029 -289.421271)
			(xy 426.487204 -289.41929) (xy 426.536059 -289.425222) (xy 426.58333 -289.438914) (xy 426.627792 -289.460012)
			(xy 426.668295 -289.487968) (xy 426.703788 -289.52206) (xy 426.733353 -289.561404) (xy 426.756224 -289.604981)
			(xy 426.771808 -289.651662) (xy 426.779703 -289.700239) (xy 426.780198 -289.724846) (xy 427.119046 -289.724846)
			(xy 427.123006 -289.675792) (xy 427.134783 -289.628008) (xy 427.154074 -289.582732) (xy 427.180377 -289.541136)
			(xy 427.213012 -289.504299) (xy 427.251133 -289.473174) (xy 427.293754 -289.448567) (xy 427.33977 -289.431115)
			(xy 427.387989 -289.421271) (xy 427.437164 -289.41929) (xy 427.486019 -289.425222) (xy 427.53329 -289.438914)
			(xy 427.577752 -289.460012) (xy 427.618255 -289.487968) (xy 427.653748 -289.52206) (xy 427.683313 -289.561404)
			(xy 427.706184 -289.604981) (xy 427.721768 -289.651662) (xy 427.729663 -289.700239) (xy 427.730158 -289.724846)
			(xy 428.069006 -289.724846) (xy 428.072966 -289.675792) (xy 428.084743 -289.628008) (xy 428.104034 -289.582732)
			(xy 428.130337 -289.541136) (xy 428.162972 -289.504299) (xy 428.201093 -289.473174) (xy 428.243714 -289.448567)
			(xy 428.28973 -289.431115) (xy 428.337949 -289.421271) (xy 428.387124 -289.41929) (xy 428.435979 -289.425222)
			(xy 428.48325 -289.438914) (xy 428.527712 -289.460012) (xy 428.568215 -289.487968) (xy 428.603708 -289.52206)
			(xy 428.633273 -289.561404) (xy 428.656144 -289.604981) (xy 428.671728 -289.651662) (xy 428.679623 -289.700239)
			(xy 428.680118 -289.724846) (xy 429.01922 -289.724846) (xy 429.02318 -289.675792) (xy 429.034957 -289.628008)
			(xy 429.054248 -289.582732) (xy 429.080551 -289.541136) (xy 429.113186 -289.504299) (xy 429.151307 -289.473174)
			(xy 429.193928 -289.448567) (xy 429.239944 -289.431115) (xy 429.288163 -289.421271) (xy 429.337338 -289.41929)
			(xy 429.386193 -289.425222) (xy 429.433464 -289.438914) (xy 429.477926 -289.460012) (xy 429.518429 -289.487968)
			(xy 429.553922 -289.52206) (xy 429.583487 -289.561404) (xy 429.606358 -289.604981) (xy 429.621942 -289.651662)
			(xy 429.629837 -289.700239) (xy 429.630332 -289.724846) (xy 429.96918 -289.724846) (xy 429.97314 -289.675792)
			(xy 429.984917 -289.628008) (xy 430.004208 -289.582732) (xy 430.030511 -289.541136) (xy 430.063146 -289.504299)
			(xy 430.101267 -289.473174) (xy 430.143888 -289.448567) (xy 430.189904 -289.431115) (xy 430.238123 -289.421271)
			(xy 430.287298 -289.41929) (xy 430.336153 -289.425222) (xy 430.383424 -289.438914) (xy 430.427886 -289.460012)
			(xy 430.468389 -289.487968) (xy 430.503882 -289.52206) (xy 430.533447 -289.561404) (xy 430.556318 -289.604981)
			(xy 430.571902 -289.651662) (xy 430.579797 -289.700239) (xy 430.580292 -289.724846) (xy 430.91914 -289.724846)
			(xy 430.9231 -289.675792) (xy 430.934877 -289.628008) (xy 430.954168 -289.582732) (xy 430.980471 -289.541136)
			(xy 431.013106 -289.504299) (xy 431.051227 -289.473174) (xy 431.093848 -289.448567) (xy 431.139864 -289.431115)
			(xy 431.188083 -289.421271) (xy 431.237258 -289.41929) (xy 431.286113 -289.425222) (xy 431.333384 -289.438914)
			(xy 431.377846 -289.460012) (xy 431.418349 -289.487968) (xy 431.453842 -289.52206) (xy 431.468868 -289.542056)
			(xy 450.443243 -289.542056) (xy 450.443243 -289.487544) (xy 450.451001 -289.433587) (xy 450.46636 -289.381284)
			(xy 450.489007 -289.331699) (xy 450.51848 -289.285843) (xy 450.55418 -289.244647) (xy 450.595379 -289.208953)
			(xy 450.64124 -289.179485) (xy 450.690827 -289.156844) (xy 450.743132 -289.141492) (xy 450.79709 -289.13374)
			(xy 450.824346 -289.13328) (xy 450.851716 -289.133758) (xy 450.905895 -289.14157) (xy 450.958399 -289.157055)
			(xy 451.008146 -289.179895) (xy 451.054113 -289.209619) (xy 451.075044 -289.22726) (xy 451.075298 -289.227514)
			(xy 451.08238 -289.233107) (xy 451.0993 -289.23935) (xy 451.108318 -289.239706) (xy 451.175374 -289.239706)
			(xy 451.184389 -289.239335) (xy 451.201306 -289.233097) (xy 451.208394 -289.227514) (xy 451.208902 -289.227006)
			(xy 451.229817 -289.2094) (xy 451.275757 -289.179764) (xy 451.325457 -289.15699) (xy 451.3779 -289.141545)
			(xy 451.432011 -289.133746) (xy 451.459346 -289.13328) (xy 451.486594 -289.133793) (xy 451.540535 -289.141555)
			(xy 451.592823 -289.156914) (xy 451.642393 -289.179557) (xy 451.688236 -289.209023) (xy 451.729419 -289.244714)
			(xy 451.765104 -289.285901) (xy 451.794565 -289.331748) (xy 451.817203 -289.38132) (xy 451.832555 -289.43361)
			(xy 451.84031 -289.487552) (xy 451.84031 -289.542048) (xy 451.840309 -289.542052) (xy 452.214966 -289.542052)
			(xy 452.214966 -289.487548) (xy 452.222722 -289.433599) (xy 452.238078 -289.381303) (xy 452.260719 -289.331724)
			(xy 452.290186 -289.285873) (xy 452.325878 -289.244681) (xy 452.36707 -289.208989) (xy 452.412921 -289.179521)
			(xy 452.462499 -289.156879) (xy 452.514795 -289.141523) (xy 452.568744 -289.133766) (xy 452.595996 -289.13328)
			(xy 452.623367 -289.133729) (xy 452.677548 -289.141548) (xy 452.730052 -289.15704) (xy 452.779798 -289.179886)
			(xy 452.825764 -289.209616) (xy 452.846694 -289.22726) (xy 452.846948 -289.227514) (xy 452.854044 -289.233087)
			(xy 452.870954 -289.239341) (xy 452.879968 -289.239706) (xy 452.947024 -289.239706) (xy 452.956042 -289.239359)
			(xy 452.972959 -289.233104) (xy 452.980044 -289.227514) (xy 452.980552 -289.227006) (xy 453.001486 -289.209424)
			(xy 453.04742 -289.179783) (xy 453.097116 -289.157005) (xy 453.149555 -289.141555) (xy 453.203662 -289.13375)
			(xy 453.230996 -289.13328) (xy 453.258248 -289.133767) (xy 453.312198 -289.141523) (xy 453.364495 -289.156879)
			(xy 453.414074 -289.17952) (xy 453.459926 -289.208987) (xy 453.501118 -289.24468) (xy 453.536811 -289.285871)
			(xy 453.566278 -289.331723) (xy 453.58892 -289.381302) (xy 453.604276 -289.433598) (xy 453.612033 -289.487548)
			(xy 453.612033 -289.542052) (xy 453.604276 -289.596002) (xy 453.58892 -289.648298) (xy 453.566278 -289.697877)
			(xy 453.536811 -289.743729) (xy 453.501118 -289.78492) (xy 453.459926 -289.820613) (xy 453.414074 -289.85008)
			(xy 453.364495 -289.872721) (xy 453.312198 -289.888077) (xy 453.258248 -289.895833) (xy 453.230996 -289.896296)
			(xy 453.203663 -289.895798) (xy 453.149557 -289.887997) (xy 453.097119 -289.872553) (xy 453.047421 -289.849785)
			(xy 453.00148 -289.820157) (xy 452.980552 -289.80257) (xy 452.980044 -289.802062) (xy 452.972952 -289.796483)
			(xy 452.956039 -289.790233) (xy 452.947024 -289.78987) (xy 452.879968 -289.78987) (xy 452.87095 -289.790218)
			(xy 452.854034 -289.796472) (xy 452.846948 -289.802062) (xy 452.84644 -289.80257) (xy 452.825506 -289.820153)
			(xy 452.779572 -289.849793) (xy 452.729876 -289.872572) (xy 452.677437 -289.888022) (xy 452.62333 -289.895827)
			(xy 452.595996 -289.896296) (xy 452.568744 -289.895834) (xy 452.514795 -289.888077) (xy 452.462499 -289.872721)
			(xy 452.412921 -289.850079) (xy 452.36707 -289.820611) (xy 452.325878 -289.784919) (xy 452.290186 -289.743727)
			(xy 452.260719 -289.697876) (xy 452.238078 -289.648297) (xy 452.222722 -289.596001) (xy 452.214966 -289.542052)
			(xy 451.840309 -289.542052) (xy 451.832555 -289.59599) (xy 451.817203 -289.64828) (xy 451.794565 -289.697852)
			(xy 451.765104 -289.743699) (xy 451.729419 -289.784886) (xy 451.688236 -289.820577) (xy 451.642393 -289.850043)
			(xy 451.592823 -289.872686) (xy 451.540535 -289.888045) (xy 451.486594 -289.895807) (xy 451.459346 -289.896296)
			(xy 451.432012 -289.895827) (xy 451.377905 -289.888019) (xy 451.325466 -289.872569) (xy 451.275768 -289.849794)
			(xy 451.229829 -289.82016) (xy 451.208902 -289.80257) (xy 451.208394 -289.802062) (xy 451.201316 -289.796463)
			(xy 451.184393 -289.790225) (xy 451.175374 -289.78987) (xy 451.108318 -289.78987) (xy 451.099303 -289.790242)
			(xy 451.082386 -289.79648) (xy 451.075298 -289.802062) (xy 451.07479 -289.80257) (xy 451.053875 -289.820176)
			(xy 451.007936 -289.849813) (xy 450.958235 -289.872588) (xy 450.905792 -289.888032) (xy 450.851681 -289.89583)
			(xy 450.824346 -289.896296) (xy 450.79709 -289.89586) (xy 450.743132 -289.888108) (xy 450.690827 -289.872756)
			(xy 450.64124 -289.850115) (xy 450.595379 -289.820647) (xy 450.55418 -289.784953) (xy 450.51848 -289.743757)
			(xy 450.489007 -289.697901) (xy 450.46636 -289.648316) (xy 450.451001 -289.596013) (xy 450.443243 -289.542056)
			(xy 431.468868 -289.542056) (xy 431.483407 -289.561404) (xy 431.506278 -289.604981) (xy 431.521862 -289.651662)
			(xy 431.529757 -289.700239) (xy 431.530252 -289.724846) (xy 431.529757 -289.749453) (xy 431.521862 -289.79803)
			(xy 431.506278 -289.844711) (xy 431.483407 -289.888288) (xy 431.453842 -289.927632) (xy 431.418349 -289.961724)
			(xy 431.377846 -289.98968) (xy 431.333384 -290.010778) (xy 431.286113 -290.02447) (xy 431.237258 -290.030402)
			(xy 431.188083 -290.028421) (xy 431.139864 -290.018577) (xy 431.093848 -290.001125) (xy 431.051227 -289.976518)
			(xy 431.013106 -289.945393) (xy 430.980471 -289.908556) (xy 430.954168 -289.86696) (xy 430.934877 -289.821684)
			(xy 430.9231 -289.7739) (xy 430.91914 -289.724846) (xy 430.580292 -289.724846) (xy 430.579797 -289.749453)
			(xy 430.571902 -289.79803) (xy 430.556318 -289.844711) (xy 430.533447 -289.888288) (xy 430.503882 -289.927632)
			(xy 430.468389 -289.961724) (xy 430.427886 -289.98968) (xy 430.383424 -290.010778) (xy 430.336153 -290.02447)
			(xy 430.287298 -290.030402) (xy 430.238123 -290.028421) (xy 430.189904 -290.018577) (xy 430.143888 -290.001125)
			(xy 430.101267 -289.976518) (xy 430.063146 -289.945393) (xy 430.030511 -289.908556) (xy 430.004208 -289.86696)
			(xy 429.984917 -289.821684) (xy 429.97314 -289.7739) (xy 429.96918 -289.724846) (xy 429.630332 -289.724846)
			(xy 429.629837 -289.749453) (xy 429.621942 -289.79803) (xy 429.606358 -289.844711) (xy 429.583487 -289.888288)
			(xy 429.553922 -289.927632) (xy 429.518429 -289.961724) (xy 429.477926 -289.98968) (xy 429.433464 -290.010778)
			(xy 429.386193 -290.02447) (xy 429.337338 -290.030402) (xy 429.288163 -290.028421) (xy 429.239944 -290.018577)
			(xy 429.193928 -290.001125) (xy 429.151307 -289.976518) (xy 429.113186 -289.945393) (xy 429.080551 -289.908556)
			(xy 429.054248 -289.86696) (xy 429.034957 -289.821684) (xy 429.02318 -289.7739) (xy 429.01922 -289.724846)
			(xy 428.680118 -289.724846) (xy 428.679623 -289.749453) (xy 428.671728 -289.79803) (xy 428.656144 -289.844711)
			(xy 428.633273 -289.888288) (xy 428.603708 -289.927632) (xy 428.568215 -289.961724) (xy 428.527712 -289.98968)
			(xy 428.48325 -290.010778) (xy 428.435979 -290.02447) (xy 428.387124 -290.030402) (xy 428.337949 -290.028421)
			(xy 428.28973 -290.018577) (xy 428.243714 -290.001125) (xy 428.201093 -289.976518) (xy 428.162972 -289.945393)
			(xy 428.130337 -289.908556) (xy 428.104034 -289.86696) (xy 428.084743 -289.821684) (xy 428.072966 -289.7739)
			(xy 428.069006 -289.724846) (xy 427.730158 -289.724846) (xy 427.729663 -289.749453) (xy 427.721768 -289.79803)
			(xy 427.706184 -289.844711) (xy 427.683313 -289.888288) (xy 427.653748 -289.927632) (xy 427.618255 -289.961724)
			(xy 427.577752 -289.98968) (xy 427.53329 -290.010778) (xy 427.486019 -290.02447) (xy 427.437164 -290.030402)
			(xy 427.387989 -290.028421) (xy 427.33977 -290.018577) (xy 427.293754 -290.001125) (xy 427.251133 -289.976518)
			(xy 427.213012 -289.945393) (xy 427.180377 -289.908556) (xy 427.154074 -289.86696) (xy 427.134783 -289.821684)
			(xy 427.123006 -289.7739) (xy 427.119046 -289.724846) (xy 426.780198 -289.724846) (xy 426.779703 -289.749453)
			(xy 426.771808 -289.79803) (xy 426.756224 -289.844711) (xy 426.733353 -289.888288) (xy 426.703788 -289.927632)
			(xy 426.668295 -289.961724) (xy 426.627792 -289.98968) (xy 426.58333 -290.010778) (xy 426.536059 -290.02447)
			(xy 426.487204 -290.030402) (xy 426.438029 -290.028421) (xy 426.38981 -290.018577) (xy 426.343794 -290.001125)
			(xy 426.301173 -289.976518) (xy 426.263052 -289.945393) (xy 426.230417 -289.908556) (xy 426.204114 -289.86696)
			(xy 426.184823 -289.821684) (xy 426.173046 -289.7739) (xy 426.169086 -289.724846) (xy 425.830238 -289.724846)
			(xy 425.829743 -289.749453) (xy 425.821848 -289.79803) (xy 425.806264 -289.844711) (xy 425.783393 -289.888288)
			(xy 425.753828 -289.927632) (xy 425.718335 -289.961724) (xy 425.677832 -289.98968) (xy 425.63337 -290.010778)
			(xy 425.586099 -290.02447) (xy 425.537244 -290.030402) (xy 425.488069 -290.028421) (xy 425.43985 -290.018577)
			(xy 425.393834 -290.001125) (xy 425.351213 -289.976518) (xy 425.313092 -289.945393) (xy 425.280457 -289.908556)
			(xy 425.254154 -289.86696) (xy 425.234863 -289.821684) (xy 425.223086 -289.7739) (xy 425.219126 -289.724846)
			(xy 424.880278 -289.724846) (xy 424.879783 -289.749453) (xy 424.871888 -289.79803) (xy 424.856304 -289.844711)
			(xy 424.833433 -289.888288) (xy 424.803868 -289.927632) (xy 424.768375 -289.961724) (xy 424.727872 -289.98968)
			(xy 424.68341 -290.010778) (xy 424.636139 -290.02447) (xy 424.587284 -290.030402) (xy 424.538109 -290.028421)
			(xy 424.48989 -290.018577) (xy 424.443874 -290.001125) (xy 424.401253 -289.976518) (xy 424.363132 -289.945393)
			(xy 424.330497 -289.908556) (xy 424.304194 -289.86696) (xy 424.284903 -289.821684) (xy 424.273126 -289.7739)
			(xy 424.269166 -289.724846) (xy 422.980218 -289.724846) (xy 422.97798 -289.766096) (xy 422.967308 -289.814565)
			(xy 422.948937 -289.86067) (xy 422.923349 -289.903195) (xy 422.891218 -289.941021) (xy 422.853392 -289.973151)
			(xy 422.810866 -289.998739) (xy 422.764761 -290.01711) (xy 422.716292 -290.02778) (xy 422.666734 -290.030469)
			(xy 422.617395 -290.025106) (xy 422.569572 -290.011831) (xy 422.524528 -289.990996) (xy 422.483447 -289.963147)
			(xy 422.447412 -289.92902) (xy 422.417373 -289.889513) (xy 422.394121 -289.845667) (xy 422.378267 -289.798636)
			(xy 422.370231 -289.749661) (xy 422.369742 -289.724846) (xy 422.369924 -289.710663) (xy 422.372592 -289.682423)
			(xy 422.375076 -289.668458) (xy 422.37661 -289.656168) (xy 422.369292 -289.632543) (xy 422.361106 -289.623246)
			(xy 422.30167 -289.56381) (xy 422.297128 -289.559556) (xy 422.286472 -289.553136) (xy 422.280588 -289.55111)
			(xy 422.274627 -289.549493) (xy 422.262298 -289.548842) (xy 422.256204 -289.54984) (xy 422.242237 -289.552311)
			(xy 422.213998 -289.554987) (xy 422.199816 -289.555174) (xy 422.185697 -289.554991) (xy 422.157584 -289.552317)
			(xy 422.143682 -289.54984) (xy 422.131236 -289.547554) (xy 422.10736 -289.55492) (xy 422.02989 -289.63239)
			(xy 422.022524 -289.656266) (xy 422.02481 -289.668712) (xy 422.027272 -289.682616) (xy 422.029944 -289.710727)
			(xy 422.030144 -289.724846) (xy 422.029573 -289.749663) (xy 422.021535 -289.798642) (xy 422.00568 -289.845675)
			(xy 421.982425 -289.889524) (xy 421.952382 -289.929033) (xy 421.916343 -289.963161) (xy 421.875257 -289.991009)
			(xy 421.830208 -290.011843) (xy 421.782381 -290.025115) (xy 421.733038 -290.030474) (xy 421.683477 -290.02778)
			(xy 421.635005 -290.017103) (xy 421.588899 -289.998726) (xy 421.546373 -289.973131) (xy 421.508548 -289.940994)
			(xy 421.476421 -289.90316) (xy 421.450838 -289.860628) (xy 421.432472 -289.814517) (xy 421.421809 -289.766042)
			(xy 421.419128 -289.71648) (xy 421.080016 -289.71648) (xy 421.080184 -289.724846) (xy 421.079689 -289.749453)
			(xy 421.071794 -289.79803) (xy 421.05621 -289.844711) (xy 421.033339 -289.888288) (xy 421.003774 -289.927632)
			(xy 420.968281 -289.961724) (xy 420.927778 -289.98968) (xy 420.883316 -290.010778) (xy 420.836045 -290.02447)
			(xy 420.78719 -290.030402) (xy 420.738015 -290.028421) (xy 420.689796 -290.018577) (xy 420.64378 -290.001125)
			(xy 420.601159 -289.976518) (xy 420.563038 -289.945393) (xy 420.530403 -289.908556) (xy 420.5041 -289.86696)
			(xy 420.484809 -289.821684) (xy 420.473032 -289.7739) (xy 420.469072 -289.724846) (xy 420.130224 -289.724846)
			(xy 420.129729 -289.749453) (xy 420.121834 -289.79803) (xy 420.10625 -289.844711) (xy 420.083379 -289.888288)
			(xy 420.053814 -289.927632) (xy 420.018321 -289.961724) (xy 419.977818 -289.98968) (xy 419.933356 -290.010778)
			(xy 419.886085 -290.02447) (xy 419.83723 -290.030402) (xy 419.788055 -290.028421) (xy 419.739836 -290.018577)
			(xy 419.69382 -290.001125) (xy 419.651199 -289.976518) (xy 419.613078 -289.945393) (xy 419.580443 -289.908556)
			(xy 419.55414 -289.86696) (xy 419.534849 -289.821684) (xy 419.523072 -289.7739) (xy 419.519112 -289.724846)
			(xy 419.180264 -289.724846) (xy 419.179769 -289.749453) (xy 419.171874 -289.79803) (xy 419.15629 -289.844711)
			(xy 419.133419 -289.888288) (xy 419.103854 -289.927632) (xy 419.068361 -289.961724) (xy 419.027858 -289.98968)
			(xy 418.983396 -290.010778) (xy 418.936125 -290.02447) (xy 418.88727 -290.030402) (xy 418.838095 -290.028421)
			(xy 418.789876 -290.018577) (xy 418.74386 -290.001125) (xy 418.701239 -289.976518) (xy 418.663118 -289.945393)
			(xy 418.630483 -289.908556) (xy 418.60418 -289.86696) (xy 418.584889 -289.821684) (xy 418.573112 -289.7739)
			(xy 418.569152 -289.724846) (xy 418.255179 -289.724846) (xy 418.255179 -289.750786) (xy 418.247049 -289.802118)
			(xy 418.230989 -289.851546) (xy 418.207394 -289.897853) (xy 418.176845 -289.939899) (xy 418.140096 -289.976648)
			(xy 418.098049 -290.007196) (xy 418.051742 -290.03079) (xy 418.002314 -290.04685) (xy 417.950982 -290.054979)
			(xy 417.924996 -290.055554) (xy 417.924742 -290.055554) (xy 417.90584 -290.055268) (xy 417.868284 -290.050939)
			(xy 417.849812 -290.046918) (xy 417.838382 -290.044124) (xy 417.81603 -290.049204) (xy 417.744402 -290.1061)
			(xy 417.735687 -290.113677) (xy 417.725639 -290.134443) (xy 417.725098 -290.145978) (xy 417.725098 -290.2458)
			(xy 433.453792 -290.2458) (xy 433.457863 -290.190178) (xy 433.469989 -290.135741) (xy 433.489912 -290.08365)
			(xy 433.517208 -290.035015) (xy 433.551294 -289.990872) (xy 433.591443 -289.952163) (xy 433.636801 -289.919712)
			(xy 433.686401 -289.894211) (xy 433.739185 -289.876204) (xy 433.794028 -289.866074) (xy 433.849762 -289.864037)
			(xy 433.905199 -289.870137) (xy 433.959156 -289.884243) (xy 434.010485 -289.906055) (xy 434.058091 -289.935109)
			(xy 434.100959 -289.970784) (xy 434.138176 -290.012321) (xy 434.168949 -290.058834) (xy 434.192621 -290.109331)
			(xy 434.208689 -290.162738) (xy 434.216809 -290.217914) (xy 434.21716 -290.237164) (xy 437.464452 -290.237164)
			(xy 437.468523 -290.181542) (xy 437.480649 -290.127105) (xy 437.500572 -290.075014) (xy 437.527868 -290.026379)
			(xy 437.561954 -289.982236) (xy 437.602103 -289.943527) (xy 437.647461 -289.911076) (xy 437.697061 -289.885575)
			(xy 437.749845 -289.867568) (xy 437.804688 -289.857438) (xy 437.860422 -289.855401) (xy 437.915859 -289.861501)
			(xy 437.969816 -289.875607) (xy 438.021145 -289.897419) (xy 438.068751 -289.926473) (xy 438.111619 -289.962148)
			(xy 438.148836 -290.003685) (xy 438.179609 -290.050198) (xy 438.203281 -290.100695) (xy 438.219349 -290.154102)
			(xy 438.227469 -290.209278) (xy 438.227978 -290.237164) (xy 438.227469 -290.26505) (xy 438.219349 -290.320226)
			(xy 438.203281 -290.373633) (xy 438.179609 -290.42413) (xy 438.148836 -290.470643) (xy 438.111619 -290.51218)
			(xy 438.068751 -290.547855) (xy 438.021145 -290.576909) (xy 437.969816 -290.598721) (xy 437.915859 -290.612827)
			(xy 437.860422 -290.618927) (xy 437.804688 -290.61689) (xy 437.749845 -290.60676) (xy 437.697061 -290.588753)
			(xy 437.647461 -290.563252) (xy 437.602103 -290.530801) (xy 437.561954 -290.492092) (xy 437.527868 -290.447949)
			(xy 437.500572 -290.399314) (xy 437.480649 -290.347223) (xy 437.468523 -290.292786) (xy 437.464452 -290.237164)
			(xy 434.21716 -290.237164) (xy 434.217318 -290.2458) (xy 434.216809 -290.273686) (xy 434.208689 -290.328862)
			(xy 434.192621 -290.382269) (xy 434.168949 -290.432766) (xy 434.138176 -290.479279) (xy 434.100959 -290.520816)
			(xy 434.058091 -290.556491) (xy 434.010485 -290.585545) (xy 433.959156 -290.607357) (xy 433.905199 -290.621463)
			(xy 433.849762 -290.627563) (xy 433.794028 -290.625526) (xy 433.739185 -290.615396) (xy 433.686401 -290.597389)
			(xy 433.636801 -290.571888) (xy 433.591443 -290.539437) (xy 433.551294 -290.500728) (xy 433.517208 -290.456585)
			(xy 433.489912 -290.40795) (xy 433.469989 -290.355859) (xy 433.457863 -290.301422) (xy 433.453792 -290.2458)
			(xy 417.725098 -290.2458) (xy 417.725098 -290.25342) (xy 417.725558 -290.263297) (xy 417.733002 -290.281595)
			(xy 417.739576 -290.28898) (xy 417.73983 -290.289234) (xy 417.74364 -290.293044) (xy 417.766754 -290.311332)
			(xy 417.81603 -290.350448) (xy 417.838382 -290.355528) (xy 417.849812 -290.352734) (xy 417.86828 -290.348688)
			(xy 417.905838 -290.344357) (xy 417.924742 -290.344098) (xy 417.924996 -290.344098) (xy 417.950985 -290.344581)
			(xy 418.002323 -290.352711) (xy 418.051757 -290.368773) (xy 418.09807 -290.39237) (xy 418.140121 -290.422922)
			(xy 418.176876 -290.459675) (xy 418.207428 -290.501726) (xy 418.231025 -290.548039) (xy 418.247088 -290.597473)
			(xy 418.255219 -290.648811) (xy 418.255219 -290.674806) (xy 418.569152 -290.674806) (xy 418.573112 -290.625752)
			(xy 418.584889 -290.577968) (xy 418.60418 -290.532692) (xy 418.630483 -290.491096) (xy 418.663118 -290.454259)
			(xy 418.701239 -290.423134) (xy 418.74386 -290.398527) (xy 418.789876 -290.381075) (xy 418.838095 -290.371231)
			(xy 418.88727 -290.36925) (xy 418.936125 -290.375182) (xy 418.983396 -290.388874) (xy 419.027858 -290.409972)
			(xy 419.068361 -290.437928) (xy 419.103854 -290.47202) (xy 419.133419 -290.511364) (xy 419.15629 -290.554941)
			(xy 419.171874 -290.601622) (xy 419.179769 -290.650199) (xy 419.180264 -290.674806) (xy 419.519112 -290.674806)
			(xy 419.523072 -290.625752) (xy 419.534849 -290.577968) (xy 419.55414 -290.532692) (xy 419.580443 -290.491096)
			(xy 419.613078 -290.454259) (xy 419.651199 -290.423134) (xy 419.69382 -290.398527) (xy 419.739836 -290.381075)
			(xy 419.788055 -290.371231) (xy 419.83723 -290.36925) (xy 419.886085 -290.375182) (xy 419.933356 -290.388874)
			(xy 419.977818 -290.409972) (xy 420.018321 -290.437928) (xy 420.053814 -290.47202) (xy 420.083379 -290.511364)
			(xy 420.10625 -290.554941) (xy 420.121834 -290.601622) (xy 420.129729 -290.650199) (xy 420.130224 -290.674806)
			(xy 420.469072 -290.674806) (xy 420.473032 -290.625752) (xy 420.484809 -290.577968) (xy 420.5041 -290.532692)
			(xy 420.530403 -290.491096) (xy 420.563038 -290.454259) (xy 420.601159 -290.423134) (xy 420.64378 -290.398527)
			(xy 420.689796 -290.381075) (xy 420.738015 -290.371231) (xy 420.78719 -290.36925) (xy 420.836045 -290.375182)
			(xy 420.883316 -290.388874) (xy 420.927778 -290.409972) (xy 420.968281 -290.437928) (xy 421.003774 -290.47202)
			(xy 421.033339 -290.511364) (xy 421.05621 -290.554941) (xy 421.071794 -290.601622) (xy 421.079689 -290.650199)
			(xy 421.080184 -290.674806) (xy 421.419032 -290.674806) (xy 421.422992 -290.625752) (xy 421.434769 -290.577968)
			(xy 421.45406 -290.532692) (xy 421.480363 -290.491096) (xy 421.512998 -290.454259) (xy 421.551119 -290.423134)
			(xy 421.59374 -290.398527) (xy 421.639756 -290.381075) (xy 421.687975 -290.371231) (xy 421.73715 -290.36925)
			(xy 421.786005 -290.375182) (xy 421.833276 -290.388874) (xy 421.877738 -290.409972) (xy 421.918241 -290.437928)
			(xy 421.953734 -290.47202) (xy 421.983299 -290.511364) (xy 422.00617 -290.554941) (xy 422.021754 -290.601622)
			(xy 422.029649 -290.650199) (xy 422.030144 -290.674806) (xy 422.368992 -290.674806) (xy 422.372952 -290.625752)
			(xy 422.384729 -290.577968) (xy 422.40402 -290.532692) (xy 422.430323 -290.491096) (xy 422.462958 -290.454259)
			(xy 422.501079 -290.423134) (xy 422.5437 -290.398527) (xy 422.589716 -290.381075) (xy 422.637935 -290.371231)
			(xy 422.68711 -290.36925) (xy 422.735965 -290.375182) (xy 422.783236 -290.388874) (xy 422.827698 -290.409972)
			(xy 422.868201 -290.437928) (xy 422.903694 -290.47202) (xy 422.933259 -290.511364) (xy 422.95613 -290.554941)
			(xy 422.971714 -290.601622) (xy 422.979609 -290.650199) (xy 422.980104 -290.674806) (xy 423.319206 -290.674806)
			(xy 423.323166 -290.625752) (xy 423.334943 -290.577968) (xy 423.354234 -290.532692) (xy 423.380537 -290.491096)
			(xy 423.413172 -290.454259) (xy 423.451293 -290.423134) (xy 423.493914 -290.398527) (xy 423.53993 -290.381075)
			(xy 423.588149 -290.371231) (xy 423.637324 -290.36925) (xy 423.686179 -290.375182) (xy 423.73345 -290.388874)
			(xy 423.777912 -290.409972) (xy 423.818415 -290.437928) (xy 423.853908 -290.47202) (xy 423.883473 -290.511364)
			(xy 423.906344 -290.554941) (xy 423.921928 -290.601622) (xy 423.929823 -290.650199) (xy 423.930318 -290.674806)
			(xy 424.269166 -290.674806) (xy 424.273126 -290.625752) (xy 424.284903 -290.577968) (xy 424.304194 -290.532692)
			(xy 424.330497 -290.491096) (xy 424.363132 -290.454259) (xy 424.401253 -290.423134) (xy 424.443874 -290.398527)
			(xy 424.48989 -290.381075) (xy 424.538109 -290.371231) (xy 424.587284 -290.36925) (xy 424.636139 -290.375182)
			(xy 424.68341 -290.388874) (xy 424.727872 -290.409972) (xy 424.768375 -290.437928) (xy 424.803868 -290.47202)
			(xy 424.833433 -290.511364) (xy 424.856304 -290.554941) (xy 424.871888 -290.601622) (xy 424.879783 -290.650199)
			(xy 424.880278 -290.674806) (xy 425.219126 -290.674806) (xy 425.223086 -290.625752) (xy 425.234863 -290.577968)
			(xy 425.254154 -290.532692) (xy 425.280457 -290.491096) (xy 425.313092 -290.454259) (xy 425.351213 -290.423134)
			(xy 425.393834 -290.398527) (xy 425.43985 -290.381075) (xy 425.488069 -290.371231) (xy 425.537244 -290.36925)
			(xy 425.586099 -290.375182) (xy 425.63337 -290.388874) (xy 425.677832 -290.409972) (xy 425.718335 -290.437928)
			(xy 425.753828 -290.47202) (xy 425.783393 -290.511364) (xy 425.806264 -290.554941) (xy 425.821848 -290.601622)
			(xy 425.829743 -290.650199) (xy 425.830238 -290.674806) (xy 426.169086 -290.674806) (xy 426.173046 -290.625752)
			(xy 426.184823 -290.577968) (xy 426.204114 -290.532692) (xy 426.230417 -290.491096) (xy 426.263052 -290.454259)
			(xy 426.301173 -290.423134) (xy 426.343794 -290.398527) (xy 426.38981 -290.381075) (xy 426.438029 -290.371231)
			(xy 426.487204 -290.36925) (xy 426.536059 -290.375182) (xy 426.58333 -290.388874) (xy 426.627792 -290.409972)
			(xy 426.668295 -290.437928) (xy 426.703788 -290.47202) (xy 426.733353 -290.511364) (xy 426.756224 -290.554941)
			(xy 426.771808 -290.601622) (xy 426.779703 -290.650199) (xy 426.780198 -290.674806) (xy 427.119046 -290.674806)
			(xy 427.123006 -290.625752) (xy 427.134783 -290.577968) (xy 427.154074 -290.532692) (xy 427.180377 -290.491096)
			(xy 427.213012 -290.454259) (xy 427.251133 -290.423134) (xy 427.293754 -290.398527) (xy 427.33977 -290.381075)
			(xy 427.387989 -290.371231) (xy 427.437164 -290.36925) (xy 427.486019 -290.375182) (xy 427.53329 -290.388874)
			(xy 427.577752 -290.409972) (xy 427.618255 -290.437928) (xy 427.653748 -290.47202) (xy 427.683313 -290.511364)
			(xy 427.706184 -290.554941) (xy 427.721768 -290.601622) (xy 427.729663 -290.650199) (xy 427.730158 -290.674806)
			(xy 428.069006 -290.674806) (xy 428.072966 -290.625752) (xy 428.084743 -290.577968) (xy 428.104034 -290.532692)
			(xy 428.130337 -290.491096) (xy 428.162972 -290.454259) (xy 428.201093 -290.423134) (xy 428.243714 -290.398527)
			(xy 428.28973 -290.381075) (xy 428.337949 -290.371231) (xy 428.387124 -290.36925) (xy 428.435979 -290.375182)
			(xy 428.48325 -290.388874) (xy 428.527712 -290.409972) (xy 428.568215 -290.437928) (xy 428.603708 -290.47202)
			(xy 428.633273 -290.511364) (xy 428.656144 -290.554941) (xy 428.671728 -290.601622) (xy 428.679623 -290.650199)
			(xy 428.680118 -290.674806) (xy 429.01922 -290.674806) (xy 429.02318 -290.625752) (xy 429.034957 -290.577968)
			(xy 429.054248 -290.532692) (xy 429.080551 -290.491096) (xy 429.113186 -290.454259) (xy 429.151307 -290.423134)
			(xy 429.193928 -290.398527) (xy 429.239944 -290.381075) (xy 429.288163 -290.371231) (xy 429.337338 -290.36925)
			(xy 429.386193 -290.375182) (xy 429.433464 -290.388874) (xy 429.477926 -290.409972) (xy 429.518429 -290.437928)
			(xy 429.553922 -290.47202) (xy 429.583487 -290.511364) (xy 429.606358 -290.554941) (xy 429.621942 -290.601622)
			(xy 429.629837 -290.650199) (xy 429.630332 -290.674806) (xy 429.96918 -290.674806) (xy 429.97314 -290.625752)
			(xy 429.984917 -290.577968) (xy 430.004208 -290.532692) (xy 430.030511 -290.491096) (xy 430.063146 -290.454259)
			(xy 430.101267 -290.423134) (xy 430.143888 -290.398527) (xy 430.189904 -290.381075) (xy 430.238123 -290.371231)
			(xy 430.287298 -290.36925) (xy 430.336153 -290.375182) (xy 430.383424 -290.388874) (xy 430.427886 -290.409972)
			(xy 430.468389 -290.437928) (xy 430.503882 -290.47202) (xy 430.533447 -290.511364) (xy 430.556318 -290.554941)
			(xy 430.571902 -290.601622) (xy 430.579797 -290.650199) (xy 430.580292 -290.674806) (xy 430.91914 -290.674806)
			(xy 430.9231 -290.625752) (xy 430.934877 -290.577968) (xy 430.954168 -290.532692) (xy 430.980471 -290.491096)
			(xy 431.013106 -290.454259) (xy 431.051227 -290.423134) (xy 431.093848 -290.398527) (xy 431.139864 -290.381075)
			(xy 431.188083 -290.371231) (xy 431.237258 -290.36925) (xy 431.286113 -290.375182) (xy 431.333384 -290.388874)
			(xy 431.377846 -290.409972) (xy 431.418349 -290.437928) (xy 431.453842 -290.47202) (xy 431.483407 -290.511364)
			(xy 431.506278 -290.554941) (xy 431.521862 -290.601622) (xy 431.529757 -290.650199) (xy 431.530252 -290.674806)
			(xy 431.529757 -290.699413) (xy 431.521862 -290.74799) (xy 431.506278 -290.794671) (xy 431.485192 -290.834847)
			(xy 458.605926 -290.834847) (xy 458.605926 -290.780353) (xy 458.613681 -290.726413) (xy 458.629034 -290.674125)
			(xy 458.651672 -290.624555) (xy 458.681133 -290.578711) (xy 458.716819 -290.537526) (xy 458.758003 -290.501839)
			(xy 458.803846 -290.472376) (xy 458.853416 -290.449738) (xy 458.905703 -290.434384) (xy 458.959643 -290.426627)
			(xy 458.98689 -290.42614) (xy 459.01426 -290.426602) (xy 459.06844 -290.434419) (xy 459.120944 -290.449909)
			(xy 459.17069 -290.472752) (xy 459.216657 -290.502478) (xy 459.237588 -290.52012) (xy 459.237842 -290.520374)
			(xy 459.244935 -290.525951) (xy 459.261847 -290.532202) (xy 459.270862 -290.532566) (xy 459.337918 -290.532566)
			(xy 459.346937 -290.532225) (xy 459.363854 -290.525967) (xy 459.370938 -290.520374) (xy 459.371446 -290.519866)
			(xy 459.392377 -290.50228) (xy 459.438313 -290.472642) (xy 459.48801 -290.449865) (xy 459.540449 -290.434415)
			(xy 459.594556 -290.42661) (xy 459.62189 -290.42614) (xy 459.649147 -290.426506) (xy 459.703106 -290.434263)
			(xy 459.755411 -290.44962) (xy 459.804999 -290.472265) (xy 459.850859 -290.501736) (xy 459.892058 -290.537435)
			(xy 459.927758 -290.578633) (xy 459.95723 -290.624492) (xy 459.979876 -290.674079) (xy 459.995235 -290.726385)
			(xy 460.002993 -290.780343) (xy 460.002993 -290.834847) (xy 460.345826 -290.834847) (xy 460.345826 -290.780353)
			(xy 460.353581 -290.726413) (xy 460.368934 -290.674125) (xy 460.391572 -290.624555) (xy 460.421033 -290.578711)
			(xy 460.456719 -290.537526) (xy 460.497903 -290.501839) (xy 460.543746 -290.472376) (xy 460.593316 -290.449738)
			(xy 460.645603 -290.434384) (xy 460.699543 -290.426627) (xy 460.72679 -290.42614) (xy 460.75416 -290.426602)
			(xy 460.80834 -290.434419) (xy 460.860844 -290.449909) (xy 460.91059 -290.472752) (xy 460.956557 -290.502478)
			(xy 460.977488 -290.52012) (xy 460.977742 -290.520374) (xy 460.984835 -290.525951) (xy 461.001747 -290.532202)
			(xy 461.010762 -290.532566) (xy 461.077818 -290.532566) (xy 461.086837 -290.532225) (xy 461.103754 -290.525967)
			(xy 461.110838 -290.520374) (xy 461.111346 -290.519866) (xy 461.132277 -290.50228) (xy 461.178213 -290.472642)
			(xy 461.22791 -290.449865) (xy 461.280349 -290.434415) (xy 461.334456 -290.42661) (xy 461.36179 -290.42614)
			(xy 461.389047 -290.426506) (xy 461.443006 -290.434263) (xy 461.495311 -290.44962) (xy 461.544899 -290.472265)
			(xy 461.590759 -290.501736) (xy 461.631958 -290.537435) (xy 461.667658 -290.578633) (xy 461.69713 -290.624492)
			(xy 461.719776 -290.674079) (xy 461.735135 -290.726385) (xy 461.742893 -290.780343) (xy 461.742893 -290.834857)
			(xy 461.735135 -290.888815) (xy 461.719776 -290.941121) (xy 461.69713 -290.990708) (xy 461.667658 -291.036567)
			(xy 461.631958 -291.077765) (xy 461.590759 -291.113464) (xy 461.544899 -291.142935) (xy 461.495311 -291.16558)
			(xy 461.443006 -291.180937) (xy 461.389047 -291.188694) (xy 461.36179 -291.189156) (xy 461.334457 -291.188671)
			(xy 461.28035 -291.180868) (xy 461.227911 -291.165422) (xy 461.178213 -291.14265) (xy 461.132273 -291.113019)
			(xy 461.111346 -291.09543) (xy 461.110838 -291.094922) (xy 461.103751 -291.089336) (xy 461.086834 -291.083091)
			(xy 461.077818 -291.08273) (xy 461.010762 -291.08273) (xy 461.001742 -291.083062) (xy 460.984825 -291.089326)
			(xy 460.977742 -291.094922) (xy 460.977234 -291.09543) (xy 460.95631 -291.113025) (xy 460.910372 -291.142662)
			(xy 460.860674 -291.165437) (xy 460.808233 -291.180885) (xy 460.754124 -291.188687) (xy 460.72679 -291.189156)
			(xy 460.699543 -291.188573) (xy 460.645603 -291.180816) (xy 460.593316 -291.165462) (xy 460.543746 -291.142824)
			(xy 460.497903 -291.113361) (xy 460.456719 -291.077674) (xy 460.421033 -291.036489) (xy 460.391572 -290.990645)
			(xy 460.368934 -290.941075) (xy 460.353581 -290.888787) (xy 460.345826 -290.834847) (xy 460.002993 -290.834847)
			(xy 460.002993 -290.834857) (xy 459.995235 -290.888815) (xy 459.979876 -290.941121) (xy 459.95723 -290.990708)
			(xy 459.927758 -291.036567) (xy 459.892058 -291.077765) (xy 459.850859 -291.113464) (xy 459.804999 -291.142935)
			(xy 459.755411 -291.16558) (xy 459.703106 -291.180937) (xy 459.649147 -291.188694) (xy 459.62189 -291.189156)
			(xy 459.594557 -291.188671) (xy 459.54045 -291.180868) (xy 459.488011 -291.165422) (xy 459.438313 -291.14265)
			(xy 459.392373 -291.113019) (xy 459.371446 -291.09543) (xy 459.370938 -291.094922) (xy 459.363851 -291.089336)
			(xy 459.346934 -291.083091) (xy 459.337918 -291.08273) (xy 459.270862 -291.08273) (xy 459.261842 -291.083062)
			(xy 459.244925 -291.089326) (xy 459.237842 -291.094922) (xy 459.237334 -291.09543) (xy 459.21641 -291.113025)
			(xy 459.170472 -291.142662) (xy 459.120774 -291.165437) (xy 459.068333 -291.180885) (xy 459.014224 -291.188687)
			(xy 458.98689 -291.189156) (xy 458.959643 -291.188573) (xy 458.905703 -291.180816) (xy 458.853416 -291.165462)
			(xy 458.803846 -291.142824) (xy 458.758003 -291.113361) (xy 458.716819 -291.077674) (xy 458.681133 -291.036489)
			(xy 458.651672 -290.990645) (xy 458.629034 -290.941075) (xy 458.613681 -290.888787) (xy 458.605926 -290.834847)
			(xy 431.485192 -290.834847) (xy 431.483407 -290.838248) (xy 431.453842 -290.877592) (xy 431.418349 -290.911684)
			(xy 431.377846 -290.93964) (xy 431.333384 -290.960738) (xy 431.286113 -290.97443) (xy 431.237258 -290.980362)
			(xy 431.188083 -290.978381) (xy 431.139864 -290.968537) (xy 431.093848 -290.951085) (xy 431.051227 -290.926478)
			(xy 431.013106 -290.895353) (xy 430.980471 -290.858516) (xy 430.954168 -290.81692) (xy 430.934877 -290.771644)
			(xy 430.9231 -290.72386) (xy 430.91914 -290.674806) (xy 430.580292 -290.674806) (xy 430.579797 -290.699413)
			(xy 430.571902 -290.74799) (xy 430.556318 -290.794671) (xy 430.533447 -290.838248) (xy 430.503882 -290.877592)
			(xy 430.468389 -290.911684) (xy 430.427886 -290.93964) (xy 430.383424 -290.960738) (xy 430.336153 -290.97443)
			(xy 430.287298 -290.980362) (xy 430.238123 -290.978381) (xy 430.189904 -290.968537) (xy 430.143888 -290.951085)
			(xy 430.101267 -290.926478) (xy 430.063146 -290.895353) (xy 430.030511 -290.858516) (xy 430.004208 -290.81692)
			(xy 429.984917 -290.771644) (xy 429.97314 -290.72386) (xy 429.96918 -290.674806) (xy 429.630332 -290.674806)
			(xy 429.629837 -290.699413) (xy 429.621942 -290.74799) (xy 429.606358 -290.794671) (xy 429.583487 -290.838248)
			(xy 429.553922 -290.877592) (xy 429.518429 -290.911684) (xy 429.477926 -290.93964) (xy 429.433464 -290.960738)
			(xy 429.386193 -290.97443) (xy 429.337338 -290.980362) (xy 429.288163 -290.978381) (xy 429.239944 -290.968537)
			(xy 429.193928 -290.951085) (xy 429.151307 -290.926478) (xy 429.113186 -290.895353) (xy 429.080551 -290.858516)
			(xy 429.054248 -290.81692) (xy 429.034957 -290.771644) (xy 429.02318 -290.72386) (xy 429.01922 -290.674806)
			(xy 428.680118 -290.674806) (xy 428.679623 -290.699413) (xy 428.671728 -290.74799) (xy 428.656144 -290.794671)
			(xy 428.633273 -290.838248) (xy 428.603708 -290.877592) (xy 428.568215 -290.911684) (xy 428.527712 -290.93964)
			(xy 428.48325 -290.960738) (xy 428.435979 -290.97443) (xy 428.387124 -290.980362) (xy 428.337949 -290.978381)
			(xy 428.28973 -290.968537) (xy 428.243714 -290.951085) (xy 428.201093 -290.926478) (xy 428.162972 -290.895353)
			(xy 428.130337 -290.858516) (xy 428.104034 -290.81692) (xy 428.084743 -290.771644) (xy 428.072966 -290.72386)
			(xy 428.069006 -290.674806) (xy 427.730158 -290.674806) (xy 427.729663 -290.699413) (xy 427.721768 -290.74799)
			(xy 427.706184 -290.794671) (xy 427.683313 -290.838248) (xy 427.653748 -290.877592) (xy 427.618255 -290.911684)
			(xy 427.577752 -290.93964) (xy 427.53329 -290.960738) (xy 427.486019 -290.97443) (xy 427.437164 -290.980362)
			(xy 427.387989 -290.978381) (xy 427.33977 -290.968537) (xy 427.293754 -290.951085) (xy 427.251133 -290.926478)
			(xy 427.213012 -290.895353) (xy 427.180377 -290.858516) (xy 427.154074 -290.81692) (xy 427.134783 -290.771644)
			(xy 427.123006 -290.72386) (xy 427.119046 -290.674806) (xy 426.780198 -290.674806) (xy 426.779703 -290.699413)
			(xy 426.771808 -290.74799) (xy 426.756224 -290.794671) (xy 426.733353 -290.838248) (xy 426.703788 -290.877592)
			(xy 426.668295 -290.911684) (xy 426.627792 -290.93964) (xy 426.58333 -290.960738) (xy 426.536059 -290.97443)
			(xy 426.487204 -290.980362) (xy 426.438029 -290.978381) (xy 426.38981 -290.968537) (xy 426.343794 -290.951085)
			(xy 426.301173 -290.926478) (xy 426.263052 -290.895353) (xy 426.230417 -290.858516) (xy 426.204114 -290.81692)
			(xy 426.184823 -290.771644) (xy 426.173046 -290.72386) (xy 426.169086 -290.674806) (xy 425.830238 -290.674806)
			(xy 425.829743 -290.699413) (xy 425.821848 -290.74799) (xy 425.806264 -290.794671) (xy 425.783393 -290.838248)
			(xy 425.753828 -290.877592) (xy 425.718335 -290.911684) (xy 425.677832 -290.93964) (xy 425.63337 -290.960738)
			(xy 425.586099 -290.97443) (xy 425.537244 -290.980362) (xy 425.488069 -290.978381) (xy 425.43985 -290.968537)
			(xy 425.393834 -290.951085) (xy 425.351213 -290.926478) (xy 425.313092 -290.895353) (xy 425.280457 -290.858516)
			(xy 425.254154 -290.81692) (xy 425.234863 -290.771644) (xy 425.223086 -290.72386) (xy 425.219126 -290.674806)
			(xy 424.880278 -290.674806) (xy 424.879783 -290.699413) (xy 424.871888 -290.74799) (xy 424.856304 -290.794671)
			(xy 424.833433 -290.838248) (xy 424.803868 -290.877592) (xy 424.768375 -290.911684) (xy 424.727872 -290.93964)
			(xy 424.68341 -290.960738) (xy 424.636139 -290.97443) (xy 424.587284 -290.980362) (xy 424.538109 -290.978381)
			(xy 424.48989 -290.968537) (xy 424.443874 -290.951085) (xy 424.401253 -290.926478) (xy 424.363132 -290.895353)
			(xy 424.330497 -290.858516) (xy 424.304194 -290.81692) (xy 424.284903 -290.771644) (xy 424.273126 -290.72386)
			(xy 424.269166 -290.674806) (xy 423.930318 -290.674806) (xy 423.929823 -290.699413) (xy 423.921928 -290.74799)
			(xy 423.906344 -290.794671) (xy 423.883473 -290.838248) (xy 423.853908 -290.877592) (xy 423.818415 -290.911684)
			(xy 423.777912 -290.93964) (xy 423.73345 -290.960738) (xy 423.686179 -290.97443) (xy 423.637324 -290.980362)
			(xy 423.588149 -290.978381) (xy 423.53993 -290.968537) (xy 423.493914 -290.951085) (xy 423.451293 -290.926478)
			(xy 423.413172 -290.895353) (xy 423.380537 -290.858516) (xy 423.354234 -290.81692) (xy 423.334943 -290.771644)
			(xy 423.323166 -290.72386) (xy 423.319206 -290.674806) (xy 422.980104 -290.674806) (xy 422.979609 -290.699413)
			(xy 422.971714 -290.74799) (xy 422.95613 -290.794671) (xy 422.933259 -290.838248) (xy 422.903694 -290.877592)
			(xy 422.868201 -290.911684) (xy 422.827698 -290.93964) (xy 422.783236 -290.960738) (xy 422.735965 -290.97443)
			(xy 422.68711 -290.980362) (xy 422.637935 -290.978381) (xy 422.589716 -290.968537) (xy 422.5437 -290.951085)
			(xy 422.501079 -290.926478) (xy 422.462958 -290.895353) (xy 422.430323 -290.858516) (xy 422.40402 -290.81692)
			(xy 422.384729 -290.771644) (xy 422.372952 -290.72386) (xy 422.368992 -290.674806) (xy 422.030144 -290.674806)
			(xy 422.029649 -290.699413) (xy 422.021754 -290.74799) (xy 422.00617 -290.794671) (xy 421.983299 -290.838248)
			(xy 421.953734 -290.877592) (xy 421.918241 -290.911684) (xy 421.877738 -290.93964) (xy 421.833276 -290.960738)
			(xy 421.786005 -290.97443) (xy 421.73715 -290.980362) (xy 421.687975 -290.978381) (xy 421.639756 -290.968537)
			(xy 421.59374 -290.951085) (xy 421.551119 -290.926478) (xy 421.512998 -290.895353) (xy 421.480363 -290.858516)
			(xy 421.45406 -290.81692) (xy 421.434769 -290.771644) (xy 421.422992 -290.72386) (xy 421.419032 -290.674806)
			(xy 421.080184 -290.674806) (xy 421.079689 -290.699413) (xy 421.071794 -290.74799) (xy 421.05621 -290.794671)
			(xy 421.033339 -290.838248) (xy 421.003774 -290.877592) (xy 420.968281 -290.911684) (xy 420.927778 -290.93964)
			(xy 420.883316 -290.960738) (xy 420.836045 -290.97443) (xy 420.78719 -290.980362) (xy 420.738015 -290.978381)
			(xy 420.689796 -290.968537) (xy 420.64378 -290.951085) (xy 420.601159 -290.926478) (xy 420.563038 -290.895353)
			(xy 420.530403 -290.858516) (xy 420.5041 -290.81692) (xy 420.484809 -290.771644) (xy 420.473032 -290.72386)
			(xy 420.469072 -290.674806) (xy 420.130224 -290.674806) (xy 420.129729 -290.699413) (xy 420.121834 -290.74799)
			(xy 420.10625 -290.794671) (xy 420.083379 -290.838248) (xy 420.053814 -290.877592) (xy 420.018321 -290.911684)
			(xy 419.977818 -290.93964) (xy 419.933356 -290.960738) (xy 419.886085 -290.97443) (xy 419.83723 -290.980362)
			(xy 419.788055 -290.978381) (xy 419.739836 -290.968537) (xy 419.69382 -290.951085) (xy 419.651199 -290.926478)
			(xy 419.613078 -290.895353) (xy 419.580443 -290.858516) (xy 419.55414 -290.81692) (xy 419.534849 -290.771644)
			(xy 419.523072 -290.72386) (xy 419.519112 -290.674806) (xy 419.180264 -290.674806) (xy 419.179769 -290.699413)
			(xy 419.171874 -290.74799) (xy 419.15629 -290.794671) (xy 419.133419 -290.838248) (xy 419.103854 -290.877592)
			(xy 419.068361 -290.911684) (xy 419.027858 -290.93964) (xy 418.983396 -290.960738) (xy 418.936125 -290.97443)
			(xy 418.88727 -290.980362) (xy 418.838095 -290.978381) (xy 418.789876 -290.968537) (xy 418.74386 -290.951085)
			(xy 418.701239 -290.926478) (xy 418.663118 -290.895353) (xy 418.630483 -290.858516) (xy 418.60418 -290.81692)
			(xy 418.584889 -290.771644) (xy 418.573112 -290.72386) (xy 418.569152 -290.674806) (xy 418.255219 -290.674806)
			(xy 418.255219 -290.700789) (xy 418.247088 -290.752127) (xy 418.231025 -290.801561) (xy 418.207428 -290.847874)
			(xy 418.176876 -290.889925) (xy 418.140121 -290.926678) (xy 418.09807 -290.95723) (xy 418.051757 -290.980827)
			(xy 418.002323 -290.996889) (xy 417.950985 -291.005019) (xy 417.924996 -291.005514) (xy 417.924742 -291.005514)
			(xy 417.90584 -291.005228) (xy 417.868284 -291.000898) (xy 417.849812 -290.996878) (xy 417.838382 -290.994084)
			(xy 417.81603 -290.999164) (xy 417.744402 -291.05606) (xy 417.735681 -291.063634) (xy 417.725617 -291.0844)
			(xy 417.725098 -291.095938) (xy 417.725098 -291.20338) (xy 417.725569 -291.213252) (xy 417.733028 -291.231535)
			(xy 417.739351 -291.238686) (xy 434.296564 -291.238686) (xy 434.300635 -291.183064) (xy 434.312761 -291.128627)
			(xy 434.332684 -291.076536) (xy 434.35998 -291.027901) (xy 434.394066 -290.983758) (xy 434.434215 -290.945049)
			(xy 434.479573 -290.912598) (xy 434.529173 -290.887097) (xy 434.581957 -290.86909) (xy 434.6368 -290.85896)
			(xy 434.692534 -290.856923) (xy 434.747971 -290.863023) (xy 434.801928 -290.877129) (xy 434.853257 -290.898941)
			(xy 434.900863 -290.927995) (xy 434.943731 -290.96367) (xy 434.980948 -291.005207) (xy 435.011721 -291.05172)
			(xy 435.035393 -291.102217) (xy 435.051461 -291.155624) (xy 435.059581 -291.2108) (xy 435.06009 -291.238686)
			(xy 435.059581 -291.266572) (xy 435.051461 -291.321748) (xy 435.035393 -291.375155) (xy 435.011721 -291.425652)
			(xy 434.980948 -291.472165) (xy 434.943731 -291.513702) (xy 434.900863 -291.549377) (xy 434.853257 -291.578431)
			(xy 434.821326 -291.592) (xy 436.741822 -291.592) (xy 436.745893 -291.536378) (xy 436.758019 -291.481941)
			(xy 436.777942 -291.42985) (xy 436.805238 -291.381215) (xy 436.839324 -291.337072) (xy 436.879473 -291.298363)
			(xy 436.924831 -291.265912) (xy 436.974431 -291.240411) (xy 437.027215 -291.222404) (xy 437.082058 -291.212274)
			(xy 437.137792 -291.210237) (xy 437.193229 -291.216337) (xy 437.247186 -291.230443) (xy 437.298515 -291.252255)
			(xy 437.346121 -291.281309) (xy 437.388989 -291.316984) (xy 437.426206 -291.358521) (xy 437.456979 -291.405034)
			(xy 437.480651 -291.455531) (xy 437.496719 -291.508938) (xy 437.504839 -291.564114) (xy 437.505348 -291.592)
			(xy 437.504839 -291.619886) (xy 437.496719 -291.675062) (xy 437.480651 -291.728469) (xy 437.456979 -291.778966)
			(xy 437.426206 -291.825479) (xy 437.388989 -291.867016) (xy 437.346121 -291.902691) (xy 437.298515 -291.931745)
			(xy 437.247186 -291.953557) (xy 437.193229 -291.967663) (xy 437.137792 -291.973763) (xy 437.082058 -291.971726)
			(xy 437.027215 -291.961596) (xy 436.974431 -291.943589) (xy 436.924831 -291.918088) (xy 436.879473 -291.885637)
			(xy 436.839324 -291.846928) (xy 436.805238 -291.802785) (xy 436.777942 -291.75415) (xy 436.758019 -291.702059)
			(xy 436.745893 -291.647622) (xy 436.741822 -291.592) (xy 434.821326 -291.592) (xy 434.801928 -291.600243)
			(xy 434.747971 -291.614349) (xy 434.692534 -291.620449) (xy 434.6368 -291.618412) (xy 434.581957 -291.608282)
			(xy 434.529173 -291.590275) (xy 434.479573 -291.564774) (xy 434.434215 -291.532323) (xy 434.394066 -291.493614)
			(xy 434.35998 -291.449471) (xy 434.332684 -291.400836) (xy 434.312761 -291.348745) (xy 434.300635 -291.294308)
			(xy 434.296564 -291.238686) (xy 417.739351 -291.238686) (xy 417.739576 -291.23894) (xy 417.73983 -291.239194)
			(xy 417.74364 -291.243004) (xy 417.766754 -291.261292) (xy 417.81603 -291.300408) (xy 417.838382 -291.305488)
			(xy 417.849812 -291.302694) (xy 417.86828 -291.298648) (xy 417.905838 -291.294318) (xy 417.924742 -291.294058)
			(xy 417.924996 -291.294058) (xy 417.950988 -291.294541) (xy 418.002332 -291.302672) (xy 418.051773 -291.318736)
			(xy 418.098091 -291.342336) (xy 418.140147 -291.372891) (xy 418.176906 -291.409649) (xy 418.207462 -291.451705)
			(xy 418.231062 -291.498024) (xy 418.247127 -291.547464) (xy 418.255259 -291.598808) (xy 418.255259 -291.624766)
			(xy 418.569152 -291.624766) (xy 418.573112 -291.575712) (xy 418.584889 -291.527928) (xy 418.60418 -291.482652)
			(xy 418.630483 -291.441056) (xy 418.663118 -291.404219) (xy 418.701239 -291.373094) (xy 418.74386 -291.348487)
			(xy 418.789876 -291.331035) (xy 418.838095 -291.321191) (xy 418.88727 -291.31921) (xy 418.936125 -291.325142)
			(xy 418.983396 -291.338834) (xy 419.027858 -291.359932) (xy 419.068361 -291.387888) (xy 419.103854 -291.42198)
			(xy 419.133419 -291.461324) (xy 419.15629 -291.504901) (xy 419.171874 -291.551582) (xy 419.179769 -291.600159)
			(xy 419.180264 -291.624766) (xy 419.519112 -291.624766) (xy 419.523072 -291.575712) (xy 419.534849 -291.527928)
			(xy 419.55414 -291.482652) (xy 419.580443 -291.441056) (xy 419.613078 -291.404219) (xy 419.651199 -291.373094)
			(xy 419.69382 -291.348487) (xy 419.739836 -291.331035) (xy 419.788055 -291.321191) (xy 419.83723 -291.31921)
			(xy 419.886085 -291.325142) (xy 419.933356 -291.338834) (xy 419.977818 -291.359932) (xy 420.018321 -291.387888)
			(xy 420.053814 -291.42198) (xy 420.083379 -291.461324) (xy 420.10625 -291.504901) (xy 420.121834 -291.551582)
			(xy 420.129729 -291.600159) (xy 420.130224 -291.624766) (xy 420.469072 -291.624766) (xy 420.473032 -291.575712)
			(xy 420.484809 -291.527928) (xy 420.5041 -291.482652) (xy 420.530403 -291.441056) (xy 420.563038 -291.404219)
			(xy 420.601159 -291.373094) (xy 420.64378 -291.348487) (xy 420.689796 -291.331035) (xy 420.738015 -291.321191)
			(xy 420.78719 -291.31921) (xy 420.836045 -291.325142) (xy 420.883316 -291.338834) (xy 420.927778 -291.359932)
			(xy 420.968281 -291.387888) (xy 421.003774 -291.42198) (xy 421.033339 -291.461324) (xy 421.05621 -291.504901)
			(xy 421.071794 -291.551582) (xy 421.079689 -291.600159) (xy 421.080184 -291.624766) (xy 421.419032 -291.624766)
			(xy 421.422992 -291.575712) (xy 421.434769 -291.527928) (xy 421.45406 -291.482652) (xy 421.480363 -291.441056)
			(xy 421.512998 -291.404219) (xy 421.551119 -291.373094) (xy 421.59374 -291.348487) (xy 421.639756 -291.331035)
			(xy 421.687975 -291.321191) (xy 421.73715 -291.31921) (xy 421.786005 -291.325142) (xy 421.833276 -291.338834)
			(xy 421.877738 -291.359932) (xy 421.918241 -291.387888) (xy 421.953734 -291.42198) (xy 421.983299 -291.461324)
			(xy 422.00617 -291.504901) (xy 422.021754 -291.551582) (xy 422.029649 -291.600159) (xy 422.030144 -291.624766)
			(xy 422.369246 -291.624766) (xy 422.373206 -291.575712) (xy 422.384983 -291.527928) (xy 422.404274 -291.482652)
			(xy 422.430577 -291.441056) (xy 422.463212 -291.404219) (xy 422.501333 -291.373094) (xy 422.543954 -291.348487)
			(xy 422.58997 -291.331035) (xy 422.638189 -291.321191) (xy 422.687364 -291.31921) (xy 422.736219 -291.325142)
			(xy 422.78349 -291.338834) (xy 422.827952 -291.359932) (xy 422.868455 -291.387888) (xy 422.903948 -291.42198)
			(xy 422.933513 -291.461324) (xy 422.956384 -291.504901) (xy 422.971968 -291.551582) (xy 422.979863 -291.600159)
			(xy 422.980358 -291.624766) (xy 424.269166 -291.624766) (xy 424.273126 -291.575712) (xy 424.284903 -291.527928)
			(xy 424.304194 -291.482652) (xy 424.330497 -291.441056) (xy 424.363132 -291.404219) (xy 424.401253 -291.373094)
			(xy 424.443874 -291.348487) (xy 424.48989 -291.331035) (xy 424.538109 -291.321191) (xy 424.587284 -291.31921)
			(xy 424.636139 -291.325142) (xy 424.68341 -291.338834) (xy 424.727872 -291.359932) (xy 424.768375 -291.387888)
			(xy 424.803868 -291.42198) (xy 424.833433 -291.461324) (xy 424.856304 -291.504901) (xy 424.871888 -291.551582)
			(xy 424.879783 -291.600159) (xy 424.880278 -291.624766) (xy 425.219126 -291.624766) (xy 425.223086 -291.575712)
			(xy 425.234863 -291.527928) (xy 425.254154 -291.482652) (xy 425.280457 -291.441056) (xy 425.313092 -291.404219)
			(xy 425.351213 -291.373094) (xy 425.393834 -291.348487) (xy 425.43985 -291.331035) (xy 425.488069 -291.321191)
			(xy 425.537244 -291.31921) (xy 425.586099 -291.325142) (xy 425.63337 -291.338834) (xy 425.677832 -291.359932)
			(xy 425.718335 -291.387888) (xy 425.753828 -291.42198) (xy 425.783393 -291.461324) (xy 425.806264 -291.504901)
			(xy 425.821848 -291.551582) (xy 425.829743 -291.600159) (xy 425.830238 -291.624766) (xy 426.169086 -291.624766)
			(xy 426.173046 -291.575712) (xy 426.184823 -291.527928) (xy 426.204114 -291.482652) (xy 426.230417 -291.441056)
			(xy 426.263052 -291.404219) (xy 426.301173 -291.373094) (xy 426.343794 -291.348487) (xy 426.38981 -291.331035)
			(xy 426.438029 -291.321191) (xy 426.487204 -291.31921) (xy 426.536059 -291.325142) (xy 426.58333 -291.338834)
			(xy 426.627792 -291.359932) (xy 426.668295 -291.387888) (xy 426.703788 -291.42198) (xy 426.733353 -291.461324)
			(xy 426.756224 -291.504901) (xy 426.771808 -291.551582) (xy 426.779703 -291.600159) (xy 426.780198 -291.624766)
			(xy 427.119046 -291.624766) (xy 427.123006 -291.575712) (xy 427.134783 -291.527928) (xy 427.154074 -291.482652)
			(xy 427.180377 -291.441056) (xy 427.213012 -291.404219) (xy 427.251133 -291.373094) (xy 427.293754 -291.348487)
			(xy 427.33977 -291.331035) (xy 427.387989 -291.321191) (xy 427.437164 -291.31921) (xy 427.486019 -291.325142)
			(xy 427.53329 -291.338834) (xy 427.577752 -291.359932) (xy 427.618255 -291.387888) (xy 427.653748 -291.42198)
			(xy 427.683313 -291.461324) (xy 427.706184 -291.504901) (xy 427.721768 -291.551582) (xy 427.729663 -291.600159)
			(xy 427.730158 -291.624766) (xy 428.069006 -291.624766) (xy 428.072966 -291.575712) (xy 428.084743 -291.527928)
			(xy 428.104034 -291.482652) (xy 428.130337 -291.441056) (xy 428.162972 -291.404219) (xy 428.201093 -291.373094)
			(xy 428.243714 -291.348487) (xy 428.28973 -291.331035) (xy 428.337949 -291.321191) (xy 428.387124 -291.31921)
			(xy 428.435979 -291.325142) (xy 428.48325 -291.338834) (xy 428.527712 -291.359932) (xy 428.568215 -291.387888)
			(xy 428.603708 -291.42198) (xy 428.633273 -291.461324) (xy 428.656144 -291.504901) (xy 428.671728 -291.551582)
			(xy 428.679623 -291.600159) (xy 428.680118 -291.624766) (xy 429.01922 -291.624766) (xy 429.02318 -291.575712)
			(xy 429.034957 -291.527928) (xy 429.054248 -291.482652) (xy 429.080551 -291.441056) (xy 429.113186 -291.404219)
			(xy 429.151307 -291.373094) (xy 429.193928 -291.348487) (xy 429.239944 -291.331035) (xy 429.288163 -291.321191)
			(xy 429.337338 -291.31921) (xy 429.386193 -291.325142) (xy 429.433464 -291.338834) (xy 429.477926 -291.359932)
			(xy 429.518429 -291.387888) (xy 429.553922 -291.42198) (xy 429.583487 -291.461324) (xy 429.606358 -291.504901)
			(xy 429.621942 -291.551582) (xy 429.629837 -291.600159) (xy 429.630332 -291.624766) (xy 429.96918 -291.624766)
			(xy 429.97314 -291.575712) (xy 429.984917 -291.527928) (xy 430.004208 -291.482652) (xy 430.030511 -291.441056)
			(xy 430.063146 -291.404219) (xy 430.101267 -291.373094) (xy 430.143888 -291.348487) (xy 430.189904 -291.331035)
			(xy 430.238123 -291.321191) (xy 430.287298 -291.31921) (xy 430.336153 -291.325142) (xy 430.383424 -291.338834)
			(xy 430.427886 -291.359932) (xy 430.468389 -291.387888) (xy 430.503882 -291.42198) (xy 430.533447 -291.461324)
			(xy 430.556318 -291.504901) (xy 430.571902 -291.551582) (xy 430.579797 -291.600159) (xy 430.580292 -291.624766)
			(xy 430.91914 -291.624766) (xy 430.9231 -291.575712) (xy 430.934877 -291.527928) (xy 430.954168 -291.482652)
			(xy 430.980471 -291.441056) (xy 431.013106 -291.404219) (xy 431.051227 -291.373094) (xy 431.093848 -291.348487)
			(xy 431.139864 -291.331035) (xy 431.188083 -291.321191) (xy 431.237258 -291.31921) (xy 431.286113 -291.325142)
			(xy 431.333384 -291.338834) (xy 431.377846 -291.359932) (xy 431.418349 -291.387888) (xy 431.453842 -291.42198)
			(xy 431.483407 -291.461324) (xy 431.506278 -291.504901) (xy 431.521862 -291.551582) (xy 431.529757 -291.600159)
			(xy 431.530252 -291.624766) (xy 431.529757 -291.649373) (xy 431.521862 -291.69795) (xy 431.506278 -291.744631)
			(xy 431.483407 -291.788208) (xy 431.453842 -291.827552) (xy 431.418349 -291.861644) (xy 431.377846 -291.8896)
			(xy 431.333384 -291.910698) (xy 431.286113 -291.92439) (xy 431.237258 -291.930322) (xy 431.188083 -291.928341)
			(xy 431.139864 -291.918497) (xy 431.093848 -291.901045) (xy 431.051227 -291.876438) (xy 431.013106 -291.845313)
			(xy 430.980471 -291.808476) (xy 430.954168 -291.76688) (xy 430.934877 -291.721604) (xy 430.9231 -291.67382)
			(xy 430.91914 -291.624766) (xy 430.580292 -291.624766) (xy 430.579797 -291.649373) (xy 430.571902 -291.69795)
			(xy 430.556318 -291.744631) (xy 430.533447 -291.788208) (xy 430.503882 -291.827552) (xy 430.468389 -291.861644)
			(xy 430.427886 -291.8896) (xy 430.383424 -291.910698) (xy 430.336153 -291.92439) (xy 430.287298 -291.930322)
			(xy 430.238123 -291.928341) (xy 430.189904 -291.918497) (xy 430.143888 -291.901045) (xy 430.101267 -291.876438)
			(xy 430.063146 -291.845313) (xy 430.030511 -291.808476) (xy 430.004208 -291.76688) (xy 429.984917 -291.721604)
			(xy 429.97314 -291.67382) (xy 429.96918 -291.624766) (xy 429.630332 -291.624766) (xy 429.629837 -291.649373)
			(xy 429.621942 -291.69795) (xy 429.606358 -291.744631) (xy 429.583487 -291.788208) (xy 429.553922 -291.827552)
			(xy 429.518429 -291.861644) (xy 429.477926 -291.8896) (xy 429.433464 -291.910698) (xy 429.386193 -291.92439)
			(xy 429.337338 -291.930322) (xy 429.288163 -291.928341) (xy 429.239944 -291.918497) (xy 429.193928 -291.901045)
			(xy 429.151307 -291.876438) (xy 429.113186 -291.845313) (xy 429.080551 -291.808476) (xy 429.054248 -291.76688)
			(xy 429.034957 -291.721604) (xy 429.02318 -291.67382) (xy 429.01922 -291.624766) (xy 428.680118 -291.624766)
			(xy 428.679623 -291.649373) (xy 428.671728 -291.69795) (xy 428.656144 -291.744631) (xy 428.633273 -291.788208)
			(xy 428.603708 -291.827552) (xy 428.568215 -291.861644) (xy 428.527712 -291.8896) (xy 428.48325 -291.910698)
			(xy 428.435979 -291.92439) (xy 428.387124 -291.930322) (xy 428.337949 -291.928341) (xy 428.28973 -291.918497)
			(xy 428.243714 -291.901045) (xy 428.201093 -291.876438) (xy 428.162972 -291.845313) (xy 428.130337 -291.808476)
			(xy 428.104034 -291.76688) (xy 428.084743 -291.721604) (xy 428.072966 -291.67382) (xy 428.069006 -291.624766)
			(xy 427.730158 -291.624766) (xy 427.729663 -291.649373) (xy 427.721768 -291.69795) (xy 427.706184 -291.744631)
			(xy 427.683313 -291.788208) (xy 427.653748 -291.827552) (xy 427.618255 -291.861644) (xy 427.577752 -291.8896)
			(xy 427.53329 -291.910698) (xy 427.486019 -291.92439) (xy 427.437164 -291.930322) (xy 427.387989 -291.928341)
			(xy 427.33977 -291.918497) (xy 427.293754 -291.901045) (xy 427.251133 -291.876438) (xy 427.213012 -291.845313)
			(xy 427.180377 -291.808476) (xy 427.154074 -291.76688) (xy 427.134783 -291.721604) (xy 427.123006 -291.67382)
			(xy 427.119046 -291.624766) (xy 426.780198 -291.624766) (xy 426.779703 -291.649373) (xy 426.771808 -291.69795)
			(xy 426.756224 -291.744631) (xy 426.733353 -291.788208) (xy 426.703788 -291.827552) (xy 426.668295 -291.861644)
			(xy 426.627792 -291.8896) (xy 426.58333 -291.910698) (xy 426.536059 -291.92439) (xy 426.487204 -291.930322)
			(xy 426.438029 -291.928341) (xy 426.38981 -291.918497) (xy 426.343794 -291.901045) (xy 426.301173 -291.876438)
			(xy 426.263052 -291.845313) (xy 426.230417 -291.808476) (xy 426.204114 -291.76688) (xy 426.184823 -291.721604)
			(xy 426.173046 -291.67382) (xy 426.169086 -291.624766) (xy 425.830238 -291.624766) (xy 425.829743 -291.649373)
			(xy 425.821848 -291.69795) (xy 425.806264 -291.744631) (xy 425.783393 -291.788208) (xy 425.753828 -291.827552)
			(xy 425.718335 -291.861644) (xy 425.677832 -291.8896) (xy 425.63337 -291.910698) (xy 425.586099 -291.92439)
			(xy 425.537244 -291.930322) (xy 425.488069 -291.928341) (xy 425.43985 -291.918497) (xy 425.393834 -291.901045)
			(xy 425.351213 -291.876438) (xy 425.313092 -291.845313) (xy 425.280457 -291.808476) (xy 425.254154 -291.76688)
			(xy 425.234863 -291.721604) (xy 425.223086 -291.67382) (xy 425.219126 -291.624766) (xy 424.880278 -291.624766)
			(xy 424.879783 -291.649373) (xy 424.871888 -291.69795) (xy 424.856304 -291.744631) (xy 424.833433 -291.788208)
			(xy 424.803868 -291.827552) (xy 424.768375 -291.861644) (xy 424.727872 -291.8896) (xy 424.68341 -291.910698)
			(xy 424.636139 -291.92439) (xy 424.587284 -291.930322) (xy 424.538109 -291.928341) (xy 424.48989 -291.918497)
			(xy 424.443874 -291.901045) (xy 424.401253 -291.876438) (xy 424.363132 -291.845313) (xy 424.330497 -291.808476)
			(xy 424.304194 -291.76688) (xy 424.284903 -291.721604) (xy 424.273126 -291.67382) (xy 424.269166 -291.624766)
			(xy 422.980358 -291.624766) (xy 422.979863 -291.649373) (xy 422.971968 -291.69795) (xy 422.956384 -291.744631)
			(xy 422.933513 -291.788208) (xy 422.903948 -291.827552) (xy 422.868455 -291.861644) (xy 422.827952 -291.8896)
			(xy 422.78349 -291.910698) (xy 422.736219 -291.92439) (xy 422.687364 -291.930322) (xy 422.638189 -291.928341)
			(xy 422.58997 -291.918497) (xy 422.543954 -291.901045) (xy 422.501333 -291.876438) (xy 422.463212 -291.845313)
			(xy 422.430577 -291.808476) (xy 422.404274 -291.76688) (xy 422.384983 -291.721604) (xy 422.373206 -291.67382)
			(xy 422.369246 -291.624766) (xy 422.030144 -291.624766) (xy 422.029649 -291.649373) (xy 422.021754 -291.69795)
			(xy 422.00617 -291.744631) (xy 421.983299 -291.788208) (xy 421.953734 -291.827552) (xy 421.918241 -291.861644)
			(xy 421.877738 -291.8896) (xy 421.833276 -291.910698) (xy 421.786005 -291.92439) (xy 421.73715 -291.930322)
			(xy 421.687975 -291.928341) (xy 421.639756 -291.918497) (xy 421.59374 -291.901045) (xy 421.551119 -291.876438)
			(xy 421.512998 -291.845313) (xy 421.480363 -291.808476) (xy 421.45406 -291.76688) (xy 421.434769 -291.721604)
			(xy 421.422992 -291.67382) (xy 421.419032 -291.624766) (xy 421.080184 -291.624766) (xy 421.079689 -291.649373)
			(xy 421.071794 -291.69795) (xy 421.05621 -291.744631) (xy 421.033339 -291.788208) (xy 421.003774 -291.827552)
			(xy 420.968281 -291.861644) (xy 420.927778 -291.8896) (xy 420.883316 -291.910698) (xy 420.836045 -291.92439)
			(xy 420.78719 -291.930322) (xy 420.738015 -291.928341) (xy 420.689796 -291.918497) (xy 420.64378 -291.901045)
			(xy 420.601159 -291.876438) (xy 420.563038 -291.845313) (xy 420.530403 -291.808476) (xy 420.5041 -291.76688)
			(xy 420.484809 -291.721604) (xy 420.473032 -291.67382) (xy 420.469072 -291.624766) (xy 420.130224 -291.624766)
			(xy 420.129729 -291.649373) (xy 420.121834 -291.69795) (xy 420.10625 -291.744631) (xy 420.083379 -291.788208)
			(xy 420.053814 -291.827552) (xy 420.018321 -291.861644) (xy 419.977818 -291.8896) (xy 419.933356 -291.910698)
			(xy 419.886085 -291.92439) (xy 419.83723 -291.930322) (xy 419.788055 -291.928341) (xy 419.739836 -291.918497)
			(xy 419.69382 -291.901045) (xy 419.651199 -291.876438) (xy 419.613078 -291.845313) (xy 419.580443 -291.808476)
			(xy 419.55414 -291.76688) (xy 419.534849 -291.721604) (xy 419.523072 -291.67382) (xy 419.519112 -291.624766)
			(xy 419.180264 -291.624766) (xy 419.179769 -291.649373) (xy 419.171874 -291.69795) (xy 419.15629 -291.744631)
			(xy 419.133419 -291.788208) (xy 419.103854 -291.827552) (xy 419.068361 -291.861644) (xy 419.027858 -291.8896)
			(xy 418.983396 -291.910698) (xy 418.936125 -291.92439) (xy 418.88727 -291.930322) (xy 418.838095 -291.928341)
			(xy 418.789876 -291.918497) (xy 418.74386 -291.901045) (xy 418.701239 -291.876438) (xy 418.663118 -291.845313)
			(xy 418.630483 -291.808476) (xy 418.60418 -291.76688) (xy 418.584889 -291.721604) (xy 418.573112 -291.67382)
			(xy 418.569152 -291.624766) (xy 418.255259 -291.624766) (xy 418.255259 -291.650792) (xy 418.247127 -291.702136)
			(xy 418.231062 -291.751576) (xy 418.207462 -291.797895) (xy 418.176906 -291.839951) (xy 418.140147 -291.876709)
			(xy 418.098091 -291.907264) (xy 418.051773 -291.930864) (xy 418.002332 -291.946928) (xy 417.950988 -291.955059)
			(xy 417.924996 -291.955474) (xy 417.924742 -291.955474) (xy 417.90584 -291.955188) (xy 417.868284 -291.950859)
			(xy 417.849812 -291.946838) (xy 417.838382 -291.944044) (xy 417.81603 -291.949124) (xy 417.744402 -292.00602)
			(xy 417.735691 -292.013598) (xy 417.725651 -292.034364) (xy 417.725098 -292.045898) (xy 417.725098 -292.122098)
			(xy 441.55741 -292.122098) (xy 441.557853 -292.095494) (xy 441.565235 -292.0428) (xy 441.57987 -291.991644)
			(xy 441.601474 -291.943019) (xy 441.629626 -291.897869) (xy 441.663781 -291.85707) (xy 441.703276 -291.821415)
			(xy 441.72505 -291.806122) (xy 441.736488 -291.797731) (xy 441.754699 -291.776003) (xy 441.766224 -291.750101)
			(xy 441.770172 -291.722027) (xy 441.766239 -291.693951) (xy 441.754727 -291.668043) (xy 441.736528 -291.646305)
			(xy 441.72505 -291.637974) (xy 441.703261 -291.622704) (xy 441.663782 -291.587034) (xy 441.62964 -291.546226)
			(xy 441.601496 -291.501072) (xy 441.579897 -291.452447) (xy 441.565261 -291.401293) (xy 441.557871 -291.348601)
			(xy 441.55741 -291.321998) (xy 441.557896 -291.294747) (xy 441.565652 -291.240799) (xy 441.581007 -291.188504)
			(xy 441.603649 -291.138927) (xy 441.633115 -291.093077) (xy 441.668806 -291.051886) (xy 441.709997 -291.016195)
			(xy 441.755847 -290.986729) (xy 441.805424 -290.964087) (xy 441.857719 -290.948732) (xy 441.911667 -290.940976)
			(xy 441.966169 -290.940976) (xy 442.020117 -290.948732) (xy 442.072412 -290.964087) (xy 442.121989 -290.986729)
			(xy 442.167839 -291.016195) (xy 442.20903 -291.051886) (xy 442.244721 -291.093077) (xy 442.274187 -291.138927)
			(xy 442.296829 -291.188504) (xy 442.312184 -291.240799) (xy 442.31994 -291.294747) (xy 442.320426 -291.321998)
			(xy 442.320008 -291.348603) (xy 442.312625 -291.401299) (xy 442.297988 -291.452457) (xy 442.276381 -291.501083)
			(xy 442.248224 -291.546233) (xy 442.224928 -291.574056) (xy 450.443243 -291.574056) (xy 450.443243 -291.519544)
			(xy 450.451001 -291.465587) (xy 450.46636 -291.413284) (xy 450.489007 -291.363699) (xy 450.51848 -291.317843)
			(xy 450.55418 -291.276647) (xy 450.595379 -291.240953) (xy 450.64124 -291.211485) (xy 450.690827 -291.188844)
			(xy 450.743132 -291.173492) (xy 450.79709 -291.16574) (xy 450.824346 -291.16528) (xy 450.851716 -291.165758)
			(xy 450.905895 -291.17357) (xy 450.958399 -291.189055) (xy 451.008146 -291.211895) (xy 451.054113 -291.241619)
			(xy 451.075044 -291.25926) (xy 451.075298 -291.259514) (xy 451.08238 -291.265107) (xy 451.0993 -291.27135)
			(xy 451.108318 -291.271706) (xy 451.175374 -291.271706) (xy 451.184389 -291.271335) (xy 451.201306 -291.265097)
			(xy 451.208394 -291.259514) (xy 451.208902 -291.259006) (xy 451.229817 -291.2414) (xy 451.275757 -291.211764)
			(xy 451.325457 -291.18899) (xy 451.3779 -291.173545) (xy 451.432011 -291.165746) (xy 451.459346 -291.16528)
			(xy 451.486594 -291.165793) (xy 451.540535 -291.173555) (xy 451.592823 -291.188914) (xy 451.642393 -291.211557)
			(xy 451.688236 -291.241023) (xy 451.729419 -291.276714) (xy 451.765104 -291.317901) (xy 451.794565 -291.363748)
			(xy 451.817203 -291.41332) (xy 451.832555 -291.46561) (xy 451.84031 -291.519552) (xy 451.84031 -291.574048)
			(xy 451.840309 -291.574054) (xy 452.196643 -291.574054) (xy 452.196643 -291.519546) (xy 452.2044 -291.465593)
			(xy 452.219757 -291.413292) (xy 452.242401 -291.36371) (xy 452.271871 -291.317855) (xy 452.307566 -291.276661)
			(xy 452.348761 -291.240966) (xy 452.394617 -291.211497) (xy 452.4442 -291.188854) (xy 452.4965 -291.173499)
			(xy 452.550454 -291.165742) (xy 452.577708 -291.16528) (xy 452.605079 -291.165722) (xy 452.65926 -291.173543)
			(xy 452.711764 -291.189036) (xy 452.761511 -291.211884) (xy 452.807476 -291.241615) (xy 452.828406 -291.25926)
			(xy 452.82866 -291.259514) (xy 452.835753 -291.265092) (xy 452.852665 -291.271343) (xy 452.86168 -291.271706)
			(xy 452.928736 -291.271706) (xy 452.937754 -291.271365) (xy 452.954671 -291.265106) (xy 452.961756 -291.259514)
			(xy 452.962264 -291.259006) (xy 452.983193 -291.241418) (xy 453.029129 -291.211779) (xy 453.078826 -291.189001)
			(xy 453.131266 -291.173553) (xy 453.185374 -291.165749) (xy 453.212708 -291.16528) (xy 453.239958 -291.165791)
			(xy 453.293903 -291.173548) (xy 453.346195 -291.188903) (xy 453.39577 -291.211544) (xy 453.441618 -291.24101)
			(xy 453.482806 -291.2767) (xy 453.518495 -291.317889) (xy 453.54796 -291.363737) (xy 453.5706 -291.413312)
			(xy 453.585954 -291.465605) (xy 453.59371 -291.51955) (xy 453.59371 -291.57405) (xy 453.585954 -291.627995)
			(xy 453.5706 -291.680288) (xy 453.54796 -291.729863) (xy 453.518495 -291.775711) (xy 453.482806 -291.8169)
			(xy 453.441618 -291.85259) (xy 453.39577 -291.882056) (xy 453.346195 -291.904697) (xy 453.293903 -291.920052)
			(xy 453.239958 -291.927809) (xy 453.212708 -291.928296) (xy 453.185376 -291.927791) (xy 453.13127 -291.919991)
			(xy 453.078831 -291.90455) (xy 453.029133 -291.881783) (xy 452.983193 -291.852156) (xy 452.962264 -291.83457)
			(xy 452.961756 -291.834062) (xy 452.954661 -291.828488) (xy 452.93775 -291.822235) (xy 452.928736 -291.82187)
			(xy 452.86168 -291.82187) (xy 452.852663 -291.822224) (xy 452.835746 -291.828474) (xy 452.82866 -291.834062)
			(xy 452.828152 -291.83457) (xy 452.807214 -291.852147) (xy 452.761281 -291.881789) (xy 452.711586 -291.904568)
			(xy 452.659148 -291.92002) (xy 452.605041 -291.927826) (xy 452.577708 -291.928296) (xy 452.550454 -291.927858)
			(xy 452.4965 -291.920101) (xy 452.4442 -291.904746) (xy 452.394617 -291.882103) (xy 452.348761 -291.852634)
			(xy 452.307566 -291.816939) (xy 452.271871 -291.775745) (xy 452.242401 -291.72989) (xy 452.219757 -291.680308)
			(xy 452.2044 -291.628007) (xy 452.196643 -291.574054) (xy 451.840309 -291.574054) (xy 451.832555 -291.62799)
			(xy 451.817203 -291.68028) (xy 451.794565 -291.729852) (xy 451.765104 -291.775699) (xy 451.729419 -291.816886)
			(xy 451.688236 -291.852577) (xy 451.642393 -291.882043) (xy 451.592823 -291.904686) (xy 451.540535 -291.920045)
			(xy 451.486594 -291.927807) (xy 451.459346 -291.928296) (xy 451.432012 -291.927827) (xy 451.377905 -291.920019)
			(xy 451.325466 -291.904569) (xy 451.275768 -291.881794) (xy 451.229829 -291.85216) (xy 451.208902 -291.83457)
			(xy 451.208394 -291.834062) (xy 451.201316 -291.828463) (xy 451.184393 -291.822225) (xy 451.175374 -291.82187)
			(xy 451.108318 -291.82187) (xy 451.099303 -291.822242) (xy 451.082386 -291.82848) (xy 451.075298 -291.834062)
			(xy 451.07479 -291.83457) (xy 451.053875 -291.852176) (xy 451.007936 -291.881813) (xy 450.958235 -291.904588)
			(xy 450.905792 -291.920032) (xy 450.851681 -291.92783) (xy 450.824346 -291.928296) (xy 450.79709 -291.92786)
			(xy 450.743132 -291.920108) (xy 450.690827 -291.904756) (xy 450.64124 -291.882115) (xy 450.595379 -291.852647)
			(xy 450.55418 -291.816953) (xy 450.51848 -291.775757) (xy 450.489007 -291.729901) (xy 450.46636 -291.680316)
			(xy 450.451001 -291.628013) (xy 450.443243 -291.574056) (xy 442.224928 -291.574056) (xy 442.214064 -291.587031)
			(xy 442.174563 -291.622683) (xy 442.152786 -291.637974) (xy 442.141261 -291.64625) (xy 442.123058 -291.668007)
			(xy 442.111546 -291.693934) (xy 442.107612 -291.722027) (xy 442.11156 -291.750118) (xy 442.123087 -291.776039)
			(xy 442.141301 -291.797786) (xy 442.152786 -291.806122) (xy 442.174581 -291.821383) (xy 442.214058 -291.857056)
			(xy 442.248199 -291.897866) (xy 442.276341 -291.943021) (xy 442.297939 -291.991648) (xy 442.312575 -292.042803)
			(xy 442.319965 -292.095494) (xy 442.320426 -292.122098) (xy 442.31994 -292.149349) (xy 442.312184 -292.203297)
			(xy 442.296829 -292.255592) (xy 442.274187 -292.305169) (xy 442.244721 -292.351019) (xy 442.20903 -292.39221)
			(xy 442.167839 -292.427901) (xy 442.121989 -292.457367) (xy 442.072412 -292.480009) (xy 442.020117 -292.495364)
			(xy 441.966169 -292.50312) (xy 441.911667 -292.50312) (xy 441.857719 -292.495364) (xy 441.805424 -292.480009)
			(xy 441.755847 -292.457367) (xy 441.709997 -292.427901) (xy 441.668806 -292.39221) (xy 441.633115 -292.351019)
			(xy 441.603649 -292.305169) (xy 441.581007 -292.255592) (xy 441.565652 -292.203297) (xy 441.557896 -292.149349)
			(xy 441.55741 -292.122098) (xy 417.725098 -292.122098) (xy 417.725098 -292.15334) (xy 417.725562 -292.163215)
			(xy 417.733011 -292.181508) (xy 417.739576 -292.1889) (xy 417.73983 -292.189154) (xy 417.74364 -292.192964)
			(xy 417.766754 -292.211252) (xy 417.81603 -292.250368) (xy 417.838382 -292.255448) (xy 417.849812 -292.252654)
			(xy 417.868279 -292.248607) (xy 417.905838 -292.244277) (xy 417.924742 -292.244018) (xy 417.924996 -292.244018)
			(xy 417.950983 -292.244501) (xy 418.002318 -292.252631) (xy 418.05175 -292.268691) (xy 418.09806 -292.292287)
			(xy 418.140109 -292.322837) (xy 418.17686 -292.359588) (xy 418.207411 -292.401637) (xy 418.231007 -292.447947)
			(xy 418.247068 -292.497378) (xy 418.255199 -292.548713) (xy 418.255199 -292.57498) (xy 418.569152 -292.57498)
			(xy 418.573112 -292.525926) (xy 418.584889 -292.478142) (xy 418.60418 -292.432866) (xy 418.630483 -292.39127)
			(xy 418.663118 -292.354433) (xy 418.701239 -292.323308) (xy 418.74386 -292.298701) (xy 418.789876 -292.281249)
			(xy 418.838095 -292.271405) (xy 418.88727 -292.269424) (xy 418.936125 -292.275356) (xy 418.983396 -292.289048)
			(xy 419.027858 -292.310146) (xy 419.068361 -292.338102) (xy 419.103854 -292.372194) (xy 419.133419 -292.411538)
			(xy 419.15629 -292.455115) (xy 419.171874 -292.501796) (xy 419.179769 -292.550373) (xy 419.180259 -292.574726)
			(xy 419.519112 -292.574726) (xy 419.523072 -292.525672) (xy 419.534849 -292.477888) (xy 419.55414 -292.432612)
			(xy 419.580443 -292.391016) (xy 419.613078 -292.354179) (xy 419.651199 -292.323054) (xy 419.69382 -292.298447)
			(xy 419.739836 -292.280995) (xy 419.788055 -292.271151) (xy 419.83723 -292.26917) (xy 419.886085 -292.275102)
			(xy 419.933356 -292.288794) (xy 419.977818 -292.309892) (xy 420.018321 -292.337848) (xy 420.053814 -292.37194)
			(xy 420.083379 -292.411284) (xy 420.10625 -292.454861) (xy 420.121834 -292.501542) (xy 420.129729 -292.550119)
			(xy 420.130224 -292.574726) (xy 420.469072 -292.574726) (xy 420.473032 -292.525672) (xy 420.484809 -292.477888)
			(xy 420.5041 -292.432612) (xy 420.530403 -292.391016) (xy 420.563038 -292.354179) (xy 420.601159 -292.323054)
			(xy 420.64378 -292.298447) (xy 420.689796 -292.280995) (xy 420.738015 -292.271151) (xy 420.78719 -292.26917)
			(xy 420.836045 -292.275102) (xy 420.883316 -292.288794) (xy 420.927778 -292.309892) (xy 420.968281 -292.337848)
			(xy 421.003774 -292.37194) (xy 421.033339 -292.411284) (xy 421.05621 -292.454861) (xy 421.071794 -292.501542)
			(xy 421.079689 -292.550119) (xy 421.080184 -292.574726) (xy 421.419032 -292.574726) (xy 421.422992 -292.525672)
			(xy 421.434769 -292.477888) (xy 421.45406 -292.432612) (xy 421.480363 -292.391016) (xy 421.512998 -292.354179)
			(xy 421.551119 -292.323054) (xy 421.59374 -292.298447) (xy 421.639756 -292.280995) (xy 421.687975 -292.271151)
			(xy 421.73715 -292.26917) (xy 421.786005 -292.275102) (xy 421.833276 -292.288794) (xy 421.877738 -292.309892)
			(xy 421.918241 -292.337848) (xy 421.953734 -292.37194) (xy 421.983299 -292.411284) (xy 422.00617 -292.454861)
			(xy 422.021754 -292.501542) (xy 422.029649 -292.550119) (xy 422.030144 -292.574726) (xy 422.368992 -292.574726)
			(xy 422.372952 -292.525672) (xy 422.384729 -292.477888) (xy 422.40402 -292.432612) (xy 422.430323 -292.391016)
			(xy 422.462958 -292.354179) (xy 422.501079 -292.323054) (xy 422.5437 -292.298447) (xy 422.589716 -292.280995)
			(xy 422.637935 -292.271151) (xy 422.68711 -292.26917) (xy 422.735965 -292.275102) (xy 422.783236 -292.288794)
			(xy 422.827698 -292.309892) (xy 422.868201 -292.337848) (xy 422.903694 -292.37194) (xy 422.933259 -292.411284)
			(xy 422.95613 -292.454861) (xy 422.971714 -292.501542) (xy 422.979609 -292.550119) (xy 422.980104 -292.574726)
			(xy 423.319206 -292.574726) (xy 423.323166 -292.525672) (xy 423.334943 -292.477888) (xy 423.354234 -292.432612)
			(xy 423.380537 -292.391016) (xy 423.413172 -292.354179) (xy 423.451293 -292.323054) (xy 423.493914 -292.298447)
			(xy 423.53993 -292.280995) (xy 423.588149 -292.271151) (xy 423.637324 -292.26917) (xy 423.686179 -292.275102)
			(xy 423.73345 -292.288794) (xy 423.777912 -292.309892) (xy 423.818415 -292.337848) (xy 423.853908 -292.37194)
			(xy 423.883473 -292.411284) (xy 423.906344 -292.454861) (xy 423.921928 -292.501542) (xy 423.929823 -292.550119)
			(xy 423.930318 -292.574726) (xy 424.269166 -292.574726) (xy 424.273126 -292.525672) (xy 424.284903 -292.477888)
			(xy 424.304194 -292.432612) (xy 424.330497 -292.391016) (xy 424.363132 -292.354179) (xy 424.401253 -292.323054)
			(xy 424.443874 -292.298447) (xy 424.48989 -292.280995) (xy 424.538109 -292.271151) (xy 424.587284 -292.26917)
			(xy 424.636139 -292.275102) (xy 424.68341 -292.288794) (xy 424.727872 -292.309892) (xy 424.768375 -292.337848)
			(xy 424.803868 -292.37194) (xy 424.833433 -292.411284) (xy 424.856304 -292.454861) (xy 424.871888 -292.501542)
			(xy 424.879783 -292.550119) (xy 424.880278 -292.574726) (xy 425.219126 -292.574726) (xy 425.223086 -292.525672)
			(xy 425.234863 -292.477888) (xy 425.254154 -292.432612) (xy 425.280457 -292.391016) (xy 425.313092 -292.354179)
			(xy 425.351213 -292.323054) (xy 425.393834 -292.298447) (xy 425.43985 -292.280995) (xy 425.488069 -292.271151)
			(xy 425.537244 -292.26917) (xy 425.586099 -292.275102) (xy 425.63337 -292.288794) (xy 425.677832 -292.309892)
			(xy 425.718335 -292.337848) (xy 425.753828 -292.37194) (xy 425.783393 -292.411284) (xy 425.806264 -292.454861)
			(xy 425.821848 -292.501542) (xy 425.829743 -292.550119) (xy 425.830238 -292.574726) (xy 426.169086 -292.574726)
			(xy 426.173046 -292.525672) (xy 426.184823 -292.477888) (xy 426.204114 -292.432612) (xy 426.230417 -292.391016)
			(xy 426.263052 -292.354179) (xy 426.301173 -292.323054) (xy 426.343794 -292.298447) (xy 426.38981 -292.280995)
			(xy 426.438029 -292.271151) (xy 426.487204 -292.26917) (xy 426.536059 -292.275102) (xy 426.58333 -292.288794)
			(xy 426.627792 -292.309892) (xy 426.668295 -292.337848) (xy 426.703788 -292.37194) (xy 426.733353 -292.411284)
			(xy 426.756224 -292.454861) (xy 426.771808 -292.501542) (xy 426.779703 -292.550119) (xy 426.780198 -292.574726)
			(xy 427.119046 -292.574726) (xy 427.123006 -292.525672) (xy 427.134783 -292.477888) (xy 427.154074 -292.432612)
			(xy 427.180377 -292.391016) (xy 427.213012 -292.354179) (xy 427.251133 -292.323054) (xy 427.293754 -292.298447)
			(xy 427.33977 -292.280995) (xy 427.387989 -292.271151) (xy 427.437164 -292.26917) (xy 427.486019 -292.275102)
			(xy 427.53329 -292.288794) (xy 427.577752 -292.309892) (xy 427.618255 -292.337848) (xy 427.653748 -292.37194)
			(xy 427.683313 -292.411284) (xy 427.706184 -292.454861) (xy 427.721768 -292.501542) (xy 427.729663 -292.550119)
			(xy 427.730158 -292.574726) (xy 428.069006 -292.574726) (xy 428.072966 -292.525672) (xy 428.084743 -292.477888)
			(xy 428.104034 -292.432612) (xy 428.130337 -292.391016) (xy 428.162972 -292.354179) (xy 428.201093 -292.323054)
			(xy 428.243714 -292.298447) (xy 428.28973 -292.280995) (xy 428.337949 -292.271151) (xy 428.387124 -292.26917)
			(xy 428.435979 -292.275102) (xy 428.48325 -292.288794) (xy 428.527712 -292.309892) (xy 428.568215 -292.337848)
			(xy 428.603708 -292.37194) (xy 428.633273 -292.411284) (xy 428.656144 -292.454861) (xy 428.671728 -292.501542)
			(xy 428.679623 -292.550119) (xy 428.680118 -292.574726) (xy 429.01922 -292.574726) (xy 429.02318 -292.525672)
			(xy 429.034957 -292.477888) (xy 429.054248 -292.432612) (xy 429.080551 -292.391016) (xy 429.113186 -292.354179)
			(xy 429.151307 -292.323054) (xy 429.193928 -292.298447) (xy 429.239944 -292.280995) (xy 429.288163 -292.271151)
			(xy 429.337338 -292.26917) (xy 429.386193 -292.275102) (xy 429.433464 -292.288794) (xy 429.477926 -292.309892)
			(xy 429.518429 -292.337848) (xy 429.553922 -292.37194) (xy 429.583487 -292.411284) (xy 429.606358 -292.454861)
			(xy 429.621942 -292.501542) (xy 429.629837 -292.550119) (xy 429.630332 -292.574726) (xy 429.630327 -292.57498)
			(xy 429.96918 -292.57498) (xy 429.97314 -292.525926) (xy 429.984917 -292.478142) (xy 430.004208 -292.432866)
			(xy 430.030511 -292.39127) (xy 430.063146 -292.354433) (xy 430.101267 -292.323308) (xy 430.143888 -292.298701)
			(xy 430.189904 -292.281249) (xy 430.238123 -292.271405) (xy 430.287298 -292.269424) (xy 430.336153 -292.275356)
			(xy 430.383424 -292.289048) (xy 430.427886 -292.310146) (xy 430.468389 -292.338102) (xy 430.503882 -292.372194)
			(xy 430.533447 -292.411538) (xy 430.556318 -292.455115) (xy 430.571902 -292.501796) (xy 430.579797 -292.550373)
			(xy 430.580292 -292.57498) (xy 430.91914 -292.57498) (xy 430.9231 -292.525926) (xy 430.934877 -292.478142)
			(xy 430.954168 -292.432866) (xy 430.980471 -292.39127) (xy 431.013106 -292.354433) (xy 431.051227 -292.323308)
			(xy 431.093848 -292.298701) (xy 431.139864 -292.281249) (xy 431.188083 -292.271405) (xy 431.237258 -292.269424)
			(xy 431.286113 -292.275356) (xy 431.333384 -292.289048) (xy 431.377846 -292.310146) (xy 431.418349 -292.338102)
			(xy 431.453842 -292.372194) (xy 431.483407 -292.411538) (xy 431.506278 -292.455115) (xy 431.521862 -292.501796)
			(xy 431.529757 -292.550373) (xy 431.530252 -292.57498) (xy 431.529757 -292.599587) (xy 431.521862 -292.648164)
			(xy 431.506278 -292.694845) (xy 431.483407 -292.738422) (xy 431.453842 -292.777766) (xy 431.418349 -292.811858)
			(xy 431.377846 -292.839814) (xy 431.333384 -292.860912) (xy 431.286113 -292.874604) (xy 431.237258 -292.880536)
			(xy 431.188083 -292.878555) (xy 431.139864 -292.868711) (xy 431.093848 -292.851259) (xy 431.051227 -292.826652)
			(xy 431.013106 -292.795527) (xy 430.980471 -292.75869) (xy 430.954168 -292.717094) (xy 430.934877 -292.671818)
			(xy 430.9231 -292.624034) (xy 430.91914 -292.57498) (xy 430.580292 -292.57498) (xy 430.579797 -292.599587)
			(xy 430.571902 -292.648164) (xy 430.556318 -292.694845) (xy 430.533447 -292.738422) (xy 430.503882 -292.777766)
			(xy 430.468389 -292.811858) (xy 430.427886 -292.839814) (xy 430.383424 -292.860912) (xy 430.336153 -292.874604)
			(xy 430.287298 -292.880536) (xy 430.238123 -292.878555) (xy 430.189904 -292.868711) (xy 430.143888 -292.851259)
			(xy 430.101267 -292.826652) (xy 430.063146 -292.795527) (xy 430.030511 -292.75869) (xy 430.004208 -292.717094)
			(xy 429.984917 -292.671818) (xy 429.97314 -292.624034) (xy 429.96918 -292.57498) (xy 429.630327 -292.57498)
			(xy 429.629837 -292.599333) (xy 429.621942 -292.64791) (xy 429.606358 -292.694591) (xy 429.583487 -292.738168)
			(xy 429.553922 -292.777512) (xy 429.518429 -292.811604) (xy 429.477926 -292.83956) (xy 429.433464 -292.860658)
			(xy 429.386193 -292.87435) (xy 429.337338 -292.880282) (xy 429.288163 -292.878301) (xy 429.239944 -292.868457)
			(xy 429.193928 -292.851005) (xy 429.151307 -292.826398) (xy 429.113186 -292.795273) (xy 429.080551 -292.758436)
			(xy 429.054248 -292.71684) (xy 429.034957 -292.671564) (xy 429.02318 -292.62378) (xy 429.01922 -292.574726)
			(xy 428.680118 -292.574726) (xy 428.679623 -292.599333) (xy 428.671728 -292.64791) (xy 428.656144 -292.694591)
			(xy 428.633273 -292.738168) (xy 428.603708 -292.777512) (xy 428.568215 -292.811604) (xy 428.527712 -292.83956)
			(xy 428.48325 -292.860658) (xy 428.435979 -292.87435) (xy 428.387124 -292.880282) (xy 428.337949 -292.878301)
			(xy 428.28973 -292.868457) (xy 428.243714 -292.851005) (xy 428.201093 -292.826398) (xy 428.162972 -292.795273)
			(xy 428.130337 -292.758436) (xy 428.104034 -292.71684) (xy 428.084743 -292.671564) (xy 428.072966 -292.62378)
			(xy 428.069006 -292.574726) (xy 427.730158 -292.574726) (xy 427.729663 -292.599333) (xy 427.721768 -292.64791)
			(xy 427.706184 -292.694591) (xy 427.683313 -292.738168) (xy 427.653748 -292.777512) (xy 427.618255 -292.811604)
			(xy 427.577752 -292.83956) (xy 427.53329 -292.860658) (xy 427.486019 -292.87435) (xy 427.437164 -292.880282)
			(xy 427.387989 -292.878301) (xy 427.33977 -292.868457) (xy 427.293754 -292.851005) (xy 427.251133 -292.826398)
			(xy 427.213012 -292.795273) (xy 427.180377 -292.758436) (xy 427.154074 -292.71684) (xy 427.134783 -292.671564)
			(xy 427.123006 -292.62378) (xy 427.119046 -292.574726) (xy 426.780198 -292.574726) (xy 426.779703 -292.599333)
			(xy 426.771808 -292.64791) (xy 426.756224 -292.694591) (xy 426.733353 -292.738168) (xy 426.703788 -292.777512)
			(xy 426.668295 -292.811604) (xy 426.627792 -292.83956) (xy 426.58333 -292.860658) (xy 426.536059 -292.87435)
			(xy 426.487204 -292.880282) (xy 426.438029 -292.878301) (xy 426.38981 -292.868457) (xy 426.343794 -292.851005)
			(xy 426.301173 -292.826398) (xy 426.263052 -292.795273) (xy 426.230417 -292.758436) (xy 426.204114 -292.71684)
			(xy 426.184823 -292.671564) (xy 426.173046 -292.62378) (xy 426.169086 -292.574726) (xy 425.830238 -292.574726)
			(xy 425.829743 -292.599333) (xy 425.821848 -292.64791) (xy 425.806264 -292.694591) (xy 425.783393 -292.738168)
			(xy 425.753828 -292.777512) (xy 425.718335 -292.811604) (xy 425.677832 -292.83956) (xy 425.63337 -292.860658)
			(xy 425.586099 -292.87435) (xy 425.537244 -292.880282) (xy 425.488069 -292.878301) (xy 425.43985 -292.868457)
			(xy 425.393834 -292.851005) (xy 425.351213 -292.826398) (xy 425.313092 -292.795273) (xy 425.280457 -292.758436)
			(xy 425.254154 -292.71684) (xy 425.234863 -292.671564) (xy 425.223086 -292.62378) (xy 425.219126 -292.574726)
			(xy 424.880278 -292.574726) (xy 424.879783 -292.599333) (xy 424.871888 -292.64791) (xy 424.856304 -292.694591)
			(xy 424.833433 -292.738168) (xy 424.803868 -292.777512) (xy 424.768375 -292.811604) (xy 424.727872 -292.83956)
			(xy 424.68341 -292.860658) (xy 424.636139 -292.87435) (xy 424.587284 -292.880282) (xy 424.538109 -292.878301)
			(xy 424.48989 -292.868457) (xy 424.443874 -292.851005) (xy 424.401253 -292.826398) (xy 424.363132 -292.795273)
			(xy 424.330497 -292.758436) (xy 424.304194 -292.71684) (xy 424.284903 -292.671564) (xy 424.273126 -292.62378)
			(xy 424.269166 -292.574726) (xy 423.930318 -292.574726) (xy 423.929823 -292.599333) (xy 423.921928 -292.64791)
			(xy 423.906344 -292.694591) (xy 423.883473 -292.738168) (xy 423.853908 -292.777512) (xy 423.818415 -292.811604)
			(xy 423.777912 -292.83956) (xy 423.73345 -292.860658) (xy 423.686179 -292.87435) (xy 423.637324 -292.880282)
			(xy 423.588149 -292.878301) (xy 423.53993 -292.868457) (xy 423.493914 -292.851005) (xy 423.451293 -292.826398)
			(xy 423.413172 -292.795273) (xy 423.380537 -292.758436) (xy 423.354234 -292.71684) (xy 423.334943 -292.671564)
			(xy 423.323166 -292.62378) (xy 423.319206 -292.574726) (xy 422.980104 -292.574726) (xy 422.979609 -292.599333)
			(xy 422.971714 -292.64791) (xy 422.95613 -292.694591) (xy 422.933259 -292.738168) (xy 422.903694 -292.777512)
			(xy 422.868201 -292.811604) (xy 422.827698 -292.83956) (xy 422.783236 -292.860658) (xy 422.735965 -292.87435)
			(xy 422.68711 -292.880282) (xy 422.637935 -292.878301) (xy 422.589716 -292.868457) (xy 422.5437 -292.851005)
			(xy 422.501079 -292.826398) (xy 422.462958 -292.795273) (xy 422.430323 -292.758436) (xy 422.40402 -292.71684)
			(xy 422.384729 -292.671564) (xy 422.372952 -292.62378) (xy 422.368992 -292.574726) (xy 422.030144 -292.574726)
			(xy 422.029649 -292.599333) (xy 422.021754 -292.64791) (xy 422.00617 -292.694591) (xy 421.983299 -292.738168)
			(xy 421.953734 -292.777512) (xy 421.918241 -292.811604) (xy 421.877738 -292.83956) (xy 421.833276 -292.860658)
			(xy 421.786005 -292.87435) (xy 421.73715 -292.880282) (xy 421.687975 -292.878301) (xy 421.639756 -292.868457)
			(xy 421.59374 -292.851005) (xy 421.551119 -292.826398) (xy 421.512998 -292.795273) (xy 421.480363 -292.758436)
			(xy 421.45406 -292.71684) (xy 421.434769 -292.671564) (xy 421.422992 -292.62378) (xy 421.419032 -292.574726)
			(xy 421.080184 -292.574726) (xy 421.079689 -292.599333) (xy 421.071794 -292.64791) (xy 421.05621 -292.694591)
			(xy 421.033339 -292.738168) (xy 421.003774 -292.777512) (xy 420.968281 -292.811604) (xy 420.927778 -292.83956)
			(xy 420.883316 -292.860658) (xy 420.836045 -292.87435) (xy 420.78719 -292.880282) (xy 420.738015 -292.878301)
			(xy 420.689796 -292.868457) (xy 420.64378 -292.851005) (xy 420.601159 -292.826398) (xy 420.563038 -292.795273)
			(xy 420.530403 -292.758436) (xy 420.5041 -292.71684) (xy 420.484809 -292.671564) (xy 420.473032 -292.62378)
			(xy 420.469072 -292.574726) (xy 420.130224 -292.574726) (xy 420.129729 -292.599333) (xy 420.121834 -292.64791)
			(xy 420.10625 -292.694591) (xy 420.083379 -292.738168) (xy 420.053814 -292.777512) (xy 420.018321 -292.811604)
			(xy 419.977818 -292.83956) (xy 419.933356 -292.860658) (xy 419.886085 -292.87435) (xy 419.83723 -292.880282)
			(xy 419.788055 -292.878301) (xy 419.739836 -292.868457) (xy 419.69382 -292.851005) (xy 419.651199 -292.826398)
			(xy 419.613078 -292.795273) (xy 419.580443 -292.758436) (xy 419.55414 -292.71684) (xy 419.534849 -292.671564)
			(xy 419.523072 -292.62378) (xy 419.519112 -292.574726) (xy 419.180259 -292.574726) (xy 419.180264 -292.57498)
			(xy 419.179769 -292.599587) (xy 419.171874 -292.648164) (xy 419.15629 -292.694845) (xy 419.133419 -292.738422)
			(xy 419.103854 -292.777766) (xy 419.068361 -292.811858) (xy 419.027858 -292.839814) (xy 418.983396 -292.860912)
			(xy 418.936125 -292.874604) (xy 418.88727 -292.880536) (xy 418.838095 -292.878555) (xy 418.789876 -292.868711)
			(xy 418.74386 -292.851259) (xy 418.701239 -292.826652) (xy 418.663118 -292.795527) (xy 418.630483 -292.75869)
			(xy 418.60418 -292.717094) (xy 418.584889 -292.671818) (xy 418.573112 -292.624034) (xy 418.569152 -292.57498)
			(xy 418.255199 -292.57498) (xy 418.255199 -292.600687) (xy 418.247068 -292.652022) (xy 418.231007 -292.701453)
			(xy 418.207411 -292.747763) (xy 418.17686 -292.789812) (xy 418.140109 -292.826563) (xy 418.09806 -292.857113)
			(xy 418.05175 -292.880709) (xy 418.002318 -292.896769) (xy 417.950983 -292.904899) (xy 417.924996 -292.905434)
			(xy 417.924742 -292.905434) (xy 417.90584 -292.905148) (xy 417.868284 -292.900819) (xy 417.849812 -292.896798)
			(xy 417.838382 -292.894004) (xy 417.81603 -292.899084) (xy 417.744402 -292.95598) (xy 417.735684 -292.963555)
			(xy 417.725628 -292.984321) (xy 417.725098 -292.995858) (xy 417.725098 -293.103554) (xy 417.725564 -293.113428)
			(xy 417.733017 -293.131718) (xy 417.739576 -293.139114) (xy 417.73983 -293.139368) (xy 417.74364 -293.143178)
			(xy 417.766754 -293.161466) (xy 417.81603 -293.200582) (xy 417.838382 -293.205662) (xy 417.849812 -293.202868)
			(xy 417.868279 -293.198821) (xy 417.905838 -293.19449) (xy 417.924742 -293.194232) (xy 417.924996 -293.194232)
			(xy 417.950982 -293.194715) (xy 418.002315 -293.202844) (xy 418.051744 -293.218904) (xy 418.098052 -293.242499)
			(xy 418.140099 -293.273048) (xy 418.17685 -293.309798) (xy 418.207399 -293.351844) (xy 418.230994 -293.398152)
			(xy 418.247055 -293.447581) (xy 418.255185 -293.498914) (xy 418.255185 -293.52494) (xy 419.519112 -293.52494)
			(xy 419.523072 -293.475886) (xy 419.534849 -293.428102) (xy 419.55414 -293.382826) (xy 419.580443 -293.34123)
			(xy 419.613078 -293.304393) (xy 419.651199 -293.273268) (xy 419.69382 -293.248661) (xy 419.739836 -293.231209)
			(xy 419.788055 -293.221365) (xy 419.83723 -293.219384) (xy 419.886085 -293.225316) (xy 419.933356 -293.239008)
			(xy 419.977818 -293.260106) (xy 420.018321 -293.288062) (xy 420.053814 -293.322154) (xy 420.083379 -293.361498)
			(xy 420.10625 -293.405075) (xy 420.121834 -293.451756) (xy 420.129729 -293.500333) (xy 420.130224 -293.52494)
			(xy 420.469072 -293.52494) (xy 420.473032 -293.475886) (xy 420.484809 -293.428102) (xy 420.5041 -293.382826)
			(xy 420.530403 -293.34123) (xy 420.563038 -293.304393) (xy 420.601159 -293.273268) (xy 420.64378 -293.248661)
			(xy 420.689796 -293.231209) (xy 420.738015 -293.221365) (xy 420.78719 -293.219384) (xy 420.836045 -293.225316)
			(xy 420.883316 -293.239008) (xy 420.927778 -293.260106) (xy 420.968281 -293.288062) (xy 421.003774 -293.322154)
			(xy 421.033339 -293.361498) (xy 421.05621 -293.405075) (xy 421.071794 -293.451756) (xy 421.079689 -293.500333)
			(xy 421.080184 -293.52494) (xy 421.419032 -293.52494) (xy 421.422992 -293.475886) (xy 421.434769 -293.428102)
			(xy 421.45406 -293.382826) (xy 421.480363 -293.34123) (xy 421.512998 -293.304393) (xy 421.551119 -293.273268)
			(xy 421.59374 -293.248661) (xy 421.639756 -293.231209) (xy 421.687975 -293.221365) (xy 421.73715 -293.219384)
			(xy 421.786005 -293.225316) (xy 421.833276 -293.239008) (xy 421.877738 -293.260106) (xy 421.918241 -293.288062)
			(xy 421.953734 -293.322154) (xy 421.983299 -293.361498) (xy 422.00617 -293.405075) (xy 422.021754 -293.451756)
			(xy 422.029649 -293.500333) (xy 422.030144 -293.52494) (xy 422.369246 -293.52494) (xy 422.373206 -293.475886)
			(xy 422.384983 -293.428102) (xy 422.404274 -293.382826) (xy 422.430577 -293.34123) (xy 422.463212 -293.304393)
			(xy 422.501333 -293.273268) (xy 422.543954 -293.248661) (xy 422.58997 -293.231209) (xy 422.638189 -293.221365)
			(xy 422.687364 -293.219384) (xy 422.736219 -293.225316) (xy 422.78349 -293.239008) (xy 422.827952 -293.260106)
			(xy 422.868455 -293.288062) (xy 422.903948 -293.322154) (xy 422.933513 -293.361498) (xy 422.956384 -293.405075)
			(xy 422.971968 -293.451756) (xy 422.979863 -293.500333) (xy 422.980358 -293.52494) (xy 423.319206 -293.52494)
			(xy 423.323166 -293.475886) (xy 423.334943 -293.428102) (xy 423.354234 -293.382826) (xy 423.380537 -293.34123)
			(xy 423.413172 -293.304393) (xy 423.451293 -293.273268) (xy 423.493914 -293.248661) (xy 423.53993 -293.231209)
			(xy 423.588149 -293.221365) (xy 423.637324 -293.219384) (xy 423.686179 -293.225316) (xy 423.73345 -293.239008)
			(xy 423.777912 -293.260106) (xy 423.818415 -293.288062) (xy 423.853908 -293.322154) (xy 423.883473 -293.361498)
			(xy 423.906344 -293.405075) (xy 423.921928 -293.451756) (xy 423.929823 -293.500333) (xy 423.930318 -293.52494)
			(xy 424.269166 -293.52494) (xy 424.273126 -293.475886) (xy 424.284903 -293.428102) (xy 424.304194 -293.382826)
			(xy 424.330497 -293.34123) (xy 424.363132 -293.304393) (xy 424.401253 -293.273268) (xy 424.443874 -293.248661)
			(xy 424.48989 -293.231209) (xy 424.538109 -293.221365) (xy 424.587284 -293.219384) (xy 424.636139 -293.225316)
			(xy 424.68341 -293.239008) (xy 424.727872 -293.260106) (xy 424.768375 -293.288062) (xy 424.803868 -293.322154)
			(xy 424.833433 -293.361498) (xy 424.856304 -293.405075) (xy 424.871888 -293.451756) (xy 424.879783 -293.500333)
			(xy 424.880278 -293.52494) (xy 425.219126 -293.52494) (xy 425.223086 -293.475886) (xy 425.234863 -293.428102)
			(xy 425.254154 -293.382826) (xy 425.280457 -293.34123) (xy 425.313092 -293.304393) (xy 425.351213 -293.273268)
			(xy 425.393834 -293.248661) (xy 425.43985 -293.231209) (xy 425.488069 -293.221365) (xy 425.537244 -293.219384)
			(xy 425.586099 -293.225316) (xy 425.63337 -293.239008) (xy 425.677832 -293.260106) (xy 425.718335 -293.288062)
			(xy 425.753828 -293.322154) (xy 425.783393 -293.361498) (xy 425.806264 -293.405075) (xy 425.821848 -293.451756)
			(xy 425.829743 -293.500333) (xy 425.830238 -293.52494) (xy 426.169086 -293.52494) (xy 426.173046 -293.475886)
			(xy 426.184823 -293.428102) (xy 426.204114 -293.382826) (xy 426.230417 -293.34123) (xy 426.263052 -293.304393)
			(xy 426.301173 -293.273268) (xy 426.343794 -293.248661) (xy 426.38981 -293.231209) (xy 426.438029 -293.221365)
			(xy 426.487204 -293.219384) (xy 426.536059 -293.225316) (xy 426.58333 -293.239008) (xy 426.627792 -293.260106)
			(xy 426.668295 -293.288062) (xy 426.703788 -293.322154) (xy 426.733353 -293.361498) (xy 426.756224 -293.405075)
			(xy 426.771808 -293.451756) (xy 426.779703 -293.500333) (xy 426.780198 -293.52494) (xy 427.119046 -293.52494)
			(xy 427.123006 -293.475886) (xy 427.134783 -293.428102) (xy 427.154074 -293.382826) (xy 427.180377 -293.34123)
			(xy 427.213012 -293.304393) (xy 427.251133 -293.273268) (xy 427.293754 -293.248661) (xy 427.33977 -293.231209)
			(xy 427.387989 -293.221365) (xy 427.437164 -293.219384) (xy 427.486019 -293.225316) (xy 427.53329 -293.239008)
			(xy 427.577752 -293.260106) (xy 427.618255 -293.288062) (xy 427.653748 -293.322154) (xy 427.683313 -293.361498)
			(xy 427.706184 -293.405075) (xy 427.721768 -293.451756) (xy 427.729663 -293.500333) (xy 427.730158 -293.52494)
			(xy 428.069006 -293.52494) (xy 428.072966 -293.475886) (xy 428.084743 -293.428102) (xy 428.104034 -293.382826)
			(xy 428.130337 -293.34123) (xy 428.162972 -293.304393) (xy 428.201093 -293.273268) (xy 428.243714 -293.248661)
			(xy 428.28973 -293.231209) (xy 428.337949 -293.221365) (xy 428.387124 -293.219384) (xy 428.435979 -293.225316)
			(xy 428.48325 -293.239008) (xy 428.527712 -293.260106) (xy 428.568215 -293.288062) (xy 428.603708 -293.322154)
			(xy 428.633273 -293.361498) (xy 428.656144 -293.405075) (xy 428.671728 -293.451756) (xy 428.679623 -293.500333)
			(xy 428.680118 -293.52494) (xy 429.01922 -293.52494) (xy 429.02318 -293.475886) (xy 429.034957 -293.428102)
			(xy 429.054248 -293.382826) (xy 429.080551 -293.34123) (xy 429.113186 -293.304393) (xy 429.151307 -293.273268)
			(xy 429.193928 -293.248661) (xy 429.239944 -293.231209) (xy 429.288163 -293.221365) (xy 429.337338 -293.219384)
			(xy 429.386193 -293.225316) (xy 429.433464 -293.239008) (xy 429.477926 -293.260106) (xy 429.518429 -293.288062)
			(xy 429.553922 -293.322154) (xy 429.583487 -293.361498) (xy 429.606358 -293.405075) (xy 429.621942 -293.451756)
			(xy 429.629837 -293.500333) (xy 429.630332 -293.52494) (xy 429.96918 -293.52494) (xy 429.97314 -293.475886)
			(xy 429.984917 -293.428102) (xy 430.004208 -293.382826) (xy 430.030511 -293.34123) (xy 430.063146 -293.304393)
			(xy 430.101267 -293.273268) (xy 430.143888 -293.248661) (xy 430.189904 -293.231209) (xy 430.238123 -293.221365)
			(xy 430.287298 -293.219384) (xy 430.336153 -293.225316) (xy 430.383424 -293.239008) (xy 430.427886 -293.260106)
			(xy 430.468389 -293.288062) (xy 430.503882 -293.322154) (xy 430.533447 -293.361498) (xy 430.556318 -293.405075)
			(xy 430.571902 -293.451756) (xy 430.579797 -293.500333) (xy 430.580292 -293.52494) (xy 430.91914 -293.52494)
			(xy 430.9231 -293.475886) (xy 430.934877 -293.428102) (xy 430.954168 -293.382826) (xy 430.980471 -293.34123)
			(xy 431.013106 -293.304393) (xy 431.051227 -293.273268) (xy 431.093848 -293.248661) (xy 431.139864 -293.231209)
			(xy 431.188083 -293.221365) (xy 431.237258 -293.219384) (xy 431.286113 -293.225316) (xy 431.333384 -293.239008)
			(xy 431.377846 -293.260106) (xy 431.418349 -293.288062) (xy 431.453842 -293.322154) (xy 431.483407 -293.361498)
			(xy 431.506278 -293.405075) (xy 431.521862 -293.451756) (xy 431.529757 -293.500333) (xy 431.530252 -293.52494)
			(xy 431.529757 -293.549547) (xy 431.521862 -293.598124) (xy 431.506278 -293.644805) (xy 431.483407 -293.688382)
			(xy 431.453842 -293.727726) (xy 431.418349 -293.761818) (xy 431.377846 -293.789774) (xy 431.333384 -293.810872)
			(xy 431.286113 -293.824564) (xy 431.237258 -293.830496) (xy 431.188083 -293.828515) (xy 431.139864 -293.818671)
			(xy 431.093848 -293.801219) (xy 431.051227 -293.776612) (xy 431.013106 -293.745487) (xy 430.980471 -293.70865)
			(xy 430.954168 -293.667054) (xy 430.934877 -293.621778) (xy 430.9231 -293.573994) (xy 430.91914 -293.52494)
			(xy 430.580292 -293.52494) (xy 430.579797 -293.549547) (xy 430.571902 -293.598124) (xy 430.556318 -293.644805)
			(xy 430.533447 -293.688382) (xy 430.503882 -293.727726) (xy 430.468389 -293.761818) (xy 430.427886 -293.789774)
			(xy 430.383424 -293.810872) (xy 430.336153 -293.824564) (xy 430.287298 -293.830496) (xy 430.238123 -293.828515)
			(xy 430.189904 -293.818671) (xy 430.143888 -293.801219) (xy 430.101267 -293.776612) (xy 430.063146 -293.745487)
			(xy 430.030511 -293.70865) (xy 430.004208 -293.667054) (xy 429.984917 -293.621778) (xy 429.97314 -293.573994)
			(xy 429.96918 -293.52494) (xy 429.630332 -293.52494) (xy 429.629837 -293.549547) (xy 429.621942 -293.598124)
			(xy 429.606358 -293.644805) (xy 429.583487 -293.688382) (xy 429.553922 -293.727726) (xy 429.518429 -293.761818)
			(xy 429.477926 -293.789774) (xy 429.433464 -293.810872) (xy 429.386193 -293.824564) (xy 429.337338 -293.830496)
			(xy 429.288163 -293.828515) (xy 429.239944 -293.818671) (xy 429.193928 -293.801219) (xy 429.151307 -293.776612)
			(xy 429.113186 -293.745487) (xy 429.080551 -293.70865) (xy 429.054248 -293.667054) (xy 429.034957 -293.621778)
			(xy 429.02318 -293.573994) (xy 429.01922 -293.52494) (xy 428.680118 -293.52494) (xy 428.679623 -293.549547)
			(xy 428.671728 -293.598124) (xy 428.656144 -293.644805) (xy 428.633273 -293.688382) (xy 428.603708 -293.727726)
			(xy 428.568215 -293.761818) (xy 428.527712 -293.789774) (xy 428.48325 -293.810872) (xy 428.435979 -293.824564)
			(xy 428.387124 -293.830496) (xy 428.337949 -293.828515) (xy 428.28973 -293.818671) (xy 428.243714 -293.801219)
			(xy 428.201093 -293.776612) (xy 428.162972 -293.745487) (xy 428.130337 -293.70865) (xy 428.104034 -293.667054)
			(xy 428.084743 -293.621778) (xy 428.072966 -293.573994) (xy 428.069006 -293.52494) (xy 427.730158 -293.52494)
			(xy 427.729663 -293.549547) (xy 427.721768 -293.598124) (xy 427.706184 -293.644805) (xy 427.683313 -293.688382)
			(xy 427.653748 -293.727726) (xy 427.618255 -293.761818) (xy 427.577752 -293.789774) (xy 427.53329 -293.810872)
			(xy 427.486019 -293.824564) (xy 427.437164 -293.830496) (xy 427.387989 -293.828515) (xy 427.33977 -293.818671)
			(xy 427.293754 -293.801219) (xy 427.251133 -293.776612) (xy 427.213012 -293.745487) (xy 427.180377 -293.70865)
			(xy 427.154074 -293.667054) (xy 427.134783 -293.621778) (xy 427.123006 -293.573994) (xy 427.119046 -293.52494)
			(xy 426.780198 -293.52494) (xy 426.779703 -293.549547) (xy 426.771808 -293.598124) (xy 426.756224 -293.644805)
			(xy 426.733353 -293.688382) (xy 426.703788 -293.727726) (xy 426.668295 -293.761818) (xy 426.627792 -293.789774)
			(xy 426.58333 -293.810872) (xy 426.536059 -293.824564) (xy 426.487204 -293.830496) (xy 426.438029 -293.828515)
			(xy 426.38981 -293.818671) (xy 426.343794 -293.801219) (xy 426.301173 -293.776612) (xy 426.263052 -293.745487)
			(xy 426.230417 -293.70865) (xy 426.204114 -293.667054) (xy 426.184823 -293.621778) (xy 426.173046 -293.573994)
			(xy 426.169086 -293.52494) (xy 425.830238 -293.52494) (xy 425.829743 -293.549547) (xy 425.821848 -293.598124)
			(xy 425.806264 -293.644805) (xy 425.783393 -293.688382) (xy 425.753828 -293.727726) (xy 425.718335 -293.761818)
			(xy 425.677832 -293.789774) (xy 425.63337 -293.810872) (xy 425.586099 -293.824564) (xy 425.537244 -293.830496)
			(xy 425.488069 -293.828515) (xy 425.43985 -293.818671) (xy 425.393834 -293.801219) (xy 425.351213 -293.776612)
			(xy 425.313092 -293.745487) (xy 425.280457 -293.70865) (xy 425.254154 -293.667054) (xy 425.234863 -293.621778)
			(xy 425.223086 -293.573994) (xy 425.219126 -293.52494) (xy 424.880278 -293.52494) (xy 424.879783 -293.549547)
			(xy 424.871888 -293.598124) (xy 424.856304 -293.644805) (xy 424.833433 -293.688382) (xy 424.803868 -293.727726)
			(xy 424.768375 -293.761818) (xy 424.727872 -293.789774) (xy 424.68341 -293.810872) (xy 424.636139 -293.824564)
			(xy 424.587284 -293.830496) (xy 424.538109 -293.828515) (xy 424.48989 -293.818671) (xy 424.443874 -293.801219)
			(xy 424.401253 -293.776612) (xy 424.363132 -293.745487) (xy 424.330497 -293.70865) (xy 424.304194 -293.667054)
			(xy 424.284903 -293.621778) (xy 424.273126 -293.573994) (xy 424.269166 -293.52494) (xy 423.930318 -293.52494)
			(xy 423.929823 -293.549547) (xy 423.921928 -293.598124) (xy 423.906344 -293.644805) (xy 423.883473 -293.688382)
			(xy 423.853908 -293.727726) (xy 423.818415 -293.761818) (xy 423.777912 -293.789774) (xy 423.73345 -293.810872)
			(xy 423.686179 -293.824564) (xy 423.637324 -293.830496) (xy 423.588149 -293.828515) (xy 423.53993 -293.818671)
			(xy 423.493914 -293.801219) (xy 423.451293 -293.776612) (xy 423.413172 -293.745487) (xy 423.380537 -293.70865)
			(xy 423.354234 -293.667054) (xy 423.334943 -293.621778) (xy 423.323166 -293.573994) (xy 423.319206 -293.52494)
			(xy 422.980358 -293.52494) (xy 422.979863 -293.549547) (xy 422.971968 -293.598124) (xy 422.956384 -293.644805)
			(xy 422.933513 -293.688382) (xy 422.903948 -293.727726) (xy 422.868455 -293.761818) (xy 422.827952 -293.789774)
			(xy 422.78349 -293.810872) (xy 422.736219 -293.824564) (xy 422.687364 -293.830496) (xy 422.638189 -293.828515)
			(xy 422.58997 -293.818671) (xy 422.543954 -293.801219) (xy 422.501333 -293.776612) (xy 422.463212 -293.745487)
			(xy 422.430577 -293.70865) (xy 422.404274 -293.667054) (xy 422.384983 -293.621778) (xy 422.373206 -293.573994)
			(xy 422.369246 -293.52494) (xy 422.030144 -293.52494) (xy 422.029649 -293.549547) (xy 422.021754 -293.598124)
			(xy 422.00617 -293.644805) (xy 421.983299 -293.688382) (xy 421.953734 -293.727726) (xy 421.918241 -293.761818)
			(xy 421.877738 -293.789774) (xy 421.833276 -293.810872) (xy 421.786005 -293.824564) (xy 421.73715 -293.830496)
			(xy 421.687975 -293.828515) (xy 421.639756 -293.818671) (xy 421.59374 -293.801219) (xy 421.551119 -293.776612)
			(xy 421.512998 -293.745487) (xy 421.480363 -293.70865) (xy 421.45406 -293.667054) (xy 421.434769 -293.621778)
			(xy 421.422992 -293.573994) (xy 421.419032 -293.52494) (xy 421.080184 -293.52494) (xy 421.079689 -293.549547)
			(xy 421.071794 -293.598124) (xy 421.05621 -293.644805) (xy 421.033339 -293.688382) (xy 421.003774 -293.727726)
			(xy 420.968281 -293.761818) (xy 420.927778 -293.789774) (xy 420.883316 -293.810872) (xy 420.836045 -293.824564)
			(xy 420.78719 -293.830496) (xy 420.738015 -293.828515) (xy 420.689796 -293.818671) (xy 420.64378 -293.801219)
			(xy 420.601159 -293.776612) (xy 420.563038 -293.745487) (xy 420.530403 -293.70865) (xy 420.5041 -293.667054)
			(xy 420.484809 -293.621778) (xy 420.473032 -293.573994) (xy 420.469072 -293.52494) (xy 420.130224 -293.52494)
			(xy 420.129729 -293.549547) (xy 420.121834 -293.598124) (xy 420.10625 -293.644805) (xy 420.083379 -293.688382)
			(xy 420.053814 -293.727726) (xy 420.018321 -293.761818) (xy 419.977818 -293.789774) (xy 419.933356 -293.810872)
			(xy 419.886085 -293.824564) (xy 419.83723 -293.830496) (xy 419.788055 -293.828515) (xy 419.739836 -293.818671)
			(xy 419.69382 -293.801219) (xy 419.651199 -293.776612) (xy 419.613078 -293.745487) (xy 419.580443 -293.70865)
			(xy 419.55414 -293.667054) (xy 419.534849 -293.621778) (xy 419.523072 -293.573994) (xy 419.519112 -293.52494)
			(xy 418.255185 -293.52494) (xy 418.255185 -293.550886) (xy 418.247055 -293.602219) (xy 418.230994 -293.651648)
			(xy 418.207399 -293.697956) (xy 418.17685 -293.740002) (xy 418.140099 -293.776752) (xy 418.098052 -293.807301)
			(xy 418.051744 -293.830896) (xy 418.002315 -293.846956) (xy 417.950982 -293.855085) (xy 417.924996 -293.855648)
			(xy 417.924742 -293.855648) (xy 417.90584 -293.855362) (xy 417.868284 -293.851033) (xy 417.849812 -293.847012)
			(xy 417.838382 -293.844218) (xy 417.81603 -293.849298) (xy 417.744402 -293.906194) (xy 417.735687 -293.91377)
			(xy 417.725636 -293.934536) (xy 417.725098 -293.946072) (xy 417.725098 -294.053514) (xy 417.725557 -294.063391)
			(xy 417.732999 -294.081691) (xy 417.739576 -294.089074) (xy 417.73983 -294.089328) (xy 417.74364 -294.093138)
			(xy 417.766754 -294.111426) (xy 417.81603 -294.150542) (xy 417.838382 -294.155622) (xy 417.849812 -294.152828)
			(xy 417.86828 -294.148782) (xy 417.905838 -294.144451) (xy 417.924742 -294.144192) (xy 417.924996 -294.144192)
			(xy 417.950985 -294.144675) (xy 418.002325 -294.152806) (xy 418.05176 -294.168867) (xy 418.098073 -294.192465)
			(xy 418.140125 -294.223017) (xy 418.17688 -294.259772) (xy 418.207433 -294.301823) (xy 418.231031 -294.348137)
			(xy 418.247094 -294.397572) (xy 418.255225 -294.448911) (xy 418.255225 -294.4749) (xy 419.519112 -294.4749)
			(xy 419.523072 -294.425846) (xy 419.534849 -294.378062) (xy 419.55414 -294.332786) (xy 419.580443 -294.29119)
			(xy 419.613078 -294.254353) (xy 419.651199 -294.223228) (xy 419.69382 -294.198621) (xy 419.739836 -294.181169)
			(xy 419.788055 -294.171325) (xy 419.83723 -294.169344) (xy 419.886085 -294.175276) (xy 419.933356 -294.188968)
			(xy 419.977818 -294.210066) (xy 420.018321 -294.238022) (xy 420.053814 -294.272114) (xy 420.083379 -294.311458)
			(xy 420.10625 -294.355035) (xy 420.121834 -294.401716) (xy 420.129729 -294.450293) (xy 420.130224 -294.4749)
			(xy 420.469072 -294.4749) (xy 420.473032 -294.425846) (xy 420.484809 -294.378062) (xy 420.5041 -294.332786)
			(xy 420.530403 -294.29119) (xy 420.563038 -294.254353) (xy 420.601159 -294.223228) (xy 420.64378 -294.198621)
			(xy 420.689796 -294.181169) (xy 420.738015 -294.171325) (xy 420.78719 -294.169344) (xy 420.836045 -294.175276)
			(xy 420.883316 -294.188968) (xy 420.927778 -294.210066) (xy 420.968281 -294.238022) (xy 421.003774 -294.272114)
			(xy 421.033339 -294.311458) (xy 421.05621 -294.355035) (xy 421.071794 -294.401716) (xy 421.079689 -294.450293)
			(xy 421.080184 -294.4749) (xy 421.419032 -294.4749) (xy 421.422992 -294.425846) (xy 421.434769 -294.378062)
			(xy 421.45406 -294.332786) (xy 421.480363 -294.29119) (xy 421.512998 -294.254353) (xy 421.551119 -294.223228)
			(xy 421.59374 -294.198621) (xy 421.639756 -294.181169) (xy 421.687975 -294.171325) (xy 421.73715 -294.169344)
			(xy 421.786005 -294.175276) (xy 421.833276 -294.188968) (xy 421.877738 -294.210066) (xy 421.918241 -294.238022)
			(xy 421.953734 -294.272114) (xy 421.983299 -294.311458) (xy 422.00617 -294.355035) (xy 422.021754 -294.401716)
			(xy 422.029649 -294.450293) (xy 422.030144 -294.4749) (xy 422.368992 -294.4749) (xy 422.372952 -294.425846)
			(xy 422.384729 -294.378062) (xy 422.40402 -294.332786) (xy 422.430323 -294.29119) (xy 422.462958 -294.254353)
			(xy 422.501079 -294.223228) (xy 422.5437 -294.198621) (xy 422.589716 -294.181169) (xy 422.637935 -294.171325)
			(xy 422.68711 -294.169344) (xy 422.735965 -294.175276) (xy 422.783236 -294.188968) (xy 422.827698 -294.210066)
			(xy 422.868201 -294.238022) (xy 422.903694 -294.272114) (xy 422.933259 -294.311458) (xy 422.95613 -294.355035)
			(xy 422.971714 -294.401716) (xy 422.979609 -294.450293) (xy 422.980104 -294.4749) (xy 423.319206 -294.4749)
			(xy 423.323166 -294.425846) (xy 423.334943 -294.378062) (xy 423.354234 -294.332786) (xy 423.380537 -294.29119)
			(xy 423.413172 -294.254353) (xy 423.451293 -294.223228) (xy 423.493914 -294.198621) (xy 423.53993 -294.181169)
			(xy 423.588149 -294.171325) (xy 423.637324 -294.169344) (xy 423.686179 -294.175276) (xy 423.73345 -294.188968)
			(xy 423.777912 -294.210066) (xy 423.818415 -294.238022) (xy 423.853908 -294.272114) (xy 423.883473 -294.311458)
			(xy 423.906344 -294.355035) (xy 423.921928 -294.401716) (xy 423.929823 -294.450293) (xy 423.930318 -294.4749)
			(xy 424.269166 -294.4749) (xy 424.273126 -294.425846) (xy 424.284903 -294.378062) (xy 424.304194 -294.332786)
			(xy 424.330497 -294.29119) (xy 424.363132 -294.254353) (xy 424.401253 -294.223228) (xy 424.443874 -294.198621)
			(xy 424.48989 -294.181169) (xy 424.538109 -294.171325) (xy 424.587284 -294.169344) (xy 424.636139 -294.175276)
			(xy 424.68341 -294.188968) (xy 424.727872 -294.210066) (xy 424.768375 -294.238022) (xy 424.803868 -294.272114)
			(xy 424.833433 -294.311458) (xy 424.856304 -294.355035) (xy 424.871888 -294.401716) (xy 424.879783 -294.450293)
			(xy 424.880278 -294.4749) (xy 426.169086 -294.4749) (xy 426.173046 -294.425846) (xy 426.184823 -294.378062)
			(xy 426.204114 -294.332786) (xy 426.230417 -294.29119) (xy 426.263052 -294.254353) (xy 426.301173 -294.223228)
			(xy 426.343794 -294.198621) (xy 426.38981 -294.181169) (xy 426.438029 -294.171325) (xy 426.487204 -294.169344)
			(xy 426.536059 -294.175276) (xy 426.58333 -294.188968) (xy 426.627792 -294.210066) (xy 426.668295 -294.238022)
			(xy 426.703788 -294.272114) (xy 426.733353 -294.311458) (xy 426.756224 -294.355035) (xy 426.771808 -294.401716)
			(xy 426.779703 -294.450293) (xy 426.780198 -294.4749) (xy 427.119046 -294.4749) (xy 427.123006 -294.425846)
			(xy 427.134783 -294.378062) (xy 427.154074 -294.332786) (xy 427.180377 -294.29119) (xy 427.213012 -294.254353)
			(xy 427.251133 -294.223228) (xy 427.293754 -294.198621) (xy 427.33977 -294.181169) (xy 427.387989 -294.171325)
			(xy 427.437164 -294.169344) (xy 427.486019 -294.175276) (xy 427.53329 -294.188968) (xy 427.577752 -294.210066)
			(xy 427.618255 -294.238022) (xy 427.653748 -294.272114) (xy 427.683313 -294.311458) (xy 427.706184 -294.355035)
			(xy 427.721768 -294.401716) (xy 427.729663 -294.450293) (xy 427.730158 -294.4749) (xy 428.069006 -294.4749)
			(xy 428.072966 -294.425846) (xy 428.084743 -294.378062) (xy 428.104034 -294.332786) (xy 428.130337 -294.29119)
			(xy 428.162972 -294.254353) (xy 428.201093 -294.223228) (xy 428.243714 -294.198621) (xy 428.28973 -294.181169)
			(xy 428.337949 -294.171325) (xy 428.387124 -294.169344) (xy 428.435979 -294.175276) (xy 428.48325 -294.188968)
			(xy 428.527712 -294.210066) (xy 428.568215 -294.238022) (xy 428.603708 -294.272114) (xy 428.633273 -294.311458)
			(xy 428.656144 -294.355035) (xy 428.671728 -294.401716) (xy 428.679623 -294.450293) (xy 428.680118 -294.4749)
			(xy 429.01922 -294.4749) (xy 429.02318 -294.425846) (xy 429.034957 -294.378062) (xy 429.054248 -294.332786)
			(xy 429.080551 -294.29119) (xy 429.113186 -294.254353) (xy 429.151307 -294.223228) (xy 429.193928 -294.198621)
			(xy 429.239944 -294.181169) (xy 429.288163 -294.171325) (xy 429.337338 -294.169344) (xy 429.386193 -294.175276)
			(xy 429.433464 -294.188968) (xy 429.477926 -294.210066) (xy 429.518429 -294.238022) (xy 429.553922 -294.272114)
			(xy 429.583487 -294.311458) (xy 429.606358 -294.355035) (xy 429.621942 -294.401716) (xy 429.629837 -294.450293)
			(xy 429.630332 -294.4749) (xy 429.96918 -294.4749) (xy 429.97314 -294.425846) (xy 429.984917 -294.378062)
			(xy 430.004208 -294.332786) (xy 430.030511 -294.29119) (xy 430.063146 -294.254353) (xy 430.101267 -294.223228)
			(xy 430.143888 -294.198621) (xy 430.189904 -294.181169) (xy 430.238123 -294.171325) (xy 430.287298 -294.169344)
			(xy 430.336153 -294.175276) (xy 430.383424 -294.188968) (xy 430.427886 -294.210066) (xy 430.468389 -294.238022)
			(xy 430.503882 -294.272114) (xy 430.533447 -294.311458) (xy 430.556318 -294.355035) (xy 430.571902 -294.401716)
			(xy 430.579797 -294.450293) (xy 430.580292 -294.4749) (xy 430.91914 -294.4749) (xy 430.9231 -294.425846)
			(xy 430.934877 -294.378062) (xy 430.954168 -294.332786) (xy 430.980471 -294.29119) (xy 431.013106 -294.254353)
			(xy 431.051227 -294.223228) (xy 431.093848 -294.198621) (xy 431.139864 -294.181169) (xy 431.188083 -294.171325)
			(xy 431.237258 -294.169344) (xy 431.286113 -294.175276) (xy 431.333384 -294.188968) (xy 431.377846 -294.210066)
			(xy 431.418349 -294.238022) (xy 431.453842 -294.272114) (xy 431.483407 -294.311458) (xy 431.506278 -294.355035)
			(xy 431.521862 -294.401716) (xy 431.529757 -294.450293) (xy 431.530252 -294.4749) (xy 431.529757 -294.499507)
			(xy 431.521862 -294.548084) (xy 431.506278 -294.594765) (xy 431.483407 -294.638342) (xy 431.47054 -294.655465)
			(xy 437.463125 -294.655465) (xy 437.47088 -294.601509) (xy 437.486235 -294.549206) (xy 437.508877 -294.499621)
			(xy 437.538345 -294.453763) (xy 437.57404 -294.412565) (xy 437.615234 -294.376867) (xy 437.661089 -294.347394)
			(xy 437.710673 -294.324748) (xy 437.762974 -294.309388) (xy 437.816929 -294.301628) (xy 437.844184 -294.301164)
			(xy 437.869584 -294.301926) (xy 437.884316 -294.302449) (xy 437.913046 -294.295896) (xy 437.938712 -294.281417)
			(xy 437.959178 -294.260214) (xy 437.97274 -294.234052) (xy 437.978272 -294.205107) (xy 437.975313 -294.175788)
			(xy 437.970168 -294.161972) (xy 437.961006 -294.13877) (xy 437.948116 -294.090579) (xy 437.941616 -294.041119)
			(xy 437.941212 -294.016176) (xy 437.941704 -293.988927) (xy 437.949463 -293.934985) (xy 437.96482 -293.882695)
			(xy 437.987461 -293.833124) (xy 438.016927 -293.787279) (xy 438.052618 -293.746094) (xy 438.093806 -293.710407)
			(xy 438.139653 -293.680945) (xy 438.189227 -293.658308) (xy 438.241517 -293.642956) (xy 438.29546 -293.635202)
			(xy 438.349958 -293.635203) (xy 438.403901 -293.64296) (xy 438.456191 -293.658314) (xy 438.505763 -293.680954)
			(xy 438.551609 -293.710418) (xy 438.592796 -293.746107) (xy 438.628484 -293.787294) (xy 438.657948 -293.83314)
			(xy 438.680587 -293.882713) (xy 438.695941 -293.935003) (xy 438.702499 -293.980616) (xy 439.58078 -293.980616)
			(xy 439.584851 -293.924994) (xy 439.596977 -293.870557) (xy 439.6169 -293.818466) (xy 439.644196 -293.769831)
			(xy 439.678282 -293.725688) (xy 439.718431 -293.686979) (xy 439.763789 -293.654528) (xy 439.813389 -293.629027)
			(xy 439.866173 -293.61102) (xy 439.921016 -293.60089) (xy 439.97675 -293.598853) (xy 440.032187 -293.604953)
			(xy 440.086144 -293.619059) (xy 440.137473 -293.640871) (xy 440.185079 -293.669925) (xy 440.227947 -293.7056)
			(xy 440.265164 -293.747137) (xy 440.295937 -293.79365) (xy 440.319609 -293.844147) (xy 440.335677 -293.897554)
			(xy 440.343797 -293.95273) (xy 440.344306 -293.980616) (xy 440.343797 -294.008502) (xy 440.335677 -294.063678)
			(xy 440.319609 -294.117085) (xy 440.295937 -294.167582) (xy 440.265164 -294.214095) (xy 440.227947 -294.255632)
			(xy 440.185079 -294.291307) (xy 440.137473 -294.320361) (xy 440.086144 -294.342173) (xy 440.032187 -294.356279)
			(xy 439.97675 -294.362379) (xy 439.921016 -294.360342) (xy 439.866173 -294.350212) (xy 439.813389 -294.332205)
			(xy 439.763789 -294.306704) (xy 439.718431 -294.274253) (xy 439.678282 -294.235544) (xy 439.644196 -294.191401)
			(xy 439.6169 -294.142766) (xy 439.596977 -294.090675) (xy 439.584851 -294.036238) (xy 439.58078 -293.980616)
			(xy 438.702499 -293.980616) (xy 438.703697 -293.988946) (xy 438.703698 -294.043444) (xy 438.695943 -294.097387)
			(xy 438.680591 -294.149677) (xy 438.657953 -294.19925) (xy 438.62849 -294.245098) (xy 438.592803 -294.286285)
			(xy 438.551618 -294.321975) (xy 438.505773 -294.351441) (xy 438.456201 -294.374082) (xy 438.403911 -294.389438)
			(xy 438.349969 -294.397196) (xy 438.32272 -294.397684) (xy 438.29732 -294.396922) (xy 438.28259 -294.396475)
			(xy 438.253872 -294.403022) (xy 438.228216 -294.417492) (xy 438.207756 -294.438681) (xy 438.194192 -294.464827)
			(xy 438.188653 -294.493757) (xy 438.189439 -294.50157) (xy 438.83656 -294.50157) (xy 438.840631 -294.445948)
			(xy 438.852757 -294.391511) (xy 438.87268 -294.33942) (xy 438.899976 -294.290785) (xy 438.934062 -294.246642)
			(xy 438.974211 -294.207933) (xy 439.019569 -294.175482) (xy 439.069169 -294.149981) (xy 439.121953 -294.131974)
			(xy 439.176796 -294.121844) (xy 439.23253 -294.119807) (xy 439.287967 -294.125907) (xy 439.341924 -294.140013)
			(xy 439.393253 -294.161825) (xy 439.440859 -294.190879) (xy 439.483727 -294.226554) (xy 439.520944 -294.268091)
			(xy 439.551717 -294.314604) (xy 439.575389 -294.365101) (xy 439.591457 -294.418508) (xy 439.599577 -294.473684)
			(xy 439.600086 -294.50157) (xy 439.599577 -294.529456) (xy 439.591457 -294.584632) (xy 439.575389 -294.638039)
			(xy 439.551717 -294.688536) (xy 439.520944 -294.735049) (xy 439.483727 -294.776586) (xy 439.440859 -294.812261)
			(xy 439.393253 -294.841315) (xy 439.341924 -294.863127) (xy 439.287967 -294.877233) (xy 439.23253 -294.883333)
			(xy 439.176796 -294.881296) (xy 439.121953 -294.871166) (xy 439.069169 -294.853159) (xy 439.019569 -294.827658)
			(xy 438.974211 -294.795207) (xy 438.934062 -294.756498) (xy 438.899976 -294.712355) (xy 438.87268 -294.66372)
			(xy 438.852757 -294.611629) (xy 438.840631 -294.557192) (xy 438.83656 -294.50157) (xy 438.189439 -294.50157)
			(xy 438.1916 -294.523064) (xy 438.196736 -294.536876) (xy 438.205882 -294.560084) (xy 438.218779 -294.608272)
			(xy 438.225284 -294.65773) (xy 438.225692 -294.682672) (xy 438.225275 -294.709927) (xy 438.217521 -294.763883)
			(xy 438.202168 -294.816186) (xy 438.179527 -294.865772) (xy 438.15006 -294.911631) (xy 438.114366 -294.952829)
			(xy 438.073172 -294.988529) (xy 438.027318 -295.018002) (xy 437.977735 -295.04065) (xy 437.925434 -295.05601)
			(xy 437.871479 -295.063771) (xy 437.816969 -295.063775) (xy 437.763013 -295.056021) (xy 437.71071 -295.040666)
			(xy 437.661125 -295.018025) (xy 437.615266 -294.988557) (xy 437.574068 -294.952863) (xy 437.538369 -294.911669)
			(xy 437.508896 -294.865814) (xy 437.486249 -294.816231) (xy 437.470889 -294.76393) (xy 437.463128 -294.709975)
			(xy 437.463125 -294.655465) (xy 431.47054 -294.655465) (xy 431.453842 -294.677686) (xy 431.418349 -294.711778)
			(xy 431.377846 -294.739734) (xy 431.333384 -294.760832) (xy 431.286113 -294.774524) (xy 431.237258 -294.780456)
			(xy 431.188083 -294.778475) (xy 431.139864 -294.768631) (xy 431.093848 -294.751179) (xy 431.051227 -294.726572)
			(xy 431.013106 -294.695447) (xy 430.980471 -294.65861) (xy 430.954168 -294.617014) (xy 430.934877 -294.571738)
			(xy 430.9231 -294.523954) (xy 430.91914 -294.4749) (xy 430.580292 -294.4749) (xy 430.579797 -294.499507)
			(xy 430.571902 -294.548084) (xy 430.556318 -294.594765) (xy 430.533447 -294.638342) (xy 430.503882 -294.677686)
			(xy 430.468389 -294.711778) (xy 430.427886 -294.739734) (xy 430.383424 -294.760832) (xy 430.336153 -294.774524)
			(xy 430.287298 -294.780456) (xy 430.238123 -294.778475) (xy 430.189904 -294.768631) (xy 430.143888 -294.751179)
			(xy 430.101267 -294.726572) (xy 430.063146 -294.695447) (xy 430.030511 -294.65861) (xy 430.004208 -294.617014)
			(xy 429.984917 -294.571738) (xy 429.97314 -294.523954) (xy 429.96918 -294.4749) (xy 429.630332 -294.4749)
			(xy 429.629837 -294.499507) (xy 429.621942 -294.548084) (xy 429.606358 -294.594765) (xy 429.583487 -294.638342)
			(xy 429.553922 -294.677686) (xy 429.518429 -294.711778) (xy 429.477926 -294.739734) (xy 429.433464 -294.760832)
			(xy 429.386193 -294.774524) (xy 429.337338 -294.780456) (xy 429.288163 -294.778475) (xy 429.239944 -294.768631)
			(xy 429.193928 -294.751179) (xy 429.151307 -294.726572) (xy 429.113186 -294.695447) (xy 429.080551 -294.65861)
			(xy 429.054248 -294.617014) (xy 429.034957 -294.571738) (xy 429.02318 -294.523954) (xy 429.01922 -294.4749)
			(xy 428.680118 -294.4749) (xy 428.679623 -294.499507) (xy 428.671728 -294.548084) (xy 428.656144 -294.594765)
			(xy 428.633273 -294.638342) (xy 428.603708 -294.677686) (xy 428.568215 -294.711778) (xy 428.527712 -294.739734)
			(xy 428.48325 -294.760832) (xy 428.435979 -294.774524) (xy 428.387124 -294.780456) (xy 428.337949 -294.778475)
			(xy 428.28973 -294.768631) (xy 428.243714 -294.751179) (xy 428.201093 -294.726572) (xy 428.162972 -294.695447)
			(xy 428.130337 -294.65861) (xy 428.104034 -294.617014) (xy 428.084743 -294.571738) (xy 428.072966 -294.523954)
			(xy 428.069006 -294.4749) (xy 427.730158 -294.4749) (xy 427.729663 -294.499507) (xy 427.721768 -294.548084)
			(xy 427.706184 -294.594765) (xy 427.683313 -294.638342) (xy 427.653748 -294.677686) (xy 427.618255 -294.711778)
			(xy 427.577752 -294.739734) (xy 427.53329 -294.760832) (xy 427.486019 -294.774524) (xy 427.437164 -294.780456)
			(xy 427.387989 -294.778475) (xy 427.33977 -294.768631) (xy 427.293754 -294.751179) (xy 427.251133 -294.726572)
			(xy 427.213012 -294.695447) (xy 427.180377 -294.65861) (xy 427.154074 -294.617014) (xy 427.134783 -294.571738)
			(xy 427.123006 -294.523954) (xy 427.119046 -294.4749) (xy 426.780198 -294.4749) (xy 426.779703 -294.499507)
			(xy 426.771808 -294.548084) (xy 426.756224 -294.594765) (xy 426.733353 -294.638342) (xy 426.703788 -294.677686)
			(xy 426.668295 -294.711778) (xy 426.627792 -294.739734) (xy 426.58333 -294.760832) (xy 426.536059 -294.774524)
			(xy 426.487204 -294.780456) (xy 426.438029 -294.778475) (xy 426.38981 -294.768631) (xy 426.343794 -294.751179)
			(xy 426.301173 -294.726572) (xy 426.263052 -294.695447) (xy 426.230417 -294.65861) (xy 426.204114 -294.617014)
			(xy 426.184823 -294.571738) (xy 426.173046 -294.523954) (xy 426.169086 -294.4749) (xy 424.880278 -294.4749)
			(xy 424.879783 -294.499507) (xy 424.871888 -294.548084) (xy 424.856304 -294.594765) (xy 424.833433 -294.638342)
			(xy 424.803868 -294.677686) (xy 424.768375 -294.711778) (xy 424.727872 -294.739734) (xy 424.68341 -294.760832)
			(xy 424.636139 -294.774524) (xy 424.587284 -294.780456) (xy 424.538109 -294.778475) (xy 424.48989 -294.768631)
			(xy 424.443874 -294.751179) (xy 424.401253 -294.726572) (xy 424.363132 -294.695447) (xy 424.330497 -294.65861)
			(xy 424.304194 -294.617014) (xy 424.284903 -294.571738) (xy 424.273126 -294.523954) (xy 424.269166 -294.4749)
			(xy 423.930318 -294.4749) (xy 423.929823 -294.499507) (xy 423.921928 -294.548084) (xy 423.906344 -294.594765)
			(xy 423.883473 -294.638342) (xy 423.853908 -294.677686) (xy 423.818415 -294.711778) (xy 423.777912 -294.739734)
			(xy 423.73345 -294.760832) (xy 423.686179 -294.774524) (xy 423.637324 -294.780456) (xy 423.588149 -294.778475)
			(xy 423.53993 -294.768631) (xy 423.493914 -294.751179) (xy 423.451293 -294.726572) (xy 423.413172 -294.695447)
			(xy 423.380537 -294.65861) (xy 423.354234 -294.617014) (xy 423.334943 -294.571738) (xy 423.323166 -294.523954)
			(xy 423.319206 -294.4749) (xy 422.980104 -294.4749) (xy 422.979609 -294.499507) (xy 422.971714 -294.548084)
			(xy 422.95613 -294.594765) (xy 422.933259 -294.638342) (xy 422.903694 -294.677686) (xy 422.868201 -294.711778)
			(xy 422.827698 -294.739734) (xy 422.783236 -294.760832) (xy 422.735965 -294.774524) (xy 422.68711 -294.780456)
			(xy 422.637935 -294.778475) (xy 422.589716 -294.768631) (xy 422.5437 -294.751179) (xy 422.501079 -294.726572)
			(xy 422.462958 -294.695447) (xy 422.430323 -294.65861) (xy 422.40402 -294.617014) (xy 422.384729 -294.571738)
			(xy 422.372952 -294.523954) (xy 422.368992 -294.4749) (xy 422.030144 -294.4749) (xy 422.029649 -294.499507)
			(xy 422.021754 -294.548084) (xy 422.00617 -294.594765) (xy 421.983299 -294.638342) (xy 421.953734 -294.677686)
			(xy 421.918241 -294.711778) (xy 421.877738 -294.739734) (xy 421.833276 -294.760832) (xy 421.786005 -294.774524)
			(xy 421.73715 -294.780456) (xy 421.687975 -294.778475) (xy 421.639756 -294.768631) (xy 421.59374 -294.751179)
			(xy 421.551119 -294.726572) (xy 421.512998 -294.695447) (xy 421.480363 -294.65861) (xy 421.45406 -294.617014)
			(xy 421.434769 -294.571738) (xy 421.422992 -294.523954) (xy 421.419032 -294.4749) (xy 421.080184 -294.4749)
			(xy 421.079689 -294.499507) (xy 421.071794 -294.548084) (xy 421.05621 -294.594765) (xy 421.033339 -294.638342)
			(xy 421.003774 -294.677686) (xy 420.968281 -294.711778) (xy 420.927778 -294.739734) (xy 420.883316 -294.760832)
			(xy 420.836045 -294.774524) (xy 420.78719 -294.780456) (xy 420.738015 -294.778475) (xy 420.689796 -294.768631)
			(xy 420.64378 -294.751179) (xy 420.601159 -294.726572) (xy 420.563038 -294.695447) (xy 420.530403 -294.65861)
			(xy 420.5041 -294.617014) (xy 420.484809 -294.571738) (xy 420.473032 -294.523954) (xy 420.469072 -294.4749)
			(xy 420.130224 -294.4749) (xy 420.129729 -294.499507) (xy 420.121834 -294.548084) (xy 420.10625 -294.594765)
			(xy 420.083379 -294.638342) (xy 420.053814 -294.677686) (xy 420.018321 -294.711778) (xy 419.977818 -294.739734)
			(xy 419.933356 -294.760832) (xy 419.886085 -294.774524) (xy 419.83723 -294.780456) (xy 419.788055 -294.778475)
			(xy 419.739836 -294.768631) (xy 419.69382 -294.751179) (xy 419.651199 -294.726572) (xy 419.613078 -294.695447)
			(xy 419.580443 -294.65861) (xy 419.55414 -294.617014) (xy 419.534849 -294.571738) (xy 419.523072 -294.523954)
			(xy 419.519112 -294.4749) (xy 418.255225 -294.4749) (xy 418.255225 -294.500889) (xy 418.247094 -294.552228)
			(xy 418.231031 -294.601663) (xy 418.207433 -294.647977) (xy 418.17688 -294.690028) (xy 418.140125 -294.726783)
			(xy 418.098073 -294.757335) (xy 418.05176 -294.780933) (xy 418.002325 -294.796994) (xy 417.950985 -294.805125)
			(xy 417.924996 -294.805608) (xy 417.924742 -294.805608) (xy 417.90584 -294.805322) (xy 417.868284 -294.800992)
			(xy 417.849812 -294.796972) (xy 417.838382 -294.794178) (xy 417.81603 -294.799258) (xy 417.744402 -294.856154)
			(xy 417.73568 -294.863728) (xy 417.725613 -294.884493) (xy 417.725098 -294.896032) (xy 417.725098 -295.355518)
			(xy 440.915804 -295.355518) (xy 440.919875 -295.299896) (xy 440.932001 -295.245459) (xy 440.951924 -295.193368)
			(xy 440.97922 -295.144733) (xy 441.013306 -295.10059) (xy 441.053455 -295.061881) (xy 441.098813 -295.02943)
			(xy 441.148413 -295.003929) (xy 441.201197 -294.985922) (xy 441.25604 -294.975792) (xy 441.311774 -294.973755)
			(xy 441.367211 -294.979855) (xy 441.421168 -294.993961) (xy 441.472497 -295.015773) (xy 441.520103 -295.044827)
			(xy 441.562971 -295.080502) (xy 441.600188 -295.122039) (xy 441.630961 -295.168552) (xy 441.654633 -295.219049)
			(xy 441.670701 -295.272456) (xy 441.678821 -295.327632) (xy 441.67933 -295.355518) (xy 441.678821 -295.383404)
			(xy 441.670701 -295.43858) (xy 441.654633 -295.491987) (xy 441.630961 -295.542484) (xy 441.600188 -295.588997)
			(xy 441.562971 -295.630534) (xy 441.520103 -295.666209) (xy 441.472497 -295.695263) (xy 441.421168 -295.717075)
			(xy 441.367211 -295.731181) (xy 441.311774 -295.737281) (xy 441.25604 -295.735244) (xy 441.201197 -295.725114)
			(xy 441.148413 -295.707107) (xy 441.098813 -295.681606) (xy 441.053455 -295.649155) (xy 441.013306 -295.610446)
			(xy 440.97922 -295.566303) (xy 440.951924 -295.517668) (xy 440.932001 -295.465577) (xy 440.919875 -295.41114)
			(xy 440.915804 -295.355518) (xy 417.725098 -295.355518) (xy 417.725098 -295.953434) (xy 417.725561 -295.96331)
			(xy 417.733008 -295.981604) (xy 417.739576 -295.988994) (xy 417.73983 -295.989248) (xy 417.74364 -295.993058)
			(xy 417.766754 -296.011346) (xy 417.81603 -296.050462) (xy 417.838382 -296.055542) (xy 417.849812 -296.052748)
			(xy 417.868279 -296.048701) (xy 417.905838 -296.044371) (xy 417.924742 -296.044112) (xy 417.924996 -296.044112)
			(xy 417.950984 -296.044595) (xy 418.00232 -296.052725) (xy 418.051752 -296.068786) (xy 418.098063 -296.092382)
			(xy 418.140112 -296.122932) (xy 418.176865 -296.159685) (xy 418.207416 -296.201734) (xy 418.231013 -296.248044)
			(xy 418.247074 -296.297476) (xy 418.255205 -296.348812) (xy 418.255205 -296.37482) (xy 419.519112 -296.37482)
			(xy 419.523072 -296.325766) (xy 419.534849 -296.277982) (xy 419.55414 -296.232706) (xy 419.580443 -296.19111)
			(xy 419.613078 -296.154273) (xy 419.651199 -296.123148) (xy 419.69382 -296.098541) (xy 419.739836 -296.081089)
			(xy 419.788055 -296.071245) (xy 419.83723 -296.069264) (xy 419.886085 -296.075196) (xy 419.933356 -296.088888)
			(xy 419.977818 -296.109986) (xy 420.018321 -296.137942) (xy 420.053814 -296.172034) (xy 420.083379 -296.211378)
			(xy 420.10625 -296.254955) (xy 420.121834 -296.301636) (xy 420.129729 -296.350213) (xy 420.130224 -296.37482)
			(xy 420.469072 -296.37482) (xy 420.473032 -296.325766) (xy 420.484809 -296.277982) (xy 420.5041 -296.232706)
			(xy 420.530403 -296.19111) (xy 420.563038 -296.154273) (xy 420.601159 -296.123148) (xy 420.64378 -296.098541)
			(xy 420.689796 -296.081089) (xy 420.738015 -296.071245) (xy 420.78719 -296.069264) (xy 420.836045 -296.075196)
			(xy 420.883316 -296.088888) (xy 420.927778 -296.109986) (xy 420.968281 -296.137942) (xy 421.003774 -296.172034)
			(xy 421.033339 -296.211378) (xy 421.05621 -296.254955) (xy 421.071794 -296.301636) (xy 421.079689 -296.350213)
			(xy 421.080184 -296.37482) (xy 421.419032 -296.37482) (xy 421.422992 -296.325766) (xy 421.434769 -296.277982)
			(xy 421.45406 -296.232706) (xy 421.480363 -296.19111) (xy 421.512998 -296.154273) (xy 421.551119 -296.123148)
			(xy 421.59374 -296.098541) (xy 421.639756 -296.081089) (xy 421.687975 -296.071245) (xy 421.73715 -296.069264)
			(xy 421.786005 -296.075196) (xy 421.833276 -296.088888) (xy 421.877738 -296.109986) (xy 421.918241 -296.137942)
			(xy 421.953734 -296.172034) (xy 421.983299 -296.211378) (xy 422.00617 -296.254955) (xy 422.021754 -296.301636)
			(xy 422.029649 -296.350213) (xy 422.030144 -296.37482) (xy 422.368992 -296.37482) (xy 422.372952 -296.325766)
			(xy 422.384729 -296.277982) (xy 422.40402 -296.232706) (xy 422.430323 -296.19111) (xy 422.462958 -296.154273)
			(xy 422.501079 -296.123148) (xy 422.5437 -296.098541) (xy 422.589716 -296.081089) (xy 422.637935 -296.071245)
			(xy 422.68711 -296.069264) (xy 422.735965 -296.075196) (xy 422.783236 -296.088888) (xy 422.827698 -296.109986)
			(xy 422.868201 -296.137942) (xy 422.903694 -296.172034) (xy 422.933259 -296.211378) (xy 422.95613 -296.254955)
			(xy 422.971714 -296.301636) (xy 422.979609 -296.350213) (xy 422.980104 -296.37482) (xy 423.319206 -296.37482)
			(xy 423.323166 -296.325766) (xy 423.334943 -296.277982) (xy 423.354234 -296.232706) (xy 423.380537 -296.19111)
			(xy 423.413172 -296.154273) (xy 423.451293 -296.123148) (xy 423.493914 -296.098541) (xy 423.53993 -296.081089)
			(xy 423.588149 -296.071245) (xy 423.637324 -296.069264) (xy 423.686179 -296.075196) (xy 423.73345 -296.088888)
			(xy 423.777912 -296.109986) (xy 423.818415 -296.137942) (xy 423.853908 -296.172034) (xy 423.883473 -296.211378)
			(xy 423.906344 -296.254955) (xy 423.921928 -296.301636) (xy 423.929823 -296.350213) (xy 423.930318 -296.37482)
			(xy 424.269166 -296.37482) (xy 424.273126 -296.325766) (xy 424.284903 -296.277982) (xy 424.304194 -296.232706)
			(xy 424.330497 -296.19111) (xy 424.363132 -296.154273) (xy 424.401253 -296.123148) (xy 424.443874 -296.098541)
			(xy 424.48989 -296.081089) (xy 424.538109 -296.071245) (xy 424.587284 -296.069264) (xy 424.636139 -296.075196)
			(xy 424.68341 -296.088888) (xy 424.727872 -296.109986) (xy 424.768375 -296.137942) (xy 424.803868 -296.172034)
			(xy 424.833433 -296.211378) (xy 424.856304 -296.254955) (xy 424.871888 -296.301636) (xy 424.879783 -296.350213)
			(xy 424.880278 -296.37482) (xy 427.119046 -296.37482) (xy 427.123006 -296.325766) (xy 427.134783 -296.277982)
			(xy 427.154074 -296.232706) (xy 427.180377 -296.19111) (xy 427.213012 -296.154273) (xy 427.251133 -296.123148)
			(xy 427.293754 -296.098541) (xy 427.33977 -296.081089) (xy 427.387989 -296.071245) (xy 427.437164 -296.069264)
			(xy 427.486019 -296.075196) (xy 427.53329 -296.088888) (xy 427.577752 -296.109986) (xy 427.618255 -296.137942)
			(xy 427.653748 -296.172034) (xy 427.683313 -296.211378) (xy 427.706184 -296.254955) (xy 427.721768 -296.301636)
			(xy 427.729663 -296.350213) (xy 427.730158 -296.37482) (xy 428.069006 -296.37482) (xy 428.072966 -296.325766)
			(xy 428.084743 -296.277982) (xy 428.104034 -296.232706) (xy 428.130337 -296.19111) (xy 428.162972 -296.154273)
			(xy 428.201093 -296.123148) (xy 428.243714 -296.098541) (xy 428.28973 -296.081089) (xy 428.337949 -296.071245)
			(xy 428.387124 -296.069264) (xy 428.435979 -296.075196) (xy 428.48325 -296.088888) (xy 428.527712 -296.109986)
			(xy 428.568215 -296.137942) (xy 428.603708 -296.172034) (xy 428.633273 -296.211378) (xy 428.656144 -296.254955)
			(xy 428.671728 -296.301636) (xy 428.679623 -296.350213) (xy 428.680118 -296.37482) (xy 429.01922 -296.37482)
			(xy 429.02318 -296.325766) (xy 429.034957 -296.277982) (xy 429.054248 -296.232706) (xy 429.080551 -296.19111)
			(xy 429.113186 -296.154273) (xy 429.151307 -296.123148) (xy 429.193928 -296.098541) (xy 429.239944 -296.081089)
			(xy 429.288163 -296.071245) (xy 429.337338 -296.069264) (xy 429.386193 -296.075196) (xy 429.433464 -296.088888)
			(xy 429.477926 -296.109986) (xy 429.518429 -296.137942) (xy 429.553922 -296.172034) (xy 429.583487 -296.211378)
			(xy 429.606358 -296.254955) (xy 429.621942 -296.301636) (xy 429.629837 -296.350213) (xy 429.630332 -296.37482)
			(xy 429.96918 -296.37482) (xy 429.97314 -296.325766) (xy 429.984917 -296.277982) (xy 430.004208 -296.232706)
			(xy 430.030511 -296.19111) (xy 430.063146 -296.154273) (xy 430.101267 -296.123148) (xy 430.143888 -296.098541)
			(xy 430.189904 -296.081089) (xy 430.238123 -296.071245) (xy 430.287298 -296.069264) (xy 430.336153 -296.075196)
			(xy 430.383424 -296.088888) (xy 430.427886 -296.109986) (xy 430.468389 -296.137942) (xy 430.503882 -296.172034)
			(xy 430.533447 -296.211378) (xy 430.556318 -296.254955) (xy 430.571902 -296.301636) (xy 430.579797 -296.350213)
			(xy 430.580292 -296.37482) (xy 430.91914 -296.37482) (xy 430.9231 -296.325766) (xy 430.934877 -296.277982)
			(xy 430.954168 -296.232706) (xy 430.980471 -296.19111) (xy 431.013106 -296.154273) (xy 431.051227 -296.123148)
			(xy 431.093848 -296.098541) (xy 431.139864 -296.081089) (xy 431.188083 -296.071245) (xy 431.237258 -296.069264)
			(xy 431.286113 -296.075196) (xy 431.333384 -296.088888) (xy 431.377846 -296.109986) (xy 431.418349 -296.137942)
			(xy 431.453842 -296.172034) (xy 431.483407 -296.211378) (xy 431.506278 -296.254955) (xy 431.521862 -296.301636)
			(xy 431.529757 -296.350213) (xy 431.530252 -296.37482) (xy 431.529757 -296.399427) (xy 431.521862 -296.448004)
			(xy 431.506278 -296.494685) (xy 431.483407 -296.538262) (xy 431.453842 -296.577606) (xy 431.418349 -296.611698)
			(xy 431.416358 -296.613072) (xy 437.562496 -296.613072) (xy 437.566567 -296.55745) (xy 437.578693 -296.503013)
			(xy 437.598616 -296.450922) (xy 437.625912 -296.402287) (xy 437.659998 -296.358144) (xy 437.700147 -296.319435)
			(xy 437.745505 -296.286984) (xy 437.795105 -296.261483) (xy 437.847889 -296.243476) (xy 437.902732 -296.233346)
			(xy 437.958466 -296.231309) (xy 438.013903 -296.237409) (xy 438.06786 -296.251515) (xy 438.119189 -296.273327)
			(xy 438.166795 -296.302381) (xy 438.209663 -296.338056) (xy 438.24688 -296.379593) (xy 438.277653 -296.426106)
			(xy 438.301325 -296.476603) (xy 438.317393 -296.53001) (xy 438.325513 -296.585186) (xy 438.326022 -296.613072)
			(xy 438.837322 -296.613072) (xy 438.841393 -296.55745) (xy 438.853519 -296.503013) (xy 438.873442 -296.450922)
			(xy 438.900738 -296.402287) (xy 438.934824 -296.358144) (xy 438.974973 -296.319435) (xy 439.020331 -296.286984)
			(xy 439.069931 -296.261483) (xy 439.122715 -296.243476) (xy 439.177558 -296.233346) (xy 439.233292 -296.231309)
			(xy 439.288729 -296.237409) (xy 439.342686 -296.251515) (xy 439.394015 -296.273327) (xy 439.441621 -296.302381)
			(xy 439.484489 -296.338056) (xy 439.521706 -296.379593) (xy 439.552479 -296.426106) (xy 439.576151 -296.476603)
			(xy 439.592219 -296.53001) (xy 439.600339 -296.585186) (xy 439.600848 -296.613072) (xy 439.600339 -296.640958)
			(xy 439.592219 -296.696134) (xy 439.576151 -296.749541) (xy 439.552479 -296.800038) (xy 439.521706 -296.846551)
			(xy 439.484489 -296.888088) (xy 439.441621 -296.923763) (xy 439.394015 -296.952817) (xy 439.342686 -296.974629)
			(xy 439.288729 -296.988735) (xy 439.233292 -296.994835) (xy 439.177558 -296.992798) (xy 439.122715 -296.982668)
			(xy 439.069931 -296.964661) (xy 439.020331 -296.93916) (xy 438.974973 -296.906709) (xy 438.934824 -296.868)
			(xy 438.900738 -296.823857) (xy 438.873442 -296.775222) (xy 438.853519 -296.723131) (xy 438.841393 -296.668694)
			(xy 438.837322 -296.613072) (xy 438.326022 -296.613072) (xy 438.325513 -296.640958) (xy 438.317393 -296.696134)
			(xy 438.301325 -296.749541) (xy 438.277653 -296.800038) (xy 438.24688 -296.846551) (xy 438.209663 -296.888088)
			(xy 438.166795 -296.923763) (xy 438.119189 -296.952817) (xy 438.06786 -296.974629) (xy 438.013903 -296.988735)
			(xy 437.958466 -296.994835) (xy 437.902732 -296.992798) (xy 437.847889 -296.982668) (xy 437.795105 -296.964661)
			(xy 437.745505 -296.93916) (xy 437.700147 -296.906709) (xy 437.659998 -296.868) (xy 437.625912 -296.823857)
			(xy 437.598616 -296.775222) (xy 437.578693 -296.723131) (xy 437.566567 -296.668694) (xy 437.562496 -296.613072)
			(xy 431.416358 -296.613072) (xy 431.377846 -296.639654) (xy 431.333384 -296.660752) (xy 431.286113 -296.674444)
			(xy 431.237258 -296.680376) (xy 431.188083 -296.678395) (xy 431.139864 -296.668551) (xy 431.093848 -296.651099)
			(xy 431.051227 -296.626492) (xy 431.013106 -296.595367) (xy 430.980471 -296.55853) (xy 430.954168 -296.516934)
			(xy 430.934877 -296.471658) (xy 430.9231 -296.423874) (xy 430.91914 -296.37482) (xy 430.580292 -296.37482)
			(xy 430.579797 -296.399427) (xy 430.571902 -296.448004) (xy 430.556318 -296.494685) (xy 430.533447 -296.538262)
			(xy 430.503882 -296.577606) (xy 430.468389 -296.611698) (xy 430.427886 -296.639654) (xy 430.383424 -296.660752)
			(xy 430.336153 -296.674444) (xy 430.287298 -296.680376) (xy 430.238123 -296.678395) (xy 430.189904 -296.668551)
			(xy 430.143888 -296.651099) (xy 430.101267 -296.626492) (xy 430.063146 -296.595367) (xy 430.030511 -296.55853)
			(xy 430.004208 -296.516934) (xy 429.984917 -296.471658) (xy 429.97314 -296.423874) (xy 429.96918 -296.37482)
			(xy 429.630332 -296.37482) (xy 429.629837 -296.399427) (xy 429.621942 -296.448004) (xy 429.606358 -296.494685)
			(xy 429.583487 -296.538262) (xy 429.553922 -296.577606) (xy 429.518429 -296.611698) (xy 429.477926 -296.639654)
			(xy 429.433464 -296.660752) (xy 429.386193 -296.674444) (xy 429.337338 -296.680376) (xy 429.288163 -296.678395)
			(xy 429.239944 -296.668551) (xy 429.193928 -296.651099) (xy 429.151307 -296.626492) (xy 429.113186 -296.595367)
			(xy 429.080551 -296.55853) (xy 429.054248 -296.516934) (xy 429.034957 -296.471658) (xy 429.02318 -296.423874)
			(xy 429.01922 -296.37482) (xy 428.680118 -296.37482) (xy 428.679623 -296.399427) (xy 428.671728 -296.448004)
			(xy 428.656144 -296.494685) (xy 428.633273 -296.538262) (xy 428.603708 -296.577606) (xy 428.568215 -296.611698)
			(xy 428.527712 -296.639654) (xy 428.48325 -296.660752) (xy 428.435979 -296.674444) (xy 428.387124 -296.680376)
			(xy 428.337949 -296.678395) (xy 428.28973 -296.668551) (xy 428.243714 -296.651099) (xy 428.201093 -296.626492)
			(xy 428.162972 -296.595367) (xy 428.130337 -296.55853) (xy 428.104034 -296.516934) (xy 428.084743 -296.471658)
			(xy 428.072966 -296.423874) (xy 428.069006 -296.37482) (xy 427.730158 -296.37482) (xy 427.729663 -296.399427)
			(xy 427.721768 -296.448004) (xy 427.706184 -296.494685) (xy 427.683313 -296.538262) (xy 427.653748 -296.577606)
			(xy 427.618255 -296.611698) (xy 427.577752 -296.639654) (xy 427.53329 -296.660752) (xy 427.486019 -296.674444)
			(xy 427.437164 -296.680376) (xy 427.387989 -296.678395) (xy 427.33977 -296.668551) (xy 427.293754 -296.651099)
			(xy 427.251133 -296.626492) (xy 427.213012 -296.595367) (xy 427.180377 -296.55853) (xy 427.154074 -296.516934)
			(xy 427.134783 -296.471658) (xy 427.123006 -296.423874) (xy 427.119046 -296.37482) (xy 424.880278 -296.37482)
			(xy 424.879783 -296.399427) (xy 424.871888 -296.448004) (xy 424.856304 -296.494685) (xy 424.833433 -296.538262)
			(xy 424.803868 -296.577606) (xy 424.768375 -296.611698) (xy 424.727872 -296.639654) (xy 424.68341 -296.660752)
			(xy 424.636139 -296.674444) (xy 424.587284 -296.680376) (xy 424.538109 -296.678395) (xy 424.48989 -296.668551)
			(xy 424.443874 -296.651099) (xy 424.401253 -296.626492) (xy 424.363132 -296.595367) (xy 424.330497 -296.55853)
			(xy 424.304194 -296.516934) (xy 424.284903 -296.471658) (xy 424.273126 -296.423874) (xy 424.269166 -296.37482)
			(xy 423.930318 -296.37482) (xy 423.929823 -296.399427) (xy 423.921928 -296.448004) (xy 423.906344 -296.494685)
			(xy 423.883473 -296.538262) (xy 423.853908 -296.577606) (xy 423.818415 -296.611698) (xy 423.777912 -296.639654)
			(xy 423.73345 -296.660752) (xy 423.686179 -296.674444) (xy 423.637324 -296.680376) (xy 423.588149 -296.678395)
			(xy 423.53993 -296.668551) (xy 423.493914 -296.651099) (xy 423.451293 -296.626492) (xy 423.413172 -296.595367)
			(xy 423.380537 -296.55853) (xy 423.354234 -296.516934) (xy 423.334943 -296.471658) (xy 423.323166 -296.423874)
			(xy 423.319206 -296.37482) (xy 422.980104 -296.37482) (xy 422.979609 -296.399427) (xy 422.971714 -296.448004)
			(xy 422.95613 -296.494685) (xy 422.933259 -296.538262) (xy 422.903694 -296.577606) (xy 422.868201 -296.611698)
			(xy 422.827698 -296.639654) (xy 422.783236 -296.660752) (xy 422.735965 -296.674444) (xy 422.68711 -296.680376)
			(xy 422.637935 -296.678395) (xy 422.589716 -296.668551) (xy 422.5437 -296.651099) (xy 422.501079 -296.626492)
			(xy 422.462958 -296.595367) (xy 422.430323 -296.55853) (xy 422.40402 -296.516934) (xy 422.384729 -296.471658)
			(xy 422.372952 -296.423874) (xy 422.368992 -296.37482) (xy 422.030144 -296.37482) (xy 422.029649 -296.399427)
			(xy 422.021754 -296.448004) (xy 422.00617 -296.494685) (xy 421.983299 -296.538262) (xy 421.953734 -296.577606)
			(xy 421.918241 -296.611698) (xy 421.877738 -296.639654) (xy 421.833276 -296.660752) (xy 421.786005 -296.674444)
			(xy 421.73715 -296.680376) (xy 421.687975 -296.678395) (xy 421.639756 -296.668551) (xy 421.59374 -296.651099)
			(xy 421.551119 -296.626492) (xy 421.512998 -296.595367) (xy 421.480363 -296.55853) (xy 421.45406 -296.516934)
			(xy 421.434769 -296.471658) (xy 421.422992 -296.423874) (xy 421.419032 -296.37482) (xy 421.080184 -296.37482)
			(xy 421.079689 -296.399427) (xy 421.071794 -296.448004) (xy 421.05621 -296.494685) (xy 421.033339 -296.538262)
			(xy 421.003774 -296.577606) (xy 420.968281 -296.611698) (xy 420.927778 -296.639654) (xy 420.883316 -296.660752)
			(xy 420.836045 -296.674444) (xy 420.78719 -296.680376) (xy 420.738015 -296.678395) (xy 420.689796 -296.668551)
			(xy 420.64378 -296.651099) (xy 420.601159 -296.626492) (xy 420.563038 -296.595367) (xy 420.530403 -296.55853)
			(xy 420.5041 -296.516934) (xy 420.484809 -296.471658) (xy 420.473032 -296.423874) (xy 420.469072 -296.37482)
			(xy 420.130224 -296.37482) (xy 420.129729 -296.399427) (xy 420.121834 -296.448004) (xy 420.10625 -296.494685)
			(xy 420.083379 -296.538262) (xy 420.053814 -296.577606) (xy 420.018321 -296.611698) (xy 419.977818 -296.639654)
			(xy 419.933356 -296.660752) (xy 419.886085 -296.674444) (xy 419.83723 -296.680376) (xy 419.788055 -296.678395)
			(xy 419.739836 -296.668551) (xy 419.69382 -296.651099) (xy 419.651199 -296.626492) (xy 419.613078 -296.595367)
			(xy 419.580443 -296.55853) (xy 419.55414 -296.516934) (xy 419.534849 -296.471658) (xy 419.523072 -296.423874)
			(xy 419.519112 -296.37482) (xy 418.255205 -296.37482) (xy 418.255205 -296.400788) (xy 418.247074 -296.452124)
			(xy 418.231013 -296.501556) (xy 418.207416 -296.547866) (xy 418.176865 -296.589915) (xy 418.140112 -296.626668)
			(xy 418.098063 -296.657218) (xy 418.051752 -296.680814) (xy 418.00232 -296.696875) (xy 417.950984 -296.705005)
			(xy 417.924996 -296.705528) (xy 417.924742 -296.705528) (xy 417.90584 -296.705242) (xy 417.868284 -296.700912)
			(xy 417.849812 -296.696892) (xy 417.838382 -296.694098) (xy 417.81603 -296.699178) (xy 417.744402 -296.756074)
			(xy 417.735683 -296.763649) (xy 417.725624 -296.784415) (xy 417.725098 -296.795952) (xy 417.725098 -296.903394)
			(xy 417.725572 -296.913265) (xy 417.733034 -296.931544) (xy 417.739576 -296.938954) (xy 417.73983 -296.939208)
			(xy 417.74364 -296.943018) (xy 417.766754 -296.961306) (xy 417.81603 -297.000422) (xy 417.838382 -297.005502)
			(xy 417.849812 -297.002708) (xy 417.86828 -296.998662) (xy 417.905838 -296.994332) (xy 417.924742 -296.994072)
			(xy 417.924996 -296.994072) (xy 417.950987 -296.994555) (xy 418.002329 -297.002686) (xy 418.051767 -297.018749)
			(xy 418.098084 -297.042348) (xy 418.140138 -297.072902) (xy 418.176895 -297.109659) (xy 418.20745 -297.151713)
			(xy 418.231049 -297.198029) (xy 418.247113 -297.247467) (xy 418.255245 -297.298809) (xy 418.255245 -297.32478)
			(xy 419.519112 -297.32478) (xy 419.523072 -297.275726) (xy 419.534849 -297.227942) (xy 419.55414 -297.182666)
			(xy 419.580443 -297.14107) (xy 419.613078 -297.104233) (xy 419.651199 -297.073108) (xy 419.69382 -297.048501)
			(xy 419.739836 -297.031049) (xy 419.788055 -297.021205) (xy 419.83723 -297.019224) (xy 419.886085 -297.025156)
			(xy 419.933356 -297.038848) (xy 419.977818 -297.059946) (xy 420.018321 -297.087902) (xy 420.053814 -297.121994)
			(xy 420.083379 -297.161338) (xy 420.10625 -297.204915) (xy 420.121834 -297.251596) (xy 420.129729 -297.300173)
			(xy 420.130224 -297.32478) (xy 420.469072 -297.32478) (xy 420.473032 -297.275726) (xy 420.484809 -297.227942)
			(xy 420.5041 -297.182666) (xy 420.530403 -297.14107) (xy 420.563038 -297.104233) (xy 420.601159 -297.073108)
			(xy 420.64378 -297.048501) (xy 420.689796 -297.031049) (xy 420.738015 -297.021205) (xy 420.78719 -297.019224)
			(xy 420.836045 -297.025156) (xy 420.883316 -297.038848) (xy 420.927778 -297.059946) (xy 420.968281 -297.087902)
			(xy 421.003774 -297.121994) (xy 421.033339 -297.161338) (xy 421.05621 -297.204915) (xy 421.071794 -297.251596)
			(xy 421.079689 -297.300173) (xy 421.080184 -297.32478) (xy 421.419032 -297.32478) (xy 421.422992 -297.275726)
			(xy 421.434769 -297.227942) (xy 421.45406 -297.182666) (xy 421.480363 -297.14107) (xy 421.512998 -297.104233)
			(xy 421.551119 -297.073108) (xy 421.59374 -297.048501) (xy 421.639756 -297.031049) (xy 421.687975 -297.021205)
			(xy 421.73715 -297.019224) (xy 421.786005 -297.025156) (xy 421.833276 -297.038848) (xy 421.877738 -297.059946)
			(xy 421.918241 -297.087902) (xy 421.953734 -297.121994) (xy 421.983299 -297.161338) (xy 422.00617 -297.204915)
			(xy 422.021754 -297.251596) (xy 422.029649 -297.300173) (xy 422.030144 -297.32478) (xy 422.369246 -297.32478)
			(xy 422.373206 -297.275726) (xy 422.384983 -297.227942) (xy 422.404274 -297.182666) (xy 422.430577 -297.14107)
			(xy 422.463212 -297.104233) (xy 422.501333 -297.073108) (xy 422.543954 -297.048501) (xy 422.58997 -297.031049)
			(xy 422.638189 -297.021205) (xy 422.687364 -297.019224) (xy 422.736219 -297.025156) (xy 422.78349 -297.038848)
			(xy 422.827952 -297.059946) (xy 422.868455 -297.087902) (xy 422.903948 -297.121994) (xy 422.933513 -297.161338)
			(xy 422.956384 -297.204915) (xy 422.971968 -297.251596) (xy 422.979863 -297.300173) (xy 422.980358 -297.32478)
			(xy 423.319206 -297.32478) (xy 423.323166 -297.275726) (xy 423.334943 -297.227942) (xy 423.354234 -297.182666)
			(xy 423.380537 -297.14107) (xy 423.413172 -297.104233) (xy 423.451293 -297.073108) (xy 423.493914 -297.048501)
			(xy 423.53993 -297.031049) (xy 423.588149 -297.021205) (xy 423.637324 -297.019224) (xy 423.686179 -297.025156)
			(xy 423.73345 -297.038848) (xy 423.777912 -297.059946) (xy 423.818415 -297.087902) (xy 423.853908 -297.121994)
			(xy 423.883473 -297.161338) (xy 423.906344 -297.204915) (xy 423.921928 -297.251596) (xy 423.929823 -297.300173)
			(xy 423.930318 -297.32478) (xy 424.269166 -297.32478) (xy 424.273126 -297.275726) (xy 424.284903 -297.227942)
			(xy 424.304194 -297.182666) (xy 424.330497 -297.14107) (xy 424.363132 -297.104233) (xy 424.401253 -297.073108)
			(xy 424.443874 -297.048501) (xy 424.48989 -297.031049) (xy 424.538109 -297.021205) (xy 424.587284 -297.019224)
			(xy 424.636139 -297.025156) (xy 424.68341 -297.038848) (xy 424.727872 -297.059946) (xy 424.768375 -297.087902)
			(xy 424.803868 -297.121994) (xy 424.833433 -297.161338) (xy 424.856304 -297.204915) (xy 424.871888 -297.251596)
			(xy 424.879783 -297.300173) (xy 424.880278 -297.32478) (xy 425.219126 -297.32478) (xy 425.223086 -297.275726)
			(xy 425.234863 -297.227942) (xy 425.254154 -297.182666) (xy 425.280457 -297.14107) (xy 425.313092 -297.104233)
			(xy 425.351213 -297.073108) (xy 425.393834 -297.048501) (xy 425.43985 -297.031049) (xy 425.488069 -297.021205)
			(xy 425.537244 -297.019224) (xy 425.586099 -297.025156) (xy 425.63337 -297.038848) (xy 425.677832 -297.059946)
			(xy 425.718335 -297.087902) (xy 425.753828 -297.121994) (xy 425.783393 -297.161338) (xy 425.806264 -297.204915)
			(xy 425.821848 -297.251596) (xy 425.829743 -297.300173) (xy 425.830238 -297.32478) (xy 426.169086 -297.32478)
			(xy 426.173046 -297.275726) (xy 426.184823 -297.227942) (xy 426.204114 -297.182666) (xy 426.230417 -297.14107)
			(xy 426.263052 -297.104233) (xy 426.301173 -297.073108) (xy 426.343794 -297.048501) (xy 426.38981 -297.031049)
			(xy 426.438029 -297.021205) (xy 426.487204 -297.019224) (xy 426.536059 -297.025156) (xy 426.58333 -297.038848)
			(xy 426.627792 -297.059946) (xy 426.668295 -297.087902) (xy 426.703788 -297.121994) (xy 426.733353 -297.161338)
			(xy 426.756224 -297.204915) (xy 426.771808 -297.251596) (xy 426.779703 -297.300173) (xy 426.780198 -297.32478)
			(xy 427.119046 -297.32478) (xy 427.123006 -297.275726) (xy 427.134783 -297.227942) (xy 427.154074 -297.182666)
			(xy 427.180377 -297.14107) (xy 427.213012 -297.104233) (xy 427.251133 -297.073108) (xy 427.293754 -297.048501)
			(xy 427.33977 -297.031049) (xy 427.387989 -297.021205) (xy 427.437164 -297.019224) (xy 427.486019 -297.025156)
			(xy 427.53329 -297.038848) (xy 427.577752 -297.059946) (xy 427.618255 -297.087902) (xy 427.653748 -297.121994)
			(xy 427.683313 -297.161338) (xy 427.706184 -297.204915) (xy 427.721768 -297.251596) (xy 427.729663 -297.300173)
			(xy 427.730158 -297.32478) (xy 428.069006 -297.32478) (xy 428.072966 -297.275726) (xy 428.084743 -297.227942)
			(xy 428.104034 -297.182666) (xy 428.130337 -297.14107) (xy 428.162972 -297.104233) (xy 428.201093 -297.073108)
			(xy 428.243714 -297.048501) (xy 428.28973 -297.031049) (xy 428.337949 -297.021205) (xy 428.387124 -297.019224)
			(xy 428.435979 -297.025156) (xy 428.48325 -297.038848) (xy 428.527712 -297.059946) (xy 428.568215 -297.087902)
			(xy 428.603708 -297.121994) (xy 428.633273 -297.161338) (xy 428.656144 -297.204915) (xy 428.671728 -297.251596)
			(xy 428.679623 -297.300173) (xy 428.680118 -297.32478) (xy 429.01922 -297.32478) (xy 429.02318 -297.275726)
			(xy 429.034957 -297.227942) (xy 429.054248 -297.182666) (xy 429.080551 -297.14107) (xy 429.113186 -297.104233)
			(xy 429.151307 -297.073108) (xy 429.193928 -297.048501) (xy 429.239944 -297.031049) (xy 429.288163 -297.021205)
			(xy 429.337338 -297.019224) (xy 429.386193 -297.025156) (xy 429.433464 -297.038848) (xy 429.477926 -297.059946)
			(xy 429.518429 -297.087902) (xy 429.553922 -297.121994) (xy 429.583487 -297.161338) (xy 429.606358 -297.204915)
			(xy 429.621942 -297.251596) (xy 429.629837 -297.300173) (xy 429.630332 -297.32478) (xy 429.96918 -297.32478)
			(xy 429.97314 -297.275726) (xy 429.984917 -297.227942) (xy 430.004208 -297.182666) (xy 430.030511 -297.14107)
			(xy 430.063146 -297.104233) (xy 430.101267 -297.073108) (xy 430.143888 -297.048501) (xy 430.189904 -297.031049)
			(xy 430.238123 -297.021205) (xy 430.287298 -297.019224) (xy 430.336153 -297.025156) (xy 430.383424 -297.038848)
			(xy 430.427886 -297.059946) (xy 430.468389 -297.087902) (xy 430.503882 -297.121994) (xy 430.533447 -297.161338)
			(xy 430.556318 -297.204915) (xy 430.571902 -297.251596) (xy 430.579797 -297.300173) (xy 430.580292 -297.32478)
			(xy 430.91914 -297.32478) (xy 430.9231 -297.275726) (xy 430.934877 -297.227942) (xy 430.954168 -297.182666)
			(xy 430.980471 -297.14107) (xy 431.013106 -297.104233) (xy 431.051227 -297.073108) (xy 431.093848 -297.048501)
			(xy 431.139864 -297.031049) (xy 431.188083 -297.021205) (xy 431.237258 -297.019224) (xy 431.286113 -297.025156)
			(xy 431.333384 -297.038848) (xy 431.377846 -297.059946) (xy 431.418349 -297.087902) (xy 431.453842 -297.121994)
			(xy 431.483407 -297.161338) (xy 431.506278 -297.204915) (xy 431.521862 -297.251596) (xy 431.529757 -297.300173)
			(xy 431.530252 -297.32478) (xy 431.529757 -297.349387) (xy 431.521862 -297.397964) (xy 431.506278 -297.444645)
			(xy 431.483407 -297.488222) (xy 431.453842 -297.527566) (xy 431.418349 -297.561658) (xy 431.377846 -297.589614)
			(xy 431.333384 -297.610712) (xy 431.286113 -297.624404) (xy 431.237258 -297.630336) (xy 431.188083 -297.628355)
			(xy 431.139864 -297.618511) (xy 431.093848 -297.601059) (xy 431.051227 -297.576452) (xy 431.013106 -297.545327)
			(xy 430.980471 -297.50849) (xy 430.954168 -297.466894) (xy 430.934877 -297.421618) (xy 430.9231 -297.373834)
			(xy 430.91914 -297.32478) (xy 430.580292 -297.32478) (xy 430.579797 -297.349387) (xy 430.571902 -297.397964)
			(xy 430.556318 -297.444645) (xy 430.533447 -297.488222) (xy 430.503882 -297.527566) (xy 430.468389 -297.561658)
			(xy 430.427886 -297.589614) (xy 430.383424 -297.610712) (xy 430.336153 -297.624404) (xy 430.287298 -297.630336)
			(xy 430.238123 -297.628355) (xy 430.189904 -297.618511) (xy 430.143888 -297.601059) (xy 430.101267 -297.576452)
			(xy 430.063146 -297.545327) (xy 430.030511 -297.50849) (xy 430.004208 -297.466894) (xy 429.984917 -297.421618)
			(xy 429.97314 -297.373834) (xy 429.96918 -297.32478) (xy 429.630332 -297.32478) (xy 429.629837 -297.349387)
			(xy 429.621942 -297.397964) (xy 429.606358 -297.444645) (xy 429.583487 -297.488222) (xy 429.553922 -297.527566)
			(xy 429.518429 -297.561658) (xy 429.477926 -297.589614) (xy 429.433464 -297.610712) (xy 429.386193 -297.624404)
			(xy 429.337338 -297.630336) (xy 429.288163 -297.628355) (xy 429.239944 -297.618511) (xy 429.193928 -297.601059)
			(xy 429.151307 -297.576452) (xy 429.113186 -297.545327) (xy 429.080551 -297.50849) (xy 429.054248 -297.466894)
			(xy 429.034957 -297.421618) (xy 429.02318 -297.373834) (xy 429.01922 -297.32478) (xy 428.680118 -297.32478)
			(xy 428.679623 -297.349387) (xy 428.671728 -297.397964) (xy 428.656144 -297.444645) (xy 428.633273 -297.488222)
			(xy 428.603708 -297.527566) (xy 428.568215 -297.561658) (xy 428.527712 -297.589614) (xy 428.48325 -297.610712)
			(xy 428.435979 -297.624404) (xy 428.387124 -297.630336) (xy 428.337949 -297.628355) (xy 428.28973 -297.618511)
			(xy 428.243714 -297.601059) (xy 428.201093 -297.576452) (xy 428.162972 -297.545327) (xy 428.130337 -297.50849)
			(xy 428.104034 -297.466894) (xy 428.084743 -297.421618) (xy 428.072966 -297.373834) (xy 428.069006 -297.32478)
			(xy 427.730158 -297.32478) (xy 427.729663 -297.349387) (xy 427.721768 -297.397964) (xy 427.706184 -297.444645)
			(xy 427.683313 -297.488222) (xy 427.653748 -297.527566) (xy 427.618255 -297.561658) (xy 427.577752 -297.589614)
			(xy 427.53329 -297.610712) (xy 427.486019 -297.624404) (xy 427.437164 -297.630336) (xy 427.387989 -297.628355)
			(xy 427.33977 -297.618511) (xy 427.293754 -297.601059) (xy 427.251133 -297.576452) (xy 427.213012 -297.545327)
			(xy 427.180377 -297.50849) (xy 427.154074 -297.466894) (xy 427.134783 -297.421618) (xy 427.123006 -297.373834)
			(xy 427.119046 -297.32478) (xy 426.780198 -297.32478) (xy 426.779703 -297.349387) (xy 426.771808 -297.397964)
			(xy 426.756224 -297.444645) (xy 426.733353 -297.488222) (xy 426.703788 -297.527566) (xy 426.668295 -297.561658)
			(xy 426.627792 -297.589614) (xy 426.58333 -297.610712) (xy 426.536059 -297.624404) (xy 426.487204 -297.630336)
			(xy 426.438029 -297.628355) (xy 426.38981 -297.618511) (xy 426.343794 -297.601059) (xy 426.301173 -297.576452)
			(xy 426.263052 -297.545327) (xy 426.230417 -297.50849) (xy 426.204114 -297.466894) (xy 426.184823 -297.421618)
			(xy 426.173046 -297.373834) (xy 426.169086 -297.32478) (xy 425.830238 -297.32478) (xy 425.829743 -297.349387)
			(xy 425.821848 -297.397964) (xy 425.806264 -297.444645) (xy 425.783393 -297.488222) (xy 425.753828 -297.527566)
			(xy 425.718335 -297.561658) (xy 425.677832 -297.589614) (xy 425.63337 -297.610712) (xy 425.586099 -297.624404)
			(xy 425.537244 -297.630336) (xy 425.488069 -297.628355) (xy 425.43985 -297.618511) (xy 425.393834 -297.601059)
			(xy 425.351213 -297.576452) (xy 425.313092 -297.545327) (xy 425.280457 -297.50849) (xy 425.254154 -297.466894)
			(xy 425.234863 -297.421618) (xy 425.223086 -297.373834) (xy 425.219126 -297.32478) (xy 424.880278 -297.32478)
			(xy 424.879783 -297.349387) (xy 424.871888 -297.397964) (xy 424.856304 -297.444645) (xy 424.833433 -297.488222)
			(xy 424.803868 -297.527566) (xy 424.768375 -297.561658) (xy 424.727872 -297.589614) (xy 424.68341 -297.610712)
			(xy 424.636139 -297.624404) (xy 424.587284 -297.630336) (xy 424.538109 -297.628355) (xy 424.48989 -297.618511)
			(xy 424.443874 -297.601059) (xy 424.401253 -297.576452) (xy 424.363132 -297.545327) (xy 424.330497 -297.50849)
			(xy 424.304194 -297.466894) (xy 424.284903 -297.421618) (xy 424.273126 -297.373834) (xy 424.269166 -297.32478)
			(xy 423.930318 -297.32478) (xy 423.929823 -297.349387) (xy 423.921928 -297.397964) (xy 423.906344 -297.444645)
			(xy 423.883473 -297.488222) (xy 423.853908 -297.527566) (xy 423.818415 -297.561658) (xy 423.777912 -297.589614)
			(xy 423.73345 -297.610712) (xy 423.686179 -297.624404) (xy 423.637324 -297.630336) (xy 423.588149 -297.628355)
			(xy 423.53993 -297.618511) (xy 423.493914 -297.601059) (xy 423.451293 -297.576452) (xy 423.413172 -297.545327)
			(xy 423.380537 -297.50849) (xy 423.354234 -297.466894) (xy 423.334943 -297.421618) (xy 423.323166 -297.373834)
			(xy 423.319206 -297.32478) (xy 422.980358 -297.32478) (xy 422.979863 -297.349387) (xy 422.971968 -297.397964)
			(xy 422.956384 -297.444645) (xy 422.933513 -297.488222) (xy 422.903948 -297.527566) (xy 422.868455 -297.561658)
			(xy 422.827952 -297.589614) (xy 422.78349 -297.610712) (xy 422.736219 -297.624404) (xy 422.687364 -297.630336)
			(xy 422.638189 -297.628355) (xy 422.58997 -297.618511) (xy 422.543954 -297.601059) (xy 422.501333 -297.576452)
			(xy 422.463212 -297.545327) (xy 422.430577 -297.50849) (xy 422.404274 -297.466894) (xy 422.384983 -297.421618)
			(xy 422.373206 -297.373834) (xy 422.369246 -297.32478) (xy 422.030144 -297.32478) (xy 422.029649 -297.349387)
			(xy 422.021754 -297.397964) (xy 422.00617 -297.444645) (xy 421.983299 -297.488222) (xy 421.953734 -297.527566)
			(xy 421.918241 -297.561658) (xy 421.877738 -297.589614) (xy 421.833276 -297.610712) (xy 421.786005 -297.624404)
			(xy 421.73715 -297.630336) (xy 421.687975 -297.628355) (xy 421.639756 -297.618511) (xy 421.59374 -297.601059)
			(xy 421.551119 -297.576452) (xy 421.512998 -297.545327) (xy 421.480363 -297.50849) (xy 421.45406 -297.466894)
			(xy 421.434769 -297.421618) (xy 421.422992 -297.373834) (xy 421.419032 -297.32478) (xy 421.080184 -297.32478)
			(xy 421.079689 -297.349387) (xy 421.071794 -297.397964) (xy 421.05621 -297.444645) (xy 421.033339 -297.488222)
			(xy 421.003774 -297.527566) (xy 420.968281 -297.561658) (xy 420.927778 -297.589614) (xy 420.883316 -297.610712)
			(xy 420.836045 -297.624404) (xy 420.78719 -297.630336) (xy 420.738015 -297.628355) (xy 420.689796 -297.618511)
			(xy 420.64378 -297.601059) (xy 420.601159 -297.576452) (xy 420.563038 -297.545327) (xy 420.530403 -297.50849)
			(xy 420.5041 -297.466894) (xy 420.484809 -297.421618) (xy 420.473032 -297.373834) (xy 420.469072 -297.32478)
			(xy 420.130224 -297.32478) (xy 420.129729 -297.349387) (xy 420.121834 -297.397964) (xy 420.10625 -297.444645)
			(xy 420.083379 -297.488222) (xy 420.053814 -297.527566) (xy 420.018321 -297.561658) (xy 419.977818 -297.589614)
			(xy 419.933356 -297.610712) (xy 419.886085 -297.624404) (xy 419.83723 -297.630336) (xy 419.788055 -297.628355)
			(xy 419.739836 -297.618511) (xy 419.69382 -297.601059) (xy 419.651199 -297.576452) (xy 419.613078 -297.545327)
			(xy 419.580443 -297.50849) (xy 419.55414 -297.466894) (xy 419.534849 -297.421618) (xy 419.523072 -297.373834)
			(xy 419.519112 -297.32478) (xy 418.255245 -297.32478) (xy 418.255245 -297.350791) (xy 418.247113 -297.402133)
			(xy 418.231049 -297.451571) (xy 418.20745 -297.497887) (xy 418.176895 -297.539941) (xy 418.140138 -297.576698)
			(xy 418.098084 -297.607252) (xy 418.051767 -297.630851) (xy 418.002329 -297.646914) (xy 417.950987 -297.655045)
			(xy 417.924996 -297.655488) (xy 417.924742 -297.655488) (xy 417.90584 -297.655202) (xy 417.868284 -297.650873)
			(xy 417.849812 -297.646852) (xy 417.838382 -297.644058) (xy 417.81603 -297.649138) (xy 417.744402 -297.706034)
			(xy 417.735676 -297.713606) (xy 417.725601 -297.734372) (xy 417.725098 -297.745912) (xy 417.725098 -297.853354)
			(xy 417.725564 -297.863228) (xy 417.733017 -297.881518) (xy 417.739576 -297.888914) (xy 417.73983 -297.889168)
			(xy 417.74364 -297.892978) (xy 417.766754 -297.911266) (xy 417.81603 -297.950382) (xy 417.838382 -297.955462)
			(xy 417.849812 -297.952668) (xy 417.868279 -297.948621) (xy 417.905838 -297.94429) (xy 417.924742 -297.944032)
			(xy 417.924996 -297.944032) (xy 417.950982 -297.944515) (xy 418.002315 -297.952644) (xy 418.051744 -297.968704)
			(xy 418.098052 -297.992299) (xy 418.140099 -298.022848) (xy 418.17685 -298.059598) (xy 418.207399 -298.101644)
			(xy 418.230994 -298.147952) (xy 418.247055 -298.197381) (xy 418.255185 -298.248714) (xy 418.255185 -298.27474)
			(xy 419.519112 -298.27474) (xy 419.523072 -298.225686) (xy 419.534849 -298.177902) (xy 419.55414 -298.132626)
			(xy 419.580443 -298.09103) (xy 419.613078 -298.054193) (xy 419.651199 -298.023068) (xy 419.69382 -297.998461)
			(xy 419.739836 -297.981009) (xy 419.788055 -297.971165) (xy 419.83723 -297.969184) (xy 419.886085 -297.975116)
			(xy 419.933356 -297.988808) (xy 419.977818 -298.009906) (xy 420.018321 -298.037862) (xy 420.053814 -298.071954)
			(xy 420.083379 -298.111298) (xy 420.10625 -298.154875) (xy 420.121834 -298.201556) (xy 420.129729 -298.250133)
			(xy 420.130224 -298.27474) (xy 420.469072 -298.27474) (xy 420.473032 -298.225686) (xy 420.484809 -298.177902)
			(xy 420.5041 -298.132626) (xy 420.530403 -298.09103) (xy 420.563038 -298.054193) (xy 420.601159 -298.023068)
			(xy 420.64378 -297.998461) (xy 420.689796 -297.981009) (xy 420.738015 -297.971165) (xy 420.78719 -297.969184)
			(xy 420.836045 -297.975116) (xy 420.883316 -297.988808) (xy 420.927778 -298.009906) (xy 420.968281 -298.037862)
			(xy 421.003774 -298.071954) (xy 421.033339 -298.111298) (xy 421.05621 -298.154875) (xy 421.071794 -298.201556)
			(xy 421.079689 -298.250133) (xy 421.080184 -298.27474) (xy 421.419032 -298.27474) (xy 421.422992 -298.225686)
			(xy 421.434769 -298.177902) (xy 421.45406 -298.132626) (xy 421.480363 -298.09103) (xy 421.512998 -298.054193)
			(xy 421.551119 -298.023068) (xy 421.59374 -297.998461) (xy 421.639756 -297.981009) (xy 421.687975 -297.971165)
			(xy 421.73715 -297.969184) (xy 421.786005 -297.975116) (xy 421.833276 -297.988808) (xy 421.877738 -298.009906)
			(xy 421.918241 -298.037862) (xy 421.953734 -298.071954) (xy 421.983299 -298.111298) (xy 422.00617 -298.154875)
			(xy 422.021754 -298.201556) (xy 422.029649 -298.250133) (xy 422.030144 -298.27474) (xy 422.368992 -298.27474)
			(xy 422.372952 -298.225686) (xy 422.384729 -298.177902) (xy 422.40402 -298.132626) (xy 422.430323 -298.09103)
			(xy 422.462958 -298.054193) (xy 422.501079 -298.023068) (xy 422.5437 -297.998461) (xy 422.589716 -297.981009)
			(xy 422.637935 -297.971165) (xy 422.68711 -297.969184) (xy 422.735965 -297.975116) (xy 422.783236 -297.988808)
			(xy 422.827698 -298.009906) (xy 422.868201 -298.037862) (xy 422.903694 -298.071954) (xy 422.933259 -298.111298)
			(xy 422.95613 -298.154875) (xy 422.971714 -298.201556) (xy 422.979609 -298.250133) (xy 422.980104 -298.27474)
			(xy 423.319206 -298.27474) (xy 423.323166 -298.225686) (xy 423.334943 -298.177902) (xy 423.354234 -298.132626)
			(xy 423.380537 -298.09103) (xy 423.413172 -298.054193) (xy 423.451293 -298.023068) (xy 423.493914 -297.998461)
			(xy 423.53993 -297.981009) (xy 423.588149 -297.971165) (xy 423.637324 -297.969184) (xy 423.686179 -297.975116)
			(xy 423.73345 -297.988808) (xy 423.777912 -298.009906) (xy 423.818415 -298.037862) (xy 423.853908 -298.071954)
			(xy 423.883473 -298.111298) (xy 423.906344 -298.154875) (xy 423.921928 -298.201556) (xy 423.929823 -298.250133)
			(xy 423.930318 -298.27474) (xy 424.269166 -298.27474) (xy 424.273126 -298.225686) (xy 424.284903 -298.177902)
			(xy 424.304194 -298.132626) (xy 424.330497 -298.09103) (xy 424.363132 -298.054193) (xy 424.401253 -298.023068)
			(xy 424.443874 -297.998461) (xy 424.48989 -297.981009) (xy 424.538109 -297.971165) (xy 424.587284 -297.969184)
			(xy 424.636139 -297.975116) (xy 424.68341 -297.988808) (xy 424.727872 -298.009906) (xy 424.768375 -298.037862)
			(xy 424.803868 -298.071954) (xy 424.833433 -298.111298) (xy 424.856304 -298.154875) (xy 424.871888 -298.201556)
			(xy 424.879783 -298.250133) (xy 424.880278 -298.27474) (xy 425.219126 -298.27474) (xy 425.223086 -298.225686)
			(xy 425.234863 -298.177902) (xy 425.254154 -298.132626) (xy 425.280457 -298.09103) (xy 425.313092 -298.054193)
			(xy 425.351213 -298.023068) (xy 425.393834 -297.998461) (xy 425.43985 -297.981009) (xy 425.488069 -297.971165)
			(xy 425.537244 -297.969184) (xy 425.586099 -297.975116) (xy 425.63337 -297.988808) (xy 425.677832 -298.009906)
			(xy 425.718335 -298.037862) (xy 425.753828 -298.071954) (xy 425.783393 -298.111298) (xy 425.806264 -298.154875)
			(xy 425.821848 -298.201556) (xy 425.829743 -298.250133) (xy 425.830238 -298.27474) (xy 426.169086 -298.27474)
			(xy 426.173046 -298.225686) (xy 426.184823 -298.177902) (xy 426.204114 -298.132626) (xy 426.230417 -298.09103)
			(xy 426.263052 -298.054193) (xy 426.301173 -298.023068) (xy 426.343794 -297.998461) (xy 426.38981 -297.981009)
			(xy 426.438029 -297.971165) (xy 426.487204 -297.969184) (xy 426.536059 -297.975116) (xy 426.58333 -297.988808)
			(xy 426.627792 -298.009906) (xy 426.668295 -298.037862) (xy 426.703788 -298.071954) (xy 426.733353 -298.111298)
			(xy 426.756224 -298.154875) (xy 426.771808 -298.201556) (xy 426.779703 -298.250133) (xy 426.780198 -298.27474)
			(xy 427.119046 -298.27474) (xy 427.123006 -298.225686) (xy 427.134783 -298.177902) (xy 427.154074 -298.132626)
			(xy 427.180377 -298.09103) (xy 427.213012 -298.054193) (xy 427.251133 -298.023068) (xy 427.293754 -297.998461)
			(xy 427.33977 -297.981009) (xy 427.387989 -297.971165) (xy 427.437164 -297.969184) (xy 427.486019 -297.975116)
			(xy 427.53329 -297.988808) (xy 427.577752 -298.009906) (xy 427.618255 -298.037862) (xy 427.653748 -298.071954)
			(xy 427.683313 -298.111298) (xy 427.706184 -298.154875) (xy 427.721768 -298.201556) (xy 427.729663 -298.250133)
			(xy 427.730158 -298.27474) (xy 428.069006 -298.27474) (xy 428.072966 -298.225686) (xy 428.084743 -298.177902)
			(xy 428.104034 -298.132626) (xy 428.130337 -298.09103) (xy 428.162972 -298.054193) (xy 428.201093 -298.023068)
			(xy 428.243714 -297.998461) (xy 428.28973 -297.981009) (xy 428.337949 -297.971165) (xy 428.387124 -297.969184)
			(xy 428.435979 -297.975116) (xy 428.48325 -297.988808) (xy 428.527712 -298.009906) (xy 428.568215 -298.037862)
			(xy 428.603708 -298.071954) (xy 428.633273 -298.111298) (xy 428.656144 -298.154875) (xy 428.671728 -298.201556)
			(xy 428.679623 -298.250133) (xy 428.680118 -298.27474) (xy 429.01922 -298.27474) (xy 429.02318 -298.225686)
			(xy 429.034957 -298.177902) (xy 429.054248 -298.132626) (xy 429.080551 -298.09103) (xy 429.113186 -298.054193)
			(xy 429.151307 -298.023068) (xy 429.193928 -297.998461) (xy 429.239944 -297.981009) (xy 429.288163 -297.971165)
			(xy 429.337338 -297.969184) (xy 429.386193 -297.975116) (xy 429.433464 -297.988808) (xy 429.477926 -298.009906)
			(xy 429.518429 -298.037862) (xy 429.553922 -298.071954) (xy 429.583487 -298.111298) (xy 429.606358 -298.154875)
			(xy 429.621942 -298.201556) (xy 429.629837 -298.250133) (xy 429.630332 -298.27474) (xy 429.96918 -298.27474)
			(xy 429.97314 -298.225686) (xy 429.984917 -298.177902) (xy 430.004208 -298.132626) (xy 430.030511 -298.09103)
			(xy 430.063146 -298.054193) (xy 430.101267 -298.023068) (xy 430.143888 -297.998461) (xy 430.189904 -297.981009)
			(xy 430.238123 -297.971165) (xy 430.287298 -297.969184) (xy 430.336153 -297.975116) (xy 430.383424 -297.988808)
			(xy 430.427886 -298.009906) (xy 430.468389 -298.037862) (xy 430.503882 -298.071954) (xy 430.533447 -298.111298)
			(xy 430.556318 -298.154875) (xy 430.571902 -298.201556) (xy 430.579797 -298.250133) (xy 430.580292 -298.27474)
			(xy 430.91914 -298.27474) (xy 430.9231 -298.225686) (xy 430.934877 -298.177902) (xy 430.954168 -298.132626)
			(xy 430.980471 -298.09103) (xy 431.013106 -298.054193) (xy 431.051227 -298.023068) (xy 431.093848 -297.998461)
			(xy 431.139864 -297.981009) (xy 431.188083 -297.971165) (xy 431.237258 -297.969184) (xy 431.286113 -297.975116)
			(xy 431.333384 -297.988808) (xy 431.377846 -298.009906) (xy 431.418349 -298.037862) (xy 431.453842 -298.071954)
			(xy 431.483407 -298.111298) (xy 431.506278 -298.154875) (xy 431.521862 -298.201556) (xy 431.529757 -298.250133)
			(xy 431.530252 -298.27474) (xy 431.529757 -298.299347) (xy 431.525612 -298.324851) (xy 432.282578 -298.324851)
			(xy 432.282578 -298.270349) (xy 432.290334 -298.216401) (xy 432.305689 -298.164106) (xy 432.328331 -298.114529)
			(xy 432.357797 -298.068679) (xy 432.393488 -298.027488) (xy 432.434679 -297.991797) (xy 432.480529 -297.962331)
			(xy 432.530106 -297.939689) (xy 432.582401 -297.924334) (xy 432.636349 -297.916578) (xy 432.6636 -297.916092)
			(xy 432.688532 -297.916503) (xy 432.737972 -297.922985) (xy 432.786146 -297.935851) (xy 432.832235 -297.954882)
			(xy 432.875452 -297.979755) (xy 432.895502 -297.994578) (xy 432.906521 -298.002476) (xy 432.931603 -298.012733)
			(xy 432.958502 -298.016018) (xy 432.985316 -298.012099) (xy 433.01015 -298.001253) (xy 433.031248 -297.984246)
			(xy 433.047119 -297.962281) (xy 433.05664 -297.93691) (xy 433.058316 -297.923458) (xy 433.061444 -297.895404)
			(xy 433.074876 -297.84058) (xy 433.096235 -297.788332) (xy 433.125056 -297.739799) (xy 433.16071 -297.696039)
			(xy 433.20242 -297.658008) (xy 433.249276 -297.626534) (xy 433.300257 -297.602303) (xy 433.354249 -297.585845)
			(xy 433.410077 -297.577518) (xy 433.4383 -297.577002) (xy 433.465552 -297.577468) (xy 433.519501 -297.585225)
			(xy 433.571797 -297.60058) (xy 433.621376 -297.623222) (xy 433.667227 -297.652689) (xy 433.693322 -297.6753)
			(xy 434.599586 -297.6753) (xy 434.603657 -297.619678) (xy 434.615783 -297.565241) (xy 434.635706 -297.51315)
			(xy 434.663002 -297.464515) (xy 434.697088 -297.420372) (xy 434.737237 -297.381663) (xy 434.782595 -297.349212)
			(xy 434.832195 -297.323711) (xy 434.884979 -297.305704) (xy 434.939822 -297.295574) (xy 434.995556 -297.293537)
			(xy 435.050993 -297.299637) (xy 435.10495 -297.313743) (xy 435.156279 -297.335555) (xy 435.203885 -297.364609)
			(xy 435.216152 -297.374818) (xy 440.915804 -297.374818) (xy 440.919875 -297.319196) (xy 440.932001 -297.264759)
			(xy 440.951924 -297.212668) (xy 440.97922 -297.164033) (xy 441.013306 -297.11989) (xy 441.053455 -297.081181)
			(xy 441.098813 -297.04873) (xy 441.148413 -297.023229) (xy 441.201197 -297.005222) (xy 441.25604 -296.995092)
			(xy 441.311774 -296.993055) (xy 441.367211 -296.999155) (xy 441.421168 -297.013261) (xy 441.472497 -297.035073)
			(xy 441.520103 -297.064127) (xy 441.562971 -297.099802) (xy 441.600188 -297.141339) (xy 441.630961 -297.187852)
			(xy 441.654633 -297.238349) (xy 441.670701 -297.291756) (xy 441.678821 -297.346932) (xy 441.67933 -297.374818)
			(xy 441.678821 -297.402704) (xy 441.670701 -297.45788) (xy 441.654633 -297.511287) (xy 441.630961 -297.561784)
			(xy 441.600188 -297.608297) (xy 441.562971 -297.649834) (xy 441.520103 -297.685509) (xy 441.472497 -297.714563)
			(xy 441.421168 -297.736375) (xy 441.367211 -297.750481) (xy 441.311774 -297.756581) (xy 441.25604 -297.754544)
			(xy 441.201197 -297.744414) (xy 441.148413 -297.726407) (xy 441.098813 -297.700906) (xy 441.053455 -297.668455)
			(xy 441.013306 -297.629746) (xy 440.97922 -297.585603) (xy 440.951924 -297.536968) (xy 440.932001 -297.484877)
			(xy 440.919875 -297.43044) (xy 440.915804 -297.374818) (xy 435.216152 -297.374818) (xy 435.246753 -297.400284)
			(xy 435.28397 -297.441821) (xy 435.314743 -297.488334) (xy 435.338415 -297.538831) (xy 435.354483 -297.592238)
			(xy 435.362603 -297.647414) (xy 435.363112 -297.6753) (xy 435.362603 -297.703186) (xy 435.354483 -297.758362)
			(xy 435.338415 -297.811769) (xy 435.314743 -297.862266) (xy 435.28397 -297.908779) (xy 435.246753 -297.950316)
			(xy 435.203885 -297.985991) (xy 435.156279 -298.015045) (xy 435.10495 -298.036857) (xy 435.050993 -298.050963)
			(xy 434.995556 -298.057063) (xy 434.939822 -298.055026) (xy 434.884979 -298.044896) (xy 434.832195 -298.026889)
			(xy 434.782595 -298.001388) (xy 434.737237 -297.968937) (xy 434.697088 -297.930228) (xy 434.663002 -297.886085)
			(xy 434.635706 -297.83745) (xy 434.615783 -297.785359) (xy 434.603657 -297.730922) (xy 434.599586 -297.6753)
			(xy 433.693322 -297.6753) (xy 433.708419 -297.688381) (xy 433.744111 -297.729573) (xy 433.773578 -297.775424)
			(xy 433.79622 -297.825003) (xy 433.811575 -297.877299) (xy 433.819332 -297.931248) (xy 433.819332 -297.985752)
			(xy 433.811575 -298.039701) (xy 433.79622 -298.091997) (xy 433.773578 -298.141576) (xy 433.744111 -298.187427)
			(xy 433.708419 -298.228619) (xy 433.667227 -298.264311) (xy 433.621376 -298.293778) (xy 433.571797 -298.31642)
			(xy 433.519501 -298.331775) (xy 433.465552 -298.339532) (xy 433.4383 -298.340018) (xy 433.413368 -298.339605)
			(xy 433.363929 -298.333123) (xy 433.315754 -298.320258) (xy 433.269666 -298.301227) (xy 433.226449 -298.276355)
			(xy 433.206398 -298.261532) (xy 433.195383 -298.253628) (xy 433.170299 -298.243369) (xy 433.143399 -298.240082)
			(xy 433.116583 -298.244002) (xy 433.091748 -298.254849) (xy 433.070649 -298.271858) (xy 433.054779 -298.293825)
			(xy 433.045259 -298.319199) (xy 433.043584 -298.332652) (xy 433.040464 -298.360707) (xy 433.027031 -298.415531)
			(xy 433.00567 -298.467779) (xy 432.976848 -298.516312) (xy 432.941193 -298.560071) (xy 432.899482 -298.598103)
			(xy 432.852626 -298.629577) (xy 432.801645 -298.653807) (xy 432.747651 -298.670265) (xy 432.691823 -298.678592)
			(xy 432.6636 -298.679108) (xy 432.636349 -298.678622) (xy 432.582401 -298.670866) (xy 432.530106 -298.655511)
			(xy 432.480529 -298.632869) (xy 432.434679 -298.603403) (xy 432.393488 -298.567712) (xy 432.357797 -298.526521)
			(xy 432.328331 -298.480671) (xy 432.305689 -298.431094) (xy 432.290334 -298.378799) (xy 432.282578 -298.324851)
			(xy 431.525612 -298.324851) (xy 431.521862 -298.347924) (xy 431.506278 -298.394605) (xy 431.483407 -298.438182)
			(xy 431.453842 -298.477526) (xy 431.418349 -298.511618) (xy 431.377846 -298.539574) (xy 431.333384 -298.560672)
			(xy 431.286113 -298.574364) (xy 431.237258 -298.580296) (xy 431.188083 -298.578315) (xy 431.139864 -298.568471)
			(xy 431.093848 -298.551019) (xy 431.051227 -298.526412) (xy 431.013106 -298.495287) (xy 430.980471 -298.45845)
			(xy 430.954168 -298.416854) (xy 430.934877 -298.371578) (xy 430.9231 -298.323794) (xy 430.91914 -298.27474)
			(xy 430.580292 -298.27474) (xy 430.579797 -298.299347) (xy 430.571902 -298.347924) (xy 430.556318 -298.394605)
			(xy 430.533447 -298.438182) (xy 430.503882 -298.477526) (xy 430.468389 -298.511618) (xy 430.427886 -298.539574)
			(xy 430.383424 -298.560672) (xy 430.336153 -298.574364) (xy 430.287298 -298.580296) (xy 430.238123 -298.578315)
			(xy 430.189904 -298.568471) (xy 430.143888 -298.551019) (xy 430.101267 -298.526412) (xy 430.063146 -298.495287)
			(xy 430.030511 -298.45845) (xy 430.004208 -298.416854) (xy 429.984917 -298.371578) (xy 429.97314 -298.323794)
			(xy 429.96918 -298.27474) (xy 429.630332 -298.27474) (xy 429.629837 -298.299347) (xy 429.621942 -298.347924)
			(xy 429.606358 -298.394605) (xy 429.583487 -298.438182) (xy 429.553922 -298.477526) (xy 429.518429 -298.511618)
			(xy 429.477926 -298.539574) (xy 429.433464 -298.560672) (xy 429.386193 -298.574364) (xy 429.337338 -298.580296)
			(xy 429.288163 -298.578315) (xy 429.239944 -298.568471) (xy 429.193928 -298.551019) (xy 429.151307 -298.526412)
			(xy 429.113186 -298.495287) (xy 429.080551 -298.45845) (xy 429.054248 -298.416854) (xy 429.034957 -298.371578)
			(xy 429.02318 -298.323794) (xy 429.01922 -298.27474) (xy 428.680118 -298.27474) (xy 428.679623 -298.299347)
			(xy 428.671728 -298.347924) (xy 428.656144 -298.394605) (xy 428.633273 -298.438182) (xy 428.603708 -298.477526)
			(xy 428.568215 -298.511618) (xy 428.527712 -298.539574) (xy 428.48325 -298.560672) (xy 428.435979 -298.574364)
			(xy 428.387124 -298.580296) (xy 428.337949 -298.578315) (xy 428.28973 -298.568471) (xy 428.243714 -298.551019)
			(xy 428.201093 -298.526412) (xy 428.162972 -298.495287) (xy 428.130337 -298.45845) (xy 428.104034 -298.416854)
			(xy 428.084743 -298.371578) (xy 428.072966 -298.323794) (xy 428.069006 -298.27474) (xy 427.730158 -298.27474)
			(xy 427.729663 -298.299347) (xy 427.721768 -298.347924) (xy 427.706184 -298.394605) (xy 427.683313 -298.438182)
			(xy 427.653748 -298.477526) (xy 427.618255 -298.511618) (xy 427.577752 -298.539574) (xy 427.53329 -298.560672)
			(xy 427.486019 -298.574364) (xy 427.437164 -298.580296) (xy 427.387989 -298.578315) (xy 427.33977 -298.568471)
			(xy 427.293754 -298.551019) (xy 427.251133 -298.526412) (xy 427.213012 -298.495287) (xy 427.180377 -298.45845)
			(xy 427.154074 -298.416854) (xy 427.134783 -298.371578) (xy 427.123006 -298.323794) (xy 427.119046 -298.27474)
			(xy 426.780198 -298.27474) (xy 426.779703 -298.299347) (xy 426.771808 -298.347924) (xy 426.756224 -298.394605)
			(xy 426.733353 -298.438182) (xy 426.703788 -298.477526) (xy 426.668295 -298.511618) (xy 426.627792 -298.539574)
			(xy 426.58333 -298.560672) (xy 426.536059 -298.574364) (xy 426.487204 -298.580296) (xy 426.438029 -298.578315)
			(xy 426.38981 -298.568471) (xy 426.343794 -298.551019) (xy 426.301173 -298.526412) (xy 426.263052 -298.495287)
			(xy 426.230417 -298.45845) (xy 426.204114 -298.416854) (xy 426.184823 -298.371578) (xy 426.173046 -298.323794)
			(xy 426.169086 -298.27474) (xy 425.830238 -298.27474) (xy 425.829743 -298.299347) (xy 425.821848 -298.347924)
			(xy 425.806264 -298.394605) (xy 425.783393 -298.438182) (xy 425.753828 -298.477526) (xy 425.718335 -298.511618)
			(xy 425.677832 -298.539574) (xy 425.63337 -298.560672) (xy 425.586099 -298.574364) (xy 425.537244 -298.580296)
			(xy 425.488069 -298.578315) (xy 425.43985 -298.568471) (xy 425.393834 -298.551019) (xy 425.351213 -298.526412)
			(xy 425.313092 -298.495287) (xy 425.280457 -298.45845) (xy 425.254154 -298.416854) (xy 425.234863 -298.371578)
			(xy 425.223086 -298.323794) (xy 425.219126 -298.27474) (xy 424.880278 -298.27474) (xy 424.879783 -298.299347)
			(xy 424.871888 -298.347924) (xy 424.856304 -298.394605) (xy 424.833433 -298.438182) (xy 424.803868 -298.477526)
			(xy 424.768375 -298.511618) (xy 424.727872 -298.539574) (xy 424.68341 -298.560672) (xy 424.636139 -298.574364)
			(xy 424.587284 -298.580296) (xy 424.538109 -298.578315) (xy 424.48989 -298.568471) (xy 424.443874 -298.551019)
			(xy 424.401253 -298.526412) (xy 424.363132 -298.495287) (xy 424.330497 -298.45845) (xy 424.304194 -298.416854)
			(xy 424.284903 -298.371578) (xy 424.273126 -298.323794) (xy 424.269166 -298.27474) (xy 423.930318 -298.27474)
			(xy 423.929823 -298.299347) (xy 423.921928 -298.347924) (xy 423.906344 -298.394605) (xy 423.883473 -298.438182)
			(xy 423.853908 -298.477526) (xy 423.818415 -298.511618) (xy 423.777912 -298.539574) (xy 423.73345 -298.560672)
			(xy 423.686179 -298.574364) (xy 423.637324 -298.580296) (xy 423.588149 -298.578315) (xy 423.53993 -298.568471)
			(xy 423.493914 -298.551019) (xy 423.451293 -298.526412) (xy 423.413172 -298.495287) (xy 423.380537 -298.45845)
			(xy 423.354234 -298.416854) (xy 423.334943 -298.371578) (xy 423.323166 -298.323794) (xy 423.319206 -298.27474)
			(xy 422.980104 -298.27474) (xy 422.979609 -298.299347) (xy 422.971714 -298.347924) (xy 422.95613 -298.394605)
			(xy 422.933259 -298.438182) (xy 422.903694 -298.477526) (xy 422.868201 -298.511618) (xy 422.827698 -298.539574)
			(xy 422.783236 -298.560672) (xy 422.735965 -298.574364) (xy 422.68711 -298.580296) (xy 422.637935 -298.578315)
			(xy 422.589716 -298.568471) (xy 422.5437 -298.551019) (xy 422.501079 -298.526412) (xy 422.462958 -298.495287)
			(xy 422.430323 -298.45845) (xy 422.40402 -298.416854) (xy 422.384729 -298.371578) (xy 422.372952 -298.323794)
			(xy 422.368992 -298.27474) (xy 422.030144 -298.27474) (xy 422.029649 -298.299347) (xy 422.021754 -298.347924)
			(xy 422.00617 -298.394605) (xy 421.983299 -298.438182) (xy 421.953734 -298.477526) (xy 421.918241 -298.511618)
			(xy 421.877738 -298.539574) (xy 421.833276 -298.560672) (xy 421.786005 -298.574364) (xy 421.73715 -298.580296)
			(xy 421.687975 -298.578315) (xy 421.639756 -298.568471) (xy 421.59374 -298.551019) (xy 421.551119 -298.526412)
			(xy 421.512998 -298.495287) (xy 421.480363 -298.45845) (xy 421.45406 -298.416854) (xy 421.434769 -298.371578)
			(xy 421.422992 -298.323794) (xy 421.419032 -298.27474) (xy 421.080184 -298.27474) (xy 421.079689 -298.299347)
			(xy 421.071794 -298.347924) (xy 421.05621 -298.394605) (xy 421.033339 -298.438182) (xy 421.003774 -298.477526)
			(xy 420.968281 -298.511618) (xy 420.927778 -298.539574) (xy 420.883316 -298.560672) (xy 420.836045 -298.574364)
			(xy 420.78719 -298.580296) (xy 420.738015 -298.578315) (xy 420.689796 -298.568471) (xy 420.64378 -298.551019)
			(xy 420.601159 -298.526412) (xy 420.563038 -298.495287) (xy 420.530403 -298.45845) (xy 420.5041 -298.416854)
			(xy 420.484809 -298.371578) (xy 420.473032 -298.323794) (xy 420.469072 -298.27474) (xy 420.130224 -298.27474)
			(xy 420.129729 -298.299347) (xy 420.121834 -298.347924) (xy 420.10625 -298.394605) (xy 420.083379 -298.438182)
			(xy 420.053814 -298.477526) (xy 420.018321 -298.511618) (xy 419.977818 -298.539574) (xy 419.933356 -298.560672)
			(xy 419.886085 -298.574364) (xy 419.83723 -298.580296) (xy 419.788055 -298.578315) (xy 419.739836 -298.568471)
			(xy 419.69382 -298.551019) (xy 419.651199 -298.526412) (xy 419.613078 -298.495287) (xy 419.580443 -298.45845)
			(xy 419.55414 -298.416854) (xy 419.534849 -298.371578) (xy 419.523072 -298.323794) (xy 419.519112 -298.27474)
			(xy 418.255185 -298.27474) (xy 418.255185 -298.300686) (xy 418.247055 -298.352019) (xy 418.230994 -298.401448)
			(xy 418.207399 -298.447756) (xy 418.17685 -298.489802) (xy 418.140099 -298.526552) (xy 418.098052 -298.557101)
			(xy 418.051744 -298.580696) (xy 418.002315 -298.596756) (xy 417.950982 -298.604885) (xy 417.924996 -298.605448)
			(xy 417.924742 -298.605448) (xy 417.90584 -298.605162) (xy 417.868284 -298.600833) (xy 417.849812 -298.596812)
			(xy 417.838382 -298.594018) (xy 417.81603 -298.599098) (xy 417.744402 -298.655994) (xy 417.735687 -298.66357)
			(xy 417.725636 -298.684336) (xy 417.725098 -298.695872) (xy 417.725098 -298.713652) (xy 434.780688 -298.713652)
			(xy 434.784759 -298.65803) (xy 434.796885 -298.603593) (xy 434.816808 -298.551502) (xy 434.844104 -298.502867)
			(xy 434.87819 -298.458724) (xy 434.918339 -298.420015) (xy 434.963697 -298.387564) (xy 435.013297 -298.362063)
			(xy 435.066081 -298.344056) (xy 435.120924 -298.333926) (xy 435.176658 -298.331889) (xy 435.232095 -298.337989)
			(xy 435.286052 -298.352095) (xy 435.337381 -298.373907) (xy 435.384987 -298.402961) (xy 435.427855 -298.438636)
			(xy 435.465072 -298.480173) (xy 435.495845 -298.526686) (xy 435.519517 -298.577183) (xy 435.535585 -298.63059)
			(xy 435.543705 -298.685766) (xy 435.544214 -298.713652) (xy 435.543705 -298.741538) (xy 435.535585 -298.796714)
			(xy 435.519517 -298.850121) (xy 435.495845 -298.900618) (xy 435.465072 -298.947131) (xy 435.427855 -298.988668)
			(xy 435.384987 -299.024343) (xy 435.337381 -299.053397) (xy 435.286052 -299.075209) (xy 435.232095 -299.089315)
			(xy 435.176658 -299.095415) (xy 435.120924 -299.093378) (xy 435.066081 -299.083248) (xy 435.013297 -299.065241)
			(xy 434.963697 -299.03974) (xy 434.918339 -299.007289) (xy 434.87819 -298.96858) (xy 434.844104 -298.924437)
			(xy 434.816808 -298.875802) (xy 434.796885 -298.823711) (xy 434.784759 -298.769274) (xy 434.780688 -298.713652)
			(xy 417.725098 -298.713652) (xy 417.725098 -298.803568) (xy 417.725567 -298.813441) (xy 417.733023 -298.831727)
			(xy 417.739576 -298.839128) (xy 417.73983 -298.839382) (xy 417.74364 -298.843192) (xy 417.766754 -298.86148)
			(xy 417.81603 -298.900596) (xy 417.838382 -298.905676) (xy 417.849812 -298.902882) (xy 417.86828 -298.898836)
			(xy 417.905838 -298.894507) (xy 417.924742 -298.894246) (xy 417.924996 -298.894246) (xy 417.950989 -298.894729)
			(xy 418.002335 -298.902861) (xy 418.051777 -298.918925) (xy 418.098097 -298.942526) (xy 418.140155 -298.973082)
			(xy 418.176915 -299.009842) (xy 418.207472 -299.051899) (xy 418.231074 -299.098219) (xy 418.247138 -299.147661)
			(xy 418.255271 -299.199007) (xy 418.255271 -299.224954) (xy 418.569152 -299.224954) (xy 418.573112 -299.1759)
			(xy 418.584889 -299.128116) (xy 418.60418 -299.08284) (xy 418.630483 -299.041244) (xy 418.663118 -299.004407)
			(xy 418.701239 -298.973282) (xy 418.74386 -298.948675) (xy 418.789876 -298.931223) (xy 418.838095 -298.921379)
			(xy 418.88727 -298.919398) (xy 418.936125 -298.92533) (xy 418.983396 -298.939022) (xy 419.027858 -298.96012)
			(xy 419.068361 -298.988076) (xy 419.103854 -299.022168) (xy 419.133419 -299.061512) (xy 419.15629 -299.105089)
			(xy 419.171874 -299.15177) (xy 419.179769 -299.200347) (xy 419.180264 -299.224954) (xy 419.519112 -299.224954)
			(xy 419.523072 -299.1759) (xy 419.534849 -299.128116) (xy 419.55414 -299.08284) (xy 419.580443 -299.041244)
			(xy 419.613078 -299.004407) (xy 419.651199 -298.973282) (xy 419.69382 -298.948675) (xy 419.739836 -298.931223)
			(xy 419.788055 -298.921379) (xy 419.83723 -298.919398) (xy 419.886085 -298.92533) (xy 419.933356 -298.939022)
			(xy 419.977818 -298.96012) (xy 420.018321 -298.988076) (xy 420.053814 -299.022168) (xy 420.083379 -299.061512)
			(xy 420.10625 -299.105089) (xy 420.121834 -299.15177) (xy 420.129729 -299.200347) (xy 420.130224 -299.224954)
			(xy 420.469072 -299.224954) (xy 420.473032 -299.1759) (xy 420.484809 -299.128116) (xy 420.5041 -299.08284)
			(xy 420.530403 -299.041244) (xy 420.563038 -299.004407) (xy 420.601159 -298.973282) (xy 420.64378 -298.948675)
			(xy 420.689796 -298.931223) (xy 420.738015 -298.921379) (xy 420.78719 -298.919398) (xy 420.836045 -298.92533)
			(xy 420.883316 -298.939022) (xy 420.927778 -298.96012) (xy 420.968281 -298.988076) (xy 421.003774 -299.022168)
			(xy 421.033339 -299.061512) (xy 421.05621 -299.105089) (xy 421.071794 -299.15177) (xy 421.079689 -299.200347)
			(xy 421.080184 -299.224954) (xy 421.419032 -299.224954) (xy 421.422992 -299.1759) (xy 421.434769 -299.128116)
			(xy 421.45406 -299.08284) (xy 421.480363 -299.041244) (xy 421.512998 -299.004407) (xy 421.551119 -298.973282)
			(xy 421.59374 -298.948675) (xy 421.639756 -298.931223) (xy 421.687975 -298.921379) (xy 421.73715 -298.919398)
			(xy 421.786005 -298.92533) (xy 421.833276 -298.939022) (xy 421.877738 -298.96012) (xy 421.918241 -298.988076)
			(xy 421.953734 -299.022168) (xy 421.983299 -299.061512) (xy 422.00617 -299.105089) (xy 422.021754 -299.15177)
			(xy 422.029649 -299.200347) (xy 422.030144 -299.224954) (xy 424.269166 -299.224954) (xy 424.273126 -299.1759)
			(xy 424.284903 -299.128116) (xy 424.304194 -299.08284) (xy 424.330497 -299.041244) (xy 424.363132 -299.004407)
			(xy 424.401253 -298.973282) (xy 424.443874 -298.948675) (xy 424.48989 -298.931223) (xy 424.538109 -298.921379)
			(xy 424.587284 -298.919398) (xy 424.636139 -298.92533) (xy 424.68341 -298.939022) (xy 424.727872 -298.96012)
			(xy 424.768375 -298.988076) (xy 424.803868 -299.022168) (xy 424.833433 -299.061512) (xy 424.856304 -299.105089)
			(xy 424.871888 -299.15177) (xy 424.879783 -299.200347) (xy 424.880278 -299.224954) (xy 425.219126 -299.224954)
			(xy 425.223086 -299.1759) (xy 425.234863 -299.128116) (xy 425.254154 -299.08284) (xy 425.280457 -299.041244)
			(xy 425.313092 -299.004407) (xy 425.351213 -298.973282) (xy 425.393834 -298.948675) (xy 425.43985 -298.931223)
			(xy 425.488069 -298.921379) (xy 425.537244 -298.919398) (xy 425.586099 -298.92533) (xy 425.63337 -298.939022)
			(xy 425.677832 -298.96012) (xy 425.718335 -298.988076) (xy 425.753828 -299.022168) (xy 425.783393 -299.061512)
			(xy 425.806264 -299.105089) (xy 425.821848 -299.15177) (xy 425.829743 -299.200347) (xy 425.830238 -299.224954)
			(xy 426.169086 -299.224954) (xy 426.173046 -299.1759) (xy 426.184823 -299.128116) (xy 426.204114 -299.08284)
			(xy 426.230417 -299.041244) (xy 426.263052 -299.004407) (xy 426.301173 -298.973282) (xy 426.343794 -298.948675)
			(xy 426.38981 -298.931223) (xy 426.438029 -298.921379) (xy 426.487204 -298.919398) (xy 426.536059 -298.92533)
			(xy 426.58333 -298.939022) (xy 426.627792 -298.96012) (xy 426.668295 -298.988076) (xy 426.703788 -299.022168)
			(xy 426.733353 -299.061512) (xy 426.756224 -299.105089) (xy 426.771808 -299.15177) (xy 426.779703 -299.200347)
			(xy 426.780198 -299.224954) (xy 427.119046 -299.224954) (xy 427.123006 -299.1759) (xy 427.134783 -299.128116)
			(xy 427.154074 -299.08284) (xy 427.180377 -299.041244) (xy 427.213012 -299.004407) (xy 427.251133 -298.973282)
			(xy 427.293754 -298.948675) (xy 427.33977 -298.931223) (xy 427.387989 -298.921379) (xy 427.437164 -298.919398)
			(xy 427.486019 -298.92533) (xy 427.53329 -298.939022) (xy 427.577752 -298.96012) (xy 427.618255 -298.988076)
			(xy 427.653748 -299.022168) (xy 427.683313 -299.061512) (xy 427.706184 -299.105089) (xy 427.721768 -299.15177)
			(xy 427.729663 -299.200347) (xy 427.730158 -299.224954) (xy 428.069006 -299.224954) (xy 428.072966 -299.1759)
			(xy 428.084743 -299.128116) (xy 428.104034 -299.08284) (xy 428.130337 -299.041244) (xy 428.162972 -299.004407)
			(xy 428.201093 -298.973282) (xy 428.243714 -298.948675) (xy 428.28973 -298.931223) (xy 428.337949 -298.921379)
			(xy 428.387124 -298.919398) (xy 428.435979 -298.92533) (xy 428.48325 -298.939022) (xy 428.527712 -298.96012)
			(xy 428.568215 -298.988076) (xy 428.603708 -299.022168) (xy 428.633273 -299.061512) (xy 428.656144 -299.105089)
			(xy 428.671728 -299.15177) (xy 428.679623 -299.200347) (xy 428.680118 -299.224954) (xy 429.01922 -299.224954)
			(xy 429.02318 -299.1759) (xy 429.034957 -299.128116) (xy 429.054248 -299.08284) (xy 429.080551 -299.041244)
			(xy 429.113186 -299.004407) (xy 429.151307 -298.973282) (xy 429.193928 -298.948675) (xy 429.239944 -298.931223)
			(xy 429.288163 -298.921379) (xy 429.337338 -298.919398) (xy 429.386193 -298.92533) (xy 429.433464 -298.939022)
			(xy 429.477926 -298.96012) (xy 429.518429 -298.988076) (xy 429.553922 -299.022168) (xy 429.583487 -299.061512)
			(xy 429.606358 -299.105089) (xy 429.621942 -299.15177) (xy 429.629837 -299.200347) (xy 429.630332 -299.224954)
			(xy 429.96918 -299.224954) (xy 429.97314 -299.1759) (xy 429.984917 -299.128116) (xy 430.004208 -299.08284)
			(xy 430.030511 -299.041244) (xy 430.063146 -299.004407) (xy 430.101267 -298.973282) (xy 430.143888 -298.948675)
			(xy 430.189904 -298.931223) (xy 430.238123 -298.921379) (xy 430.287298 -298.919398) (xy 430.336153 -298.92533)
			(xy 430.383424 -298.939022) (xy 430.427886 -298.96012) (xy 430.468389 -298.988076) (xy 430.503882 -299.022168)
			(xy 430.533447 -299.061512) (xy 430.556318 -299.105089) (xy 430.571902 -299.15177) (xy 430.579797 -299.200347)
			(xy 430.580292 -299.224954) (xy 430.91914 -299.224954) (xy 430.9231 -299.1759) (xy 430.934877 -299.128116)
			(xy 430.954168 -299.08284) (xy 430.980471 -299.041244) (xy 431.013106 -299.004407) (xy 431.051227 -298.973282)
			(xy 431.093848 -298.948675) (xy 431.139864 -298.931223) (xy 431.188083 -298.921379) (xy 431.237258 -298.919398)
			(xy 431.286113 -298.92533) (xy 431.333384 -298.939022) (xy 431.377846 -298.96012) (xy 431.418349 -298.988076)
			(xy 431.453842 -299.022168) (xy 431.483407 -299.061512) (xy 431.506278 -299.105089) (xy 431.521862 -299.15177)
			(xy 431.529757 -299.200347) (xy 431.530252 -299.224954) (xy 431.529757 -299.249561) (xy 431.525954 -299.27296)
			(xy 438.614564 -299.27296) (xy 438.618635 -299.217338) (xy 438.630761 -299.162901) (xy 438.650684 -299.11081)
			(xy 438.67798 -299.062175) (xy 438.712066 -299.018032) (xy 438.752215 -298.979323) (xy 438.797573 -298.946872)
			(xy 438.847173 -298.921371) (xy 438.899957 -298.903364) (xy 438.9548 -298.893234) (xy 439.010534 -298.891197)
			(xy 439.065971 -298.897297) (xy 439.119928 -298.911403) (xy 439.171257 -298.933215) (xy 439.218863 -298.962269)
			(xy 439.261731 -298.997944) (xy 439.298948 -299.039481) (xy 439.329721 -299.085994) (xy 439.353393 -299.136491)
			(xy 439.369461 -299.189898) (xy 439.377581 -299.245074) (xy 439.37809 -299.27296) (xy 439.377581 -299.300846)
			(xy 439.369461 -299.356022) (xy 439.353393 -299.409429) (xy 439.329721 -299.459926) (xy 439.298948 -299.506439)
			(xy 439.261731 -299.547976) (xy 439.218863 -299.583651) (xy 439.171257 -299.612705) (xy 439.119928 -299.634517)
			(xy 439.065971 -299.648623) (xy 439.010534 -299.654723) (xy 438.9548 -299.652686) (xy 438.899957 -299.642556)
			(xy 438.847173 -299.624549) (xy 438.797573 -299.599048) (xy 438.752215 -299.566597) (xy 438.712066 -299.527888)
			(xy 438.67798 -299.483745) (xy 438.650684 -299.43511) (xy 438.630761 -299.383019) (xy 438.618635 -299.328582)
			(xy 438.614564 -299.27296) (xy 431.525954 -299.27296) (xy 431.521862 -299.298138) (xy 431.506278 -299.344819)
			(xy 431.483407 -299.388396) (xy 431.453842 -299.42774) (xy 431.418349 -299.461832) (xy 431.377846 -299.489788)
			(xy 431.333384 -299.510886) (xy 431.286113 -299.524578) (xy 431.237258 -299.53051) (xy 431.188083 -299.528529)
			(xy 431.139864 -299.518685) (xy 431.093848 -299.501233) (xy 431.051227 -299.476626) (xy 431.013106 -299.445501)
			(xy 430.980471 -299.408664) (xy 430.954168 -299.367068) (xy 430.934877 -299.321792) (xy 430.9231 -299.274008)
			(xy 430.91914 -299.224954) (xy 430.580292 -299.224954) (xy 430.579797 -299.249561) (xy 430.571902 -299.298138)
			(xy 430.556318 -299.344819) (xy 430.533447 -299.388396) (xy 430.503882 -299.42774) (xy 430.468389 -299.461832)
			(xy 430.427886 -299.489788) (xy 430.383424 -299.510886) (xy 430.336153 -299.524578) (xy 430.287298 -299.53051)
			(xy 430.238123 -299.528529) (xy 430.189904 -299.518685) (xy 430.143888 -299.501233) (xy 430.101267 -299.476626)
			(xy 430.063146 -299.445501) (xy 430.030511 -299.408664) (xy 430.004208 -299.367068) (xy 429.984917 -299.321792)
			(xy 429.97314 -299.274008) (xy 429.96918 -299.224954) (xy 429.630332 -299.224954) (xy 429.629837 -299.249561)
			(xy 429.621942 -299.298138) (xy 429.606358 -299.344819) (xy 429.583487 -299.388396) (xy 429.553922 -299.42774)
			(xy 429.518429 -299.461832) (xy 429.477926 -299.489788) (xy 429.433464 -299.510886) (xy 429.386193 -299.524578)
			(xy 429.337338 -299.53051) (xy 429.288163 -299.528529) (xy 429.239944 -299.518685) (xy 429.193928 -299.501233)
			(xy 429.151307 -299.476626) (xy 429.113186 -299.445501) (xy 429.080551 -299.408664) (xy 429.054248 -299.367068)
			(xy 429.034957 -299.321792) (xy 429.02318 -299.274008) (xy 429.01922 -299.224954) (xy 428.680118 -299.224954)
			(xy 428.679623 -299.249561) (xy 428.671728 -299.298138) (xy 428.656144 -299.344819) (xy 428.633273 -299.388396)
			(xy 428.603708 -299.42774) (xy 428.568215 -299.461832) (xy 428.527712 -299.489788) (xy 428.48325 -299.510886)
			(xy 428.435979 -299.524578) (xy 428.387124 -299.53051) (xy 428.337949 -299.528529) (xy 428.28973 -299.518685)
			(xy 428.243714 -299.501233) (xy 428.201093 -299.476626) (xy 428.162972 -299.445501) (xy 428.130337 -299.408664)
			(xy 428.104034 -299.367068) (xy 428.084743 -299.321792) (xy 428.072966 -299.274008) (xy 428.069006 -299.224954)
			(xy 427.730158 -299.224954) (xy 427.729663 -299.249561) (xy 427.721768 -299.298138) (xy 427.706184 -299.344819)
			(xy 427.683313 -299.388396) (xy 427.653748 -299.42774) (xy 427.618255 -299.461832) (xy 427.577752 -299.489788)
			(xy 427.53329 -299.510886) (xy 427.486019 -299.524578) (xy 427.437164 -299.53051) (xy 427.387989 -299.528529)
			(xy 427.33977 -299.518685) (xy 427.293754 -299.501233) (xy 427.251133 -299.476626) (xy 427.213012 -299.445501)
			(xy 427.180377 -299.408664) (xy 427.154074 -299.367068) (xy 427.134783 -299.321792) (xy 427.123006 -299.274008)
			(xy 427.119046 -299.224954) (xy 426.780198 -299.224954) (xy 426.779703 -299.249561) (xy 426.771808 -299.298138)
			(xy 426.756224 -299.344819) (xy 426.733353 -299.388396) (xy 426.703788 -299.42774) (xy 426.668295 -299.461832)
			(xy 426.627792 -299.489788) (xy 426.58333 -299.510886) (xy 426.536059 -299.524578) (xy 426.487204 -299.53051)
			(xy 426.438029 -299.528529) (xy 426.38981 -299.518685) (xy 426.343794 -299.501233) (xy 426.301173 -299.476626)
			(xy 426.263052 -299.445501) (xy 426.230417 -299.408664) (xy 426.204114 -299.367068) (xy 426.184823 -299.321792)
			(xy 426.173046 -299.274008) (xy 426.169086 -299.224954) (xy 425.830238 -299.224954) (xy 425.829743 -299.249561)
			(xy 425.821848 -299.298138) (xy 425.806264 -299.344819) (xy 425.783393 -299.388396) (xy 425.753828 -299.42774)
			(xy 425.718335 -299.461832) (xy 425.677832 -299.489788) (xy 425.63337 -299.510886) (xy 425.586099 -299.524578)
			(xy 425.537244 -299.53051) (xy 425.488069 -299.528529) (xy 425.43985 -299.518685) (xy 425.393834 -299.501233)
			(xy 425.351213 -299.476626) (xy 425.313092 -299.445501) (xy 425.280457 -299.408664) (xy 425.254154 -299.367068)
			(xy 425.234863 -299.321792) (xy 425.223086 -299.274008) (xy 425.219126 -299.224954) (xy 424.880278 -299.224954)
			(xy 424.879783 -299.249561) (xy 424.871888 -299.298138) (xy 424.856304 -299.344819) (xy 424.833433 -299.388396)
			(xy 424.803868 -299.42774) (xy 424.768375 -299.461832) (xy 424.727872 -299.489788) (xy 424.68341 -299.510886)
			(xy 424.636139 -299.524578) (xy 424.587284 -299.53051) (xy 424.538109 -299.528529) (xy 424.48989 -299.518685)
			(xy 424.443874 -299.501233) (xy 424.401253 -299.476626) (xy 424.363132 -299.445501) (xy 424.330497 -299.408664)
			(xy 424.304194 -299.367068) (xy 424.284903 -299.321792) (xy 424.273126 -299.274008) (xy 424.269166 -299.224954)
			(xy 422.030144 -299.224954) (xy 422.029649 -299.249561) (xy 422.021754 -299.298138) (xy 422.00617 -299.344819)
			(xy 421.983299 -299.388396) (xy 421.953734 -299.42774) (xy 421.918241 -299.461832) (xy 421.877738 -299.489788)
			(xy 421.833276 -299.510886) (xy 421.786005 -299.524578) (xy 421.73715 -299.53051) (xy 421.687975 -299.528529)
			(xy 421.639756 -299.518685) (xy 421.59374 -299.501233) (xy 421.551119 -299.476626) (xy 421.512998 -299.445501)
			(xy 421.480363 -299.408664) (xy 421.45406 -299.367068) (xy 421.434769 -299.321792) (xy 421.422992 -299.274008)
			(xy 421.419032 -299.224954) (xy 421.080184 -299.224954) (xy 421.079689 -299.249561) (xy 421.071794 -299.298138)
			(xy 421.05621 -299.344819) (xy 421.033339 -299.388396) (xy 421.003774 -299.42774) (xy 420.968281 -299.461832)
			(xy 420.927778 -299.489788) (xy 420.883316 -299.510886) (xy 420.836045 -299.524578) (xy 420.78719 -299.53051)
			(xy 420.738015 -299.528529) (xy 420.689796 -299.518685) (xy 420.64378 -299.501233) (xy 420.601159 -299.476626)
			(xy 420.563038 -299.445501) (xy 420.530403 -299.408664) (xy 420.5041 -299.367068) (xy 420.484809 -299.321792)
			(xy 420.473032 -299.274008) (xy 420.469072 -299.224954) (xy 420.130224 -299.224954) (xy 420.129729 -299.249561)
			(xy 420.121834 -299.298138) (xy 420.10625 -299.344819) (xy 420.083379 -299.388396) (xy 420.053814 -299.42774)
			(xy 420.018321 -299.461832) (xy 419.977818 -299.489788) (xy 419.933356 -299.510886) (xy 419.886085 -299.524578)
			(xy 419.83723 -299.53051) (xy 419.788055 -299.528529) (xy 419.739836 -299.518685) (xy 419.69382 -299.501233)
			(xy 419.651199 -299.476626) (xy 419.613078 -299.445501) (xy 419.580443 -299.408664) (xy 419.55414 -299.367068)
			(xy 419.534849 -299.321792) (xy 419.523072 -299.274008) (xy 419.519112 -299.224954) (xy 419.180264 -299.224954)
			(xy 419.179769 -299.249561) (xy 419.171874 -299.298138) (xy 419.15629 -299.344819) (xy 419.133419 -299.388396)
			(xy 419.103854 -299.42774) (xy 419.068361 -299.461832) (xy 419.027858 -299.489788) (xy 418.983396 -299.510886)
			(xy 418.936125 -299.524578) (xy 418.88727 -299.53051) (xy 418.838095 -299.528529) (xy 418.789876 -299.518685)
			(xy 418.74386 -299.501233) (xy 418.701239 -299.476626) (xy 418.663118 -299.445501) (xy 418.630483 -299.408664)
			(xy 418.60418 -299.367068) (xy 418.584889 -299.321792) (xy 418.573112 -299.274008) (xy 418.569152 -299.224954)
			(xy 418.255271 -299.224954) (xy 418.255271 -299.250993) (xy 418.247138 -299.302339) (xy 418.231074 -299.351781)
			(xy 418.207472 -299.398101) (xy 418.176915 -299.440158) (xy 418.140155 -299.476918) (xy 418.098097 -299.507474)
			(xy 418.051777 -299.531075) (xy 418.002335 -299.547139) (xy 417.950989 -299.555271) (xy 417.924996 -299.555662)
			(xy 417.924742 -299.555662) (xy 417.90584 -299.555376) (xy 417.868284 -299.551047) (xy 417.849812 -299.547026)
			(xy 417.838382 -299.544232) (xy 417.81603 -299.549312) (xy 417.744402 -299.606208) (xy 417.735689 -299.613785)
			(xy 417.725644 -299.634551) (xy 417.725098 -299.646086) (xy 417.725098 -299.753528) (xy 417.72556 -299.763404)
			(xy 417.725986 -299.76445) (xy 436.341772 -299.76445) (xy 436.345843 -299.708828) (xy 436.357969 -299.654391)
			(xy 436.377892 -299.6023) (xy 436.405188 -299.553665) (xy 436.439274 -299.509522) (xy 436.479423 -299.470813)
			(xy 436.524781 -299.438362) (xy 436.574381 -299.412861) (xy 436.627165 -299.394854) (xy 436.682008 -299.384724)
			(xy 436.737742 -299.382687) (xy 436.793179 -299.388787) (xy 436.847136 -299.402893) (xy 436.898465 -299.424705)
			(xy 436.946071 -299.453759) (xy 436.988939 -299.489434) (xy 437.026156 -299.530971) (xy 437.056929 -299.577484)
			(xy 437.080601 -299.627981) (xy 437.096669 -299.681388) (xy 437.104789 -299.736564) (xy 437.105298 -299.76445)
			(xy 437.10502 -299.77969) (xy 440.93841 -299.77969) (xy 440.942481 -299.724068) (xy 440.954607 -299.669631)
			(xy 440.97453 -299.61754) (xy 441.001826 -299.568905) (xy 441.035912 -299.524762) (xy 441.076061 -299.486053)
			(xy 441.121419 -299.453602) (xy 441.171019 -299.428101) (xy 441.223803 -299.410094) (xy 441.278646 -299.399964)
			(xy 441.33438 -299.397927) (xy 441.389817 -299.404027) (xy 441.443774 -299.418133) (xy 441.495103 -299.439945)
			(xy 441.542709 -299.468999) (xy 441.585577 -299.504674) (xy 441.622794 -299.546211) (xy 441.653567 -299.592724)
			(xy 441.677239 -299.643221) (xy 441.693307 -299.696628) (xy 441.701427 -299.751804) (xy 441.701936 -299.77969)
			(xy 441.701427 -299.807576) (xy 441.693307 -299.862752) (xy 441.677239 -299.916159) (xy 441.653567 -299.966656)
			(xy 441.622794 -300.013169) (xy 441.585577 -300.054706) (xy 441.542709 -300.090381) (xy 441.495103 -300.119435)
			(xy 441.443774 -300.141247) (xy 441.389817 -300.155353) (xy 441.33438 -300.161453) (xy 441.278646 -300.159416)
			(xy 441.223803 -300.149286) (xy 441.171019 -300.131279) (xy 441.121419 -300.105778) (xy 441.076061 -300.073327)
			(xy 441.035912 -300.034618) (xy 441.001826 -299.990475) (xy 440.97453 -299.94184) (xy 440.954607 -299.889749)
			(xy 440.942481 -299.835312) (xy 440.93841 -299.77969) (xy 437.10502 -299.77969) (xy 437.104789 -299.792336)
			(xy 437.096669 -299.847512) (xy 437.080601 -299.900919) (xy 437.056929 -299.951416) (xy 437.026156 -299.997929)
			(xy 436.988939 -300.039466) (xy 436.946071 -300.075141) (xy 436.898465 -300.104195) (xy 436.847136 -300.126007)
			(xy 436.793179 -300.140113) (xy 436.737742 -300.146213) (xy 436.682008 -300.144176) (xy 436.627165 -300.134046)
			(xy 436.574381 -300.116039) (xy 436.524781 -300.090538) (xy 436.479423 -300.058087) (xy 436.439274 -300.019378)
			(xy 436.405188 -299.975235) (xy 436.377892 -299.9266) (xy 436.357969 -299.874509) (xy 436.345843 -299.820072)
			(xy 436.341772 -299.76445) (xy 417.725986 -299.76445) (xy 417.733005 -299.7817) (xy 417.739576 -299.789088)
			(xy 417.73983 -299.789342) (xy 417.74364 -299.793152) (xy 417.766754 -299.81144) (xy 417.81603 -299.850556)
			(xy 417.838382 -299.855636) (xy 417.849812 -299.852842) (xy 417.868279 -299.848796) (xy 417.905838 -299.844465)
			(xy 417.924742 -299.844206) (xy 417.924996 -299.844206) (xy 417.950984 -299.844689) (xy 418.002321 -299.852819)
			(xy 418.051754 -299.86888) (xy 418.098066 -299.892477) (xy 418.140116 -299.923028) (xy 418.17687 -299.959781)
			(xy 418.207421 -300.001831) (xy 418.231018 -300.048142) (xy 418.24708 -300.097575) (xy 418.255211 -300.148912)
			(xy 418.255211 -300.174914) (xy 418.569152 -300.174914) (xy 418.573112 -300.12586) (xy 418.584889 -300.078076)
			(xy 418.60418 -300.0328) (xy 418.630483 -299.991204) (xy 418.663118 -299.954367) (xy 418.701239 -299.923242)
			(xy 418.74386 -299.898635) (xy 418.789876 -299.881183) (xy 418.838095 -299.871339) (xy 418.88727 -299.869358)
			(xy 418.936125 -299.87529) (xy 418.983396 -299.888982) (xy 419.027858 -299.91008) (xy 419.068361 -299.938036)
			(xy 419.103854 -299.972128) (xy 419.133419 -300.011472) (xy 419.15629 -300.055049) (xy 419.171874 -300.10173)
			(xy 419.179769 -300.150307) (xy 419.180264 -300.174914) (xy 419.519112 -300.174914) (xy 419.523072 -300.12586)
			(xy 419.534849 -300.078076) (xy 419.55414 -300.0328) (xy 419.580443 -299.991204) (xy 419.613078 -299.954367)
			(xy 419.651199 -299.923242) (xy 419.69382 -299.898635) (xy 419.739836 -299.881183) (xy 419.788055 -299.871339)
			(xy 419.83723 -299.869358) (xy 419.886085 -299.87529) (xy 419.933356 -299.888982) (xy 419.977818 -299.91008)
			(xy 420.018321 -299.938036) (xy 420.053814 -299.972128) (xy 420.083379 -300.011472) (xy 420.10625 -300.055049)
			(xy 420.121834 -300.10173) (xy 420.129729 -300.150307) (xy 420.130224 -300.174914) (xy 420.469072 -300.174914)
			(xy 420.473032 -300.12586) (xy 420.484809 -300.078076) (xy 420.5041 -300.0328) (xy 420.530403 -299.991204)
			(xy 420.563038 -299.954367) (xy 420.601159 -299.923242) (xy 420.64378 -299.898635) (xy 420.689796 -299.881183)
			(xy 420.738015 -299.871339) (xy 420.78719 -299.869358) (xy 420.836045 -299.87529) (xy 420.883316 -299.888982)
			(xy 420.927778 -299.91008) (xy 420.968281 -299.938036) (xy 421.003774 -299.972128) (xy 421.033339 -300.011472)
			(xy 421.05621 -300.055049) (xy 421.071794 -300.10173) (xy 421.079689 -300.150307) (xy 421.080184 -300.174914)
			(xy 421.419032 -300.174914) (xy 421.422992 -300.12586) (xy 421.434769 -300.078076) (xy 421.45406 -300.0328)
			(xy 421.480363 -299.991204) (xy 421.512998 -299.954367) (xy 421.551119 -299.923242) (xy 421.59374 -299.898635)
			(xy 421.639756 -299.881183) (xy 421.687975 -299.871339) (xy 421.73715 -299.869358) (xy 421.786005 -299.87529)
			(xy 421.833276 -299.888982) (xy 421.877738 -299.91008) (xy 421.918241 -299.938036) (xy 421.953734 -299.972128)
			(xy 421.983299 -300.011472) (xy 422.00617 -300.055049) (xy 422.021754 -300.10173) (xy 422.029649 -300.150307)
			(xy 422.030144 -300.174914) (xy 422.368992 -300.174914) (xy 422.372952 -300.12586) (xy 422.384729 -300.078076)
			(xy 422.40402 -300.0328) (xy 422.430323 -299.991204) (xy 422.462958 -299.954367) (xy 422.501079 -299.923242)
			(xy 422.5437 -299.898635) (xy 422.589716 -299.881183) (xy 422.637935 -299.871339) (xy 422.68711 -299.869358)
			(xy 422.735965 -299.87529) (xy 422.783236 -299.888982) (xy 422.827698 -299.91008) (xy 422.868201 -299.938036)
			(xy 422.903694 -299.972128) (xy 422.933259 -300.011472) (xy 422.95613 -300.055049) (xy 422.971714 -300.10173)
			(xy 422.979609 -300.150307) (xy 422.980104 -300.174914) (xy 423.319206 -300.174914) (xy 423.323166 -300.12586)
			(xy 423.334943 -300.078076) (xy 423.354234 -300.0328) (xy 423.380537 -299.991204) (xy 423.413172 -299.954367)
			(xy 423.451293 -299.923242) (xy 423.493914 -299.898635) (xy 423.53993 -299.881183) (xy 423.588149 -299.871339)
			(xy 423.637324 -299.869358) (xy 423.686179 -299.87529) (xy 423.73345 -299.888982) (xy 423.777912 -299.91008)
			(xy 423.818415 -299.938036) (xy 423.853908 -299.972128) (xy 423.883473 -300.011472) (xy 423.906344 -300.055049)
			(xy 423.921928 -300.10173) (xy 423.929823 -300.150307) (xy 423.930318 -300.174914) (xy 424.269166 -300.174914)
			(xy 424.273126 -300.12586) (xy 424.284903 -300.078076) (xy 424.304194 -300.0328) (xy 424.330497 -299.991204)
			(xy 424.363132 -299.954367) (xy 424.401253 -299.923242) (xy 424.443874 -299.898635) (xy 424.48989 -299.881183)
			(xy 424.538109 -299.871339) (xy 424.587284 -299.869358) (xy 424.636139 -299.87529) (xy 424.68341 -299.888982)
			(xy 424.727872 -299.91008) (xy 424.768375 -299.938036) (xy 424.803868 -299.972128) (xy 424.833433 -300.011472)
			(xy 424.856304 -300.055049) (xy 424.871888 -300.10173) (xy 424.879783 -300.150307) (xy 424.880278 -300.174914)
			(xy 425.219126 -300.174914) (xy 425.223086 -300.12586) (xy 425.234863 -300.078076) (xy 425.254154 -300.0328)
			(xy 425.280457 -299.991204) (xy 425.313092 -299.954367) (xy 425.351213 -299.923242) (xy 425.393834 -299.898635)
			(xy 425.43985 -299.881183) (xy 425.488069 -299.871339) (xy 425.537244 -299.869358) (xy 425.586099 -299.87529)
			(xy 425.63337 -299.888982) (xy 425.677832 -299.91008) (xy 425.718335 -299.938036) (xy 425.753828 -299.972128)
			(xy 425.783393 -300.011472) (xy 425.806264 -300.055049) (xy 425.821848 -300.10173) (xy 425.829743 -300.150307)
			(xy 425.830238 -300.174914) (xy 426.169086 -300.174914) (xy 426.173046 -300.12586) (xy 426.184823 -300.078076)
			(xy 426.204114 -300.0328) (xy 426.230417 -299.991204) (xy 426.263052 -299.954367) (xy 426.301173 -299.923242)
			(xy 426.343794 -299.898635) (xy 426.38981 -299.881183) (xy 426.438029 -299.871339) (xy 426.487204 -299.869358)
			(xy 426.536059 -299.87529) (xy 426.58333 -299.888982) (xy 426.627792 -299.91008) (xy 426.668295 -299.938036)
			(xy 426.703788 -299.972128) (xy 426.733353 -300.011472) (xy 426.756224 -300.055049) (xy 426.771808 -300.10173)
			(xy 426.779703 -300.150307) (xy 426.780198 -300.174914) (xy 427.119046 -300.174914) (xy 427.123006 -300.12586)
			(xy 427.134783 -300.078076) (xy 427.154074 -300.0328) (xy 427.180377 -299.991204) (xy 427.213012 -299.954367)
			(xy 427.251133 -299.923242) (xy 427.293754 -299.898635) (xy 427.33977 -299.881183) (xy 427.387989 -299.871339)
			(xy 427.437164 -299.869358) (xy 427.486019 -299.87529) (xy 427.53329 -299.888982) (xy 427.577752 -299.91008)
			(xy 427.618255 -299.938036) (xy 427.653748 -299.972128) (xy 427.683313 -300.011472) (xy 427.706184 -300.055049)
			(xy 427.721768 -300.10173) (xy 427.729663 -300.150307) (xy 427.730158 -300.174914) (xy 428.069006 -300.174914)
			(xy 428.072966 -300.12586) (xy 428.084743 -300.078076) (xy 428.104034 -300.0328) (xy 428.130337 -299.991204)
			(xy 428.162972 -299.954367) (xy 428.201093 -299.923242) (xy 428.243714 -299.898635) (xy 428.28973 -299.881183)
			(xy 428.337949 -299.871339) (xy 428.387124 -299.869358) (xy 428.435979 -299.87529) (xy 428.48325 -299.888982)
			(xy 428.527712 -299.91008) (xy 428.568215 -299.938036) (xy 428.603708 -299.972128) (xy 428.633273 -300.011472)
			(xy 428.656144 -300.055049) (xy 428.671728 -300.10173) (xy 428.679623 -300.150307) (xy 428.680118 -300.174914)
			(xy 429.01922 -300.174914) (xy 429.02318 -300.12586) (xy 429.034957 -300.078076) (xy 429.054248 -300.0328)
			(xy 429.080551 -299.991204) (xy 429.113186 -299.954367) (xy 429.151307 -299.923242) (xy 429.193928 -299.898635)
			(xy 429.239944 -299.881183) (xy 429.288163 -299.871339) (xy 429.337338 -299.869358) (xy 429.386193 -299.87529)
			(xy 429.433464 -299.888982) (xy 429.477926 -299.91008) (xy 429.518429 -299.938036) (xy 429.553922 -299.972128)
			(xy 429.583487 -300.011472) (xy 429.606358 -300.055049) (xy 429.621942 -300.10173) (xy 429.629837 -300.150307)
			(xy 429.630332 -300.174914) (xy 429.96918 -300.174914) (xy 429.97314 -300.12586) (xy 429.984917 -300.078076)
			(xy 430.004208 -300.0328) (xy 430.030511 -299.991204) (xy 430.063146 -299.954367) (xy 430.101267 -299.923242)
			(xy 430.143888 -299.898635) (xy 430.189904 -299.881183) (xy 430.238123 -299.871339) (xy 430.287298 -299.869358)
			(xy 430.336153 -299.87529) (xy 430.383424 -299.888982) (xy 430.427886 -299.91008) (xy 430.468389 -299.938036)
			(xy 430.503882 -299.972128) (xy 430.533447 -300.011472) (xy 430.556318 -300.055049) (xy 430.571902 -300.10173)
			(xy 430.579797 -300.150307) (xy 430.580292 -300.174914) (xy 430.91914 -300.174914) (xy 430.9231 -300.12586)
			(xy 430.934877 -300.078076) (xy 430.954168 -300.0328) (xy 430.980471 -299.991204) (xy 431.013106 -299.954367)
			(xy 431.051227 -299.923242) (xy 431.093848 -299.898635) (xy 431.139864 -299.881183) (xy 431.188083 -299.871339)
			(xy 431.237258 -299.869358) (xy 431.286113 -299.87529) (xy 431.333384 -299.888982) (xy 431.377846 -299.91008)
			(xy 431.418349 -299.938036) (xy 431.453842 -299.972128) (xy 431.483407 -300.011472) (xy 431.506278 -300.055049)
			(xy 431.521862 -300.10173) (xy 431.529757 -300.150307) (xy 431.530252 -300.174914) (xy 431.529757 -300.199521)
			(xy 431.521862 -300.248098) (xy 431.506278 -300.294779) (xy 431.483407 -300.338356) (xy 431.453842 -300.3777)
			(xy 431.418349 -300.411792) (xy 431.377846 -300.439748) (xy 431.333384 -300.460846) (xy 431.286113 -300.474538)
			(xy 431.237258 -300.48047) (xy 431.188083 -300.478489) (xy 431.139864 -300.468645) (xy 431.093848 -300.451193)
			(xy 431.051227 -300.426586) (xy 431.013106 -300.395461) (xy 430.980471 -300.358624) (xy 430.954168 -300.317028)
			(xy 430.934877 -300.271752) (xy 430.9231 -300.223968) (xy 430.91914 -300.174914) (xy 430.580292 -300.174914)
			(xy 430.579797 -300.199521) (xy 430.571902 -300.248098) (xy 430.556318 -300.294779) (xy 430.533447 -300.338356)
			(xy 430.503882 -300.3777) (xy 430.468389 -300.411792) (xy 430.427886 -300.439748) (xy 430.383424 -300.460846)
			(xy 430.336153 -300.474538) (xy 430.287298 -300.48047) (xy 430.238123 -300.478489) (xy 430.189904 -300.468645)
			(xy 430.143888 -300.451193) (xy 430.101267 -300.426586) (xy 430.063146 -300.395461) (xy 430.030511 -300.358624)
			(xy 430.004208 -300.317028) (xy 429.984917 -300.271752) (xy 429.97314 -300.223968) (xy 429.96918 -300.174914)
			(xy 429.630332 -300.174914) (xy 429.629837 -300.199521) (xy 429.621942 -300.248098) (xy 429.606358 -300.294779)
			(xy 429.583487 -300.338356) (xy 429.553922 -300.3777) (xy 429.518429 -300.411792) (xy 429.477926 -300.439748)
			(xy 429.433464 -300.460846) (xy 429.386193 -300.474538) (xy 429.337338 -300.48047) (xy 429.288163 -300.478489)
			(xy 429.239944 -300.468645) (xy 429.193928 -300.451193) (xy 429.151307 -300.426586) (xy 429.113186 -300.395461)
			(xy 429.080551 -300.358624) (xy 429.054248 -300.317028) (xy 429.034957 -300.271752) (xy 429.02318 -300.223968)
			(xy 429.01922 -300.174914) (xy 428.680118 -300.174914) (xy 428.679623 -300.199521) (xy 428.671728 -300.248098)
			(xy 428.656144 -300.294779) (xy 428.633273 -300.338356) (xy 428.603708 -300.3777) (xy 428.568215 -300.411792)
			(xy 428.527712 -300.439748) (xy 428.48325 -300.460846) (xy 428.435979 -300.474538) (xy 428.387124 -300.48047)
			(xy 428.337949 -300.478489) (xy 428.28973 -300.468645) (xy 428.243714 -300.451193) (xy 428.201093 -300.426586)
			(xy 428.162972 -300.395461) (xy 428.130337 -300.358624) (xy 428.104034 -300.317028) (xy 428.084743 -300.271752)
			(xy 428.072966 -300.223968) (xy 428.069006 -300.174914) (xy 427.730158 -300.174914) (xy 427.729663 -300.199521)
			(xy 427.721768 -300.248098) (xy 427.706184 -300.294779) (xy 427.683313 -300.338356) (xy 427.653748 -300.3777)
			(xy 427.618255 -300.411792) (xy 427.577752 -300.439748) (xy 427.53329 -300.460846) (xy 427.486019 -300.474538)
			(xy 427.437164 -300.48047) (xy 427.387989 -300.478489) (xy 427.33977 -300.468645) (xy 427.293754 -300.451193)
			(xy 427.251133 -300.426586) (xy 427.213012 -300.395461) (xy 427.180377 -300.358624) (xy 427.154074 -300.317028)
			(xy 427.134783 -300.271752) (xy 427.123006 -300.223968) (xy 427.119046 -300.174914) (xy 426.780198 -300.174914)
			(xy 426.779703 -300.199521) (xy 426.771808 -300.248098) (xy 426.756224 -300.294779) (xy 426.733353 -300.338356)
			(xy 426.703788 -300.3777) (xy 426.668295 -300.411792) (xy 426.627792 -300.439748) (xy 426.58333 -300.460846)
			(xy 426.536059 -300.474538) (xy 426.487204 -300.48047) (xy 426.438029 -300.478489) (xy 426.38981 -300.468645)
			(xy 426.343794 -300.451193) (xy 426.301173 -300.426586) (xy 426.263052 -300.395461) (xy 426.230417 -300.358624)
			(xy 426.204114 -300.317028) (xy 426.184823 -300.271752) (xy 426.173046 -300.223968) (xy 426.169086 -300.174914)
			(xy 425.830238 -300.174914) (xy 425.829743 -300.199521) (xy 425.821848 -300.248098) (xy 425.806264 -300.294779)
			(xy 425.783393 -300.338356) (xy 425.753828 -300.3777) (xy 425.718335 -300.411792) (xy 425.677832 -300.439748)
			(xy 425.63337 -300.460846) (xy 425.586099 -300.474538) (xy 425.537244 -300.48047) (xy 425.488069 -300.478489)
			(xy 425.43985 -300.468645) (xy 425.393834 -300.451193) (xy 425.351213 -300.426586) (xy 425.313092 -300.395461)
			(xy 425.280457 -300.358624) (xy 425.254154 -300.317028) (xy 425.234863 -300.271752) (xy 425.223086 -300.223968)
			(xy 425.219126 -300.174914) (xy 424.880278 -300.174914) (xy 424.879783 -300.199521) (xy 424.871888 -300.248098)
			(xy 424.856304 -300.294779) (xy 424.833433 -300.338356) (xy 424.803868 -300.3777) (xy 424.768375 -300.411792)
			(xy 424.727872 -300.439748) (xy 424.68341 -300.460846) (xy 424.636139 -300.474538) (xy 424.587284 -300.48047)
			(xy 424.538109 -300.478489) (xy 424.48989 -300.468645) (xy 424.443874 -300.451193) (xy 424.401253 -300.426586)
			(xy 424.363132 -300.395461) (xy 424.330497 -300.358624) (xy 424.304194 -300.317028) (xy 424.284903 -300.271752)
			(xy 424.273126 -300.223968) (xy 424.269166 -300.174914) (xy 423.930318 -300.174914) (xy 423.929823 -300.199521)
			(xy 423.921928 -300.248098) (xy 423.906344 -300.294779) (xy 423.883473 -300.338356) (xy 423.853908 -300.3777)
			(xy 423.818415 -300.411792) (xy 423.777912 -300.439748) (xy 423.73345 -300.460846) (xy 423.686179 -300.474538)
			(xy 423.637324 -300.48047) (xy 423.588149 -300.478489) (xy 423.53993 -300.468645) (xy 423.493914 -300.451193)
			(xy 423.451293 -300.426586) (xy 423.413172 -300.395461) (xy 423.380537 -300.358624) (xy 423.354234 -300.317028)
			(xy 423.334943 -300.271752) (xy 423.323166 -300.223968) (xy 423.319206 -300.174914) (xy 422.980104 -300.174914)
			(xy 422.979609 -300.199521) (xy 422.971714 -300.248098) (xy 422.95613 -300.294779) (xy 422.933259 -300.338356)
			(xy 422.903694 -300.3777) (xy 422.868201 -300.411792) (xy 422.827698 -300.439748) (xy 422.783236 -300.460846)
			(xy 422.735965 -300.474538) (xy 422.68711 -300.48047) (xy 422.637935 -300.478489) (xy 422.589716 -300.468645)
			(xy 422.5437 -300.451193) (xy 422.501079 -300.426586) (xy 422.462958 -300.395461) (xy 422.430323 -300.358624)
			(xy 422.40402 -300.317028) (xy 422.384729 -300.271752) (xy 422.372952 -300.223968) (xy 422.368992 -300.174914)
			(xy 422.030144 -300.174914) (xy 422.029649 -300.199521) (xy 422.021754 -300.248098) (xy 422.00617 -300.294779)
			(xy 421.983299 -300.338356) (xy 421.953734 -300.3777) (xy 421.918241 -300.411792) (xy 421.877738 -300.439748)
			(xy 421.833276 -300.460846) (xy 421.786005 -300.474538) (xy 421.73715 -300.48047) (xy 421.687975 -300.478489)
			(xy 421.639756 -300.468645) (xy 421.59374 -300.451193) (xy 421.551119 -300.426586) (xy 421.512998 -300.395461)
			(xy 421.480363 -300.358624) (xy 421.45406 -300.317028) (xy 421.434769 -300.271752) (xy 421.422992 -300.223968)
			(xy 421.419032 -300.174914) (xy 421.080184 -300.174914) (xy 421.079689 -300.199521) (xy 421.071794 -300.248098)
			(xy 421.05621 -300.294779) (xy 421.033339 -300.338356) (xy 421.003774 -300.3777) (xy 420.968281 -300.411792)
			(xy 420.927778 -300.439748) (xy 420.883316 -300.460846) (xy 420.836045 -300.474538) (xy 420.78719 -300.48047)
			(xy 420.738015 -300.478489) (xy 420.689796 -300.468645) (xy 420.64378 -300.451193) (xy 420.601159 -300.426586)
			(xy 420.563038 -300.395461) (xy 420.530403 -300.358624) (xy 420.5041 -300.317028) (xy 420.484809 -300.271752)
			(xy 420.473032 -300.223968) (xy 420.469072 -300.174914) (xy 420.130224 -300.174914) (xy 420.129729 -300.199521)
			(xy 420.121834 -300.248098) (xy 420.10625 -300.294779) (xy 420.083379 -300.338356) (xy 420.053814 -300.3777)
			(xy 420.018321 -300.411792) (xy 419.977818 -300.439748) (xy 419.933356 -300.460846) (xy 419.886085 -300.474538)
			(xy 419.83723 -300.48047) (xy 419.788055 -300.478489) (xy 419.739836 -300.468645) (xy 419.69382 -300.451193)
			(xy 419.651199 -300.426586) (xy 419.613078 -300.395461) (xy 419.580443 -300.358624) (xy 419.55414 -300.317028)
			(xy 419.534849 -300.271752) (xy 419.523072 -300.223968) (xy 419.519112 -300.174914) (xy 419.180264 -300.174914)
			(xy 419.179769 -300.199521) (xy 419.171874 -300.248098) (xy 419.15629 -300.294779) (xy 419.133419 -300.338356)
			(xy 419.103854 -300.3777) (xy 419.068361 -300.411792) (xy 419.027858 -300.439748) (xy 418.983396 -300.460846)
			(xy 418.936125 -300.474538) (xy 418.88727 -300.48047) (xy 418.838095 -300.478489) (xy 418.789876 -300.468645)
			(xy 418.74386 -300.451193) (xy 418.701239 -300.426586) (xy 418.663118 -300.395461) (xy 418.630483 -300.358624)
			(xy 418.60418 -300.317028) (xy 418.584889 -300.271752) (xy 418.573112 -300.223968) (xy 418.569152 -300.174914)
			(xy 418.255211 -300.174914) (xy 418.255211 -300.200888) (xy 418.24708 -300.252225) (xy 418.231018 -300.301658)
			(xy 418.207421 -300.347969) (xy 418.17687 -300.390019) (xy 418.140116 -300.426772) (xy 418.098066 -300.457323)
			(xy 418.051754 -300.48092) (xy 418.002321 -300.496981) (xy 417.950984 -300.505111) (xy 417.924996 -300.505622)
			(xy 417.924742 -300.505622) (xy 417.90584 -300.505336) (xy 417.868284 -300.501006) (xy 417.849812 -300.496986)
			(xy 417.838382 -300.494192) (xy 417.81603 -300.499272) (xy 417.744402 -300.556168) (xy 417.735682 -300.563743)
			(xy 417.725621 -300.584508) (xy 417.725098 -300.596046) (xy 417.725098 -300.703488) (xy 417.725571 -300.71336)
			(xy 417.733032 -300.73164) (xy 417.739576 -300.739048) (xy 417.73983 -300.739302) (xy 417.74364 -300.743112)
			(xy 417.766754 -300.7614) (xy 417.81603 -300.800516) (xy 417.838382 -300.805596) (xy 417.849812 -300.802802)
			(xy 417.86828 -300.798756) (xy 417.905838 -300.794426) (xy 417.924742 -300.794166) (xy 417.924996 -300.794166)
			(xy 417.950988 -300.794649) (xy 418.002331 -300.80278) (xy 418.05177 -300.818843) (xy 418.098087 -300.842443)
			(xy 418.140142 -300.872997) (xy 418.1769 -300.909755) (xy 418.207455 -300.95181) (xy 418.231055 -300.998127)
			(xy 418.247119 -301.047566) (xy 418.255251 -301.098908) (xy 418.255251 -301.124874) (xy 418.569152 -301.124874)
			(xy 418.573112 -301.07582) (xy 418.584889 -301.028036) (xy 418.60418 -300.98276) (xy 418.630483 -300.941164)
			(xy 418.663118 -300.904327) (xy 418.701239 -300.873202) (xy 418.74386 -300.848595) (xy 418.789876 -300.831143)
			(xy 418.838095 -300.821299) (xy 418.88727 -300.819318) (xy 418.936125 -300.82525) (xy 418.983396 -300.838942)
			(xy 419.027858 -300.86004) (xy 419.068361 -300.887996) (xy 419.103854 -300.922088) (xy 419.133419 -300.961432)
			(xy 419.15629 -301.005009) (xy 419.171874 -301.05169) (xy 419.179769 -301.100267) (xy 419.180264 -301.124874)
			(xy 419.519112 -301.124874) (xy 419.523072 -301.07582) (xy 419.534849 -301.028036) (xy 419.55414 -300.98276)
			(xy 419.580443 -300.941164) (xy 419.613078 -300.904327) (xy 419.651199 -300.873202) (xy 419.69382 -300.848595)
			(xy 419.739836 -300.831143) (xy 419.788055 -300.821299) (xy 419.83723 -300.819318) (xy 419.886085 -300.82525)
			(xy 419.933356 -300.838942) (xy 419.977818 -300.86004) (xy 420.018321 -300.887996) (xy 420.053814 -300.922088)
			(xy 420.083379 -300.961432) (xy 420.10625 -301.005009) (xy 420.121834 -301.05169) (xy 420.129729 -301.100267)
			(xy 420.130224 -301.124874) (xy 420.469072 -301.124874) (xy 420.473032 -301.07582) (xy 420.484809 -301.028036)
			(xy 420.5041 -300.98276) (xy 420.530403 -300.941164) (xy 420.563038 -300.904327) (xy 420.601159 -300.873202)
			(xy 420.64378 -300.848595) (xy 420.689796 -300.831143) (xy 420.738015 -300.821299) (xy 420.78719 -300.819318)
			(xy 420.836045 -300.82525) (xy 420.883316 -300.838942) (xy 420.927778 -300.86004) (xy 420.968281 -300.887996)
			(xy 421.003774 -300.922088) (xy 421.033339 -300.961432) (xy 421.05621 -301.005009) (xy 421.071794 -301.05169)
			(xy 421.079689 -301.100267) (xy 421.080184 -301.124874) (xy 421.419032 -301.124874) (xy 421.422992 -301.07582)
			(xy 421.434769 -301.028036) (xy 421.45406 -300.98276) (xy 421.480363 -300.941164) (xy 421.512998 -300.904327)
			(xy 421.551119 -300.873202) (xy 421.59374 -300.848595) (xy 421.639756 -300.831143) (xy 421.687975 -300.821299)
			(xy 421.73715 -300.819318) (xy 421.786005 -300.82525) (xy 421.833276 -300.838942) (xy 421.877738 -300.86004)
			(xy 421.918241 -300.887996) (xy 421.953734 -300.922088) (xy 421.983299 -300.961432) (xy 422.00617 -301.005009)
			(xy 422.021754 -301.05169) (xy 422.029649 -301.100267) (xy 422.030144 -301.124874) (xy 424.269166 -301.124874)
			(xy 424.273126 -301.07582) (xy 424.284903 -301.028036) (xy 424.304194 -300.98276) (xy 424.330497 -300.941164)
			(xy 424.363132 -300.904327) (xy 424.401253 -300.873202) (xy 424.443874 -300.848595) (xy 424.48989 -300.831143)
			(xy 424.538109 -300.821299) (xy 424.587284 -300.819318) (xy 424.636139 -300.82525) (xy 424.68341 -300.838942)
			(xy 424.727872 -300.86004) (xy 424.768375 -300.887996) (xy 424.803868 -300.922088) (xy 424.833433 -300.961432)
			(xy 424.856304 -301.005009) (xy 424.871888 -301.05169) (xy 424.879783 -301.100267) (xy 424.880278 -301.124874)
			(xy 425.219126 -301.124874) (xy 425.223086 -301.07582) (xy 425.234863 -301.028036) (xy 425.254154 -300.98276)
			(xy 425.280457 -300.941164) (xy 425.313092 -300.904327) (xy 425.351213 -300.873202) (xy 425.393834 -300.848595)
			(xy 425.43985 -300.831143) (xy 425.488069 -300.821299) (xy 425.537244 -300.819318) (xy 425.586099 -300.82525)
			(xy 425.63337 -300.838942) (xy 425.677832 -300.86004) (xy 425.718335 -300.887996) (xy 425.753828 -300.922088)
			(xy 425.783393 -300.961432) (xy 425.806264 -301.005009) (xy 425.821848 -301.05169) (xy 425.829743 -301.100267)
			(xy 425.830238 -301.124874) (xy 426.169086 -301.124874) (xy 426.173046 -301.07582) (xy 426.184823 -301.028036)
			(xy 426.204114 -300.98276) (xy 426.230417 -300.941164) (xy 426.263052 -300.904327) (xy 426.301173 -300.873202)
			(xy 426.343794 -300.848595) (xy 426.38981 -300.831143) (xy 426.438029 -300.821299) (xy 426.487204 -300.819318)
			(xy 426.536059 -300.82525) (xy 426.58333 -300.838942) (xy 426.627792 -300.86004) (xy 426.668295 -300.887996)
			(xy 426.703788 -300.922088) (xy 426.733353 -300.961432) (xy 426.756224 -301.005009) (xy 426.771808 -301.05169)
			(xy 426.779703 -301.100267) (xy 426.780198 -301.124874) (xy 427.119046 -301.124874) (xy 427.123006 -301.07582)
			(xy 427.134783 -301.028036) (xy 427.154074 -300.98276) (xy 427.180377 -300.941164) (xy 427.213012 -300.904327)
			(xy 427.251133 -300.873202) (xy 427.293754 -300.848595) (xy 427.33977 -300.831143) (xy 427.387989 -300.821299)
			(xy 427.437164 -300.819318) (xy 427.486019 -300.82525) (xy 427.53329 -300.838942) (xy 427.577752 -300.86004)
			(xy 427.618255 -300.887996) (xy 427.653748 -300.922088) (xy 427.683313 -300.961432) (xy 427.706184 -301.005009)
			(xy 427.721768 -301.05169) (xy 427.729663 -301.100267) (xy 427.730158 -301.124874) (xy 428.069006 -301.124874)
			(xy 428.072966 -301.07582) (xy 428.084743 -301.028036) (xy 428.104034 -300.98276) (xy 428.130337 -300.941164)
			(xy 428.162972 -300.904327) (xy 428.201093 -300.873202) (xy 428.243714 -300.848595) (xy 428.28973 -300.831143)
			(xy 428.337949 -300.821299) (xy 428.387124 -300.819318) (xy 428.435979 -300.82525) (xy 428.48325 -300.838942)
			(xy 428.527712 -300.86004) (xy 428.568215 -300.887996) (xy 428.603708 -300.922088) (xy 428.633273 -300.961432)
			(xy 428.656144 -301.005009) (xy 428.671728 -301.05169) (xy 428.679623 -301.100267) (xy 428.680118 -301.124874)
			(xy 429.01922 -301.124874) (xy 429.02318 -301.07582) (xy 429.034957 -301.028036) (xy 429.054248 -300.98276)
			(xy 429.080551 -300.941164) (xy 429.113186 -300.904327) (xy 429.151307 -300.873202) (xy 429.193928 -300.848595)
			(xy 429.239944 -300.831143) (xy 429.288163 -300.821299) (xy 429.337338 -300.819318) (xy 429.386193 -300.82525)
			(xy 429.433464 -300.838942) (xy 429.477926 -300.86004) (xy 429.518429 -300.887996) (xy 429.553922 -300.922088)
			(xy 429.583487 -300.961432) (xy 429.606358 -301.005009) (xy 429.621942 -301.05169) (xy 429.629837 -301.100267)
			(xy 429.630332 -301.124874) (xy 429.96918 -301.124874) (xy 429.97314 -301.07582) (xy 429.984917 -301.028036)
			(xy 430.004208 -300.98276) (xy 430.030511 -300.941164) (xy 430.063146 -300.904327) (xy 430.101267 -300.873202)
			(xy 430.143888 -300.848595) (xy 430.189904 -300.831143) (xy 430.238123 -300.821299) (xy 430.287298 -300.819318)
			(xy 430.336153 -300.82525) (xy 430.383424 -300.838942) (xy 430.427886 -300.86004) (xy 430.468389 -300.887996)
			(xy 430.503882 -300.922088) (xy 430.533447 -300.961432) (xy 430.556318 -301.005009) (xy 430.571902 -301.05169)
			(xy 430.579797 -301.100267) (xy 430.580292 -301.124874) (xy 430.91914 -301.124874) (xy 430.9231 -301.07582)
			(xy 430.934877 -301.028036) (xy 430.954168 -300.98276) (xy 430.980471 -300.941164) (xy 431.013106 -300.904327)
			(xy 431.051227 -300.873202) (xy 431.093848 -300.848595) (xy 431.139864 -300.831143) (xy 431.188083 -300.821299)
			(xy 431.237258 -300.819318) (xy 431.286113 -300.82525) (xy 431.333384 -300.838942) (xy 431.377846 -300.86004)
			(xy 431.418349 -300.887996) (xy 431.453842 -300.922088) (xy 431.483407 -300.961432) (xy 431.506278 -301.005009)
			(xy 431.51865 -301.04207) (xy 438.617104 -301.04207) (xy 438.621175 -300.986448) (xy 438.633301 -300.932011)
			(xy 438.653224 -300.87992) (xy 438.68052 -300.831285) (xy 438.714606 -300.787142) (xy 438.754755 -300.748433)
			(xy 438.800113 -300.715982) (xy 438.849713 -300.690481) (xy 438.902497 -300.672474) (xy 438.95734 -300.662344)
			(xy 439.013074 -300.660307) (xy 439.068511 -300.666407) (xy 439.122468 -300.680513) (xy 439.173797 -300.702325)
			(xy 439.221403 -300.731379) (xy 439.264271 -300.767054) (xy 439.301488 -300.808591) (xy 439.332261 -300.855104)
			(xy 439.355933 -300.905601) (xy 439.372001 -300.959008) (xy 439.380121 -301.014184) (xy 439.38063 -301.04207)
			(xy 439.380477 -301.050452) (xy 440.990988 -301.050452) (xy 440.995059 -300.99483) (xy 441.007185 -300.940393)
			(xy 441.027108 -300.888302) (xy 441.054404 -300.839667) (xy 441.08849 -300.795524) (xy 441.128639 -300.756815)
			(xy 441.173997 -300.724364) (xy 441.223597 -300.698863) (xy 441.276381 -300.680856) (xy 441.331224 -300.670726)
			(xy 441.386958 -300.668689) (xy 441.442395 -300.674789) (xy 441.496352 -300.688895) (xy 441.547681 -300.710707)
			(xy 441.595287 -300.739761) (xy 441.638155 -300.775436) (xy 441.675372 -300.816973) (xy 441.706145 -300.863486)
			(xy 441.729817 -300.913983) (xy 441.745885 -300.96739) (xy 441.754005 -301.022566) (xy 441.754514 -301.050452)
			(xy 441.754005 -301.078338) (xy 441.745885 -301.133514) (xy 441.729817 -301.186921) (xy 441.706145 -301.237418)
			(xy 441.675372 -301.283931) (xy 441.638155 -301.325468) (xy 441.595287 -301.361143) (xy 441.547681 -301.390197)
			(xy 441.496352 -301.412009) (xy 441.442395 -301.426115) (xy 441.386958 -301.432215) (xy 441.331224 -301.430178)
			(xy 441.276381 -301.420048) (xy 441.223597 -301.402041) (xy 441.173997 -301.37654) (xy 441.128639 -301.344089)
			(xy 441.08849 -301.30538) (xy 441.054404 -301.261237) (xy 441.027108 -301.212602) (xy 441.007185 -301.160511)
			(xy 440.995059 -301.106074) (xy 440.990988 -301.050452) (xy 439.380477 -301.050452) (xy 439.380121 -301.069956)
			(xy 439.372001 -301.125132) (xy 439.355933 -301.178539) (xy 439.332261 -301.229036) (xy 439.301488 -301.275549)
			(xy 439.264271 -301.317086) (xy 439.221403 -301.352761) (xy 439.173797 -301.381815) (xy 439.122468 -301.403627)
			(xy 439.068511 -301.417733) (xy 439.013074 -301.423833) (xy 438.95734 -301.421796) (xy 438.902497 -301.411666)
			(xy 438.849713 -301.393659) (xy 438.800113 -301.368158) (xy 438.754755 -301.335707) (xy 438.714606 -301.296998)
			(xy 438.68052 -301.252855) (xy 438.653224 -301.20422) (xy 438.633301 -301.152129) (xy 438.621175 -301.097692)
			(xy 438.617104 -301.04207) (xy 431.51865 -301.04207) (xy 431.521862 -301.05169) (xy 431.529757 -301.100267)
			(xy 431.530252 -301.124874) (xy 431.529757 -301.149481) (xy 431.521862 -301.198058) (xy 431.506278 -301.244739)
			(xy 431.483407 -301.288316) (xy 431.453842 -301.32766) (xy 431.418349 -301.361752) (xy 431.377846 -301.389708)
			(xy 431.333384 -301.410806) (xy 431.286113 -301.424498) (xy 431.237258 -301.43043) (xy 431.188083 -301.428449)
			(xy 431.139864 -301.418605) (xy 431.093848 -301.401153) (xy 431.051227 -301.376546) (xy 431.013106 -301.345421)
			(xy 430.980471 -301.308584) (xy 430.954168 -301.266988) (xy 430.934877 -301.221712) (xy 430.9231 -301.173928)
			(xy 430.91914 -301.124874) (xy 430.580292 -301.124874) (xy 430.579797 -301.149481) (xy 430.571902 -301.198058)
			(xy 430.556318 -301.244739) (xy 430.533447 -301.288316) (xy 430.503882 -301.32766) (xy 430.468389 -301.361752)
			(xy 430.427886 -301.389708) (xy 430.383424 -301.410806) (xy 430.336153 -301.424498) (xy 430.287298 -301.43043)
			(xy 430.238123 -301.428449) (xy 430.189904 -301.418605) (xy 430.143888 -301.401153) (xy 430.101267 -301.376546)
			(xy 430.063146 -301.345421) (xy 430.030511 -301.308584) (xy 430.004208 -301.266988) (xy 429.984917 -301.221712)
			(xy 429.97314 -301.173928) (xy 429.96918 -301.124874) (xy 429.630332 -301.124874) (xy 429.629837 -301.149481)
			(xy 429.621942 -301.198058) (xy 429.606358 -301.244739) (xy 429.583487 -301.288316) (xy 429.553922 -301.32766)
			(xy 429.518429 -301.361752) (xy 429.477926 -301.389708) (xy 429.433464 -301.410806) (xy 429.386193 -301.424498)
			(xy 429.337338 -301.43043) (xy 429.288163 -301.428449) (xy 429.239944 -301.418605) (xy 429.193928 -301.401153)
			(xy 429.151307 -301.376546) (xy 429.113186 -301.345421) (xy 429.080551 -301.308584) (xy 429.054248 -301.266988)
			(xy 429.034957 -301.221712) (xy 429.02318 -301.173928) (xy 429.01922 -301.124874) (xy 428.680118 -301.124874)
			(xy 428.679623 -301.149481) (xy 428.671728 -301.198058) (xy 428.656144 -301.244739) (xy 428.633273 -301.288316)
			(xy 428.603708 -301.32766) (xy 428.568215 -301.361752) (xy 428.527712 -301.389708) (xy 428.48325 -301.410806)
			(xy 428.435979 -301.424498) (xy 428.387124 -301.43043) (xy 428.337949 -301.428449) (xy 428.28973 -301.418605)
			(xy 428.243714 -301.401153) (xy 428.201093 -301.376546) (xy 428.162972 -301.345421) (xy 428.130337 -301.308584)
			(xy 428.104034 -301.266988) (xy 428.084743 -301.221712) (xy 428.072966 -301.173928) (xy 428.069006 -301.124874)
			(xy 427.730158 -301.124874) (xy 427.729663 -301.149481) (xy 427.721768 -301.198058) (xy 427.706184 -301.244739)
			(xy 427.683313 -301.288316) (xy 427.653748 -301.32766) (xy 427.618255 -301.361752) (xy 427.577752 -301.389708)
			(xy 427.53329 -301.410806) (xy 427.486019 -301.424498) (xy 427.437164 -301.43043) (xy 427.387989 -301.428449)
			(xy 427.33977 -301.418605) (xy 427.293754 -301.401153) (xy 427.251133 -301.376546) (xy 427.213012 -301.345421)
			(xy 427.180377 -301.308584) (xy 427.154074 -301.266988) (xy 427.134783 -301.221712) (xy 427.123006 -301.173928)
			(xy 427.119046 -301.124874) (xy 426.780198 -301.124874) (xy 426.779703 -301.149481) (xy 426.771808 -301.198058)
			(xy 426.756224 -301.244739) (xy 426.733353 -301.288316) (xy 426.703788 -301.32766) (xy 426.668295 -301.361752)
			(xy 426.627792 -301.389708) (xy 426.58333 -301.410806) (xy 426.536059 -301.424498) (xy 426.487204 -301.43043)
			(xy 426.438029 -301.428449) (xy 426.38981 -301.418605) (xy 426.343794 -301.401153) (xy 426.301173 -301.376546)
			(xy 426.263052 -301.345421) (xy 426.230417 -301.308584) (xy 426.204114 -301.266988) (xy 426.184823 -301.221712)
			(xy 426.173046 -301.173928) (xy 426.169086 -301.124874) (xy 425.830238 -301.124874) (xy 425.829743 -301.149481)
			(xy 425.821848 -301.198058) (xy 425.806264 -301.244739) (xy 425.783393 -301.288316) (xy 425.753828 -301.32766)
			(xy 425.718335 -301.361752) (xy 425.677832 -301.389708) (xy 425.63337 -301.410806) (xy 425.586099 -301.424498)
			(xy 425.537244 -301.43043) (xy 425.488069 -301.428449) (xy 425.43985 -301.418605) (xy 425.393834 -301.401153)
			(xy 425.351213 -301.376546) (xy 425.313092 -301.345421) (xy 425.280457 -301.308584) (xy 425.254154 -301.266988)
			(xy 425.234863 -301.221712) (xy 425.223086 -301.173928) (xy 425.219126 -301.124874) (xy 424.880278 -301.124874)
			(xy 424.879783 -301.149481) (xy 424.871888 -301.198058) (xy 424.856304 -301.244739) (xy 424.833433 -301.288316)
			(xy 424.803868 -301.32766) (xy 424.768375 -301.361752) (xy 424.727872 -301.389708) (xy 424.68341 -301.410806)
			(xy 424.636139 -301.424498) (xy 424.587284 -301.43043) (xy 424.538109 -301.428449) (xy 424.48989 -301.418605)
			(xy 424.443874 -301.401153) (xy 424.401253 -301.376546) (xy 424.363132 -301.345421) (xy 424.330497 -301.308584)
			(xy 424.304194 -301.266988) (xy 424.284903 -301.221712) (xy 424.273126 -301.173928) (xy 424.269166 -301.124874)
			(xy 422.030144 -301.124874) (xy 422.029649 -301.149481) (xy 422.021754 -301.198058) (xy 422.00617 -301.244739)
			(xy 421.983299 -301.288316) (xy 421.953734 -301.32766) (xy 421.918241 -301.361752) (xy 421.877738 -301.389708)
			(xy 421.833276 -301.410806) (xy 421.786005 -301.424498) (xy 421.73715 -301.43043) (xy 421.687975 -301.428449)
			(xy 421.639756 -301.418605) (xy 421.59374 -301.401153) (xy 421.551119 -301.376546) (xy 421.512998 -301.345421)
			(xy 421.480363 -301.308584) (xy 421.45406 -301.266988) (xy 421.434769 -301.221712) (xy 421.422992 -301.173928)
			(xy 421.419032 -301.124874) (xy 421.080184 -301.124874) (xy 421.079689 -301.149481) (xy 421.071794 -301.198058)
			(xy 421.05621 -301.244739) (xy 421.033339 -301.288316) (xy 421.003774 -301.32766) (xy 420.968281 -301.361752)
			(xy 420.927778 -301.389708) (xy 420.883316 -301.410806) (xy 420.836045 -301.424498) (xy 420.78719 -301.43043)
			(xy 420.738015 -301.428449) (xy 420.689796 -301.418605) (xy 420.64378 -301.401153) (xy 420.601159 -301.376546)
			(xy 420.563038 -301.345421) (xy 420.530403 -301.308584) (xy 420.5041 -301.266988) (xy 420.484809 -301.221712)
			(xy 420.473032 -301.173928) (xy 420.469072 -301.124874) (xy 420.130224 -301.124874) (xy 420.129729 -301.149481)
			(xy 420.121834 -301.198058) (xy 420.10625 -301.244739) (xy 420.083379 -301.288316) (xy 420.053814 -301.32766)
			(xy 420.018321 -301.361752) (xy 419.977818 -301.389708) (xy 419.933356 -301.410806) (xy 419.886085 -301.424498)
			(xy 419.83723 -301.43043) (xy 419.788055 -301.428449) (xy 419.739836 -301.418605) (xy 419.69382 -301.401153)
			(xy 419.651199 -301.376546) (xy 419.613078 -301.345421) (xy 419.580443 -301.308584) (xy 419.55414 -301.266988)
			(xy 419.534849 -301.221712) (xy 419.523072 -301.173928) (xy 419.519112 -301.124874) (xy 419.180264 -301.124874)
			(xy 419.179769 -301.149481) (xy 419.171874 -301.198058) (xy 419.15629 -301.244739) (xy 419.133419 -301.288316)
			(xy 419.103854 -301.32766) (xy 419.068361 -301.361752) (xy 419.027858 -301.389708) (xy 418.983396 -301.410806)
			(xy 418.936125 -301.424498) (xy 418.88727 -301.43043) (xy 418.838095 -301.428449) (xy 418.789876 -301.418605)
			(xy 418.74386 -301.401153) (xy 418.701239 -301.376546) (xy 418.663118 -301.345421) (xy 418.630483 -301.308584)
			(xy 418.60418 -301.266988) (xy 418.584889 -301.221712) (xy 418.573112 -301.173928) (xy 418.569152 -301.124874)
			(xy 418.255251 -301.124874) (xy 418.255251 -301.150892) (xy 418.247119 -301.202234) (xy 418.231055 -301.251673)
			(xy 418.207455 -301.29799) (xy 418.1769 -301.340045) (xy 418.140142 -301.376803) (xy 418.098087 -301.407357)
			(xy 418.05177 -301.430957) (xy 418.002331 -301.44702) (xy 417.950988 -301.455151) (xy 417.924996 -301.455582)
			(xy 417.924742 -301.455582) (xy 417.90584 -301.455296) (xy 417.868284 -301.450967) (xy 417.849812 -301.446946)
			(xy 417.838382 -301.444152) (xy 417.81603 -301.449232) (xy 417.744402 -301.506128) (xy 417.735675 -301.5137)
			(xy 417.725598 -301.534465) (xy 417.725098 -301.546006) (xy 417.725098 -301.653448) (xy 417.725563 -301.663323)
			(xy 417.733014 -301.681614) (xy 417.739576 -301.689008) (xy 417.73983 -301.689262) (xy 417.74364 -301.693072)
			(xy 417.766754 -301.71136) (xy 417.81603 -301.750476) (xy 417.838382 -301.755556) (xy 417.849812 -301.752762)
			(xy 417.868279 -301.748715) (xy 417.905838 -301.744385) (xy 417.924742 -301.744126) (xy 417.924996 -301.744126)
			(xy 417.950983 -301.744609) (xy 418.002317 -301.752739) (xy 418.051747 -301.768799) (xy 418.098056 -301.792394)
			(xy 418.140103 -301.822943) (xy 418.176854 -301.859694) (xy 418.207404 -301.901741) (xy 418.231 -301.94805)
			(xy 418.24706 -301.99748) (xy 418.255191 -302.048813) (xy 418.255191 -302.074834) (xy 418.569152 -302.074834)
			(xy 418.573112 -302.02578) (xy 418.584889 -301.977996) (xy 418.60418 -301.93272) (xy 418.630483 -301.891124)
			(xy 418.663118 -301.854287) (xy 418.701239 -301.823162) (xy 418.74386 -301.798555) (xy 418.789876 -301.781103)
			(xy 418.838095 -301.771259) (xy 418.88727 -301.769278) (xy 418.936125 -301.77521) (xy 418.983396 -301.788902)
			(xy 419.027858 -301.81) (xy 419.068361 -301.837956) (xy 419.103854 -301.872048) (xy 419.133419 -301.911392)
			(xy 419.15629 -301.954969) (xy 419.171874 -302.00165) (xy 419.179769 -302.050227) (xy 419.180264 -302.074834)
			(xy 419.519112 -302.074834) (xy 419.523072 -302.02578) (xy 419.534849 -301.977996) (xy 419.55414 -301.93272)
			(xy 419.580443 -301.891124) (xy 419.613078 -301.854287) (xy 419.651199 -301.823162) (xy 419.69382 -301.798555)
			(xy 419.739836 -301.781103) (xy 419.788055 -301.771259) (xy 419.83723 -301.769278) (xy 419.886085 -301.77521)
			(xy 419.933356 -301.788902) (xy 419.977818 -301.81) (xy 420.018321 -301.837956) (xy 420.053814 -301.872048)
			(xy 420.083379 -301.911392) (xy 420.10625 -301.954969) (xy 420.121834 -302.00165) (xy 420.129729 -302.050227)
			(xy 420.130224 -302.074834) (xy 420.469072 -302.074834) (xy 420.473032 -302.02578) (xy 420.484809 -301.977996)
			(xy 420.5041 -301.93272) (xy 420.530403 -301.891124) (xy 420.563038 -301.854287) (xy 420.601159 -301.823162)
			(xy 420.64378 -301.798555) (xy 420.689796 -301.781103) (xy 420.738015 -301.771259) (xy 420.78719 -301.769278)
			(xy 420.836045 -301.77521) (xy 420.883316 -301.788902) (xy 420.927778 -301.81) (xy 420.968281 -301.837956)
			(xy 421.003774 -301.872048) (xy 421.033339 -301.911392) (xy 421.05621 -301.954969) (xy 421.071794 -302.00165)
			(xy 421.079689 -302.050227) (xy 421.080184 -302.074834) (xy 421.419032 -302.074834) (xy 421.422992 -302.02578)
			(xy 421.434769 -301.977996) (xy 421.45406 -301.93272) (xy 421.480363 -301.891124) (xy 421.512998 -301.854287)
			(xy 421.551119 -301.823162) (xy 421.59374 -301.798555) (xy 421.639756 -301.781103) (xy 421.687975 -301.771259)
			(xy 421.73715 -301.769278) (xy 421.786005 -301.77521) (xy 421.833276 -301.788902) (xy 421.877738 -301.81)
			(xy 421.918241 -301.837956) (xy 421.953734 -301.872048) (xy 421.983299 -301.911392) (xy 422.00617 -301.954969)
			(xy 422.021754 -302.00165) (xy 422.029649 -302.050227) (xy 422.030144 -302.074834) (xy 422.368992 -302.074834)
			(xy 422.372952 -302.02578) (xy 422.384729 -301.977996) (xy 422.40402 -301.93272) (xy 422.430323 -301.891124)
			(xy 422.462958 -301.854287) (xy 422.501079 -301.823162) (xy 422.5437 -301.798555) (xy 422.589716 -301.781103)
			(xy 422.637935 -301.771259) (xy 422.68711 -301.769278) (xy 422.735965 -301.77521) (xy 422.783236 -301.788902)
			(xy 422.827698 -301.81) (xy 422.868201 -301.837956) (xy 422.903694 -301.872048) (xy 422.933259 -301.911392)
			(xy 422.95613 -301.954969) (xy 422.971714 -302.00165) (xy 422.979609 -302.050227) (xy 422.980104 -302.074834)
			(xy 423.319206 -302.074834) (xy 423.323166 -302.02578) (xy 423.334943 -301.977996) (xy 423.354234 -301.93272)
			(xy 423.380537 -301.891124) (xy 423.413172 -301.854287) (xy 423.451293 -301.823162) (xy 423.493914 -301.798555)
			(xy 423.53993 -301.781103) (xy 423.588149 -301.771259) (xy 423.637324 -301.769278) (xy 423.686179 -301.77521)
			(xy 423.73345 -301.788902) (xy 423.777912 -301.81) (xy 423.818415 -301.837956) (xy 423.853908 -301.872048)
			(xy 423.883473 -301.911392) (xy 423.906344 -301.954969) (xy 423.921928 -302.00165) (xy 423.929823 -302.050227)
			(xy 423.930318 -302.074834) (xy 424.269166 -302.074834) (xy 424.273126 -302.02578) (xy 424.284903 -301.977996)
			(xy 424.304194 -301.93272) (xy 424.330497 -301.891124) (xy 424.363132 -301.854287) (xy 424.401253 -301.823162)
			(xy 424.443874 -301.798555) (xy 424.48989 -301.781103) (xy 424.538109 -301.771259) (xy 424.587284 -301.769278)
			(xy 424.636139 -301.77521) (xy 424.68341 -301.788902) (xy 424.727872 -301.81) (xy 424.768375 -301.837956)
			(xy 424.803868 -301.872048) (xy 424.833433 -301.911392) (xy 424.856304 -301.954969) (xy 424.871888 -302.00165)
			(xy 424.879783 -302.050227) (xy 424.880278 -302.074834) (xy 425.219126 -302.074834) (xy 425.223086 -302.02578)
			(xy 425.234863 -301.977996) (xy 425.254154 -301.93272) (xy 425.280457 -301.891124) (xy 425.313092 -301.854287)
			(xy 425.351213 -301.823162) (xy 425.393834 -301.798555) (xy 425.43985 -301.781103) (xy 425.488069 -301.771259)
			(xy 425.537244 -301.769278) (xy 425.586099 -301.77521) (xy 425.63337 -301.788902) (xy 425.677832 -301.81)
			(xy 425.718335 -301.837956) (xy 425.753828 -301.872048) (xy 425.783393 -301.911392) (xy 425.806264 -301.954969)
			(xy 425.821848 -302.00165) (xy 425.829743 -302.050227) (xy 425.830238 -302.074834) (xy 426.169086 -302.074834)
			(xy 426.173046 -302.02578) (xy 426.184823 -301.977996) (xy 426.204114 -301.93272) (xy 426.230417 -301.891124)
			(xy 426.263052 -301.854287) (xy 426.301173 -301.823162) (xy 426.343794 -301.798555) (xy 426.38981 -301.781103)
			(xy 426.438029 -301.771259) (xy 426.487204 -301.769278) (xy 426.536059 -301.77521) (xy 426.58333 -301.788902)
			(xy 426.627792 -301.81) (xy 426.668295 -301.837956) (xy 426.703788 -301.872048) (xy 426.733353 -301.911392)
			(xy 426.756224 -301.954969) (xy 426.771808 -302.00165) (xy 426.779703 -302.050227) (xy 426.780198 -302.074834)
			(xy 427.119046 -302.074834) (xy 427.123006 -302.02578) (xy 427.134783 -301.977996) (xy 427.154074 -301.93272)
			(xy 427.180377 -301.891124) (xy 427.213012 -301.854287) (xy 427.251133 -301.823162) (xy 427.293754 -301.798555)
			(xy 427.33977 -301.781103) (xy 427.387989 -301.771259) (xy 427.437164 -301.769278) (xy 427.486019 -301.77521)
			(xy 427.53329 -301.788902) (xy 427.577752 -301.81) (xy 427.618255 -301.837956) (xy 427.653748 -301.872048)
			(xy 427.683313 -301.911392) (xy 427.706184 -301.954969) (xy 427.721768 -302.00165) (xy 427.729663 -302.050227)
			(xy 427.730158 -302.074834) (xy 428.069006 -302.074834) (xy 428.072966 -302.02578) (xy 428.084743 -301.977996)
			(xy 428.104034 -301.93272) (xy 428.130337 -301.891124) (xy 428.162972 -301.854287) (xy 428.201093 -301.823162)
			(xy 428.243714 -301.798555) (xy 428.28973 -301.781103) (xy 428.337949 -301.771259) (xy 428.387124 -301.769278)
			(xy 428.435979 -301.77521) (xy 428.48325 -301.788902) (xy 428.527712 -301.81) (xy 428.568215 -301.837956)
			(xy 428.603708 -301.872048) (xy 428.633273 -301.911392) (xy 428.656144 -301.954969) (xy 428.671728 -302.00165)
			(xy 428.679623 -302.050227) (xy 428.680118 -302.074834) (xy 429.01922 -302.074834) (xy 429.02318 -302.02578)
			(xy 429.034957 -301.977996) (xy 429.054248 -301.93272) (xy 429.080551 -301.891124) (xy 429.113186 -301.854287)
			(xy 429.151307 -301.823162) (xy 429.193928 -301.798555) (xy 429.239944 -301.781103) (xy 429.288163 -301.771259)
			(xy 429.337338 -301.769278) (xy 429.386193 -301.77521) (xy 429.433464 -301.788902) (xy 429.477926 -301.81)
			(xy 429.518429 -301.837956) (xy 429.553922 -301.872048) (xy 429.583487 -301.911392) (xy 429.606358 -301.954969)
			(xy 429.621942 -302.00165) (xy 429.629837 -302.050227) (xy 429.630332 -302.074834) (xy 429.96918 -302.074834)
			(xy 429.97314 -302.02578) (xy 429.984917 -301.977996) (xy 430.004208 -301.93272) (xy 430.030511 -301.891124)
			(xy 430.063146 -301.854287) (xy 430.101267 -301.823162) (xy 430.143888 -301.798555) (xy 430.189904 -301.781103)
			(xy 430.238123 -301.771259) (xy 430.287298 -301.769278) (xy 430.336153 -301.77521) (xy 430.383424 -301.788902)
			(xy 430.427886 -301.81) (xy 430.468389 -301.837956) (xy 430.503882 -301.872048) (xy 430.533447 -301.911392)
			(xy 430.556318 -301.954969) (xy 430.571902 -302.00165) (xy 430.579797 -302.050227) (xy 430.580292 -302.074834)
			(xy 430.91914 -302.074834) (xy 430.9231 -302.02578) (xy 430.934877 -301.977996) (xy 430.954168 -301.93272)
			(xy 430.980471 -301.891124) (xy 431.013106 -301.854287) (xy 431.051227 -301.823162) (xy 431.093848 -301.798555)
			(xy 431.139864 -301.781103) (xy 431.188083 -301.771259) (xy 431.237258 -301.769278) (xy 431.286113 -301.77521)
			(xy 431.333384 -301.788902) (xy 431.377846 -301.81) (xy 431.418349 -301.837956) (xy 431.453842 -301.872048)
			(xy 431.483407 -301.911392) (xy 431.506278 -301.954969) (xy 431.521862 -302.00165) (xy 431.529757 -302.050227)
			(xy 431.529997 -302.062134) (xy 433.675788 -302.062134) (xy 433.679859 -302.006512) (xy 433.691985 -301.952075)
			(xy 433.711908 -301.899984) (xy 433.739204 -301.851349) (xy 433.77329 -301.807206) (xy 433.813439 -301.768497)
			(xy 433.858797 -301.736046) (xy 433.908397 -301.710545) (xy 433.961181 -301.692538) (xy 434.016024 -301.682408)
			(xy 434.071758 -301.680371) (xy 434.127195 -301.686471) (xy 434.181152 -301.700577) (xy 434.232481 -301.722389)
			(xy 434.280087 -301.751443) (xy 434.322955 -301.787118) (xy 434.360172 -301.828655) (xy 434.390945 -301.875168)
			(xy 434.392741 -301.879) (xy 434.647592 -301.879) (xy 434.651663 -301.823378) (xy 434.663789 -301.768941)
			(xy 434.683712 -301.71685) (xy 434.711008 -301.668215) (xy 434.745094 -301.624072) (xy 434.785243 -301.585363)
			(xy 434.830601 -301.552912) (xy 434.880201 -301.527411) (xy 434.932985 -301.509404) (xy 434.987828 -301.499274)
			(xy 435.043562 -301.497237) (xy 435.098999 -301.503337) (xy 435.152956 -301.517443) (xy 435.204285 -301.539255)
			(xy 435.226168 -301.55261) (xy 436.41975 -301.55261) (xy 436.423821 -301.496988) (xy 436.435947 -301.442551)
			(xy 436.45587 -301.39046) (xy 436.483166 -301.341825) (xy 436.517252 -301.297682) (xy 436.557401 -301.258973)
			(xy 436.602759 -301.226522) (xy 436.652359 -301.201021) (xy 436.705143 -301.183014) (xy 436.759986 -301.172884)
			(xy 436.81572 -301.170847) (xy 436.871157 -301.176947) (xy 436.925114 -301.191053) (xy 436.976443 -301.212865)
			(xy 437.024049 -301.241919) (xy 437.066917 -301.277594) (xy 437.104134 -301.319131) (xy 437.134907 -301.365644)
			(xy 437.158579 -301.416141) (xy 437.174647 -301.469548) (xy 437.182767 -301.524724) (xy 437.183276 -301.55261)
			(xy 437.182836 -301.57674) (xy 439.81319 -301.57674) (xy 439.817261 -301.521118) (xy 439.829387 -301.466681)
			(xy 439.84931 -301.41459) (xy 439.876606 -301.365955) (xy 439.910692 -301.321812) (xy 439.950841 -301.283103)
			(xy 439.996199 -301.250652) (xy 440.045799 -301.225151) (xy 440.098583 -301.207144) (xy 440.153426 -301.197014)
			(xy 440.20916 -301.194977) (xy 440.264597 -301.201077) (xy 440.318554 -301.215183) (xy 440.369883 -301.236995)
			(xy 440.417489 -301.266049) (xy 440.460357 -301.301724) (xy 440.497574 -301.343261) (xy 440.528347 -301.389774)
			(xy 440.552019 -301.440271) (xy 440.568087 -301.493678) (xy 440.576207 -301.548854) (xy 440.576716 -301.57674)
			(xy 440.576207 -301.604626) (xy 440.568087 -301.659802) (xy 440.552019 -301.713209) (xy 440.528347 -301.763706)
			(xy 440.497574 -301.810219) (xy 440.460357 -301.851756) (xy 440.417489 -301.887431) (xy 440.369883 -301.916485)
			(xy 440.318554 -301.938297) (xy 440.264597 -301.952403) (xy 440.20916 -301.958503) (xy 440.153426 -301.956466)
			(xy 440.098583 -301.946336) (xy 440.045799 -301.928329) (xy 439.996199 -301.902828) (xy 439.950841 -301.870377)
			(xy 439.910692 -301.831668) (xy 439.876606 -301.787525) (xy 439.84931 -301.73889) (xy 439.829387 -301.686799)
			(xy 439.817261 -301.632362) (xy 439.81319 -301.57674) (xy 437.182836 -301.57674) (xy 437.182767 -301.580496)
			(xy 437.174647 -301.635672) (xy 437.158579 -301.689079) (xy 437.134907 -301.739576) (xy 437.104134 -301.786089)
			(xy 437.066917 -301.827626) (xy 437.024049 -301.863301) (xy 436.976443 -301.892355) (xy 436.925114 -301.914167)
			(xy 436.871157 -301.928273) (xy 436.81572 -301.934373) (xy 436.759986 -301.932336) (xy 436.705143 -301.922206)
			(xy 436.652359 -301.904199) (xy 436.602759 -301.878698) (xy 436.557401 -301.846247) (xy 436.517252 -301.807538)
			(xy 436.483166 -301.763395) (xy 436.45587 -301.71476) (xy 436.435947 -301.662669) (xy 436.423821 -301.608232)
			(xy 436.41975 -301.55261) (xy 435.226168 -301.55261) (xy 435.251891 -301.568309) (xy 435.294759 -301.603984)
			(xy 435.331976 -301.645521) (xy 435.362749 -301.692034) (xy 435.386421 -301.742531) (xy 435.402489 -301.795938)
			(xy 435.410609 -301.851114) (xy 435.411118 -301.879) (xy 435.410609 -301.906886) (xy 435.402489 -301.962062)
			(xy 435.386421 -302.015469) (xy 435.362749 -302.065966) (xy 435.331976 -302.112479) (xy 435.294759 -302.154016)
			(xy 435.251891 -302.189691) (xy 435.204285 -302.218745) (xy 435.152956 -302.240557) (xy 435.098999 -302.254663)
			(xy 435.043562 -302.260763) (xy 434.987828 -302.258726) (xy 434.932985 -302.248596) (xy 434.880201 -302.230589)
			(xy 434.830601 -302.205088) (xy 434.785243 -302.172637) (xy 434.745094 -302.133928) (xy 434.711008 -302.089785)
			(xy 434.683712 -302.04115) (xy 434.663789 -301.989059) (xy 434.651663 -301.934622) (xy 434.647592 -301.879)
			(xy 434.392741 -301.879) (xy 434.414617 -301.925665) (xy 434.430685 -301.979072) (xy 434.438805 -302.034248)
			(xy 434.439314 -302.062134) (xy 434.438805 -302.09002) (xy 434.430685 -302.145196) (xy 434.414617 -302.198603)
			(xy 434.390945 -302.2491) (xy 434.360172 -302.295613) (xy 434.322955 -302.33715) (xy 434.280087 -302.372825)
			(xy 434.232481 -302.401879) (xy 434.181152 -302.423691) (xy 434.127195 -302.437797) (xy 434.071758 -302.443897)
			(xy 434.016024 -302.44186) (xy 433.961181 -302.43173) (xy 433.908397 -302.413723) (xy 433.858797 -302.388222)
			(xy 433.813439 -302.355771) (xy 433.77329 -302.317062) (xy 433.739204 -302.272919) (xy 433.711908 -302.224284)
			(xy 433.691985 -302.172193) (xy 433.679859 -302.117756) (xy 433.675788 -302.062134) (xy 431.529997 -302.062134)
			(xy 431.530252 -302.074834) (xy 431.529757 -302.099441) (xy 431.521862 -302.148018) (xy 431.506278 -302.194699)
			(xy 431.483407 -302.238276) (xy 431.453842 -302.27762) (xy 431.418349 -302.311712) (xy 431.377846 -302.339668)
			(xy 431.333384 -302.360766) (xy 431.286113 -302.374458) (xy 431.237258 -302.38039) (xy 431.188083 -302.378409)
			(xy 431.139864 -302.368565) (xy 431.093848 -302.351113) (xy 431.051227 -302.326506) (xy 431.013106 -302.295381)
			(xy 430.980471 -302.258544) (xy 430.954168 -302.216948) (xy 430.934877 -302.171672) (xy 430.9231 -302.123888)
			(xy 430.91914 -302.074834) (xy 430.580292 -302.074834) (xy 430.579797 -302.099441) (xy 430.571902 -302.148018)
			(xy 430.556318 -302.194699) (xy 430.533447 -302.238276) (xy 430.503882 -302.27762) (xy 430.468389 -302.311712)
			(xy 430.427886 -302.339668) (xy 430.383424 -302.360766) (xy 430.336153 -302.374458) (xy 430.287298 -302.38039)
			(xy 430.238123 -302.378409) (xy 430.189904 -302.368565) (xy 430.143888 -302.351113) (xy 430.101267 -302.326506)
			(xy 430.063146 -302.295381) (xy 430.030511 -302.258544) (xy 430.004208 -302.216948) (xy 429.984917 -302.171672)
			(xy 429.97314 -302.123888) (xy 429.96918 -302.074834) (xy 429.630332 -302.074834) (xy 429.629837 -302.099441)
			(xy 429.621942 -302.148018) (xy 429.606358 -302.194699) (xy 429.583487 -302.238276) (xy 429.553922 -302.27762)
			(xy 429.518429 -302.311712) (xy 429.477926 -302.339668) (xy 429.433464 -302.360766) (xy 429.386193 -302.374458)
			(xy 429.337338 -302.38039) (xy 429.288163 -302.378409) (xy 429.239944 -302.368565) (xy 429.193928 -302.351113)
			(xy 429.151307 -302.326506) (xy 429.113186 -302.295381) (xy 429.080551 -302.258544) (xy 429.054248 -302.216948)
			(xy 429.034957 -302.171672) (xy 429.02318 -302.123888) (xy 429.01922 -302.074834) (xy 428.680118 -302.074834)
			(xy 428.679623 -302.099441) (xy 428.671728 -302.148018) (xy 428.656144 -302.194699) (xy 428.633273 -302.238276)
			(xy 428.603708 -302.27762) (xy 428.568215 -302.311712) (xy 428.527712 -302.339668) (xy 428.48325 -302.360766)
			(xy 428.435979 -302.374458) (xy 428.387124 -302.38039) (xy 428.337949 -302.378409) (xy 428.28973 -302.368565)
			(xy 428.243714 -302.351113) (xy 428.201093 -302.326506) (xy 428.162972 -302.295381) (xy 428.130337 -302.258544)
			(xy 428.104034 -302.216948) (xy 428.084743 -302.171672) (xy 428.072966 -302.123888) (xy 428.069006 -302.074834)
			(xy 427.730158 -302.074834) (xy 427.729663 -302.099441) (xy 427.721768 -302.148018) (xy 427.706184 -302.194699)
			(xy 427.683313 -302.238276) (xy 427.653748 -302.27762) (xy 427.618255 -302.311712) (xy 427.577752 -302.339668)
			(xy 427.53329 -302.360766) (xy 427.486019 -302.374458) (xy 427.437164 -302.38039) (xy 427.387989 -302.378409)
			(xy 427.33977 -302.368565) (xy 427.293754 -302.351113) (xy 427.251133 -302.326506) (xy 427.213012 -302.295381)
			(xy 427.180377 -302.258544) (xy 427.154074 -302.216948) (xy 427.134783 -302.171672) (xy 427.123006 -302.123888)
			(xy 427.119046 -302.074834) (xy 426.780198 -302.074834) (xy 426.779703 -302.099441) (xy 426.771808 -302.148018)
			(xy 426.756224 -302.194699) (xy 426.733353 -302.238276) (xy 426.703788 -302.27762) (xy 426.668295 -302.311712)
			(xy 426.627792 -302.339668) (xy 426.58333 -302.360766) (xy 426.536059 -302.374458) (xy 426.487204 -302.38039)
			(xy 426.438029 -302.378409) (xy 426.38981 -302.368565) (xy 426.343794 -302.351113) (xy 426.301173 -302.326506)
			(xy 426.263052 -302.295381) (xy 426.230417 -302.258544) (xy 426.204114 -302.216948) (xy 426.184823 -302.171672)
			(xy 426.173046 -302.123888) (xy 426.169086 -302.074834) (xy 425.830238 -302.074834) (xy 425.829743 -302.099441)
			(xy 425.821848 -302.148018) (xy 425.806264 -302.194699) (xy 425.783393 -302.238276) (xy 425.753828 -302.27762)
			(xy 425.718335 -302.311712) (xy 425.677832 -302.339668) (xy 425.63337 -302.360766) (xy 425.586099 -302.374458)
			(xy 425.537244 -302.38039) (xy 425.488069 -302.378409) (xy 425.43985 -302.368565) (xy 425.393834 -302.351113)
			(xy 425.351213 -302.326506) (xy 425.313092 -302.295381) (xy 425.280457 -302.258544) (xy 425.254154 -302.216948)
			(xy 425.234863 -302.171672) (xy 425.223086 -302.123888) (xy 425.219126 -302.074834) (xy 424.880278 -302.074834)
			(xy 424.879783 -302.099441) (xy 424.871888 -302.148018) (xy 424.856304 -302.194699) (xy 424.833433 -302.238276)
			(xy 424.803868 -302.27762) (xy 424.768375 -302.311712) (xy 424.727872 -302.339668) (xy 424.68341 -302.360766)
			(xy 424.636139 -302.374458) (xy 424.587284 -302.38039) (xy 424.538109 -302.378409) (xy 424.48989 -302.368565)
			(xy 424.443874 -302.351113) (xy 424.401253 -302.326506) (xy 424.363132 -302.295381) (xy 424.330497 -302.258544)
			(xy 424.304194 -302.216948) (xy 424.284903 -302.171672) (xy 424.273126 -302.123888) (xy 424.269166 -302.074834)
			(xy 423.930318 -302.074834) (xy 423.929823 -302.099441) (xy 423.921928 -302.148018) (xy 423.906344 -302.194699)
			(xy 423.883473 -302.238276) (xy 423.853908 -302.27762) (xy 423.818415 -302.311712) (xy 423.777912 -302.339668)
			(xy 423.73345 -302.360766) (xy 423.686179 -302.374458) (xy 423.637324 -302.38039) (xy 423.588149 -302.378409)
			(xy 423.53993 -302.368565) (xy 423.493914 -302.351113) (xy 423.451293 -302.326506) (xy 423.413172 -302.295381)
			(xy 423.380537 -302.258544) (xy 423.354234 -302.216948) (xy 423.334943 -302.171672) (xy 423.323166 -302.123888)
			(xy 423.319206 -302.074834) (xy 422.980104 -302.074834) (xy 422.979609 -302.099441) (xy 422.971714 -302.148018)
			(xy 422.95613 -302.194699) (xy 422.933259 -302.238276) (xy 422.903694 -302.27762) (xy 422.868201 -302.311712)
			(xy 422.827698 -302.339668) (xy 422.783236 -302.360766) (xy 422.735965 -302.374458) (xy 422.68711 -302.38039)
			(xy 422.637935 -302.378409) (xy 422.589716 -302.368565) (xy 422.5437 -302.351113) (xy 422.501079 -302.326506)
			(xy 422.462958 -302.295381) (xy 422.430323 -302.258544) (xy 422.40402 -302.216948) (xy 422.384729 -302.171672)
			(xy 422.372952 -302.123888) (xy 422.368992 -302.074834) (xy 422.030144 -302.074834) (xy 422.029649 -302.099441)
			(xy 422.021754 -302.148018) (xy 422.00617 -302.194699) (xy 421.983299 -302.238276) (xy 421.953734 -302.27762)
			(xy 421.918241 -302.311712) (xy 421.877738 -302.339668) (xy 421.833276 -302.360766) (xy 421.786005 -302.374458)
			(xy 421.73715 -302.38039) (xy 421.687975 -302.378409) (xy 421.639756 -302.368565) (xy 421.59374 -302.351113)
			(xy 421.551119 -302.326506) (xy 421.512998 -302.295381) (xy 421.480363 -302.258544) (xy 421.45406 -302.216948)
			(xy 421.434769 -302.171672) (xy 421.422992 -302.123888) (xy 421.419032 -302.074834) (xy 421.080184 -302.074834)
			(xy 421.079689 -302.099441) (xy 421.071794 -302.148018) (xy 421.05621 -302.194699) (xy 421.033339 -302.238276)
			(xy 421.003774 -302.27762) (xy 420.968281 -302.311712) (xy 420.927778 -302.339668) (xy 420.883316 -302.360766)
			(xy 420.836045 -302.374458) (xy 420.78719 -302.38039) (xy 420.738015 -302.378409) (xy 420.689796 -302.368565)
			(xy 420.64378 -302.351113) (xy 420.601159 -302.326506) (xy 420.563038 -302.295381) (xy 420.530403 -302.258544)
			(xy 420.5041 -302.216948) (xy 420.484809 -302.171672) (xy 420.473032 -302.123888) (xy 420.469072 -302.074834)
			(xy 420.130224 -302.074834) (xy 420.129729 -302.099441) (xy 420.121834 -302.148018) (xy 420.10625 -302.194699)
			(xy 420.083379 -302.238276) (xy 420.053814 -302.27762) (xy 420.018321 -302.311712) (xy 419.977818 -302.339668)
			(xy 419.933356 -302.360766) (xy 419.886085 -302.374458) (xy 419.83723 -302.38039) (xy 419.788055 -302.378409)
			(xy 419.739836 -302.368565) (xy 419.69382 -302.351113) (xy 419.651199 -302.326506) (xy 419.613078 -302.295381)
			(xy 419.580443 -302.258544) (xy 419.55414 -302.216948) (xy 419.534849 -302.171672) (xy 419.523072 -302.123888)
			(xy 419.519112 -302.074834) (xy 419.180264 -302.074834) (xy 419.179769 -302.099441) (xy 419.171874 -302.148018)
			(xy 419.15629 -302.194699) (xy 419.133419 -302.238276) (xy 419.103854 -302.27762) (xy 419.068361 -302.311712)
			(xy 419.027858 -302.339668) (xy 418.983396 -302.360766) (xy 418.936125 -302.374458) (xy 418.88727 -302.38039)
			(xy 418.838095 -302.378409) (xy 418.789876 -302.368565) (xy 418.74386 -302.351113) (xy 418.701239 -302.326506)
			(xy 418.663118 -302.295381) (xy 418.630483 -302.258544) (xy 418.60418 -302.216948) (xy 418.584889 -302.171672)
			(xy 418.573112 -302.123888) (xy 418.569152 -302.074834) (xy 418.255191 -302.074834) (xy 418.255191 -302.100787)
			(xy 418.24706 -302.15212) (xy 418.231 -302.20155) (xy 418.207404 -302.247859) (xy 418.176854 -302.289906)
			(xy 418.140103 -302.326657) (xy 418.098056 -302.357206) (xy 418.051747 -302.380801) (xy 418.002317 -302.396861)
			(xy 417.950983 -302.404991) (xy 417.924996 -302.405542) (xy 417.924742 -302.405542) (xy 417.90584 -302.405256)
			(xy 417.868284 -302.400927) (xy 417.849812 -302.396906) (xy 417.838382 -302.394112) (xy 417.81603 -302.399192)
			(xy 417.744402 -302.456088) (xy 417.735686 -302.463664) (xy 417.725633 -302.48443) (xy 417.725098 -302.495966)
			(xy 417.725098 -302.603408) (xy 417.725556 -302.613286) (xy 417.732997 -302.631587) (xy 417.739576 -302.638968)
			(xy 417.73983 -302.639222) (xy 417.74364 -302.643032) (xy 417.766754 -302.66132) (xy 417.81603 -302.700436)
			(xy 417.838382 -302.705516) (xy 417.849812 -302.702722) (xy 417.86828 -302.698676) (xy 417.905838 -302.694346)
			(xy 417.924742 -302.694086) (xy 417.924996 -302.694086) (xy 417.950986 -302.694569) (xy 418.002326 -302.7027)
			(xy 418.051762 -302.718762) (xy 418.098076 -302.74236) (xy 418.140129 -302.772913) (xy 418.176885 -302.809668)
			(xy 418.207438 -302.85172) (xy 418.231037 -302.898034) (xy 418.247099 -302.94747) (xy 418.255231 -302.99881)
			(xy 418.255231 -303.024794) (xy 418.569152 -303.024794) (xy 418.573112 -302.97574) (xy 418.584889 -302.927956)
			(xy 418.60418 -302.88268) (xy 418.630483 -302.841084) (xy 418.663118 -302.804247) (xy 418.701239 -302.773122)
			(xy 418.74386 -302.748515) (xy 418.789876 -302.731063) (xy 418.838095 -302.721219) (xy 418.88727 -302.719238)
			(xy 418.936125 -302.72517) (xy 418.983396 -302.738862) (xy 419.027858 -302.75996) (xy 419.068361 -302.787916)
			(xy 419.103854 -302.822008) (xy 419.133419 -302.861352) (xy 419.15629 -302.904929) (xy 419.171874 -302.95161)
			(xy 419.179769 -303.000187) (xy 419.180264 -303.024794) (xy 419.519112 -303.024794) (xy 419.523072 -302.97574)
			(xy 419.534849 -302.927956) (xy 419.55414 -302.88268) (xy 419.580443 -302.841084) (xy 419.613078 -302.804247)
			(xy 419.651199 -302.773122) (xy 419.69382 -302.748515) (xy 419.739836 -302.731063) (xy 419.788055 -302.721219)
			(xy 419.83723 -302.719238) (xy 419.886085 -302.72517) (xy 419.933356 -302.738862) (xy 419.977818 -302.75996)
			(xy 420.018321 -302.787916) (xy 420.053814 -302.822008) (xy 420.083379 -302.861352) (xy 420.10625 -302.904929)
			(xy 420.121834 -302.95161) (xy 420.129729 -303.000187) (xy 420.130224 -303.024794) (xy 420.469072 -303.024794)
			(xy 420.473032 -302.97574) (xy 420.484809 -302.927956) (xy 420.5041 -302.88268) (xy 420.530403 -302.841084)
			(xy 420.563038 -302.804247) (xy 420.601159 -302.773122) (xy 420.64378 -302.748515) (xy 420.689796 -302.731063)
			(xy 420.738015 -302.721219) (xy 420.78719 -302.719238) (xy 420.836045 -302.72517) (xy 420.883316 -302.738862)
			(xy 420.927778 -302.75996) (xy 420.968281 -302.787916) (xy 421.003774 -302.822008) (xy 421.033339 -302.861352)
			(xy 421.05621 -302.904929) (xy 421.071794 -302.95161) (xy 421.079689 -303.000187) (xy 421.080184 -303.024794)
			(xy 421.419032 -303.024794) (xy 421.422992 -302.97574) (xy 421.434769 -302.927956) (xy 421.45406 -302.88268)
			(xy 421.480363 -302.841084) (xy 421.512998 -302.804247) (xy 421.551119 -302.773122) (xy 421.59374 -302.748515)
			(xy 421.639756 -302.731063) (xy 421.687975 -302.721219) (xy 421.73715 -302.719238) (xy 421.786005 -302.72517)
			(xy 421.833276 -302.738862) (xy 421.877738 -302.75996) (xy 421.918241 -302.787916) (xy 421.953734 -302.822008)
			(xy 421.983299 -302.861352) (xy 422.00617 -302.904929) (xy 422.021754 -302.95161) (xy 422.029649 -303.000187)
			(xy 422.030144 -303.024794) (xy 422.029649 -303.049401) (xy 422.021754 -303.097978) (xy 422.00617 -303.144659)
			(xy 421.983299 -303.188236) (xy 421.953734 -303.22758) (xy 421.918241 -303.261672) (xy 421.877738 -303.289628)
			(xy 421.833276 -303.310726) (xy 421.786005 -303.324418) (xy 421.73715 -303.33035) (xy 421.687975 -303.328369)
			(xy 421.639756 -303.318525) (xy 421.59374 -303.301073) (xy 421.551119 -303.276466) (xy 421.512998 -303.245341)
			(xy 421.480363 -303.208504) (xy 421.45406 -303.166908) (xy 421.434769 -303.121632) (xy 421.422992 -303.073848)
			(xy 421.419032 -303.024794) (xy 421.080184 -303.024794) (xy 421.079689 -303.049401) (xy 421.071794 -303.097978)
			(xy 421.05621 -303.144659) (xy 421.033339 -303.188236) (xy 421.003774 -303.22758) (xy 420.968281 -303.261672)
			(xy 420.927778 -303.289628) (xy 420.883316 -303.310726) (xy 420.836045 -303.324418) (xy 420.78719 -303.33035)
			(xy 420.738015 -303.328369) (xy 420.689796 -303.318525) (xy 420.64378 -303.301073) (xy 420.601159 -303.276466)
			(xy 420.563038 -303.245341) (xy 420.530403 -303.208504) (xy 420.5041 -303.166908) (xy 420.484809 -303.121632)
			(xy 420.473032 -303.073848) (xy 420.469072 -303.024794) (xy 420.130224 -303.024794) (xy 420.129729 -303.049401)
			(xy 420.121834 -303.097978) (xy 420.10625 -303.144659) (xy 420.083379 -303.188236) (xy 420.053814 -303.22758)
			(xy 420.018321 -303.261672) (xy 419.977818 -303.289628) (xy 419.933356 -303.310726) (xy 419.886085 -303.324418)
			(xy 419.83723 -303.33035) (xy 419.788055 -303.328369) (xy 419.739836 -303.318525) (xy 419.69382 -303.301073)
			(xy 419.651199 -303.276466) (xy 419.613078 -303.245341) (xy 419.580443 -303.208504) (xy 419.55414 -303.166908)
			(xy 419.534849 -303.121632) (xy 419.523072 -303.073848) (xy 419.519112 -303.024794) (xy 419.180264 -303.024794)
			(xy 419.179769 -303.049401) (xy 419.171874 -303.097978) (xy 419.15629 -303.144659) (xy 419.133419 -303.188236)
			(xy 419.103854 -303.22758) (xy 419.068361 -303.261672) (xy 419.027858 -303.289628) (xy 418.983396 -303.310726)
			(xy 418.936125 -303.324418) (xy 418.88727 -303.33035) (xy 418.838095 -303.328369) (xy 418.789876 -303.318525)
			(xy 418.74386 -303.301073) (xy 418.701239 -303.276466) (xy 418.663118 -303.245341) (xy 418.630483 -303.208504)
			(xy 418.60418 -303.166908) (xy 418.584889 -303.121632) (xy 418.573112 -303.073848) (xy 418.569152 -303.024794)
			(xy 418.255231 -303.024794) (xy 418.255231 -303.05079) (xy 418.247099 -303.10213) (xy 418.231037 -303.151566)
			(xy 418.207438 -303.19788) (xy 418.176885 -303.239932) (xy 418.140129 -303.276687) (xy 418.098076 -303.30724)
			(xy 418.051762 -303.330838) (xy 418.002326 -303.3469) (xy 417.950986 -303.355031) (xy 417.924996 -303.355502)
			(xy 417.924742 -303.355502) (xy 417.90584 -303.355216) (xy 417.868284 -303.350886) (xy 417.849812 -303.346866)
			(xy 417.838382 -303.344072) (xy 417.81603 -303.349152) (xy 417.744402 -303.406048) (xy 417.735679 -303.413621)
			(xy 417.72561 -303.434387) (xy 417.725098 -303.445926) (xy 417.725098 -303.553368) (xy 417.725567 -303.563241)
			(xy 417.733023 -303.581527) (xy 417.739576 -303.588928) (xy 417.73983 -303.589182) (xy 417.74364 -303.592992)
			(xy 417.766754 -303.61128) (xy 417.81603 -303.650396) (xy 417.838382 -303.655476) (xy 417.849812 -303.652682)
			(xy 417.86828 -303.648636) (xy 417.905838 -303.644307) (xy 417.924742 -303.644046) (xy 417.924996 -303.644046)
			(xy 417.950989 -303.644529) (xy 418.002335 -303.652661) (xy 418.051777 -303.668725) (xy 418.098097 -303.692326)
			(xy 418.140155 -303.722882) (xy 418.176915 -303.759642) (xy 418.207472 -303.801699) (xy 418.231074 -303.848019)
			(xy 418.247138 -303.897461) (xy 418.255271 -303.948807) (xy 418.255271 -303.974754) (xy 418.569152 -303.974754)
			(xy 418.573112 -303.9257) (xy 418.584889 -303.877916) (xy 418.60418 -303.83264) (xy 418.630483 -303.791044)
			(xy 418.663118 -303.754207) (xy 418.701239 -303.723082) (xy 418.74386 -303.698475) (xy 418.789876 -303.681023)
			(xy 418.838095 -303.671179) (xy 418.88727 -303.669198) (xy 418.936125 -303.67513) (xy 418.983396 -303.688822)
			(xy 419.027858 -303.70992) (xy 419.068361 -303.737876) (xy 419.103854 -303.771968) (xy 419.133419 -303.811312)
			(xy 419.15629 -303.854889) (xy 419.171874 -303.90157) (xy 419.179769 -303.950147) (xy 419.180264 -303.974754)
			(xy 419.519112 -303.974754) (xy 419.523072 -303.9257) (xy 419.534849 -303.877916) (xy 419.55414 -303.83264)
			(xy 419.580443 -303.791044) (xy 419.613078 -303.754207) (xy 419.651199 -303.723082) (xy 419.69382 -303.698475)
			(xy 419.739836 -303.681023) (xy 419.788055 -303.671179) (xy 419.83723 -303.669198) (xy 419.886085 -303.67513)
			(xy 419.933356 -303.688822) (xy 419.977818 -303.70992) (xy 420.018321 -303.737876) (xy 420.053814 -303.771968)
			(xy 420.083379 -303.811312) (xy 420.10625 -303.854889) (xy 420.121834 -303.90157) (xy 420.129729 -303.950147)
			(xy 420.130224 -303.974754) (xy 420.469072 -303.974754) (xy 420.473032 -303.9257) (xy 420.484809 -303.877916)
			(xy 420.5041 -303.83264) (xy 420.530403 -303.791044) (xy 420.563038 -303.754207) (xy 420.601159 -303.723082)
			(xy 420.64378 -303.698475) (xy 420.689796 -303.681023) (xy 420.738015 -303.671179) (xy 420.78719 -303.669198)
			(xy 420.836045 -303.67513) (xy 420.883316 -303.688822) (xy 420.927778 -303.70992) (xy 420.968281 -303.737876)
			(xy 421.003774 -303.771968) (xy 421.033339 -303.811312) (xy 421.05621 -303.854889) (xy 421.071794 -303.90157)
			(xy 421.079689 -303.950147) (xy 421.080184 -303.974754) (xy 421.079689 -303.999361) (xy 421.071794 -304.047938)
			(xy 421.05621 -304.094619) (xy 421.033339 -304.138196) (xy 421.003774 -304.17754) (xy 420.968281 -304.211632)
			(xy 420.927778 -304.239588) (xy 420.883316 -304.260686) (xy 420.836045 -304.274378) (xy 420.78719 -304.28031)
			(xy 420.738015 -304.278329) (xy 420.689796 -304.268485) (xy 420.64378 -304.251033) (xy 420.601159 -304.226426)
			(xy 420.563038 -304.195301) (xy 420.530403 -304.158464) (xy 420.5041 -304.116868) (xy 420.484809 -304.071592)
			(xy 420.473032 -304.023808) (xy 420.469072 -303.974754) (xy 420.130224 -303.974754) (xy 420.129729 -303.999361)
			(xy 420.121834 -304.047938) (xy 420.10625 -304.094619) (xy 420.083379 -304.138196) (xy 420.053814 -304.17754)
			(xy 420.018321 -304.211632) (xy 419.977818 -304.239588) (xy 419.933356 -304.260686) (xy 419.886085 -304.274378)
			(xy 419.83723 -304.28031) (xy 419.788055 -304.278329) (xy 419.739836 -304.268485) (xy 419.69382 -304.251033)
			(xy 419.651199 -304.226426) (xy 419.613078 -304.195301) (xy 419.580443 -304.158464) (xy 419.55414 -304.116868)
			(xy 419.534849 -304.071592) (xy 419.523072 -304.023808) (xy 419.519112 -303.974754) (xy 419.180264 -303.974754)
			(xy 419.179769 -303.999361) (xy 419.171874 -304.047938) (xy 419.15629 -304.094619) (xy 419.133419 -304.138196)
			(xy 419.103854 -304.17754) (xy 419.068361 -304.211632) (xy 419.027858 -304.239588) (xy 418.983396 -304.260686)
			(xy 418.936125 -304.274378) (xy 418.88727 -304.28031) (xy 418.838095 -304.278329) (xy 418.789876 -304.268485)
			(xy 418.74386 -304.251033) (xy 418.701239 -304.226426) (xy 418.663118 -304.195301) (xy 418.630483 -304.158464)
			(xy 418.60418 -304.116868) (xy 418.584889 -304.071592) (xy 418.573112 -304.023808) (xy 418.569152 -303.974754)
			(xy 418.255271 -303.974754) (xy 418.255271 -304.000793) (xy 418.247138 -304.052139) (xy 418.231074 -304.101581)
			(xy 418.207472 -304.147901) (xy 418.176915 -304.189958) (xy 418.140155 -304.226718) (xy 418.098097 -304.257274)
			(xy 418.051777 -304.280875) (xy 418.002335 -304.296939) (xy 417.950989 -304.305071) (xy 417.924996 -304.305462)
			(xy 417.897985 -304.304933) (xy 417.84468 -304.296165) (xy 417.793511 -304.278846) (xy 417.745838 -304.253437)
			(xy 417.702931 -304.220615) (xy 417.665932 -304.181253) (xy 417.635825 -304.136399) (xy 417.613413 -304.087247)
			(xy 417.59929 -304.035104) (xy 417.596066 -304.008282) (xy 417.594542 -303.99355) (xy 417.576254 -303.970182)
			(xy 417.514278 -303.948846) (xy 417.47567 -303.935384) (xy 417.469506 -303.933491) (xy 417.456657 -303.932469)
			(xy 417.45027 -303.933352) (xy 417.437316 -303.935638) (xy 417.427156 -303.943766) (xy 417.42487 -303.945544)
			(xy 417.29279 -304.077624) (xy 417.288472 -304.088292) (xy 417.284916 -304.097182) (xy 417.2741 -304.121735)
			(xy 417.245713 -304.167258) (xy 417.210353 -304.207604) (xy 417.168946 -304.241717) (xy 417.122578 -304.268702)
			(xy 417.097718 -304.278792) (xy 417.087558 -304.282856) (xy 416.947604 -304.42281) (xy 416.941165 -304.429874)
			(xy 416.933584 -304.447407) (xy 416.932889 -304.466496) (xy 416.935666 -304.475642) (xy 416.962844 -304.552604)
			(xy 416.965882 -304.560242) (xy 416.975991 -304.573192) (xy 416.982656 -304.578004) (xy 416.984942 -304.579528)
			(xy 417.008056 -304.595276) (xy 417.019994 -304.597054) (xy 417.046034 -304.601164) (xy 417.096449 -304.616563)
			(xy 417.143782 -304.639767) (xy 417.186834 -304.670186) (xy 417.224514 -304.707051) (xy 417.255868 -304.749427)
			(xy 417.280101 -304.796241) (xy 417.2966 -304.846307) (xy 417.304946 -304.898357) (xy 417.30549 -304.924714)
			(xy 417.619192 -304.924714) (xy 417.623152 -304.87566) (xy 417.634929 -304.827876) (xy 417.65422 -304.7826)
			(xy 417.680523 -304.741004) (xy 417.713158 -304.704167) (xy 417.751279 -304.673042) (xy 417.7939 -304.648435)
			(xy 417.839916 -304.630983) (xy 417.888135 -304.621139) (xy 417.93731 -304.619158) (xy 417.986165 -304.62509)
			(xy 418.033436 -304.638782) (xy 418.077898 -304.65988) (xy 418.118401 -304.687836) (xy 418.153894 -304.721928)
			(xy 418.183459 -304.761272) (xy 418.20633 -304.804849) (xy 418.221914 -304.85153) (xy 418.229809 -304.900107)
			(xy 418.230304 -304.924714) (xy 418.569152 -304.924714) (xy 418.573112 -304.87566) (xy 418.584889 -304.827876)
			(xy 418.60418 -304.7826) (xy 418.630483 -304.741004) (xy 418.663118 -304.704167) (xy 418.701239 -304.673042)
			(xy 418.74386 -304.648435) (xy 418.789876 -304.630983) (xy 418.838095 -304.621139) (xy 418.88727 -304.619158)
			(xy 418.936125 -304.62509) (xy 418.983396 -304.638782) (xy 419.027858 -304.65988) (xy 419.068361 -304.687836)
			(xy 419.103854 -304.721928) (xy 419.133419 -304.761272) (xy 419.15629 -304.804849) (xy 419.171874 -304.85153)
			(xy 419.179769 -304.900107) (xy 419.180264 -304.924714) (xy 419.519112 -304.924714) (xy 419.523072 -304.87566)
			(xy 419.534849 -304.827876) (xy 419.55414 -304.7826) (xy 419.580443 -304.741004) (xy 419.613078 -304.704167)
			(xy 419.651199 -304.673042) (xy 419.69382 -304.648435) (xy 419.739836 -304.630983) (xy 419.788055 -304.621139)
			(xy 419.83723 -304.619158) (xy 419.886085 -304.62509) (xy 419.933356 -304.638782) (xy 419.977818 -304.65988)
			(xy 420.018321 -304.687836) (xy 420.053814 -304.721928) (xy 420.083379 -304.761272) (xy 420.10625 -304.804849)
			(xy 420.121834 -304.85153) (xy 420.129729 -304.900107) (xy 420.130224 -304.924714) (xy 420.469072 -304.924714)
			(xy 420.473032 -304.87566) (xy 420.484809 -304.827876) (xy 420.5041 -304.7826) (xy 420.530403 -304.741004)
			(xy 420.563038 -304.704167) (xy 420.601159 -304.673042) (xy 420.64378 -304.648435) (xy 420.689796 -304.630983)
			(xy 420.738015 -304.621139) (xy 420.78719 -304.619158) (xy 420.836045 -304.62509) (xy 420.883316 -304.638782)
			(xy 420.927778 -304.65988) (xy 420.968281 -304.687836) (xy 421.003774 -304.721928) (xy 421.033339 -304.761272)
			(xy 421.05621 -304.804849) (xy 421.071794 -304.85153) (xy 421.079689 -304.900107) (xy 421.080184 -304.924714)
			(xy 421.079689 -304.949321) (xy 421.071794 -304.997898) (xy 421.05621 -305.044579) (xy 421.033339 -305.088156)
			(xy 421.003774 -305.1275) (xy 420.968281 -305.161592) (xy 420.927778 -305.189548) (xy 420.883316 -305.210646)
			(xy 420.836045 -305.224338) (xy 420.78719 -305.23027) (xy 420.738015 -305.228289) (xy 420.689796 -305.218445)
			(xy 420.64378 -305.200993) (xy 420.601159 -305.176386) (xy 420.563038 -305.145261) (xy 420.530403 -305.108424)
			(xy 420.5041 -305.066828) (xy 420.484809 -305.021552) (xy 420.473032 -304.973768) (xy 420.469072 -304.924714)
			(xy 420.130224 -304.924714) (xy 420.129729 -304.949321) (xy 420.121834 -304.997898) (xy 420.10625 -305.044579)
			(xy 420.083379 -305.088156) (xy 420.053814 -305.1275) (xy 420.018321 -305.161592) (xy 419.977818 -305.189548)
			(xy 419.933356 -305.210646) (xy 419.886085 -305.224338) (xy 419.83723 -305.23027) (xy 419.788055 -305.228289)
			(xy 419.739836 -305.218445) (xy 419.69382 -305.200993) (xy 419.651199 -305.176386) (xy 419.613078 -305.145261)
			(xy 419.580443 -305.108424) (xy 419.55414 -305.066828) (xy 419.534849 -305.021552) (xy 419.523072 -304.973768)
			(xy 419.519112 -304.924714) (xy 419.180264 -304.924714) (xy 419.179769 -304.949321) (xy 419.171874 -304.997898)
			(xy 419.15629 -305.044579) (xy 419.133419 -305.088156) (xy 419.103854 -305.1275) (xy 419.068361 -305.161592)
			(xy 419.027858 -305.189548) (xy 418.983396 -305.210646) (xy 418.936125 -305.224338) (xy 418.88727 -305.23027)
			(xy 418.838095 -305.228289) (xy 418.789876 -305.218445) (xy 418.74386 -305.200993) (xy 418.701239 -305.176386)
			(xy 418.663118 -305.145261) (xy 418.630483 -305.108424) (xy 418.60418 -305.066828) (xy 418.584889 -305.021552)
			(xy 418.573112 -304.973768) (xy 418.569152 -304.924714) (xy 418.230304 -304.924714) (xy 418.229809 -304.949321)
			(xy 418.221914 -304.997898) (xy 418.20633 -305.044579) (xy 418.183459 -305.088156) (xy 418.153894 -305.1275)
			(xy 418.118401 -305.161592) (xy 418.077898 -305.189548) (xy 418.033436 -305.210646) (xy 417.986165 -305.224338)
			(xy 417.93731 -305.23027) (xy 417.888135 -305.228289) (xy 417.839916 -305.218445) (xy 417.7939 -305.200993)
			(xy 417.751279 -305.176386) (xy 417.713158 -305.145261) (xy 417.680523 -305.108424) (xy 417.65422 -305.066828)
			(xy 417.634929 -305.021552) (xy 417.623152 -304.973768) (xy 417.619192 -304.924714) (xy 417.30549 -304.924714)
			(xy 417.30498 -304.950701) (xy 417.29685 -305.002036) (xy 417.280789 -305.051466) (xy 417.257193 -305.097776)
			(xy 417.226643 -305.139824) (xy 417.189892 -305.176575) (xy 417.147844 -305.207125) (xy 417.101534 -305.230721)
			(xy 417.052104 -305.246782) (xy 417.000769 -305.254912) (xy 416.948795 -305.254912) (xy 416.89746 -305.246782)
			(xy 416.84803 -305.230721) (xy 416.80172 -305.207125) (xy 416.759672 -305.176575) (xy 416.722921 -305.139824)
			(xy 416.692371 -305.097776) (xy 416.668775 -305.051466) (xy 416.652714 -305.002036) (xy 416.644584 -304.950701)
			(xy 416.644074 -304.924714) (xy 416.644535 -304.899959) (xy 416.651911 -304.851003) (xy 416.6665 -304.803693)
			(xy 416.687977 -304.759084) (xy 416.715862 -304.718175) (xy 416.749532 -304.681878) (xy 416.788235 -304.651004)
			(xy 416.809428 -304.638202) (xy 416.815016 -304.6349) (xy 416.82416 -304.625756) (xy 416.837368 -304.603404)
			(xy 416.840924 -304.596292) (xy 416.843972 -304.586386) (xy 416.844662 -304.581967) (xy 416.844661 -304.573025)
			(xy 416.843972 -304.568606) (xy 416.842448 -304.560986) (xy 416.84051 -304.552315) (xy 416.831602 -304.536958)
			(xy 416.817981 -304.525573) (xy 416.801287 -304.519532) (xy 416.79241 -304.519076) (xy 416.756088 -304.519076)
			(xy 416.74621 -304.519534) (xy 416.727908 -304.526973) (xy 416.720528 -304.533554) (xy 416.693858 -304.559716)
			(xy 416.693604 -304.55997) (xy 416.68626 -304.566784) (xy 416.667798 -304.574523) (xy 416.65779 -304.574956)
			(xy 416.347402 -304.574956) (xy 416.337912 -304.575353) (xy 416.320225 -304.582245) (xy 416.306223 -304.595061)
			(xy 416.301682 -304.603404) (xy 416.263328 -304.68189) (xy 416.259272 -304.691157) (xy 416.258083 -304.711334)
			(xy 416.261042 -304.721006) (xy 416.266884 -304.738278) (xy 416.271456 -304.744374) (xy 416.285259 -304.764078)
			(xy 416.307157 -304.806913) (xy 416.322084 -304.852647) (xy 416.329671 -304.900153) (xy 416.33013 -304.924206)
			(xy 416.33013 -304.924714) (xy 416.329608 -304.949969) (xy 416.321295 -304.999791) (xy 416.304894 -305.047565)
			(xy 416.280853 -305.091988) (xy 416.249829 -305.131848) (xy 416.212667 -305.166058) (xy 416.170381 -305.193684)
			(xy 416.124125 -305.213974) (xy 416.07516 -305.226374) (xy 416.024822 -305.230545) (xy 415.974484 -305.226374)
			(xy 415.925519 -305.213974) (xy 415.879263 -305.193684) (xy 415.836977 -305.166058) (xy 415.799815 -305.131848)
			(xy 415.768791 -305.091988) (xy 415.74475 -305.047565) (xy 415.728349 -304.999791) (xy 415.720036 -304.949969)
			(xy 415.719514 -304.924714) (xy 415.719514 -304.924206) (xy 415.719979 -304.900151) (xy 415.727548 -304.852641)
			(xy 415.742467 -304.806903) (xy 415.764369 -304.764068) (xy 415.778188 -304.744374) (xy 415.78276 -304.738278)
			(xy 415.788602 -304.721006) (xy 415.79152 -304.711328) (xy 415.790343 -304.691162) (xy 415.786316 -304.68189)
			(xy 415.747962 -304.603404) (xy 415.743451 -304.595032) (xy 415.729468 -304.582163) (xy 415.711746 -304.575302)
			(xy 415.702242 -304.574956) (xy 415.397442 -304.574956) (xy 415.387948 -304.575346) (xy 415.37025 -304.582229)
			(xy 415.356236 -304.595044) (xy 415.351722 -304.603404) (xy 415.313368 -304.68189) (xy 415.30931 -304.691157)
			(xy 415.30812 -304.711334) (xy 415.311082 -304.721006) (xy 415.316924 -304.738278) (xy 415.321496 -304.744374)
			(xy 415.335276 -304.764092) (xy 415.35717 -304.806924) (xy 415.372093 -304.852654) (xy 415.379679 -304.900155)
			(xy 415.38017 -304.924206) (xy 415.38017 -304.924714) (xy 415.379648 -304.949969) (xy 415.371335 -304.999791)
			(xy 415.354934 -305.047565) (xy 415.330893 -305.091988) (xy 415.299869 -305.131848) (xy 415.262707 -305.166058)
			(xy 415.220421 -305.193684) (xy 415.174165 -305.213974) (xy 415.1252 -305.226374) (xy 415.074862 -305.230545)
			(xy 415.024524 -305.226374) (xy 414.975559 -305.213974) (xy 414.929303 -305.193684) (xy 414.887017 -305.166058)
			(xy 414.849855 -305.131848) (xy 414.818831 -305.091988) (xy 414.79479 -305.047565) (xy 414.778389 -304.999791)
			(xy 414.770076 -304.949969) (xy 414.769554 -304.924714) (xy 414.769554 -304.924206) (xy 414.770019 -304.900152)
			(xy 414.777588 -304.852642) (xy 414.79251 -304.806905) (xy 414.814414 -304.764072) (xy 414.828228 -304.744374)
			(xy 414.8328 -304.738278) (xy 414.838642 -304.721006) (xy 414.841562 -304.711328) (xy 414.840384 -304.691162)
			(xy 414.836356 -304.68189) (xy 414.798002 -304.603404) (xy 414.793493 -304.595027) (xy 414.779511 -304.582148)
			(xy 414.761788 -304.575273) (xy 414.752282 -304.574956) (xy 414.447482 -304.574956) (xy 414.438004 -304.575413)
			(xy 414.420343 -304.582302) (xy 414.406362 -304.595105) (xy 414.401762 -304.603404) (xy 414.363408 -304.68189)
			(xy 414.359354 -304.691157) (xy 414.358165 -304.711334) (xy 414.361122 -304.721006) (xy 414.366964 -304.738278)
			(xy 414.371536 -304.744374) (xy 414.38534 -304.764078) (xy 414.407239 -304.806913) (xy 414.422167 -304.852646)
			(xy 414.429755 -304.900152) (xy 414.43021 -304.924206) (xy 414.43021 -304.924714) (xy 414.429688 -304.949969)
			(xy 414.421375 -304.999791) (xy 414.404974 -305.047565) (xy 414.380933 -305.091988) (xy 414.349909 -305.131848)
			(xy 414.312747 -305.166058) (xy 414.270461 -305.193684) (xy 414.224205 -305.213974) (xy 414.17524 -305.226374)
			(xy 414.124902 -305.230545) (xy 414.074564 -305.226374) (xy 414.025599 -305.213974) (xy 413.979343 -305.193684)
			(xy 413.937057 -305.166058) (xy 413.899895 -305.131848) (xy 413.868871 -305.091988) (xy 413.84483 -305.047565)
			(xy 413.828429 -304.999791) (xy 413.820116 -304.949969) (xy 413.819594 -304.924714) (xy 413.819594 -304.924206)
			(xy 413.820059 -304.900151) (xy 413.827627 -304.852641) (xy 413.842546 -304.806902) (xy 413.864447 -304.764067)
			(xy 413.878268 -304.744374) (xy 413.88284 -304.738278) (xy 413.888682 -304.721006) (xy 413.891601 -304.711328)
			(xy 413.890423 -304.691162) (xy 413.886396 -304.68189) (xy 413.848042 -304.603404) (xy 413.84353 -304.595034)
			(xy 413.829546 -304.582171) (xy 413.811824 -304.575316) (xy 413.802322 -304.574956) (xy 413.497522 -304.574956)
			(xy 413.48803 -304.575349) (xy 413.470337 -304.582237) (xy 413.456329 -304.595053) (xy 413.451802 -304.603404)
			(xy 413.413448 -304.68189) (xy 413.409392 -304.691157) (xy 413.408202 -304.711334) (xy 413.411162 -304.721006)
			(xy 413.417004 -304.738278) (xy 413.421576 -304.744374) (xy 413.435379 -304.764079) (xy 413.457275 -304.806914)
			(xy 413.4722 -304.852648) (xy 413.479788 -304.900153) (xy 413.48025 -304.924206) (xy 413.48025 -304.924714)
			(xy 413.479728 -304.949969) (xy 413.471415 -304.999791) (xy 413.455014 -305.047565) (xy 413.430973 -305.091988)
			(xy 413.399949 -305.131848) (xy 413.362787 -305.166058) (xy 413.320501 -305.193684) (xy 413.274245 -305.213974)
			(xy 413.22528 -305.226374) (xy 413.174942 -305.230545) (xy 413.124604 -305.226374) (xy 413.075639 -305.213974)
			(xy 413.029383 -305.193684) (xy 412.987097 -305.166058) (xy 412.949935 -305.131848) (xy 412.918911 -305.091988)
			(xy 412.89487 -305.047565) (xy 412.878469 -304.999791) (xy 412.870156 -304.949969) (xy 412.869634 -304.924714)
			(xy 412.869634 -304.924206) (xy 412.870099 -304.900152) (xy 412.877668 -304.852641) (xy 412.892588 -304.806904)
			(xy 412.914492 -304.76407) (xy 412.928308 -304.744374) (xy 412.93288 -304.738278) (xy 412.938722 -304.721006)
			(xy 412.941639 -304.711327) (xy 412.940463 -304.691162) (xy 412.936436 -304.68189) (xy 412.898082 -304.603404)
			(xy 412.893572 -304.595029) (xy 412.87959 -304.582155) (xy 412.861867 -304.575287) (xy 412.852362 -304.574956)
			(xy 412.547562 -304.574956) (xy 412.538066 -304.575343) (xy 412.520362 -304.582222) (xy 412.506342 -304.595035)
			(xy 412.501842 -304.603404) (xy 412.463488 -304.68189) (xy 412.459429 -304.691156) (xy 412.458239 -304.711335)
			(xy 412.461202 -304.721006) (xy 412.467044 -304.738278) (xy 412.471616 -304.744374) (xy 412.485421 -304.764078)
			(xy 412.507322 -304.806912) (xy 412.52225 -304.852646) (xy 412.529839 -304.900152) (xy 412.53029 -304.924206)
			(xy 412.53029 -304.924714) (xy 412.529768 -304.949969) (xy 412.521455 -304.999791) (xy 412.505054 -305.047565)
			(xy 412.481013 -305.091988) (xy 412.449989 -305.131848) (xy 412.412827 -305.166058) (xy 412.370541 -305.193684)
			(xy 412.324285 -305.213974) (xy 412.27532 -305.226374) (xy 412.224982 -305.230545) (xy 412.174644 -305.226374)
			(xy 412.125679 -305.213974) (xy 412.079423 -305.193684) (xy 412.037137 -305.166058) (xy 411.999975 -305.131848)
			(xy 411.968951 -305.091988) (xy 411.94491 -305.047565) (xy 411.928509 -304.999791) (xy 411.920196 -304.949969)
			(xy 411.919674 -304.924714) (xy 411.919674 -304.924206) (xy 411.920139 -304.900151) (xy 411.927707 -304.85264)
			(xy 411.942625 -304.806902) (xy 411.964524 -304.764065) (xy 411.978348 -304.744374) (xy 411.98292 -304.738278)
			(xy 411.988762 -304.721006) (xy 411.991681 -304.711328) (xy 411.990504 -304.691162) (xy 411.986476 -304.68189)
			(xy 411.948122 -304.603404) (xy 411.943614 -304.595025) (xy 411.929633 -304.58214) (xy 411.91191 -304.575259)
			(xy 411.902402 -304.574956) (xy 411.597602 -304.574956) (xy 411.588112 -304.575353) (xy 411.570425 -304.582245)
			(xy 411.556423 -304.595061) (xy 411.551882 -304.603404) (xy 411.513528 -304.68189) (xy 411.509472 -304.691157)
			(xy 411.508283 -304.711334) (xy 411.511242 -304.721006) (xy 411.517084 -304.738278) (xy 411.521656 -304.744374)
			(xy 411.535459 -304.764078) (xy 411.557357 -304.806913) (xy 411.572284 -304.852647) (xy 411.579871 -304.900153)
			(xy 411.58033 -304.924206) (xy 411.58033 -304.924714) (xy 411.579808 -304.949969) (xy 411.571495 -304.999791)
			(xy 411.555094 -305.047565) (xy 411.531053 -305.091988) (xy 411.500029 -305.131848) (xy 411.462867 -305.166058)
			(xy 411.420581 -305.193684) (xy 411.374325 -305.213974) (xy 411.32536 -305.226374) (xy 411.275022 -305.230545)
			(xy 411.224684 -305.226374) (xy 411.175719 -305.213974) (xy 411.129463 -305.193684) (xy 411.087177 -305.166058)
			(xy 411.050015 -305.131848) (xy 411.018991 -305.091988) (xy 410.99495 -305.047565) (xy 410.978549 -304.999791)
			(xy 410.970236 -304.949969) (xy 410.969714 -304.924714) (xy 410.969714 -304.924206) (xy 410.970179 -304.900151)
			(xy 410.977748 -304.852641) (xy 410.992667 -304.806903) (xy 411.014569 -304.764068) (xy 411.028388 -304.744374)
			(xy 411.03296 -304.738278) (xy 411.038802 -304.721006) (xy 411.04172 -304.711328) (xy 411.040543 -304.691162)
			(xy 411.036516 -304.68189) (xy 410.998162 -304.603404) (xy 410.993651 -304.595032) (xy 410.979668 -304.582163)
			(xy 410.961946 -304.575302) (xy 410.952442 -304.574956) (xy 410.647388 -304.574956) (xy 410.637899 -304.575355)
			(xy 410.620216 -304.58225) (xy 410.606218 -304.595067) (xy 410.601668 -304.603404) (xy 410.563314 -304.68189)
			(xy 410.559259 -304.691157) (xy 410.55807 -304.711334) (xy 410.561028 -304.721006) (xy 410.56687 -304.738278)
			(xy 410.571442 -304.744374) (xy 410.585246 -304.764078) (xy 410.607145 -304.806913) (xy 410.622072 -304.852647)
			(xy 410.62966 -304.900153) (xy 410.630116 -304.924206) (xy 410.630116 -304.924714) (xy 410.629594 -304.949969)
			(xy 410.621281 -304.999791) (xy 410.60488 -305.047565) (xy 410.580839 -305.091988) (xy 410.549815 -305.131848)
			(xy 410.512653 -305.166058) (xy 410.470367 -305.193684) (xy 410.424111 -305.213974) (xy 410.375146 -305.226374)
			(xy 410.324808 -305.230545) (xy 410.27447 -305.226374) (xy 410.225505 -305.213974) (xy 410.179249 -305.193684)
			(xy 410.136963 -305.166058) (xy 410.099801 -305.131848) (xy 410.068777 -305.091988) (xy 410.044736 -305.047565)
			(xy 410.028335 -304.999791) (xy 410.020022 -304.949969) (xy 410.0195 -304.924714) (xy 410.0195 -304.924206)
			(xy 410.019965 -304.900151) (xy 410.027533 -304.852641) (xy 410.042452 -304.806903) (xy 410.064353 -304.764067)
			(xy 410.078174 -304.744374) (xy 410.082746 -304.738278) (xy 410.088588 -304.721006) (xy 410.091506 -304.711328)
			(xy 410.090329 -304.691162) (xy 410.086302 -304.68189) (xy 410.047948 -304.603404) (xy 410.043437 -304.595033)
			(xy 410.029452 -304.582169) (xy 410.011731 -304.575312) (xy 410.002228 -304.574956) (xy 409.697428 -304.574956)
			(xy 409.687935 -304.575348) (xy 409.670241 -304.582235) (xy 409.656231 -304.59505) (xy 409.651708 -304.603404)
			(xy 409.613354 -304.68189) (xy 409.609297 -304.691157) (xy 409.608107 -304.711334) (xy 409.611068 -304.721006)
			(xy 409.61691 -304.738278) (xy 409.621482 -304.744374) (xy 409.635284 -304.764079) (xy 409.65718 -304.806914)
			(xy 409.672105 -304.852648) (xy 409.679692 -304.900153) (xy 409.680156 -304.924206) (xy 409.680156 -304.924714)
			(xy 409.679634 -304.949969) (xy 409.671321 -304.999791) (xy 409.65492 -305.047565) (xy 409.630879 -305.091988)
			(xy 409.599855 -305.131848) (xy 409.562693 -305.166058) (xy 409.520407 -305.193684) (xy 409.474151 -305.213974)
			(xy 409.425186 -305.226374) (xy 409.374848 -305.230545) (xy 409.32451 -305.226374) (xy 409.275545 -305.213974)
			(xy 409.229289 -305.193684) (xy 409.187003 -305.166058) (xy 409.149841 -305.131848) (xy 409.118817 -305.091988)
			(xy 409.094776 -305.047565) (xy 409.078375 -304.999791) (xy 409.070062 -304.949969) (xy 409.06954 -304.924714)
			(xy 409.06954 -304.924206) (xy 409.070005 -304.900152) (xy 409.077574 -304.852641) (xy 409.092495 -304.806904)
			(xy 409.114398 -304.76407) (xy 409.128214 -304.744374) (xy 409.132786 -304.738278) (xy 409.138628 -304.721006)
			(xy 409.141545 -304.711327) (xy 409.140369 -304.691162) (xy 409.136342 -304.68189) (xy 409.097988 -304.603404)
			(xy 409.093479 -304.595029) (xy 409.079496 -304.582153) (xy 409.061773 -304.575283) (xy 409.052268 -304.574956)
			(xy 408.747468 -304.574956) (xy 408.737992 -304.575415) (xy 408.720334 -304.582307) (xy 408.706358 -304.595111)
			(xy 408.701748 -304.603404) (xy 408.663394 -304.68189) (xy 408.659335 -304.691156) (xy 408.658144 -304.711335)
			(xy 408.661108 -304.721006) (xy 408.66695 -304.738278) (xy 408.671522 -304.744374) (xy 408.685327 -304.764078)
			(xy 408.707227 -304.806912) (xy 408.722155 -304.852646) (xy 408.729744 -304.900152) (xy 408.730196 -304.924206)
			(xy 408.730196 -304.924714) (xy 408.729674 -304.949969) (xy 408.721361 -304.999791) (xy 408.70496 -305.047565)
			(xy 408.680919 -305.091988) (xy 408.649895 -305.131848) (xy 408.612733 -305.166058) (xy 408.570447 -305.193684)
			(xy 408.524191 -305.213974) (xy 408.475226 -305.226374) (xy 408.424888 -305.230545) (xy 408.37455 -305.226374)
			(xy 408.325585 -305.213974) (xy 408.279329 -305.193684) (xy 408.237043 -305.166058) (xy 408.199881 -305.131848)
			(xy 408.168857 -305.091988) (xy 408.144816 -305.047565) (xy 408.128415 -304.999791) (xy 408.120102 -304.949969)
			(xy 408.11958 -304.924714) (xy 408.11958 -304.924206) (xy 408.120045 -304.900151) (xy 408.127613 -304.85264)
			(xy 408.142531 -304.806902) (xy 408.164431 -304.764065) (xy 408.178254 -304.744374) (xy 408.182826 -304.738278)
			(xy 408.188668 -304.721006) (xy 408.191587 -304.711328) (xy 408.190409 -304.691162) (xy 408.186382 -304.68189)
			(xy 408.148028 -304.603404) (xy 408.14352 -304.595024) (xy 408.12954 -304.582138) (xy 408.111816 -304.575254)
			(xy 408.102308 -304.574956) (xy 406.847548 -304.574956) (xy 406.838053 -304.575345) (xy 406.820353 -304.582227)
			(xy 406.806338 -304.595042) (xy 406.801828 -304.603404) (xy 406.763474 -304.68189) (xy 406.759416 -304.691157)
			(xy 406.758225 -304.711334) (xy 406.761188 -304.721006) (xy 406.76703 -304.738278) (xy 406.771602 -304.744374)
			(xy 406.785408 -304.764077) (xy 406.807309 -304.806912) (xy 406.822238 -304.852646) (xy 406.829827 -304.900152)
			(xy 406.830276 -304.924206) (xy 406.830276 -304.924714) (xy 406.829754 -304.949969) (xy 406.821441 -304.999791)
			(xy 406.80504 -305.047565) (xy 406.780999 -305.091988) (xy 406.749975 -305.131848) (xy 406.712813 -305.166058)
			(xy 406.670527 -305.193684) (xy 406.624271 -305.213974) (xy 406.575306 -305.226374) (xy 406.524968 -305.230545)
			(xy 406.47463 -305.226374) (xy 406.425665 -305.213974) (xy 406.379409 -305.193684) (xy 406.337123 -305.166058)
			(xy 406.299961 -305.131848) (xy 406.268937 -305.091988) (xy 406.244896 -305.047565) (xy 406.228495 -304.999791)
			(xy 406.220182 -304.949969) (xy 406.21966 -304.924714) (xy 406.21966 -304.924206) (xy 406.220125 -304.900151)
			(xy 406.227692 -304.85264) (xy 406.24261 -304.806901) (xy 406.264509 -304.764064) (xy 406.278334 -304.744374)
			(xy 406.282906 -304.738278) (xy 406.288748 -304.721006) (xy 406.291668 -304.711328) (xy 406.290489 -304.691162)
			(xy 406.286462 -304.68189) (xy 406.248108 -304.603404) (xy 406.243599 -304.595027) (xy 406.229618 -304.582145)
			(xy 406.211895 -304.575269) (xy 406.202388 -304.574956) (xy 405.897588 -304.574956) (xy 405.888099 -304.575355)
			(xy 405.870416 -304.58225) (xy 405.856418 -304.595067) (xy 405.851868 -304.603404) (xy 405.813514 -304.68189)
			(xy 405.809459 -304.691157) (xy 405.80827 -304.711334) (xy 405.811228 -304.721006) (xy 405.81707 -304.738278)
			(xy 405.821642 -304.744374) (xy 405.835446 -304.764078) (xy 405.857345 -304.806913) (xy 405.872272 -304.852647)
			(xy 405.87986 -304.900153) (xy 405.880316 -304.924206) (xy 405.880316 -304.924714) (xy 405.879794 -304.949969)
			(xy 405.871481 -304.999791) (xy 405.85508 -305.047565) (xy 405.831039 -305.091988) (xy 405.800015 -305.131848)
			(xy 405.762853 -305.166058) (xy 405.720567 -305.193684) (xy 405.674311 -305.213974) (xy 405.625346 -305.226374)
			(xy 405.575008 -305.230545) (xy 405.52467 -305.226374) (xy 405.475705 -305.213974) (xy 405.429449 -305.193684)
			(xy 405.387163 -305.166058) (xy 405.350001 -305.131848) (xy 405.318977 -305.091988) (xy 405.294936 -305.047565)
			(xy 405.278535 -304.999791) (xy 405.270222 -304.949969) (xy 405.2697 -304.924714) (xy 405.2697 -304.924206)
			(xy 405.270165 -304.900151) (xy 405.277733 -304.852641) (xy 405.292652 -304.806903) (xy 405.314553 -304.764067)
			(xy 405.328374 -304.744374) (xy 405.332946 -304.738278) (xy 405.338788 -304.721006) (xy 405.341706 -304.711328)
			(xy 405.340529 -304.691162) (xy 405.336502 -304.68189) (xy 405.298148 -304.603404) (xy 405.293637 -304.595033)
			(xy 405.279652 -304.582169) (xy 405.261931 -304.575312) (xy 405.252428 -304.574956) (xy 404.947374 -304.574956)
			(xy 404.937897 -304.575414) (xy 404.920238 -304.582305) (xy 404.90626 -304.595108) (xy 404.901654 -304.603404)
			(xy 404.8633 -304.68189) (xy 404.859241 -304.691156) (xy 404.85805 -304.711335) (xy 404.861014 -304.721006)
			(xy 404.866856 -304.738278) (xy 404.871428 -304.744374) (xy 404.885233 -304.764078) (xy 404.907132 -304.806913)
			(xy 404.92206 -304.852646) (xy 404.929649 -304.900152) (xy 404.930102 -304.924206) (xy 404.930102 -304.924714)
			(xy 404.92958 -304.949969) (xy 404.921267 -304.999791) (xy 404.904866 -305.047565) (xy 404.880825 -305.091988)
			(xy 404.849801 -305.131848) (xy 404.812639 -305.166058) (xy 404.770353 -305.193684) (xy 404.724097 -305.213974)
			(xy 404.675132 -305.226374) (xy 404.624794 -305.230545) (xy 404.574456 -305.226374) (xy 404.525491 -305.213974)
			(xy 404.479235 -305.193684) (xy 404.436949 -305.166058) (xy 404.399787 -305.131848) (xy 404.368763 -305.091988)
			(xy 404.344722 -305.047565) (xy 404.328321 -304.999791) (xy 404.320008 -304.949969) (xy 404.319486 -304.924714)
			(xy 404.319486 -304.924206) (xy 404.319951 -304.900151) (xy 404.327519 -304.85264) (xy 404.342437 -304.806902)
			(xy 404.364338 -304.764066) (xy 404.37816 -304.744374) (xy 404.382732 -304.738278) (xy 404.388574 -304.721006)
			(xy 404.391493 -304.711328) (xy 404.390315 -304.691162) (xy 404.386288 -304.68189) (xy 404.347934 -304.603404)
			(xy 404.343427 -304.595023) (xy 404.329447 -304.582135) (xy 404.311722 -304.575249) (xy 404.302214 -304.574956)
			(xy 403.997414 -304.574956) (xy 403.987922 -304.575351) (xy 403.970232 -304.58224) (xy 403.956227 -304.595056)
			(xy 403.951694 -304.603404) (xy 403.91334 -304.68189) (xy 403.909284 -304.691157) (xy 403.908095 -304.711334)
			(xy 403.911054 -304.721006) (xy 403.916896 -304.738278) (xy 403.921468 -304.744374) (xy 403.935271 -304.764078)
			(xy 403.957168 -304.806914) (xy 403.972094 -304.852647) (xy 403.979681 -304.900153) (xy 403.980142 -304.924206)
			(xy 403.980142 -304.924714) (xy 403.97962 -304.949969) (xy 403.971307 -304.999791) (xy 403.954906 -305.047565)
			(xy 403.930865 -305.091988) (xy 403.899841 -305.131848) (xy 403.862679 -305.166058) (xy 403.820393 -305.193684)
			(xy 403.774137 -305.213974) (xy 403.725172 -305.226374) (xy 403.674834 -305.230545) (xy 403.624496 -305.226374)
			(xy 403.575531 -305.213974) (xy 403.529275 -305.193684) (xy 403.486989 -305.166058) (xy 403.449827 -305.131848)
			(xy 403.418803 -305.091988) (xy 403.394762 -305.047565) (xy 403.378361 -304.999791) (xy 403.370048 -304.949969)
			(xy 403.369526 -304.924714) (xy 403.369526 -304.924206) (xy 403.369991 -304.900152) (xy 403.37756 -304.852641)
			(xy 403.39248 -304.806904) (xy 403.414383 -304.764069) (xy 403.4282 -304.744374) (xy 403.432772 -304.738278)
			(xy 403.438614 -304.721006) (xy 403.441532 -304.711327) (xy 403.440355 -304.691162) (xy 403.436328 -304.68189)
			(xy 403.397974 -304.603404) (xy 403.393464 -304.59503) (xy 403.379481 -304.582159) (xy 403.361758 -304.575293)
			(xy 403.352254 -304.574956) (xy 403.047454 -304.574956) (xy 403.037958 -304.575344) (xy 403.020257 -304.582225)
			(xy 403.00624 -304.595039) (xy 403.001734 -304.603404) (xy 402.96338 -304.68189) (xy 402.959321 -304.691156)
			(xy 402.958131 -304.711334) (xy 402.961094 -304.721006) (xy 402.966936 -304.738278) (xy 402.971508 -304.744374)
			(xy 402.985313 -304.764077) (xy 403.007215 -304.806912) (xy 403.022143 -304.852646) (xy 403.029732 -304.900152)
			(xy 403.030182 -304.924206) (xy 403.030182 -304.924714) (xy 403.02966 -304.949969) (xy 403.021347 -304.999791)
			(xy 403.004946 -305.047565) (xy 402.980905 -305.091988) (xy 402.949881 -305.131848) (xy 402.912719 -305.166058)
			(xy 402.870433 -305.193684) (xy 402.824177 -305.213974) (xy 402.775212 -305.226374) (xy 402.724874 -305.230545)
			(xy 402.674536 -305.226374) (xy 402.625571 -305.213974) (xy 402.579315 -305.193684) (xy 402.537029 -305.166058)
			(xy 402.499867 -305.131848) (xy 402.468843 -305.091988) (xy 402.444802 -305.047565) (xy 402.428401 -304.999791)
			(xy 402.420088 -304.949969) (xy 402.419566 -304.924714) (xy 402.419566 -304.924206) (xy 402.420031 -304.900151)
			(xy 402.427598 -304.85264) (xy 402.442516 -304.806901) (xy 402.464415 -304.764064) (xy 402.47824 -304.744374)
			(xy 402.482812 -304.738278) (xy 402.488654 -304.721006) (xy 402.491574 -304.711328) (xy 402.490396 -304.691162)
			(xy 402.486368 -304.68189) (xy 402.448014 -304.603404) (xy 402.443506 -304.595026) (xy 402.429525 -304.582143)
			(xy 402.411801 -304.575264) (xy 402.402294 -304.574956) (xy 402.097494 -304.574956) (xy 402.088004 -304.575354)
			(xy 402.07032 -304.582248) (xy 402.05632 -304.595065) (xy 402.051774 -304.603404) (xy 402.01342 -304.68189)
			(xy 402.009365 -304.691157) (xy 402.008176 -304.711334) (xy 402.011134 -304.721006) (xy 402.016976 -304.738278)
			(xy 402.021548 -304.744374) (xy 402.035352 -304.764078) (xy 402.05725 -304.806913) (xy 402.072177 -304.852647)
			(xy 402.079765 -304.900153) (xy 402.080222 -304.924206) (xy 402.080222 -304.924714) (xy 402.0797 -304.949969)
			(xy 402.071387 -304.999791) (xy 402.054986 -305.047565) (xy 402.030945 -305.091988) (xy 401.999921 -305.131848)
			(xy 401.962759 -305.166058) (xy 401.920473 -305.193684) (xy 401.874217 -305.213974) (xy 401.825252 -305.226374)
			(xy 401.774914 -305.230545) (xy 401.724576 -305.226374) (xy 401.675611 -305.213974) (xy 401.629355 -305.193684)
			(xy 401.587069 -305.166058) (xy 401.549907 -305.131848) (xy 401.518883 -305.091988) (xy 401.494842 -305.047565)
			(xy 401.478441 -304.999791) (xy 401.470128 -304.949969) (xy 401.469606 -304.924714) (xy 401.469606 -304.924206)
			(xy 401.470071 -304.900151) (xy 401.477639 -304.852641) (xy 401.492559 -304.806903) (xy 401.51446 -304.764068)
			(xy 401.52828 -304.744374) (xy 401.532852 -304.738278) (xy 401.538694 -304.721006) (xy 401.541612 -304.711327)
			(xy 401.540435 -304.691162) (xy 401.536408 -304.68189) (xy 401.498054 -304.603404) (xy 401.493543 -304.595033)
			(xy 401.479559 -304.582166) (xy 401.461837 -304.575308) (xy 401.452334 -304.574956) (xy 401.147534 -304.574956)
			(xy 401.13804 -304.575347) (xy 401.120345 -304.582233) (xy 401.106333 -304.595048) (xy 401.101814 -304.603404)
			(xy 401.06346 -304.68189) (xy 401.059403 -304.691157) (xy 401.058213 -304.711334) (xy 401.061174 -304.721006)
			(xy 401.067016 -304.738278) (xy 401.071588 -304.744374) (xy 401.08539 -304.764079) (xy 401.107286 -304.806914)
			(xy 401.12221 -304.852648) (xy 401.129797 -304.900153) (xy 401.130262 -304.924206) (xy 401.130262 -304.924714)
			(xy 401.12974 -304.949969) (xy 401.121427 -304.999791) (xy 401.105026 -305.047565) (xy 401.080985 -305.091988)
			(xy 401.049961 -305.131848) (xy 401.012799 -305.166058) (xy 400.970513 -305.193684) (xy 400.924257 -305.213974)
			(xy 400.875292 -305.226374) (xy 400.824954 -305.230545) (xy 400.774616 -305.226374) (xy 400.725651 -305.213974)
			(xy 400.679395 -305.193684) (xy 400.637109 -305.166058) (xy 400.599947 -305.131848) (xy 400.568923 -305.091988)
			(xy 400.544882 -305.047565) (xy 400.528481 -304.999791) (xy 400.520168 -304.949969) (xy 400.519646 -304.924714)
			(xy 400.519646 -304.924206) (xy 400.520111 -304.900152) (xy 400.52768 -304.852642) (xy 400.542601 -304.806905)
			(xy 400.564505 -304.764071) (xy 400.57832 -304.744374) (xy 400.582892 -304.738278) (xy 400.588734 -304.721006)
			(xy 400.591651 -304.711327) (xy 400.590474 -304.691162) (xy 400.586448 -304.68189) (xy 400.548094 -304.603404)
			(xy 400.543585 -304.595028) (xy 400.529603 -304.582151) (xy 400.51188 -304.575279) (xy 400.502374 -304.574956)
			(xy 400.197574 -304.574956) (xy 400.188097 -304.575414) (xy 400.170438 -304.582305) (xy 400.15646 -304.595108)
			(xy 400.151854 -304.603404) (xy 400.1135 -304.68189) (xy 400.109441 -304.691156) (xy 400.10825 -304.711335)
			(xy 400.111214 -304.721006) (xy 400.117056 -304.738278) (xy 400.121628 -304.744374) (xy 400.135433 -304.764078)
			(xy 400.157332 -304.806913) (xy 400.17226 -304.852646) (xy 400.179849 -304.900152) (xy 400.180302 -304.924206)
			(xy 400.180302 -304.924714) (xy 400.17978 -304.949969) (xy 400.171467 -304.999791) (xy 400.155066 -305.047565)
			(xy 400.131025 -305.091988) (xy 400.100001 -305.131848) (xy 400.062839 -305.166058) (xy 400.020553 -305.193684)
			(xy 399.974297 -305.213974) (xy 399.925332 -305.226374) (xy 399.874994 -305.230545) (xy 399.824656 -305.226374)
			(xy 399.775691 -305.213974) (xy 399.729435 -305.193684) (xy 399.687149 -305.166058) (xy 399.649987 -305.131848)
			(xy 399.618963 -305.091988) (xy 399.594922 -305.047565) (xy 399.578521 -304.999791) (xy 399.570208 -304.949969)
			(xy 399.569686 -304.924714) (xy 399.569686 -304.924206) (xy 399.570151 -304.900151) (xy 399.577719 -304.85264)
			(xy 399.592637 -304.806902) (xy 399.614538 -304.764066) (xy 399.62836 -304.744374) (xy 399.632932 -304.738278)
			(xy 399.638774 -304.721006) (xy 399.641693 -304.711328) (xy 399.640515 -304.691162) (xy 399.636488 -304.68189)
			(xy 399.598134 -304.603404) (xy 399.593627 -304.595023) (xy 399.579647 -304.582135) (xy 399.561922 -304.575249)
			(xy 399.552414 -304.574956) (xy 399.247614 -304.574956) (xy 399.238122 -304.575351) (xy 399.220432 -304.58224)
			(xy 399.206427 -304.595056) (xy 399.201894 -304.603404) (xy 399.16354 -304.68189) (xy 399.159484 -304.691157)
			(xy 399.158295 -304.711334) (xy 399.161254 -304.721006) (xy 399.167096 -304.738278) (xy 399.171668 -304.744374)
			(xy 399.185471 -304.764078) (xy 399.207368 -304.806914) (xy 399.222294 -304.852647) (xy 399.229881 -304.900153)
			(xy 399.230342 -304.924206) (xy 399.230342 -304.924714) (xy 399.22987 -304.948705) (xy 399.222363 -304.996097)
			(xy 399.207535 -305.041732) (xy 399.185751 -305.084485) (xy 399.157548 -305.123305) (xy 399.12362 -305.157235)
			(xy 399.084802 -305.18544) (xy 399.04205 -305.207227) (xy 398.996417 -305.222058) (xy 398.949025 -305.229569)
			(xy 398.925034 -305.230022) (xy 398.901351 -305.229578) (xy 398.854553 -305.222272) (xy 398.809443 -305.207827)
			(xy 398.767105 -305.186593) (xy 398.728551 -305.159076) (xy 398.694709 -305.125938) (xy 398.666387 -305.087972)
			(xy 398.644266 -305.04609) (xy 398.628876 -305.001294) (xy 398.624298 -304.978054) (xy 398.622274 -304.969004)
			(xy 398.612752 -304.953108) (xy 398.598206 -304.941628) (xy 398.5895 -304.93843) (xy 398.503648 -304.911506)
			(xy 398.494719 -304.909113) (xy 398.47628 -304.910177) (xy 398.459419 -304.917717) (xy 398.452594 -304.923952)
			(xy 398.356074 -305.020472) (xy 398.349231 -305.027871) (xy 398.341511 -305.04647) (xy 398.341088 -305.05654)
			(xy 398.341088 -305.874928) (xy 398.61923 -305.874928) (xy 398.62319 -305.825874) (xy 398.634967 -305.77809)
			(xy 398.654258 -305.732814) (xy 398.680561 -305.691218) (xy 398.713196 -305.654381) (xy 398.751317 -305.623256)
			(xy 398.793938 -305.598649) (xy 398.839954 -305.581197) (xy 398.888173 -305.571353) (xy 398.937348 -305.569372)
			(xy 398.986203 -305.575304) (xy 399.033474 -305.588996) (xy 399.077936 -305.610094) (xy 399.118439 -305.63805)
			(xy 399.153932 -305.672142) (xy 399.183497 -305.711486) (xy 399.206368 -305.755063) (xy 399.221952 -305.801744)
			(xy 399.229847 -305.850321) (xy 399.230342 -305.874928) (xy 399.56919 -305.874928) (xy 399.57315 -305.825874)
			(xy 399.584927 -305.77809) (xy 399.604218 -305.732814) (xy 399.630521 -305.691218) (xy 399.663156 -305.654381)
			(xy 399.701277 -305.623256) (xy 399.743898 -305.598649) (xy 399.789914 -305.581197) (xy 399.838133 -305.571353)
			(xy 399.887308 -305.569372) (xy 399.936163 -305.575304) (xy 399.983434 -305.588996) (xy 400.027896 -305.610094)
			(xy 400.068399 -305.63805) (xy 400.103892 -305.672142) (xy 400.133457 -305.711486) (xy 400.156328 -305.755063)
			(xy 400.171912 -305.801744) (xy 400.179807 -305.850321) (xy 400.180302 -305.874928) (xy 400.51915 -305.874928)
			(xy 400.52311 -305.825874) (xy 400.534887 -305.77809) (xy 400.554178 -305.732814) (xy 400.580481 -305.691218)
			(xy 400.613116 -305.654381) (xy 400.651237 -305.623256) (xy 400.693858 -305.598649) (xy 400.739874 -305.581197)
			(xy 400.788093 -305.571353) (xy 400.837268 -305.569372) (xy 400.886123 -305.575304) (xy 400.933394 -305.588996)
			(xy 400.977856 -305.610094) (xy 401.018359 -305.63805) (xy 401.053852 -305.672142) (xy 401.083417 -305.711486)
			(xy 401.106288 -305.755063) (xy 401.121872 -305.801744) (xy 401.129767 -305.850321) (xy 401.130262 -305.874928)
			(xy 401.46911 -305.874928) (xy 401.47307 -305.825874) (xy 401.484847 -305.77809) (xy 401.504138 -305.732814)
			(xy 401.530441 -305.691218) (xy 401.563076 -305.654381) (xy 401.601197 -305.623256) (xy 401.643818 -305.598649)
			(xy 401.689834 -305.581197) (xy 401.738053 -305.571353) (xy 401.787228 -305.569372) (xy 401.836083 -305.575304)
			(xy 401.883354 -305.588996) (xy 401.927816 -305.610094) (xy 401.968319 -305.63805) (xy 402.003812 -305.672142)
			(xy 402.033377 -305.711486) (xy 402.056248 -305.755063) (xy 402.071832 -305.801744) (xy 402.079727 -305.850321)
			(xy 402.080222 -305.874928) (xy 402.41907 -305.874928) (xy 402.42303 -305.825874) (xy 402.434807 -305.77809)
			(xy 402.454098 -305.732814) (xy 402.480401 -305.691218) (xy 402.513036 -305.654381) (xy 402.551157 -305.623256)
			(xy 402.593778 -305.598649) (xy 402.639794 -305.581197) (xy 402.688013 -305.571353) (xy 402.737188 -305.569372)
			(xy 402.786043 -305.575304) (xy 402.833314 -305.588996) (xy 402.877776 -305.610094) (xy 402.918279 -305.63805)
			(xy 402.953772 -305.672142) (xy 402.983337 -305.711486) (xy 403.006208 -305.755063) (xy 403.021792 -305.801744)
			(xy 403.029687 -305.850321) (xy 403.030182 -305.874928) (xy 403.36903 -305.874928) (xy 403.37299 -305.825874)
			(xy 403.384767 -305.77809) (xy 403.404058 -305.732814) (xy 403.430361 -305.691218) (xy 403.462996 -305.654381)
			(xy 403.501117 -305.623256) (xy 403.543738 -305.598649) (xy 403.589754 -305.581197) (xy 403.637973 -305.571353)
			(xy 403.687148 -305.569372) (xy 403.736003 -305.575304) (xy 403.783274 -305.588996) (xy 403.827736 -305.610094)
			(xy 403.868239 -305.63805) (xy 403.903732 -305.672142) (xy 403.933297 -305.711486) (xy 403.956168 -305.755063)
			(xy 403.971752 -305.801744) (xy 403.979647 -305.850321) (xy 403.980142 -305.874928) (xy 404.31899 -305.874928)
			(xy 404.32295 -305.825874) (xy 404.334727 -305.77809) (xy 404.354018 -305.732814) (xy 404.380321 -305.691218)
			(xy 404.412956 -305.654381) (xy 404.451077 -305.623256) (xy 404.493698 -305.598649) (xy 404.539714 -305.581197)
			(xy 404.587933 -305.571353) (xy 404.637108 -305.569372) (xy 404.685963 -305.575304) (xy 404.733234 -305.588996)
			(xy 404.777696 -305.610094) (xy 404.818199 -305.63805) (xy 404.853692 -305.672142) (xy 404.883257 -305.711486)
			(xy 404.906128 -305.755063) (xy 404.921712 -305.801744) (xy 404.929607 -305.850321) (xy 404.930102 -305.874928)
			(xy 405.269204 -305.874928) (xy 405.273164 -305.825874) (xy 405.284941 -305.77809) (xy 405.304232 -305.732814)
			(xy 405.330535 -305.691218) (xy 405.36317 -305.654381) (xy 405.401291 -305.623256) (xy 405.443912 -305.598649)
			(xy 405.489928 -305.581197) (xy 405.538147 -305.571353) (xy 405.587322 -305.569372) (xy 405.636177 -305.575304)
			(xy 405.683448 -305.588996) (xy 405.72791 -305.610094) (xy 405.768413 -305.63805) (xy 405.803906 -305.672142)
			(xy 405.833471 -305.711486) (xy 405.856342 -305.755063) (xy 405.871926 -305.801744) (xy 405.879821 -305.850321)
			(xy 405.880316 -305.874928) (xy 406.219164 -305.874928) (xy 406.223124 -305.825874) (xy 406.234901 -305.77809)
			(xy 406.254192 -305.732814) (xy 406.280495 -305.691218) (xy 406.31313 -305.654381) (xy 406.351251 -305.623256)
			(xy 406.393872 -305.598649) (xy 406.439888 -305.581197) (xy 406.488107 -305.571353) (xy 406.537282 -305.569372)
			(xy 406.586137 -305.575304) (xy 406.633408 -305.588996) (xy 406.67787 -305.610094) (xy 406.718373 -305.63805)
			(xy 406.753866 -305.672142) (xy 406.783431 -305.711486) (xy 406.806302 -305.755063) (xy 406.821886 -305.801744)
			(xy 406.829781 -305.850321) (xy 406.830276 -305.874928) (xy 408.119084 -305.874928) (xy 408.123044 -305.825874)
			(xy 408.134821 -305.77809) (xy 408.154112 -305.732814) (xy 408.180415 -305.691218) (xy 408.21305 -305.654381)
			(xy 408.251171 -305.623256) (xy 408.293792 -305.598649) (xy 408.339808 -305.581197) (xy 408.388027 -305.571353)
			(xy 408.437202 -305.569372) (xy 408.486057 -305.575304) (xy 408.533328 -305.588996) (xy 408.57779 -305.610094)
			(xy 408.618293 -305.63805) (xy 408.653786 -305.672142) (xy 408.683351 -305.711486) (xy 408.706222 -305.755063)
			(xy 408.721806 -305.801744) (xy 408.729701 -305.850321) (xy 408.730196 -305.874928) (xy 409.069044 -305.874928)
			(xy 409.073004 -305.825874) (xy 409.084781 -305.77809) (xy 409.104072 -305.732814) (xy 409.130375 -305.691218)
			(xy 409.16301 -305.654381) (xy 409.201131 -305.623256) (xy 409.243752 -305.598649) (xy 409.289768 -305.581197)
			(xy 409.337987 -305.571353) (xy 409.387162 -305.569372) (xy 409.436017 -305.575304) (xy 409.483288 -305.588996)
			(xy 409.52775 -305.610094) (xy 409.568253 -305.63805) (xy 409.603746 -305.672142) (xy 409.633311 -305.711486)
			(xy 409.656182 -305.755063) (xy 409.671766 -305.801744) (xy 409.679661 -305.850321) (xy 409.680156 -305.874928)
			(xy 410.019004 -305.874928) (xy 410.022964 -305.825874) (xy 410.034741 -305.77809) (xy 410.054032 -305.732814)
			(xy 410.080335 -305.691218) (xy 410.11297 -305.654381) (xy 410.151091 -305.623256) (xy 410.193712 -305.598649)
			(xy 410.239728 -305.581197) (xy 410.287947 -305.571353) (xy 410.337122 -305.569372) (xy 410.385977 -305.575304)
			(xy 410.433248 -305.588996) (xy 410.47771 -305.610094) (xy 410.518213 -305.63805) (xy 410.553706 -305.672142)
			(xy 410.583271 -305.711486) (xy 410.606142 -305.755063) (xy 410.621726 -305.801744) (xy 410.629621 -305.850321)
			(xy 410.630116 -305.874928) (xy 410.969218 -305.874928) (xy 410.973178 -305.825874) (xy 410.984955 -305.77809)
			(xy 411.004246 -305.732814) (xy 411.030549 -305.691218) (xy 411.063184 -305.654381) (xy 411.101305 -305.623256)
			(xy 411.143926 -305.598649) (xy 411.189942 -305.581197) (xy 411.238161 -305.571353) (xy 411.287336 -305.569372)
			(xy 411.336191 -305.575304) (xy 411.383462 -305.588996) (xy 411.427924 -305.610094) (xy 411.468427 -305.63805)
			(xy 411.50392 -305.672142) (xy 411.533485 -305.711486) (xy 411.556356 -305.755063) (xy 411.57194 -305.801744)
			(xy 411.579835 -305.850321) (xy 411.58033 -305.874928) (xy 411.919178 -305.874928) (xy 411.923138 -305.825874)
			(xy 411.934915 -305.77809) (xy 411.954206 -305.732814) (xy 411.980509 -305.691218) (xy 412.013144 -305.654381)
			(xy 412.051265 -305.623256) (xy 412.093886 -305.598649) (xy 412.139902 -305.581197) (xy 412.188121 -305.571353)
			(xy 412.237296 -305.569372) (xy 412.286151 -305.575304) (xy 412.333422 -305.588996) (xy 412.377884 -305.610094)
			(xy 412.418387 -305.63805) (xy 412.45388 -305.672142) (xy 412.483445 -305.711486) (xy 412.506316 -305.755063)
			(xy 412.5219 -305.801744) (xy 412.529795 -305.850321) (xy 412.53029 -305.874928) (xy 412.869138 -305.874928)
			(xy 412.873098 -305.825874) (xy 412.884875 -305.77809) (xy 412.904166 -305.732814) (xy 412.930469 -305.691218)
			(xy 412.963104 -305.654381) (xy 413.001225 -305.623256) (xy 413.043846 -305.598649) (xy 413.089862 -305.581197)
			(xy 413.138081 -305.571353) (xy 413.187256 -305.569372) (xy 413.236111 -305.575304) (xy 413.283382 -305.588996)
			(xy 413.327844 -305.610094) (xy 413.368347 -305.63805) (xy 413.40384 -305.672142) (xy 413.433405 -305.711486)
			(xy 413.456276 -305.755063) (xy 413.47186 -305.801744) (xy 413.479755 -305.850321) (xy 413.48025 -305.874928)
			(xy 413.819098 -305.874928) (xy 413.823058 -305.825874) (xy 413.834835 -305.77809) (xy 413.854126 -305.732814)
			(xy 413.880429 -305.691218) (xy 413.913064 -305.654381) (xy 413.951185 -305.623256) (xy 413.993806 -305.598649)
			(xy 414.039822 -305.581197) (xy 414.088041 -305.571353) (xy 414.137216 -305.569372) (xy 414.186071 -305.575304)
			(xy 414.233342 -305.588996) (xy 414.277804 -305.610094) (xy 414.318307 -305.63805) (xy 414.3538 -305.672142)
			(xy 414.383365 -305.711486) (xy 414.406236 -305.755063) (xy 414.42182 -305.801744) (xy 414.429715 -305.850321)
			(xy 414.43021 -305.874928) (xy 414.769058 -305.874928) (xy 414.773018 -305.825874) (xy 414.784795 -305.77809)
			(xy 414.804086 -305.732814) (xy 414.830389 -305.691218) (xy 414.863024 -305.654381) (xy 414.901145 -305.623256)
			(xy 414.943766 -305.598649) (xy 414.989782 -305.581197) (xy 415.038001 -305.571353) (xy 415.087176 -305.569372)
			(xy 415.136031 -305.575304) (xy 415.183302 -305.588996) (xy 415.227764 -305.610094) (xy 415.268267 -305.63805)
			(xy 415.30376 -305.672142) (xy 415.333325 -305.711486) (xy 415.356196 -305.755063) (xy 415.37178 -305.801744)
			(xy 415.379675 -305.850321) (xy 415.38017 -305.874928) (xy 415.719018 -305.874928) (xy 415.722978 -305.825874)
			(xy 415.734755 -305.77809) (xy 415.754046 -305.732814) (xy 415.780349 -305.691218) (xy 415.812984 -305.654381)
			(xy 415.851105 -305.623256) (xy 415.893726 -305.598649) (xy 415.939742 -305.581197) (xy 415.987961 -305.571353)
			(xy 416.037136 -305.569372) (xy 416.085991 -305.575304) (xy 416.133262 -305.588996) (xy 416.177724 -305.610094)
			(xy 416.218227 -305.63805) (xy 416.25372 -305.672142) (xy 416.283285 -305.711486) (xy 416.306156 -305.755063)
			(xy 416.32174 -305.801744) (xy 416.329635 -305.850321) (xy 416.33013 -305.874928) (xy 416.668978 -305.874928)
			(xy 416.672938 -305.825874) (xy 416.684715 -305.77809) (xy 416.704006 -305.732814) (xy 416.730309 -305.691218)
			(xy 416.762944 -305.654381) (xy 416.801065 -305.623256) (xy 416.843686 -305.598649) (xy 416.889702 -305.581197)
			(xy 416.937921 -305.571353) (xy 416.987096 -305.569372) (xy 417.035951 -305.575304) (xy 417.083222 -305.588996)
			(xy 417.127684 -305.610094) (xy 417.168187 -305.63805) (xy 417.20368 -305.672142) (xy 417.233245 -305.711486)
			(xy 417.256116 -305.755063) (xy 417.2717 -305.801744) (xy 417.279595 -305.850321) (xy 417.28009 -305.874928)
			(xy 417.619192 -305.874928) (xy 417.623152 -305.825874) (xy 417.634929 -305.77809) (xy 417.65422 -305.732814)
			(xy 417.680523 -305.691218) (xy 417.713158 -305.654381) (xy 417.751279 -305.623256) (xy 417.7939 -305.598649)
			(xy 417.839916 -305.581197) (xy 417.888135 -305.571353) (xy 417.93731 -305.569372) (xy 417.986165 -305.575304)
			(xy 418.033436 -305.588996) (xy 418.077898 -305.610094) (xy 418.118401 -305.63805) (xy 418.153894 -305.672142)
			(xy 418.183459 -305.711486) (xy 418.20633 -305.755063) (xy 418.221914 -305.801744) (xy 418.229809 -305.850321)
			(xy 418.230304 -305.874928) (xy 418.569152 -305.874928) (xy 418.573112 -305.825874) (xy 418.584889 -305.77809)
			(xy 418.60418 -305.732814) (xy 418.630483 -305.691218) (xy 418.663118 -305.654381) (xy 418.701239 -305.623256)
			(xy 418.74386 -305.598649) (xy 418.789876 -305.581197) (xy 418.838095 -305.571353) (xy 418.88727 -305.569372)
			(xy 418.936125 -305.575304) (xy 418.983396 -305.588996) (xy 419.027858 -305.610094) (xy 419.068361 -305.63805)
			(xy 419.103854 -305.672142) (xy 419.133419 -305.711486) (xy 419.15629 -305.755063) (xy 419.171874 -305.801744)
			(xy 419.179769 -305.850321) (xy 419.180264 -305.874928) (xy 419.519112 -305.874928) (xy 419.523072 -305.825874)
			(xy 419.534849 -305.77809) (xy 419.55414 -305.732814) (xy 419.580443 -305.691218) (xy 419.613078 -305.654381)
			(xy 419.651199 -305.623256) (xy 419.69382 -305.598649) (xy 419.739836 -305.581197) (xy 419.788055 -305.571353)
			(xy 419.83723 -305.569372) (xy 419.886085 -305.575304) (xy 419.933356 -305.588996) (xy 419.977818 -305.610094)
			(xy 420.018321 -305.63805) (xy 420.053814 -305.672142) (xy 420.083379 -305.711486) (xy 420.10625 -305.755063)
			(xy 420.121834 -305.801744) (xy 420.129729 -305.850321) (xy 420.130224 -305.874928) (xy 420.469072 -305.874928)
			(xy 420.473032 -305.825874) (xy 420.484809 -305.77809) (xy 420.5041 -305.732814) (xy 420.530403 -305.691218)
			(xy 420.563038 -305.654381) (xy 420.601159 -305.623256) (xy 420.64378 -305.598649) (xy 420.689796 -305.581197)
			(xy 420.738015 -305.571353) (xy 420.78719 -305.569372) (xy 420.836045 -305.575304) (xy 420.883316 -305.588996)
			(xy 420.927778 -305.610094) (xy 420.968281 -305.63805) (xy 421.003774 -305.672142) (xy 421.033339 -305.711486)
			(xy 421.05621 -305.755063) (xy 421.071794 -305.801744) (xy 421.079689 -305.850321) (xy 421.080184 -305.874928)
			(xy 421.079689 -305.899535) (xy 421.071794 -305.948112) (xy 421.05621 -305.994793) (xy 421.033339 -306.03837)
			(xy 421.003774 -306.077714) (xy 420.968281 -306.111806) (xy 420.927778 -306.139762) (xy 420.883316 -306.16086)
			(xy 420.836045 -306.174552) (xy 420.78719 -306.180484) (xy 420.738015 -306.178503) (xy 420.689796 -306.168659)
			(xy 420.64378 -306.151207) (xy 420.601159 -306.1266) (xy 420.563038 -306.095475) (xy 420.530403 -306.058638)
			(xy 420.5041 -306.017042) (xy 420.484809 -305.971766) (xy 420.473032 -305.923982) (xy 420.469072 -305.874928)
			(xy 420.130224 -305.874928) (xy 420.129729 -305.899535) (xy 420.121834 -305.948112) (xy 420.10625 -305.994793)
			(xy 420.083379 -306.03837) (xy 420.053814 -306.077714) (xy 420.018321 -306.111806) (xy 419.977818 -306.139762)
			(xy 419.933356 -306.16086) (xy 419.886085 -306.174552) (xy 419.83723 -306.180484) (xy 419.788055 -306.178503)
			(xy 419.739836 -306.168659) (xy 419.69382 -306.151207) (xy 419.651199 -306.1266) (xy 419.613078 -306.095475)
			(xy 419.580443 -306.058638) (xy 419.55414 -306.017042) (xy 419.534849 -305.971766) (xy 419.523072 -305.923982)
			(xy 419.519112 -305.874928) (xy 419.180264 -305.874928) (xy 419.179769 -305.899535) (xy 419.171874 -305.948112)
			(xy 419.15629 -305.994793) (xy 419.133419 -306.03837) (xy 419.103854 -306.077714) (xy 419.068361 -306.111806)
			(xy 419.027858 -306.139762) (xy 418.983396 -306.16086) (xy 418.936125 -306.174552) (xy 418.88727 -306.180484)
			(xy 418.838095 -306.178503) (xy 418.789876 -306.168659) (xy 418.74386 -306.151207) (xy 418.701239 -306.1266)
			(xy 418.663118 -306.095475) (xy 418.630483 -306.058638) (xy 418.60418 -306.017042) (xy 418.584889 -305.971766)
			(xy 418.573112 -305.923982) (xy 418.569152 -305.874928) (xy 418.230304 -305.874928) (xy 418.229809 -305.899535)
			(xy 418.221914 -305.948112) (xy 418.20633 -305.994793) (xy 418.183459 -306.03837) (xy 418.153894 -306.077714)
			(xy 418.118401 -306.111806) (xy 418.077898 -306.139762) (xy 418.033436 -306.16086) (xy 417.986165 -306.174552)
			(xy 417.93731 -306.180484) (xy 417.888135 -306.178503) (xy 417.839916 -306.168659) (xy 417.7939 -306.151207)
			(xy 417.751279 -306.1266) (xy 417.713158 -306.095475) (xy 417.680523 -306.058638) (xy 417.65422 -306.017042)
			(xy 417.634929 -305.971766) (xy 417.623152 -305.923982) (xy 417.619192 -305.874928) (xy 417.28009 -305.874928)
			(xy 417.279595 -305.899535) (xy 417.2717 -305.948112) (xy 417.256116 -305.994793) (xy 417.233245 -306.03837)
			(xy 417.20368 -306.077714) (xy 417.168187 -306.111806) (xy 417.127684 -306.139762) (xy 417.083222 -306.16086)
			(xy 417.035951 -306.174552) (xy 416.987096 -306.180484) (xy 416.937921 -306.178503) (xy 416.889702 -306.168659)
			(xy 416.843686 -306.151207) (xy 416.801065 -306.1266) (xy 416.762944 -306.095475) (xy 416.730309 -306.058638)
			(xy 416.704006 -306.017042) (xy 416.684715 -305.971766) (xy 416.672938 -305.923982) (xy 416.668978 -305.874928)
			(xy 416.33013 -305.874928) (xy 416.329635 -305.899535) (xy 416.32174 -305.948112) (xy 416.306156 -305.994793)
			(xy 416.283285 -306.03837) (xy 416.25372 -306.077714) (xy 416.218227 -306.111806) (xy 416.177724 -306.139762)
			(xy 416.133262 -306.16086) (xy 416.085991 -306.174552) (xy 416.037136 -306.180484) (xy 415.987961 -306.178503)
			(xy 415.939742 -306.168659) (xy 415.893726 -306.151207) (xy 415.851105 -306.1266) (xy 415.812984 -306.095475)
			(xy 415.780349 -306.058638) (xy 415.754046 -306.017042) (xy 415.734755 -305.971766) (xy 415.722978 -305.923982)
			(xy 415.719018 -305.874928) (xy 415.38017 -305.874928) (xy 415.379675 -305.899535) (xy 415.37178 -305.948112)
			(xy 415.356196 -305.994793) (xy 415.333325 -306.03837) (xy 415.30376 -306.077714) (xy 415.268267 -306.111806)
			(xy 415.227764 -306.139762) (xy 415.183302 -306.16086) (xy 415.136031 -306.174552) (xy 415.087176 -306.180484)
			(xy 415.038001 -306.178503) (xy 414.989782 -306.168659) (xy 414.943766 -306.151207) (xy 414.901145 -306.1266)
			(xy 414.863024 -306.095475) (xy 414.830389 -306.058638) (xy 414.804086 -306.017042) (xy 414.784795 -305.971766)
			(xy 414.773018 -305.923982) (xy 414.769058 -305.874928) (xy 414.43021 -305.874928) (xy 414.429715 -305.899535)
			(xy 414.42182 -305.948112) (xy 414.406236 -305.994793) (xy 414.383365 -306.03837) (xy 414.3538 -306.077714)
			(xy 414.318307 -306.111806) (xy 414.277804 -306.139762) (xy 414.233342 -306.16086) (xy 414.186071 -306.174552)
			(xy 414.137216 -306.180484) (xy 414.088041 -306.178503) (xy 414.039822 -306.168659) (xy 413.993806 -306.151207)
			(xy 413.951185 -306.1266) (xy 413.913064 -306.095475) (xy 413.880429 -306.058638) (xy 413.854126 -306.017042)
			(xy 413.834835 -305.971766) (xy 413.823058 -305.923982) (xy 413.819098 -305.874928) (xy 413.48025 -305.874928)
			(xy 413.479755 -305.899535) (xy 413.47186 -305.948112) (xy 413.456276 -305.994793) (xy 413.433405 -306.03837)
			(xy 413.40384 -306.077714) (xy 413.368347 -306.111806) (xy 413.327844 -306.139762) (xy 413.283382 -306.16086)
			(xy 413.236111 -306.174552) (xy 413.187256 -306.180484) (xy 413.138081 -306.178503) (xy 413.089862 -306.168659)
			(xy 413.043846 -306.151207) (xy 413.001225 -306.1266) (xy 412.963104 -306.095475) (xy 412.930469 -306.058638)
			(xy 412.904166 -306.017042) (xy 412.884875 -305.971766) (xy 412.873098 -305.923982) (xy 412.869138 -305.874928)
			(xy 412.53029 -305.874928) (xy 412.529795 -305.899535) (xy 412.5219 -305.948112) (xy 412.506316 -305.994793)
			(xy 412.483445 -306.03837) (xy 412.45388 -306.077714) (xy 412.418387 -306.111806) (xy 412.377884 -306.139762)
			(xy 412.333422 -306.16086) (xy 412.286151 -306.174552) (xy 412.237296 -306.180484) (xy 412.188121 -306.178503)
			(xy 412.139902 -306.168659) (xy 412.093886 -306.151207) (xy 412.051265 -306.1266) (xy 412.013144 -306.095475)
			(xy 411.980509 -306.058638) (xy 411.954206 -306.017042) (xy 411.934915 -305.971766) (xy 411.923138 -305.923982)
			(xy 411.919178 -305.874928) (xy 411.58033 -305.874928) (xy 411.579835 -305.899535) (xy 411.57194 -305.948112)
			(xy 411.556356 -305.994793) (xy 411.533485 -306.03837) (xy 411.50392 -306.077714) (xy 411.468427 -306.111806)
			(xy 411.427924 -306.139762) (xy 411.383462 -306.16086) (xy 411.336191 -306.174552) (xy 411.287336 -306.180484)
			(xy 411.238161 -306.178503) (xy 411.189942 -306.168659) (xy 411.143926 -306.151207) (xy 411.101305 -306.1266)
			(xy 411.063184 -306.095475) (xy 411.030549 -306.058638) (xy 411.004246 -306.017042) (xy 410.984955 -305.971766)
			(xy 410.973178 -305.923982) (xy 410.969218 -305.874928) (xy 410.630116 -305.874928) (xy 410.629621 -305.899535)
			(xy 410.621726 -305.948112) (xy 410.606142 -305.994793) (xy 410.583271 -306.03837) (xy 410.553706 -306.077714)
			(xy 410.518213 -306.111806) (xy 410.47771 -306.139762) (xy 410.433248 -306.16086) (xy 410.385977 -306.174552)
			(xy 410.337122 -306.180484) (xy 410.287947 -306.178503) (xy 410.239728 -306.168659) (xy 410.193712 -306.151207)
			(xy 410.151091 -306.1266) (xy 410.11297 -306.095475) (xy 410.080335 -306.058638) (xy 410.054032 -306.017042)
			(xy 410.034741 -305.971766) (xy 410.022964 -305.923982) (xy 410.019004 -305.874928) (xy 409.680156 -305.874928)
			(xy 409.679661 -305.899535) (xy 409.671766 -305.948112) (xy 409.656182 -305.994793) (xy 409.633311 -306.03837)
			(xy 409.603746 -306.077714) (xy 409.568253 -306.111806) (xy 409.52775 -306.139762) (xy 409.483288 -306.16086)
			(xy 409.436017 -306.174552) (xy 409.387162 -306.180484) (xy 409.337987 -306.178503) (xy 409.289768 -306.168659)
			(xy 409.243752 -306.151207) (xy 409.201131 -306.1266) (xy 409.16301 -306.095475) (xy 409.130375 -306.058638)
			(xy 409.104072 -306.017042) (xy 409.084781 -305.971766) (xy 409.073004 -305.923982) (xy 409.069044 -305.874928)
			(xy 408.730196 -305.874928) (xy 408.729701 -305.899535) (xy 408.721806 -305.948112) (xy 408.706222 -305.994793)
			(xy 408.683351 -306.03837) (xy 408.653786 -306.077714) (xy 408.618293 -306.111806) (xy 408.57779 -306.139762)
			(xy 408.533328 -306.16086) (xy 408.486057 -306.174552) (xy 408.437202 -306.180484) (xy 408.388027 -306.178503)
			(xy 408.339808 -306.168659) (xy 408.293792 -306.151207) (xy 408.251171 -306.1266) (xy 408.21305 -306.095475)
			(xy 408.180415 -306.058638) (xy 408.154112 -306.017042) (xy 408.134821 -305.971766) (xy 408.123044 -305.923982)
			(xy 408.119084 -305.874928) (xy 406.830276 -305.874928) (xy 406.829781 -305.899535) (xy 406.821886 -305.948112)
			(xy 406.806302 -305.994793) (xy 406.783431 -306.03837) (xy 406.753866 -306.077714) (xy 406.718373 -306.111806)
			(xy 406.67787 -306.139762) (xy 406.633408 -306.16086) (xy 406.586137 -306.174552) (xy 406.537282 -306.180484)
			(xy 406.488107 -306.178503) (xy 406.439888 -306.168659) (xy 406.393872 -306.151207) (xy 406.351251 -306.1266)
			(xy 406.31313 -306.095475) (xy 406.280495 -306.058638) (xy 406.254192 -306.017042) (xy 406.234901 -305.971766)
			(xy 406.223124 -305.923982) (xy 406.219164 -305.874928) (xy 405.880316 -305.874928) (xy 405.879821 -305.899535)
			(xy 405.871926 -305.948112) (xy 405.856342 -305.994793) (xy 405.833471 -306.03837) (xy 405.803906 -306.077714)
			(xy 405.768413 -306.111806) (xy 405.72791 -306.139762) (xy 405.683448 -306.16086) (xy 405.636177 -306.174552)
			(xy 405.587322 -306.180484) (xy 405.538147 -306.178503) (xy 405.489928 -306.168659) (xy 405.443912 -306.151207)
			(xy 405.401291 -306.1266) (xy 405.36317 -306.095475) (xy 405.330535 -306.058638) (xy 405.304232 -306.017042)
			(xy 405.284941 -305.971766) (xy 405.273164 -305.923982) (xy 405.269204 -305.874928) (xy 404.930102 -305.874928)
			(xy 404.929607 -305.899535) (xy 404.921712 -305.948112) (xy 404.906128 -305.994793) (xy 404.883257 -306.03837)
			(xy 404.853692 -306.077714) (xy 404.818199 -306.111806) (xy 404.777696 -306.139762) (xy 404.733234 -306.16086)
			(xy 404.685963 -306.174552) (xy 404.637108 -306.180484) (xy 404.587933 -306.178503) (xy 404.539714 -306.168659)
			(xy 404.493698 -306.151207) (xy 404.451077 -306.1266) (xy 404.412956 -306.095475) (xy 404.380321 -306.058638)
			(xy 404.354018 -306.017042) (xy 404.334727 -305.971766) (xy 404.32295 -305.923982) (xy 404.31899 -305.874928)
			(xy 403.980142 -305.874928) (xy 403.979647 -305.899535) (xy 403.971752 -305.948112) (xy 403.956168 -305.994793)
			(xy 403.933297 -306.03837) (xy 403.903732 -306.077714) (xy 403.868239 -306.111806) (xy 403.827736 -306.139762)
			(xy 403.783274 -306.16086) (xy 403.736003 -306.174552) (xy 403.687148 -306.180484) (xy 403.637973 -306.178503)
			(xy 403.589754 -306.168659) (xy 403.543738 -306.151207) (xy 403.501117 -306.1266) (xy 403.462996 -306.095475)
			(xy 403.430361 -306.058638) (xy 403.404058 -306.017042) (xy 403.384767 -305.971766) (xy 403.37299 -305.923982)
			(xy 403.36903 -305.874928) (xy 403.030182 -305.874928) (xy 403.029687 -305.899535) (xy 403.021792 -305.948112)
			(xy 403.006208 -305.994793) (xy 402.983337 -306.03837) (xy 402.953772 -306.077714) (xy 402.918279 -306.111806)
			(xy 402.877776 -306.139762) (xy 402.833314 -306.16086) (xy 402.786043 -306.174552) (xy 402.737188 -306.180484)
			(xy 402.688013 -306.178503) (xy 402.639794 -306.168659) (xy 402.593778 -306.151207) (xy 402.551157 -306.1266)
			(xy 402.513036 -306.095475) (xy 402.480401 -306.058638) (xy 402.454098 -306.017042) (xy 402.434807 -305.971766)
			(xy 402.42303 -305.923982) (xy 402.41907 -305.874928) (xy 402.080222 -305.874928) (xy 402.079727 -305.899535)
			(xy 402.071832 -305.948112) (xy 402.056248 -305.994793) (xy 402.033377 -306.03837) (xy 402.003812 -306.077714)
			(xy 401.968319 -306.111806) (xy 401.927816 -306.139762) (xy 401.883354 -306.16086) (xy 401.836083 -306.174552)
			(xy 401.787228 -306.180484) (xy 401.738053 -306.178503) (xy 401.689834 -306.168659) (xy 401.643818 -306.151207)
			(xy 401.601197 -306.1266) (xy 401.563076 -306.095475) (xy 401.530441 -306.058638) (xy 401.504138 -306.017042)
			(xy 401.484847 -305.971766) (xy 401.47307 -305.923982) (xy 401.46911 -305.874928) (xy 401.130262 -305.874928)
			(xy 401.129767 -305.899535) (xy 401.121872 -305.948112) (xy 401.106288 -305.994793) (xy 401.083417 -306.03837)
			(xy 401.053852 -306.077714) (xy 401.018359 -306.111806) (xy 400.977856 -306.139762) (xy 400.933394 -306.16086)
			(xy 400.886123 -306.174552) (xy 400.837268 -306.180484) (xy 400.788093 -306.178503) (xy 400.739874 -306.168659)
			(xy 400.693858 -306.151207) (xy 400.651237 -306.1266) (xy 400.613116 -306.095475) (xy 400.580481 -306.058638)
			(xy 400.554178 -306.017042) (xy 400.534887 -305.971766) (xy 400.52311 -305.923982) (xy 400.51915 -305.874928)
			(xy 400.180302 -305.874928) (xy 400.179807 -305.899535) (xy 400.171912 -305.948112) (xy 400.156328 -305.994793)
			(xy 400.133457 -306.03837) (xy 400.103892 -306.077714) (xy 400.068399 -306.111806) (xy 400.027896 -306.139762)
			(xy 399.983434 -306.16086) (xy 399.936163 -306.174552) (xy 399.887308 -306.180484) (xy 399.838133 -306.178503)
			(xy 399.789914 -306.168659) (xy 399.743898 -306.151207) (xy 399.701277 -306.1266) (xy 399.663156 -306.095475)
			(xy 399.630521 -306.058638) (xy 399.604218 -306.017042) (xy 399.584927 -305.971766) (xy 399.57315 -305.923982)
			(xy 399.56919 -305.874928) (xy 399.230342 -305.874928) (xy 399.229847 -305.899535) (xy 399.221952 -305.948112)
			(xy 399.206368 -305.994793) (xy 399.183497 -306.03837) (xy 399.153932 -306.077714) (xy 399.118439 -306.111806)
			(xy 399.077936 -306.139762) (xy 399.033474 -306.16086) (xy 398.986203 -306.174552) (xy 398.937348 -306.180484)
			(xy 398.888173 -306.178503) (xy 398.839954 -306.168659) (xy 398.793938 -306.151207) (xy 398.751317 -306.1266)
			(xy 398.713196 -306.095475) (xy 398.680561 -306.058638) (xy 398.654258 -306.017042) (xy 398.634967 -305.971766)
			(xy 398.62319 -305.923982) (xy 398.61923 -305.874928) (xy 398.341088 -305.874928) (xy 398.341088 -306.824888)
			(xy 398.61923 -306.824888) (xy 398.62319 -306.775834) (xy 398.634967 -306.72805) (xy 398.654258 -306.682774)
			(xy 398.680561 -306.641178) (xy 398.713196 -306.604341) (xy 398.751317 -306.573216) (xy 398.793938 -306.548609)
			(xy 398.839954 -306.531157) (xy 398.888173 -306.521313) (xy 398.937348 -306.519332) (xy 398.986203 -306.525264)
			(xy 399.033474 -306.538956) (xy 399.077936 -306.560054) (xy 399.118439 -306.58801) (xy 399.153932 -306.622102)
			(xy 399.183497 -306.661446) (xy 399.206368 -306.705023) (xy 399.221952 -306.751704) (xy 399.229847 -306.800281)
			(xy 399.230342 -306.824888) (xy 399.56919 -306.824888) (xy 399.57315 -306.775834) (xy 399.584927 -306.72805)
			(xy 399.604218 -306.682774) (xy 399.630521 -306.641178) (xy 399.663156 -306.604341) (xy 399.701277 -306.573216)
			(xy 399.743898 -306.548609) (xy 399.789914 -306.531157) (xy 399.838133 -306.521313) (xy 399.887308 -306.519332)
			(xy 399.936163 -306.525264) (xy 399.983434 -306.538956) (xy 400.027896 -306.560054) (xy 400.068399 -306.58801)
			(xy 400.103892 -306.622102) (xy 400.133457 -306.661446) (xy 400.156328 -306.705023) (xy 400.171912 -306.751704)
			(xy 400.179807 -306.800281) (xy 400.180302 -306.824888) (xy 400.51915 -306.824888) (xy 400.52311 -306.775834)
			(xy 400.534887 -306.72805) (xy 400.554178 -306.682774) (xy 400.580481 -306.641178) (xy 400.613116 -306.604341)
			(xy 400.651237 -306.573216) (xy 400.693858 -306.548609) (xy 400.739874 -306.531157) (xy 400.788093 -306.521313)
			(xy 400.837268 -306.519332) (xy 400.886123 -306.525264) (xy 400.933394 -306.538956) (xy 400.977856 -306.560054)
			(xy 401.018359 -306.58801) (xy 401.053852 -306.622102) (xy 401.083417 -306.661446) (xy 401.106288 -306.705023)
			(xy 401.121872 -306.751704) (xy 401.129767 -306.800281) (xy 401.130262 -306.824888) (xy 401.46911 -306.824888)
			(xy 401.47307 -306.775834) (xy 401.484847 -306.72805) (xy 401.504138 -306.682774) (xy 401.530441 -306.641178)
			(xy 401.563076 -306.604341) (xy 401.601197 -306.573216) (xy 401.643818 -306.548609) (xy 401.689834 -306.531157)
			(xy 401.738053 -306.521313) (xy 401.787228 -306.519332) (xy 401.836083 -306.525264) (xy 401.883354 -306.538956)
			(xy 401.927816 -306.560054) (xy 401.968319 -306.58801) (xy 402.003812 -306.622102) (xy 402.033377 -306.661446)
			(xy 402.056248 -306.705023) (xy 402.071832 -306.751704) (xy 402.079727 -306.800281) (xy 402.080222 -306.824888)
			(xy 402.41907 -306.824888) (xy 402.42303 -306.775834) (xy 402.434807 -306.72805) (xy 402.454098 -306.682774)
			(xy 402.480401 -306.641178) (xy 402.513036 -306.604341) (xy 402.551157 -306.573216) (xy 402.593778 -306.548609)
			(xy 402.639794 -306.531157) (xy 402.688013 -306.521313) (xy 402.737188 -306.519332) (xy 402.786043 -306.525264)
			(xy 402.833314 -306.538956) (xy 402.877776 -306.560054) (xy 402.918279 -306.58801) (xy 402.953772 -306.622102)
			(xy 402.983337 -306.661446) (xy 403.006208 -306.705023) (xy 403.021792 -306.751704) (xy 403.029687 -306.800281)
			(xy 403.030182 -306.824888) (xy 403.36903 -306.824888) (xy 403.37299 -306.775834) (xy 403.384767 -306.72805)
			(xy 403.404058 -306.682774) (xy 403.430361 -306.641178) (xy 403.462996 -306.604341) (xy 403.501117 -306.573216)
			(xy 403.543738 -306.548609) (xy 403.589754 -306.531157) (xy 403.637973 -306.521313) (xy 403.687148 -306.519332)
			(xy 403.736003 -306.525264) (xy 403.783274 -306.538956) (xy 403.827736 -306.560054) (xy 403.868239 -306.58801)
			(xy 403.903732 -306.622102) (xy 403.933297 -306.661446) (xy 403.956168 -306.705023) (xy 403.971752 -306.751704)
			(xy 403.979647 -306.800281) (xy 403.980142 -306.824888) (xy 404.31899 -306.824888) (xy 404.32295 -306.775834)
			(xy 404.334727 -306.72805) (xy 404.354018 -306.682774) (xy 404.380321 -306.641178) (xy 404.412956 -306.604341)
			(xy 404.451077 -306.573216) (xy 404.493698 -306.548609) (xy 404.539714 -306.531157) (xy 404.587933 -306.521313)
			(xy 404.637108 -306.519332) (xy 404.685963 -306.525264) (xy 404.733234 -306.538956) (xy 404.777696 -306.560054)
			(xy 404.818199 -306.58801) (xy 404.853692 -306.622102) (xy 404.883257 -306.661446) (xy 404.906128 -306.705023)
			(xy 404.921712 -306.751704) (xy 404.929607 -306.800281) (xy 404.930102 -306.824888) (xy 405.269204 -306.824888)
			(xy 405.273164 -306.775834) (xy 405.284941 -306.72805) (xy 405.304232 -306.682774) (xy 405.330535 -306.641178)
			(xy 405.36317 -306.604341) (xy 405.401291 -306.573216) (xy 405.443912 -306.548609) (xy 405.489928 -306.531157)
			(xy 405.538147 -306.521313) (xy 405.587322 -306.519332) (xy 405.636177 -306.525264) (xy 405.683448 -306.538956)
			(xy 405.72791 -306.560054) (xy 405.768413 -306.58801) (xy 405.803906 -306.622102) (xy 405.833471 -306.661446)
			(xy 405.856342 -306.705023) (xy 405.871926 -306.751704) (xy 405.879821 -306.800281) (xy 405.880316 -306.824888)
			(xy 406.219164 -306.824888) (xy 406.223124 -306.775834) (xy 406.234901 -306.72805) (xy 406.254192 -306.682774)
			(xy 406.280495 -306.641178) (xy 406.31313 -306.604341) (xy 406.351251 -306.573216) (xy 406.393872 -306.548609)
			(xy 406.439888 -306.531157) (xy 406.488107 -306.521313) (xy 406.537282 -306.519332) (xy 406.586137 -306.525264)
			(xy 406.633408 -306.538956) (xy 406.67787 -306.560054) (xy 406.718373 -306.58801) (xy 406.753866 -306.622102)
			(xy 406.783431 -306.661446) (xy 406.806302 -306.705023) (xy 406.821886 -306.751704) (xy 406.829781 -306.800281)
			(xy 406.830276 -306.824888) (xy 408.119084 -306.824888) (xy 408.123044 -306.775834) (xy 408.134821 -306.72805)
			(xy 408.154112 -306.682774) (xy 408.180415 -306.641178) (xy 408.21305 -306.604341) (xy 408.251171 -306.573216)
			(xy 408.293792 -306.548609) (xy 408.339808 -306.531157) (xy 408.388027 -306.521313) (xy 408.437202 -306.519332)
			(xy 408.486057 -306.525264) (xy 408.533328 -306.538956) (xy 408.57779 -306.560054) (xy 408.618293 -306.58801)
			(xy 408.653786 -306.622102) (xy 408.683351 -306.661446) (xy 408.706222 -306.705023) (xy 408.721806 -306.751704)
			(xy 408.729701 -306.800281) (xy 408.730196 -306.824888) (xy 409.069044 -306.824888) (xy 409.073004 -306.775834)
			(xy 409.084781 -306.72805) (xy 409.104072 -306.682774) (xy 409.130375 -306.641178) (xy 409.16301 -306.604341)
			(xy 409.201131 -306.573216) (xy 409.243752 -306.548609) (xy 409.289768 -306.531157) (xy 409.337987 -306.521313)
			(xy 409.387162 -306.519332) (xy 409.436017 -306.525264) (xy 409.483288 -306.538956) (xy 409.52775 -306.560054)
			(xy 409.568253 -306.58801) (xy 409.603746 -306.622102) (xy 409.633311 -306.661446) (xy 409.656182 -306.705023)
			(xy 409.671766 -306.751704) (xy 409.679661 -306.800281) (xy 409.680156 -306.824888) (xy 410.019004 -306.824888)
			(xy 410.022964 -306.775834) (xy 410.034741 -306.72805) (xy 410.054032 -306.682774) (xy 410.080335 -306.641178)
			(xy 410.11297 -306.604341) (xy 410.151091 -306.573216) (xy 410.193712 -306.548609) (xy 410.239728 -306.531157)
			(xy 410.287947 -306.521313) (xy 410.337122 -306.519332) (xy 410.385977 -306.525264) (xy 410.433248 -306.538956)
			(xy 410.47771 -306.560054) (xy 410.518213 -306.58801) (xy 410.553706 -306.622102) (xy 410.583271 -306.661446)
			(xy 410.606142 -306.705023) (xy 410.621726 -306.751704) (xy 410.629621 -306.800281) (xy 410.630116 -306.824888)
			(xy 410.969218 -306.824888) (xy 410.973178 -306.775834) (xy 410.984955 -306.72805) (xy 411.004246 -306.682774)
			(xy 411.030549 -306.641178) (xy 411.063184 -306.604341) (xy 411.101305 -306.573216) (xy 411.143926 -306.548609)
			(xy 411.189942 -306.531157) (xy 411.238161 -306.521313) (xy 411.287336 -306.519332) (xy 411.336191 -306.525264)
			(xy 411.383462 -306.538956) (xy 411.427924 -306.560054) (xy 411.468427 -306.58801) (xy 411.50392 -306.622102)
			(xy 411.533485 -306.661446) (xy 411.556356 -306.705023) (xy 411.57194 -306.751704) (xy 411.579835 -306.800281)
			(xy 411.58033 -306.824888) (xy 411.919178 -306.824888) (xy 411.923138 -306.775834) (xy 411.934915 -306.72805)
			(xy 411.954206 -306.682774) (xy 411.980509 -306.641178) (xy 412.013144 -306.604341) (xy 412.051265 -306.573216)
			(xy 412.093886 -306.548609) (xy 412.139902 -306.531157) (xy 412.188121 -306.521313) (xy 412.237296 -306.519332)
			(xy 412.286151 -306.525264) (xy 412.333422 -306.538956) (xy 412.377884 -306.560054) (xy 412.418387 -306.58801)
			(xy 412.45388 -306.622102) (xy 412.483445 -306.661446) (xy 412.506316 -306.705023) (xy 412.5219 -306.751704)
			(xy 412.529795 -306.800281) (xy 412.53029 -306.824888) (xy 412.869138 -306.824888) (xy 412.873098 -306.775834)
			(xy 412.884875 -306.72805) (xy 412.904166 -306.682774) (xy 412.930469 -306.641178) (xy 412.963104 -306.604341)
			(xy 413.001225 -306.573216) (xy 413.043846 -306.548609) (xy 413.089862 -306.531157) (xy 413.138081 -306.521313)
			(xy 413.187256 -306.519332) (xy 413.236111 -306.525264) (xy 413.283382 -306.538956) (xy 413.327844 -306.560054)
			(xy 413.368347 -306.58801) (xy 413.40384 -306.622102) (xy 413.433405 -306.661446) (xy 413.456276 -306.705023)
			(xy 413.47186 -306.751704) (xy 413.479755 -306.800281) (xy 413.48025 -306.824888) (xy 413.819098 -306.824888)
			(xy 413.823058 -306.775834) (xy 413.834835 -306.72805) (xy 413.854126 -306.682774) (xy 413.880429 -306.641178)
			(xy 413.913064 -306.604341) (xy 413.951185 -306.573216) (xy 413.993806 -306.548609) (xy 414.039822 -306.531157)
			(xy 414.088041 -306.521313) (xy 414.137216 -306.519332) (xy 414.186071 -306.525264) (xy 414.233342 -306.538956)
			(xy 414.277804 -306.560054) (xy 414.318307 -306.58801) (xy 414.3538 -306.622102) (xy 414.383365 -306.661446)
			(xy 414.406236 -306.705023) (xy 414.42182 -306.751704) (xy 414.429715 -306.800281) (xy 414.43021 -306.824888)
			(xy 414.769058 -306.824888) (xy 414.773018 -306.775834) (xy 414.784795 -306.72805) (xy 414.804086 -306.682774)
			(xy 414.830389 -306.641178) (xy 414.863024 -306.604341) (xy 414.901145 -306.573216) (xy 414.943766 -306.548609)
			(xy 414.989782 -306.531157) (xy 415.038001 -306.521313) (xy 415.087176 -306.519332) (xy 415.136031 -306.525264)
			(xy 415.183302 -306.538956) (xy 415.227764 -306.560054) (xy 415.268267 -306.58801) (xy 415.30376 -306.622102)
			(xy 415.333325 -306.661446) (xy 415.356196 -306.705023) (xy 415.37178 -306.751704) (xy 415.379675 -306.800281)
			(xy 415.38017 -306.824888) (xy 415.719018 -306.824888) (xy 415.722978 -306.775834) (xy 415.734755 -306.72805)
			(xy 415.754046 -306.682774) (xy 415.780349 -306.641178) (xy 415.812984 -306.604341) (xy 415.851105 -306.573216)
			(xy 415.893726 -306.548609) (xy 415.939742 -306.531157) (xy 415.987961 -306.521313) (xy 416.037136 -306.519332)
			(xy 416.085991 -306.525264) (xy 416.133262 -306.538956) (xy 416.177724 -306.560054) (xy 416.218227 -306.58801)
			(xy 416.25372 -306.622102) (xy 416.283285 -306.661446) (xy 416.306156 -306.705023) (xy 416.32174 -306.751704)
			(xy 416.329635 -306.800281) (xy 416.33013 -306.824888) (xy 416.668978 -306.824888) (xy 416.672938 -306.775834)
			(xy 416.684715 -306.72805) (xy 416.704006 -306.682774) (xy 416.730309 -306.641178) (xy 416.762944 -306.604341)
			(xy 416.801065 -306.573216) (xy 416.843686 -306.548609) (xy 416.889702 -306.531157) (xy 416.937921 -306.521313)
			(xy 416.987096 -306.519332) (xy 417.035951 -306.525264) (xy 417.083222 -306.538956) (xy 417.127684 -306.560054)
			(xy 417.168187 -306.58801) (xy 417.20368 -306.622102) (xy 417.233245 -306.661446) (xy 417.256116 -306.705023)
			(xy 417.2717 -306.751704) (xy 417.279595 -306.800281) (xy 417.28009 -306.824888) (xy 417.619192 -306.824888)
			(xy 417.623152 -306.775834) (xy 417.634929 -306.72805) (xy 417.65422 -306.682774) (xy 417.680523 -306.641178)
			(xy 417.713158 -306.604341) (xy 417.751279 -306.573216) (xy 417.7939 -306.548609) (xy 417.839916 -306.531157)
			(xy 417.888135 -306.521313) (xy 417.93731 -306.519332) (xy 417.986165 -306.525264) (xy 418.033436 -306.538956)
			(xy 418.077898 -306.560054) (xy 418.118401 -306.58801) (xy 418.153894 -306.622102) (xy 418.183459 -306.661446)
			(xy 418.20633 -306.705023) (xy 418.221914 -306.751704) (xy 418.229809 -306.800281) (xy 418.230304 -306.824888)
			(xy 418.569152 -306.824888) (xy 418.573112 -306.775834) (xy 418.584889 -306.72805) (xy 418.60418 -306.682774)
			(xy 418.630483 -306.641178) (xy 418.663118 -306.604341) (xy 418.701239 -306.573216) (xy 418.74386 -306.548609)
			(xy 418.789876 -306.531157) (xy 418.838095 -306.521313) (xy 418.88727 -306.519332) (xy 418.936125 -306.525264)
			(xy 418.983396 -306.538956) (xy 419.027858 -306.560054) (xy 419.068361 -306.58801) (xy 419.103854 -306.622102)
			(xy 419.133419 -306.661446) (xy 419.15629 -306.705023) (xy 419.171874 -306.751704) (xy 419.179769 -306.800281)
			(xy 419.180264 -306.824888) (xy 419.519112 -306.824888) (xy 419.523072 -306.775834) (xy 419.534849 -306.72805)
			(xy 419.55414 -306.682774) (xy 419.580443 -306.641178) (xy 419.613078 -306.604341) (xy 419.651199 -306.573216)
			(xy 419.69382 -306.548609) (xy 419.739836 -306.531157) (xy 419.788055 -306.521313) (xy 419.83723 -306.519332)
			(xy 419.886085 -306.525264) (xy 419.933356 -306.538956) (xy 419.977818 -306.560054) (xy 420.018321 -306.58801)
			(xy 420.053814 -306.622102) (xy 420.083379 -306.661446) (xy 420.10625 -306.705023) (xy 420.121834 -306.751704)
			(xy 420.129729 -306.800281) (xy 420.130224 -306.824888) (xy 420.469072 -306.824888) (xy 420.473032 -306.775834)
			(xy 420.484809 -306.72805) (xy 420.5041 -306.682774) (xy 420.530403 -306.641178) (xy 420.563038 -306.604341)
			(xy 420.601159 -306.573216) (xy 420.64378 -306.548609) (xy 420.689796 -306.531157) (xy 420.738015 -306.521313)
			(xy 420.78719 -306.519332) (xy 420.836045 -306.525264) (xy 420.883316 -306.538956) (xy 420.927778 -306.560054)
			(xy 420.968281 -306.58801) (xy 421.003774 -306.622102) (xy 421.033339 -306.661446) (xy 421.05621 -306.705023)
			(xy 421.071794 -306.751704) (xy 421.079689 -306.800281) (xy 421.080184 -306.824888) (xy 421.079689 -306.849495)
			(xy 421.071794 -306.898072) (xy 421.05621 -306.944753) (xy 421.033339 -306.98833) (xy 421.003774 -307.027674)
			(xy 420.968281 -307.061766) (xy 420.927778 -307.089722) (xy 420.883316 -307.11082) (xy 420.836045 -307.124512)
			(xy 420.78719 -307.130444) (xy 420.738015 -307.128463) (xy 420.689796 -307.118619) (xy 420.64378 -307.101167)
			(xy 420.601159 -307.07656) (xy 420.563038 -307.045435) (xy 420.530403 -307.008598) (xy 420.5041 -306.967002)
			(xy 420.484809 -306.921726) (xy 420.473032 -306.873942) (xy 420.469072 -306.824888) (xy 420.130224 -306.824888)
			(xy 420.129729 -306.849495) (xy 420.121834 -306.898072) (xy 420.10625 -306.944753) (xy 420.083379 -306.98833)
			(xy 420.053814 -307.027674) (xy 420.018321 -307.061766) (xy 419.977818 -307.089722) (xy 419.933356 -307.11082)
			(xy 419.886085 -307.124512) (xy 419.83723 -307.130444) (xy 419.788055 -307.128463) (xy 419.739836 -307.118619)
			(xy 419.69382 -307.101167) (xy 419.651199 -307.07656) (xy 419.613078 -307.045435) (xy 419.580443 -307.008598)
			(xy 419.55414 -306.967002) (xy 419.534849 -306.921726) (xy 419.523072 -306.873942) (xy 419.519112 -306.824888)
			(xy 419.180264 -306.824888) (xy 419.179769 -306.849495) (xy 419.171874 -306.898072) (xy 419.15629 -306.944753)
			(xy 419.133419 -306.98833) (xy 419.103854 -307.027674) (xy 419.068361 -307.061766) (xy 419.027858 -307.089722)
			(xy 418.983396 -307.11082) (xy 418.936125 -307.124512) (xy 418.88727 -307.130444) (xy 418.838095 -307.128463)
			(xy 418.789876 -307.118619) (xy 418.74386 -307.101167) (xy 418.701239 -307.07656) (xy 418.663118 -307.045435)
			(xy 418.630483 -307.008598) (xy 418.60418 -306.967002) (xy 418.584889 -306.921726) (xy 418.573112 -306.873942)
			(xy 418.569152 -306.824888) (xy 418.230304 -306.824888) (xy 418.229809 -306.849495) (xy 418.221914 -306.898072)
			(xy 418.20633 -306.944753) (xy 418.183459 -306.98833) (xy 418.153894 -307.027674) (xy 418.118401 -307.061766)
			(xy 418.077898 -307.089722) (xy 418.033436 -307.11082) (xy 417.986165 -307.124512) (xy 417.93731 -307.130444)
			(xy 417.888135 -307.128463) (xy 417.839916 -307.118619) (xy 417.7939 -307.101167) (xy 417.751279 -307.07656)
			(xy 417.713158 -307.045435) (xy 417.680523 -307.008598) (xy 417.65422 -306.967002) (xy 417.634929 -306.921726)
			(xy 417.623152 -306.873942) (xy 417.619192 -306.824888) (xy 417.28009 -306.824888) (xy 417.279595 -306.849495)
			(xy 417.2717 -306.898072) (xy 417.256116 -306.944753) (xy 417.233245 -306.98833) (xy 417.20368 -307.027674)
			(xy 417.168187 -307.061766) (xy 417.127684 -307.089722) (xy 417.083222 -307.11082) (xy 417.035951 -307.124512)
			(xy 416.987096 -307.130444) (xy 416.937921 -307.128463) (xy 416.889702 -307.118619) (xy 416.843686 -307.101167)
			(xy 416.801065 -307.07656) (xy 416.762944 -307.045435) (xy 416.730309 -307.008598) (xy 416.704006 -306.967002)
			(xy 416.684715 -306.921726) (xy 416.672938 -306.873942) (xy 416.668978 -306.824888) (xy 416.33013 -306.824888)
			(xy 416.329635 -306.849495) (xy 416.32174 -306.898072) (xy 416.306156 -306.944753) (xy 416.283285 -306.98833)
			(xy 416.25372 -307.027674) (xy 416.218227 -307.061766) (xy 416.177724 -307.089722) (xy 416.133262 -307.11082)
			(xy 416.085991 -307.124512) (xy 416.037136 -307.130444) (xy 415.987961 -307.128463) (xy 415.939742 -307.118619)
			(xy 415.893726 -307.101167) (xy 415.851105 -307.07656) (xy 415.812984 -307.045435) (xy 415.780349 -307.008598)
			(xy 415.754046 -306.967002) (xy 415.734755 -306.921726) (xy 415.722978 -306.873942) (xy 415.719018 -306.824888)
			(xy 415.38017 -306.824888) (xy 415.379675 -306.849495) (xy 415.37178 -306.898072) (xy 415.356196 -306.944753)
			(xy 415.333325 -306.98833) (xy 415.30376 -307.027674) (xy 415.268267 -307.061766) (xy 415.227764 -307.089722)
			(xy 415.183302 -307.11082) (xy 415.136031 -307.124512) (xy 415.087176 -307.130444) (xy 415.038001 -307.128463)
			(xy 414.989782 -307.118619) (xy 414.943766 -307.101167) (xy 414.901145 -307.07656) (xy 414.863024 -307.045435)
			(xy 414.830389 -307.008598) (xy 414.804086 -306.967002) (xy 414.784795 -306.921726) (xy 414.773018 -306.873942)
			(xy 414.769058 -306.824888) (xy 414.43021 -306.824888) (xy 414.429715 -306.849495) (xy 414.42182 -306.898072)
			(xy 414.406236 -306.944753) (xy 414.383365 -306.98833) (xy 414.3538 -307.027674) (xy 414.318307 -307.061766)
			(xy 414.277804 -307.089722) (xy 414.233342 -307.11082) (xy 414.186071 -307.124512) (xy 414.137216 -307.130444)
			(xy 414.088041 -307.128463) (xy 414.039822 -307.118619) (xy 413.993806 -307.101167) (xy 413.951185 -307.07656)
			(xy 413.913064 -307.045435) (xy 413.880429 -307.008598) (xy 413.854126 -306.967002) (xy 413.834835 -306.921726)
			(xy 413.823058 -306.873942) (xy 413.819098 -306.824888) (xy 413.48025 -306.824888) (xy 413.479755 -306.849495)
			(xy 413.47186 -306.898072) (xy 413.456276 -306.944753) (xy 413.433405 -306.98833) (xy 413.40384 -307.027674)
			(xy 413.368347 -307.061766) (xy 413.327844 -307.089722) (xy 413.283382 -307.11082) (xy 413.236111 -307.124512)
			(xy 413.187256 -307.130444) (xy 413.138081 -307.128463) (xy 413.089862 -307.118619) (xy 413.043846 -307.101167)
			(xy 413.001225 -307.07656) (xy 412.963104 -307.045435) (xy 412.930469 -307.008598) (xy 412.904166 -306.967002)
			(xy 412.884875 -306.921726) (xy 412.873098 -306.873942) (xy 412.869138 -306.824888) (xy 412.53029 -306.824888)
			(xy 412.529795 -306.849495) (xy 412.5219 -306.898072) (xy 412.506316 -306.944753) (xy 412.483445 -306.98833)
			(xy 412.45388 -307.027674) (xy 412.418387 -307.061766) (xy 412.377884 -307.089722) (xy 412.333422 -307.11082)
			(xy 412.286151 -307.124512) (xy 412.237296 -307.130444) (xy 412.188121 -307.128463) (xy 412.139902 -307.118619)
			(xy 412.093886 -307.101167) (xy 412.051265 -307.07656) (xy 412.013144 -307.045435) (xy 411.980509 -307.008598)
			(xy 411.954206 -306.967002) (xy 411.934915 -306.921726) (xy 411.923138 -306.873942) (xy 411.919178 -306.824888)
			(xy 411.58033 -306.824888) (xy 411.579835 -306.849495) (xy 411.57194 -306.898072) (xy 411.556356 -306.944753)
			(xy 411.533485 -306.98833) (xy 411.50392 -307.027674) (xy 411.468427 -307.061766) (xy 411.427924 -307.089722)
			(xy 411.383462 -307.11082) (xy 411.336191 -307.124512) (xy 411.287336 -307.130444) (xy 411.238161 -307.128463)
			(xy 411.189942 -307.118619) (xy 411.143926 -307.101167) (xy 411.101305 -307.07656) (xy 411.063184 -307.045435)
			(xy 411.030549 -307.008598) (xy 411.004246 -306.967002) (xy 410.984955 -306.921726) (xy 410.973178 -306.873942)
			(xy 410.969218 -306.824888) (xy 410.630116 -306.824888) (xy 410.629621 -306.849495) (xy 410.621726 -306.898072)
			(xy 410.606142 -306.944753) (xy 410.583271 -306.98833) (xy 410.553706 -307.027674) (xy 410.518213 -307.061766)
			(xy 410.47771 -307.089722) (xy 410.433248 -307.11082) (xy 410.385977 -307.124512) (xy 410.337122 -307.130444)
			(xy 410.287947 -307.128463) (xy 410.239728 -307.118619) (xy 410.193712 -307.101167) (xy 410.151091 -307.07656)
			(xy 410.11297 -307.045435) (xy 410.080335 -307.008598) (xy 410.054032 -306.967002) (xy 410.034741 -306.921726)
			(xy 410.022964 -306.873942) (xy 410.019004 -306.824888) (xy 409.680156 -306.824888) (xy 409.679661 -306.849495)
			(xy 409.671766 -306.898072) (xy 409.656182 -306.944753) (xy 409.633311 -306.98833) (xy 409.603746 -307.027674)
			(xy 409.568253 -307.061766) (xy 409.52775 -307.089722) (xy 409.483288 -307.11082) (xy 409.436017 -307.124512)
			(xy 409.387162 -307.130444) (xy 409.337987 -307.128463) (xy 409.289768 -307.118619) (xy 409.243752 -307.101167)
			(xy 409.201131 -307.07656) (xy 409.16301 -307.045435) (xy 409.130375 -307.008598) (xy 409.104072 -306.967002)
			(xy 409.084781 -306.921726) (xy 409.073004 -306.873942) (xy 409.069044 -306.824888) (xy 408.730196 -306.824888)
			(xy 408.729701 -306.849495) (xy 408.721806 -306.898072) (xy 408.706222 -306.944753) (xy 408.683351 -306.98833)
			(xy 408.653786 -307.027674) (xy 408.618293 -307.061766) (xy 408.57779 -307.089722) (xy 408.533328 -307.11082)
			(xy 408.486057 -307.124512) (xy 408.437202 -307.130444) (xy 408.388027 -307.128463) (xy 408.339808 -307.118619)
			(xy 408.293792 -307.101167) (xy 408.251171 -307.07656) (xy 408.21305 -307.045435) (xy 408.180415 -307.008598)
			(xy 408.154112 -306.967002) (xy 408.134821 -306.921726) (xy 408.123044 -306.873942) (xy 408.119084 -306.824888)
			(xy 406.830276 -306.824888) (xy 406.829781 -306.849495) (xy 406.821886 -306.898072) (xy 406.806302 -306.944753)
			(xy 406.783431 -306.98833) (xy 406.753866 -307.027674) (xy 406.718373 -307.061766) (xy 406.67787 -307.089722)
			(xy 406.633408 -307.11082) (xy 406.586137 -307.124512) (xy 406.537282 -307.130444) (xy 406.488107 -307.128463)
			(xy 406.439888 -307.118619) (xy 406.393872 -307.101167) (xy 406.351251 -307.07656) (xy 406.31313 -307.045435)
			(xy 406.280495 -307.008598) (xy 406.254192 -306.967002) (xy 406.234901 -306.921726) (xy 406.223124 -306.873942)
			(xy 406.219164 -306.824888) (xy 405.880316 -306.824888) (xy 405.879821 -306.849495) (xy 405.871926 -306.898072)
			(xy 405.856342 -306.944753) (xy 405.833471 -306.98833) (xy 405.803906 -307.027674) (xy 405.768413 -307.061766)
			(xy 405.72791 -307.089722) (xy 405.683448 -307.11082) (xy 405.636177 -307.124512) (xy 405.587322 -307.130444)
			(xy 405.538147 -307.128463) (xy 405.489928 -307.118619) (xy 405.443912 -307.101167) (xy 405.401291 -307.07656)
			(xy 405.36317 -307.045435) (xy 405.330535 -307.008598) (xy 405.304232 -306.967002) (xy 405.284941 -306.921726)
			(xy 405.273164 -306.873942) (xy 405.269204 -306.824888) (xy 404.930102 -306.824888) (xy 404.929607 -306.849495)
			(xy 404.921712 -306.898072) (xy 404.906128 -306.944753) (xy 404.883257 -306.98833) (xy 404.853692 -307.027674)
			(xy 404.818199 -307.061766) (xy 404.777696 -307.089722) (xy 404.733234 -307.11082) (xy 404.685963 -307.124512)
			(xy 404.637108 -307.130444) (xy 404.587933 -307.128463) (xy 404.539714 -307.118619) (xy 404.493698 -307.101167)
			(xy 404.451077 -307.07656) (xy 404.412956 -307.045435) (xy 404.380321 -307.008598) (xy 404.354018 -306.967002)
			(xy 404.334727 -306.921726) (xy 404.32295 -306.873942) (xy 404.31899 -306.824888) (xy 403.980142 -306.824888)
			(xy 403.979647 -306.849495) (xy 403.971752 -306.898072) (xy 403.956168 -306.944753) (xy 403.933297 -306.98833)
			(xy 403.903732 -307.027674) (xy 403.868239 -307.061766) (xy 403.827736 -307.089722) (xy 403.783274 -307.11082)
			(xy 403.736003 -307.124512) (xy 403.687148 -307.130444) (xy 403.637973 -307.128463) (xy 403.589754 -307.118619)
			(xy 403.543738 -307.101167) (xy 403.501117 -307.07656) (xy 403.462996 -307.045435) (xy 403.430361 -307.008598)
			(xy 403.404058 -306.967002) (xy 403.384767 -306.921726) (xy 403.37299 -306.873942) (xy 403.36903 -306.824888)
			(xy 403.030182 -306.824888) (xy 403.029687 -306.849495) (xy 403.021792 -306.898072) (xy 403.006208 -306.944753)
			(xy 402.983337 -306.98833) (xy 402.953772 -307.027674) (xy 402.918279 -307.061766) (xy 402.877776 -307.089722)
			(xy 402.833314 -307.11082) (xy 402.786043 -307.124512) (xy 402.737188 -307.130444) (xy 402.688013 -307.128463)
			(xy 402.639794 -307.118619) (xy 402.593778 -307.101167) (xy 402.551157 -307.07656) (xy 402.513036 -307.045435)
			(xy 402.480401 -307.008598) (xy 402.454098 -306.967002) (xy 402.434807 -306.921726) (xy 402.42303 -306.873942)
			(xy 402.41907 -306.824888) (xy 402.080222 -306.824888) (xy 402.079727 -306.849495) (xy 402.071832 -306.898072)
			(xy 402.056248 -306.944753) (xy 402.033377 -306.98833) (xy 402.003812 -307.027674) (xy 401.968319 -307.061766)
			(xy 401.927816 -307.089722) (xy 401.883354 -307.11082) (xy 401.836083 -307.124512) (xy 401.787228 -307.130444)
			(xy 401.738053 -307.128463) (xy 401.689834 -307.118619) (xy 401.643818 -307.101167) (xy 401.601197 -307.07656)
			(xy 401.563076 -307.045435) (xy 401.530441 -307.008598) (xy 401.504138 -306.967002) (xy 401.484847 -306.921726)
			(xy 401.47307 -306.873942) (xy 401.46911 -306.824888) (xy 401.130262 -306.824888) (xy 401.129767 -306.849495)
			(xy 401.121872 -306.898072) (xy 401.106288 -306.944753) (xy 401.083417 -306.98833) (xy 401.053852 -307.027674)
			(xy 401.018359 -307.061766) (xy 400.977856 -307.089722) (xy 400.933394 -307.11082) (xy 400.886123 -307.124512)
			(xy 400.837268 -307.130444) (xy 400.788093 -307.128463) (xy 400.739874 -307.118619) (xy 400.693858 -307.101167)
			(xy 400.651237 -307.07656) (xy 400.613116 -307.045435) (xy 400.580481 -307.008598) (xy 400.554178 -306.967002)
			(xy 400.534887 -306.921726) (xy 400.52311 -306.873942) (xy 400.51915 -306.824888) (xy 400.180302 -306.824888)
			(xy 400.179807 -306.849495) (xy 400.171912 -306.898072) (xy 400.156328 -306.944753) (xy 400.133457 -306.98833)
			(xy 400.103892 -307.027674) (xy 400.068399 -307.061766) (xy 400.027896 -307.089722) (xy 399.983434 -307.11082)
			(xy 399.936163 -307.124512) (xy 399.887308 -307.130444) (xy 399.838133 -307.128463) (xy 399.789914 -307.118619)
			(xy 399.743898 -307.101167) (xy 399.701277 -307.07656) (xy 399.663156 -307.045435) (xy 399.630521 -307.008598)
			(xy 399.604218 -306.967002) (xy 399.584927 -306.921726) (xy 399.57315 -306.873942) (xy 399.56919 -306.824888)
			(xy 399.230342 -306.824888) (xy 399.229847 -306.849495) (xy 399.221952 -306.898072) (xy 399.206368 -306.944753)
			(xy 399.183497 -306.98833) (xy 399.153932 -307.027674) (xy 399.118439 -307.061766) (xy 399.077936 -307.089722)
			(xy 399.033474 -307.11082) (xy 398.986203 -307.124512) (xy 398.937348 -307.130444) (xy 398.888173 -307.128463)
			(xy 398.839954 -307.118619) (xy 398.793938 -307.101167) (xy 398.751317 -307.07656) (xy 398.713196 -307.045435)
			(xy 398.680561 -307.008598) (xy 398.654258 -306.967002) (xy 398.634967 -306.921726) (xy 398.62319 -306.873942)
			(xy 398.61923 -306.824888) (xy 398.341088 -306.824888) (xy 398.341088 -307.774848) (xy 398.61923 -307.774848)
			(xy 398.62319 -307.725794) (xy 398.634967 -307.67801) (xy 398.654258 -307.632734) (xy 398.680561 -307.591138)
			(xy 398.713196 -307.554301) (xy 398.751317 -307.523176) (xy 398.793938 -307.498569) (xy 398.839954 -307.481117)
			(xy 398.888173 -307.471273) (xy 398.937348 -307.469292) (xy 398.986203 -307.475224) (xy 399.033474 -307.488916)
			(xy 399.077936 -307.510014) (xy 399.118439 -307.53797) (xy 399.153932 -307.572062) (xy 399.183497 -307.611406)
			(xy 399.206368 -307.654983) (xy 399.221952 -307.701664) (xy 399.229847 -307.750241) (xy 399.230342 -307.774848)
			(xy 399.56919 -307.774848) (xy 399.57315 -307.725794) (xy 399.584927 -307.67801) (xy 399.604218 -307.632734)
			(xy 399.630521 -307.591138) (xy 399.663156 -307.554301) (xy 399.701277 -307.523176) (xy 399.743898 -307.498569)
			(xy 399.789914 -307.481117) (xy 399.838133 -307.471273) (xy 399.887308 -307.469292) (xy 399.936163 -307.475224)
			(xy 399.983434 -307.488916) (xy 400.027896 -307.510014) (xy 400.068399 -307.53797) (xy 400.103892 -307.572062)
			(xy 400.133457 -307.611406) (xy 400.156328 -307.654983) (xy 400.171912 -307.701664) (xy 400.179807 -307.750241)
			(xy 400.180302 -307.774848) (xy 400.51915 -307.774848) (xy 400.52311 -307.725794) (xy 400.534887 -307.67801)
			(xy 400.554178 -307.632734) (xy 400.580481 -307.591138) (xy 400.613116 -307.554301) (xy 400.651237 -307.523176)
			(xy 400.693858 -307.498569) (xy 400.739874 -307.481117) (xy 400.788093 -307.471273) (xy 400.837268 -307.469292)
			(xy 400.886123 -307.475224) (xy 400.933394 -307.488916) (xy 400.977856 -307.510014) (xy 401.018359 -307.53797)
			(xy 401.053852 -307.572062) (xy 401.083417 -307.611406) (xy 401.106288 -307.654983) (xy 401.121872 -307.701664)
			(xy 401.129767 -307.750241) (xy 401.130262 -307.774848) (xy 401.46911 -307.774848) (xy 401.47307 -307.725794)
			(xy 401.484847 -307.67801) (xy 401.504138 -307.632734) (xy 401.530441 -307.591138) (xy 401.563076 -307.554301)
			(xy 401.601197 -307.523176) (xy 401.643818 -307.498569) (xy 401.689834 -307.481117) (xy 401.738053 -307.471273)
			(xy 401.787228 -307.469292) (xy 401.836083 -307.475224) (xy 401.883354 -307.488916) (xy 401.927816 -307.510014)
			(xy 401.968319 -307.53797) (xy 402.003812 -307.572062) (xy 402.033377 -307.611406) (xy 402.056248 -307.654983)
			(xy 402.071832 -307.701664) (xy 402.079727 -307.750241) (xy 402.080222 -307.774848) (xy 402.41907 -307.774848)
			(xy 402.42303 -307.725794) (xy 402.434807 -307.67801) (xy 402.454098 -307.632734) (xy 402.480401 -307.591138)
			(xy 402.513036 -307.554301) (xy 402.551157 -307.523176) (xy 402.593778 -307.498569) (xy 402.639794 -307.481117)
			(xy 402.688013 -307.471273) (xy 402.737188 -307.469292) (xy 402.786043 -307.475224) (xy 402.833314 -307.488916)
			(xy 402.877776 -307.510014) (xy 402.918279 -307.53797) (xy 402.953772 -307.572062) (xy 402.983337 -307.611406)
			(xy 403.006208 -307.654983) (xy 403.021792 -307.701664) (xy 403.029687 -307.750241) (xy 403.030182 -307.774848)
			(xy 403.36903 -307.774848) (xy 403.37299 -307.725794) (xy 403.384767 -307.67801) (xy 403.404058 -307.632734)
			(xy 403.430361 -307.591138) (xy 403.462996 -307.554301) (xy 403.501117 -307.523176) (xy 403.543738 -307.498569)
			(xy 403.589754 -307.481117) (xy 403.637973 -307.471273) (xy 403.687148 -307.469292) (xy 403.736003 -307.475224)
			(xy 403.783274 -307.488916) (xy 403.827736 -307.510014) (xy 403.868239 -307.53797) (xy 403.903732 -307.572062)
			(xy 403.933297 -307.611406) (xy 403.956168 -307.654983) (xy 403.971752 -307.701664) (xy 403.979647 -307.750241)
			(xy 403.980142 -307.774848) (xy 404.319244 -307.774848) (xy 404.323204 -307.725794) (xy 404.334981 -307.67801)
			(xy 404.354272 -307.632734) (xy 404.380575 -307.591138) (xy 404.41321 -307.554301) (xy 404.451331 -307.523176)
			(xy 404.493952 -307.498569) (xy 404.539968 -307.481117) (xy 404.588187 -307.471273) (xy 404.637362 -307.469292)
			(xy 404.686217 -307.475224) (xy 404.733488 -307.488916) (xy 404.77795 -307.510014) (xy 404.818453 -307.53797)
			(xy 404.853946 -307.572062) (xy 404.883511 -307.611406) (xy 404.906382 -307.654983) (xy 404.921966 -307.701664)
			(xy 404.929861 -307.750241) (xy 404.930356 -307.774848) (xy 405.269204 -307.774848) (xy 405.273164 -307.725794)
			(xy 405.284941 -307.67801) (xy 405.304232 -307.632734) (xy 405.330535 -307.591138) (xy 405.36317 -307.554301)
			(xy 405.401291 -307.523176) (xy 405.443912 -307.498569) (xy 405.489928 -307.481117) (xy 405.538147 -307.471273)
			(xy 405.587322 -307.469292) (xy 405.636177 -307.475224) (xy 405.683448 -307.488916) (xy 405.72791 -307.510014)
			(xy 405.768413 -307.53797) (xy 405.803906 -307.572062) (xy 405.833471 -307.611406) (xy 405.856342 -307.654983)
			(xy 405.871926 -307.701664) (xy 405.879821 -307.750241) (xy 405.880316 -307.774848) (xy 406.219164 -307.774848)
			(xy 406.223124 -307.725794) (xy 406.234901 -307.67801) (xy 406.254192 -307.632734) (xy 406.280495 -307.591138)
			(xy 406.31313 -307.554301) (xy 406.351251 -307.523176) (xy 406.393872 -307.498569) (xy 406.439888 -307.481117)
			(xy 406.488107 -307.471273) (xy 406.537282 -307.469292) (xy 406.586137 -307.475224) (xy 406.633408 -307.488916)
			(xy 406.67787 -307.510014) (xy 406.718373 -307.53797) (xy 406.753866 -307.572062) (xy 406.783431 -307.611406)
			(xy 406.806302 -307.654983) (xy 406.821886 -307.701664) (xy 406.829781 -307.750241) (xy 406.830276 -307.774848)
			(xy 408.119084 -307.774848) (xy 408.123044 -307.725794) (xy 408.134821 -307.67801) (xy 408.154112 -307.632734)
			(xy 408.180415 -307.591138) (xy 408.21305 -307.554301) (xy 408.251171 -307.523176) (xy 408.293792 -307.498569)
			(xy 408.339808 -307.481117) (xy 408.388027 -307.471273) (xy 408.437202 -307.469292) (xy 408.486057 -307.475224)
			(xy 408.533328 -307.488916) (xy 408.57779 -307.510014) (xy 408.618293 -307.53797) (xy 408.653786 -307.572062)
			(xy 408.683351 -307.611406) (xy 408.706222 -307.654983) (xy 408.721806 -307.701664) (xy 408.729701 -307.750241)
			(xy 408.730196 -307.774848) (xy 409.069044 -307.774848) (xy 409.073004 -307.725794) (xy 409.084781 -307.67801)
			(xy 409.104072 -307.632734) (xy 409.130375 -307.591138) (xy 409.16301 -307.554301) (xy 409.201131 -307.523176)
			(xy 409.243752 -307.498569) (xy 409.289768 -307.481117) (xy 409.337987 -307.471273) (xy 409.387162 -307.469292)
			(xy 409.436017 -307.475224) (xy 409.483288 -307.488916) (xy 409.52775 -307.510014) (xy 409.568253 -307.53797)
			(xy 409.603746 -307.572062) (xy 409.633311 -307.611406) (xy 409.656182 -307.654983) (xy 409.671766 -307.701664)
			(xy 409.679661 -307.750241) (xy 409.680156 -307.774848) (xy 410.019004 -307.774848) (xy 410.022964 -307.725794)
			(xy 410.034741 -307.67801) (xy 410.054032 -307.632734) (xy 410.080335 -307.591138) (xy 410.11297 -307.554301)
			(xy 410.151091 -307.523176) (xy 410.193712 -307.498569) (xy 410.239728 -307.481117) (xy 410.287947 -307.471273)
			(xy 410.337122 -307.469292) (xy 410.385977 -307.475224) (xy 410.433248 -307.488916) (xy 410.47771 -307.510014)
			(xy 410.518213 -307.53797) (xy 410.553706 -307.572062) (xy 410.583271 -307.611406) (xy 410.606142 -307.654983)
			(xy 410.621726 -307.701664) (xy 410.629621 -307.750241) (xy 410.630111 -307.774594) (xy 410.968964 -307.774594)
			(xy 410.972924 -307.72554) (xy 410.984701 -307.677756) (xy 411.003992 -307.63248) (xy 411.030295 -307.590884)
			(xy 411.06293 -307.554047) (xy 411.101051 -307.522922) (xy 411.143672 -307.498315) (xy 411.189688 -307.480863)
			(xy 411.237907 -307.471019) (xy 411.287082 -307.469038) (xy 411.335937 -307.47497) (xy 411.383208 -307.488662)
			(xy 411.42767 -307.50976) (xy 411.468173 -307.537716) (xy 411.503666 -307.571808) (xy 411.533231 -307.611152)
			(xy 411.556102 -307.654729) (xy 411.571686 -307.70141) (xy 411.579581 -307.749987) (xy 411.580076 -307.774594)
			(xy 411.919178 -307.774594) (xy 411.923138 -307.72554) (xy 411.934915 -307.677756) (xy 411.954206 -307.63248)
			(xy 411.980509 -307.590884) (xy 412.013144 -307.554047) (xy 412.051265 -307.522922) (xy 412.093886 -307.498315)
			(xy 412.139902 -307.480863) (xy 412.188121 -307.471019) (xy 412.237296 -307.469038) (xy 412.286151 -307.47497)
			(xy 412.333422 -307.488662) (xy 412.377884 -307.50976) (xy 412.418387 -307.537716) (xy 412.45388 -307.571808)
			(xy 412.483445 -307.611152) (xy 412.506316 -307.654729) (xy 412.5219 -307.70141) (xy 412.529795 -307.749987)
			(xy 412.53029 -307.774594) (xy 412.530285 -307.774848) (xy 412.869138 -307.774848) (xy 412.873098 -307.725794)
			(xy 412.884875 -307.67801) (xy 412.904166 -307.632734) (xy 412.930469 -307.591138) (xy 412.963104 -307.554301)
			(xy 413.001225 -307.523176) (xy 413.043846 -307.498569) (xy 413.089862 -307.481117) (xy 413.138081 -307.471273)
			(xy 413.187256 -307.469292) (xy 413.236111 -307.475224) (xy 413.283382 -307.488916) (xy 413.327844 -307.510014)
			(xy 413.368347 -307.53797) (xy 413.40384 -307.572062) (xy 413.433405 -307.611406) (xy 413.456276 -307.654983)
			(xy 413.47186 -307.701664) (xy 413.479755 -307.750241) (xy 413.48025 -307.774848) (xy 413.819098 -307.774848)
			(xy 413.823058 -307.725794) (xy 413.834835 -307.67801) (xy 413.854126 -307.632734) (xy 413.880429 -307.591138)
			(xy 413.913064 -307.554301) (xy 413.951185 -307.523176) (xy 413.993806 -307.498569) (xy 414.039822 -307.481117)
			(xy 414.088041 -307.471273) (xy 414.137216 -307.469292) (xy 414.186071 -307.475224) (xy 414.233342 -307.488916)
			(xy 414.277804 -307.510014) (xy 414.318307 -307.53797) (xy 414.3538 -307.572062) (xy 414.383365 -307.611406)
			(xy 414.406236 -307.654983) (xy 414.42182 -307.701664) (xy 414.429715 -307.750241) (xy 414.43021 -307.774848)
			(xy 414.769058 -307.774848) (xy 414.773018 -307.725794) (xy 414.784795 -307.67801) (xy 414.804086 -307.632734)
			(xy 414.830389 -307.591138) (xy 414.863024 -307.554301) (xy 414.901145 -307.523176) (xy 414.943766 -307.498569)
			(xy 414.989782 -307.481117) (xy 415.038001 -307.471273) (xy 415.087176 -307.469292) (xy 415.136031 -307.475224)
			(xy 415.183302 -307.488916) (xy 415.227764 -307.510014) (xy 415.268267 -307.53797) (xy 415.30376 -307.572062)
			(xy 415.333325 -307.611406) (xy 415.356196 -307.654983) (xy 415.37178 -307.701664) (xy 415.379675 -307.750241)
			(xy 415.38017 -307.774848) (xy 415.719018 -307.774848) (xy 415.722978 -307.725794) (xy 415.734755 -307.67801)
			(xy 415.754046 -307.632734) (xy 415.780349 -307.591138) (xy 415.812984 -307.554301) (xy 415.851105 -307.523176)
			(xy 415.893726 -307.498569) (xy 415.939742 -307.481117) (xy 415.987961 -307.471273) (xy 416.037136 -307.469292)
			(xy 416.085991 -307.475224) (xy 416.133262 -307.488916) (xy 416.177724 -307.510014) (xy 416.218227 -307.53797)
			(xy 416.25372 -307.572062) (xy 416.283285 -307.611406) (xy 416.306156 -307.654983) (xy 416.32174 -307.701664)
			(xy 416.329635 -307.750241) (xy 416.33013 -307.774848) (xy 416.668978 -307.774848) (xy 416.672938 -307.725794)
			(xy 416.684715 -307.67801) (xy 416.704006 -307.632734) (xy 416.730309 -307.591138) (xy 416.762944 -307.554301)
			(xy 416.801065 -307.523176) (xy 416.843686 -307.498569) (xy 416.889702 -307.481117) (xy 416.937921 -307.471273)
			(xy 416.987096 -307.469292) (xy 417.035951 -307.475224) (xy 417.083222 -307.488916) (xy 417.127684 -307.510014)
			(xy 417.168187 -307.53797) (xy 417.20368 -307.572062) (xy 417.233245 -307.611406) (xy 417.256116 -307.654983)
			(xy 417.2717 -307.701664) (xy 417.279595 -307.750241) (xy 417.28009 -307.774848) (xy 417.619192 -307.774848)
			(xy 417.623152 -307.725794) (xy 417.634929 -307.67801) (xy 417.65422 -307.632734) (xy 417.680523 -307.591138)
			(xy 417.713158 -307.554301) (xy 417.751279 -307.523176) (xy 417.7939 -307.498569) (xy 417.839916 -307.481117)
			(xy 417.888135 -307.471273) (xy 417.93731 -307.469292) (xy 417.986165 -307.475224) (xy 418.033436 -307.488916)
			(xy 418.077898 -307.510014) (xy 418.118401 -307.53797) (xy 418.153894 -307.572062) (xy 418.183459 -307.611406)
			(xy 418.20633 -307.654983) (xy 418.221914 -307.701664) (xy 418.229809 -307.750241) (xy 418.230304 -307.774848)
			(xy 418.569152 -307.774848) (xy 418.573112 -307.725794) (xy 418.584889 -307.67801) (xy 418.60418 -307.632734)
			(xy 418.630483 -307.591138) (xy 418.663118 -307.554301) (xy 418.701239 -307.523176) (xy 418.74386 -307.498569)
			(xy 418.789876 -307.481117) (xy 418.838095 -307.471273) (xy 418.88727 -307.469292) (xy 418.936125 -307.475224)
			(xy 418.983396 -307.488916) (xy 419.027858 -307.510014) (xy 419.068361 -307.53797) (xy 419.103854 -307.572062)
			(xy 419.133419 -307.611406) (xy 419.15629 -307.654983) (xy 419.171874 -307.701664) (xy 419.179769 -307.750241)
			(xy 419.180264 -307.774848) (xy 419.519112 -307.774848) (xy 419.523072 -307.725794) (xy 419.534849 -307.67801)
			(xy 419.55414 -307.632734) (xy 419.580443 -307.591138) (xy 419.613078 -307.554301) (xy 419.651199 -307.523176)
			(xy 419.69382 -307.498569) (xy 419.739836 -307.481117) (xy 419.788055 -307.471273) (xy 419.83723 -307.469292)
			(xy 419.886085 -307.475224) (xy 419.933356 -307.488916) (xy 419.977818 -307.510014) (xy 420.018321 -307.53797)
			(xy 420.053814 -307.572062) (xy 420.083379 -307.611406) (xy 420.10625 -307.654983) (xy 420.121834 -307.701664)
			(xy 420.129729 -307.750241) (xy 420.130224 -307.774848) (xy 420.469072 -307.774848) (xy 420.473032 -307.725794)
			(xy 420.484809 -307.67801) (xy 420.5041 -307.632734) (xy 420.530403 -307.591138) (xy 420.563038 -307.554301)
			(xy 420.601159 -307.523176) (xy 420.64378 -307.498569) (xy 420.689796 -307.481117) (xy 420.738015 -307.471273)
			(xy 420.78719 -307.469292) (xy 420.836045 -307.475224) (xy 420.883316 -307.488916) (xy 420.927778 -307.510014)
			(xy 420.968281 -307.53797) (xy 421.003774 -307.572062) (xy 421.033339 -307.611406) (xy 421.05621 -307.654983)
			(xy 421.071794 -307.701664) (xy 421.079689 -307.750241) (xy 421.080184 -307.774848) (xy 421.079689 -307.799455)
			(xy 421.071794 -307.848032) (xy 421.05621 -307.894713) (xy 421.033339 -307.93829) (xy 421.003774 -307.977634)
			(xy 420.968281 -308.011726) (xy 420.927778 -308.039682) (xy 420.883316 -308.06078) (xy 420.836045 -308.074472)
			(xy 420.78719 -308.080404) (xy 420.738015 -308.078423) (xy 420.689796 -308.068579) (xy 420.64378 -308.051127)
			(xy 420.601159 -308.02652) (xy 420.563038 -307.995395) (xy 420.530403 -307.958558) (xy 420.5041 -307.916962)
			(xy 420.484809 -307.871686) (xy 420.473032 -307.823902) (xy 420.469072 -307.774848) (xy 420.130224 -307.774848)
			(xy 420.129729 -307.799455) (xy 420.121834 -307.848032) (xy 420.10625 -307.894713) (xy 420.083379 -307.93829)
			(xy 420.053814 -307.977634) (xy 420.018321 -308.011726) (xy 419.977818 -308.039682) (xy 419.933356 -308.06078)
			(xy 419.886085 -308.074472) (xy 419.83723 -308.080404) (xy 419.788055 -308.078423) (xy 419.739836 -308.068579)
			(xy 419.69382 -308.051127) (xy 419.651199 -308.02652) (xy 419.613078 -307.995395) (xy 419.580443 -307.958558)
			(xy 419.55414 -307.916962) (xy 419.534849 -307.871686) (xy 419.523072 -307.823902) (xy 419.519112 -307.774848)
			(xy 419.180264 -307.774848) (xy 419.179769 -307.799455) (xy 419.171874 -307.848032) (xy 419.15629 -307.894713)
			(xy 419.133419 -307.93829) (xy 419.103854 -307.977634) (xy 419.068361 -308.011726) (xy 419.027858 -308.039682)
			(xy 418.983396 -308.06078) (xy 418.936125 -308.074472) (xy 418.88727 -308.080404) (xy 418.838095 -308.078423)
			(xy 418.789876 -308.068579) (xy 418.74386 -308.051127) (xy 418.701239 -308.02652) (xy 418.663118 -307.995395)
			(xy 418.630483 -307.958558) (xy 418.60418 -307.916962) (xy 418.584889 -307.871686) (xy 418.573112 -307.823902)
			(xy 418.569152 -307.774848) (xy 418.230304 -307.774848) (xy 418.229809 -307.799455) (xy 418.221914 -307.848032)
			(xy 418.20633 -307.894713) (xy 418.183459 -307.93829) (xy 418.153894 -307.977634) (xy 418.118401 -308.011726)
			(xy 418.077898 -308.039682) (xy 418.033436 -308.06078) (xy 417.986165 -308.074472) (xy 417.93731 -308.080404)
			(xy 417.888135 -308.078423) (xy 417.839916 -308.068579) (xy 417.7939 -308.051127) (xy 417.751279 -308.02652)
			(xy 417.713158 -307.995395) (xy 417.680523 -307.958558) (xy 417.65422 -307.916962) (xy 417.634929 -307.871686)
			(xy 417.623152 -307.823902) (xy 417.619192 -307.774848) (xy 417.28009 -307.774848) (xy 417.279595 -307.799455)
			(xy 417.2717 -307.848032) (xy 417.256116 -307.894713) (xy 417.233245 -307.93829) (xy 417.20368 -307.977634)
			(xy 417.168187 -308.011726) (xy 417.127684 -308.039682) (xy 417.083222 -308.06078) (xy 417.035951 -308.074472)
			(xy 416.987096 -308.080404) (xy 416.937921 -308.078423) (xy 416.889702 -308.068579) (xy 416.843686 -308.051127)
			(xy 416.801065 -308.02652) (xy 416.762944 -307.995395) (xy 416.730309 -307.958558) (xy 416.704006 -307.916962)
			(xy 416.684715 -307.871686) (xy 416.672938 -307.823902) (xy 416.668978 -307.774848) (xy 416.33013 -307.774848)
			(xy 416.329635 -307.799455) (xy 416.32174 -307.848032) (xy 416.306156 -307.894713) (xy 416.283285 -307.93829)
			(xy 416.25372 -307.977634) (xy 416.218227 -308.011726) (xy 416.177724 -308.039682) (xy 416.133262 -308.06078)
			(xy 416.085991 -308.074472) (xy 416.037136 -308.080404) (xy 415.987961 -308.078423) (xy 415.939742 -308.068579)
			(xy 415.893726 -308.051127) (xy 415.851105 -308.02652) (xy 415.812984 -307.995395) (xy 415.780349 -307.958558)
			(xy 415.754046 -307.916962) (xy 415.734755 -307.871686) (xy 415.722978 -307.823902) (xy 415.719018 -307.774848)
			(xy 415.38017 -307.774848) (xy 415.379675 -307.799455) (xy 415.37178 -307.848032) (xy 415.356196 -307.894713)
			(xy 415.333325 -307.93829) (xy 415.30376 -307.977634) (xy 415.268267 -308.011726) (xy 415.227764 -308.039682)
			(xy 415.183302 -308.06078) (xy 415.136031 -308.074472) (xy 415.087176 -308.080404) (xy 415.038001 -308.078423)
			(xy 414.989782 -308.068579) (xy 414.943766 -308.051127) (xy 414.901145 -308.02652) (xy 414.863024 -307.995395)
			(xy 414.830389 -307.958558) (xy 414.804086 -307.916962) (xy 414.784795 -307.871686) (xy 414.773018 -307.823902)
			(xy 414.769058 -307.774848) (xy 414.43021 -307.774848) (xy 414.429715 -307.799455) (xy 414.42182 -307.848032)
			(xy 414.406236 -307.894713) (xy 414.383365 -307.93829) (xy 414.3538 -307.977634) (xy 414.318307 -308.011726)
			(xy 414.277804 -308.039682) (xy 414.233342 -308.06078) (xy 414.186071 -308.074472) (xy 414.137216 -308.080404)
			(xy 414.088041 -308.078423) (xy 414.039822 -308.068579) (xy 413.993806 -308.051127) (xy 413.951185 -308.02652)
			(xy 413.913064 -307.995395) (xy 413.880429 -307.958558) (xy 413.854126 -307.916962) (xy 413.834835 -307.871686)
			(xy 413.823058 -307.823902) (xy 413.819098 -307.774848) (xy 413.48025 -307.774848) (xy 413.479755 -307.799455)
			(xy 413.47186 -307.848032) (xy 413.456276 -307.894713) (xy 413.433405 -307.93829) (xy 413.40384 -307.977634)
			(xy 413.368347 -308.011726) (xy 413.327844 -308.039682) (xy 413.283382 -308.06078) (xy 413.236111 -308.074472)
			(xy 413.187256 -308.080404) (xy 413.138081 -308.078423) (xy 413.089862 -308.068579) (xy 413.043846 -308.051127)
			(xy 413.001225 -308.02652) (xy 412.963104 -307.995395) (xy 412.930469 -307.958558) (xy 412.904166 -307.916962)
			(xy 412.884875 -307.871686) (xy 412.873098 -307.823902) (xy 412.869138 -307.774848) (xy 412.530285 -307.774848)
			(xy 412.529795 -307.799201) (xy 412.5219 -307.847778) (xy 412.506316 -307.894459) (xy 412.483445 -307.938036)
			(xy 412.45388 -307.97738) (xy 412.418387 -308.011472) (xy 412.377884 -308.039428) (xy 412.333422 -308.060526)
			(xy 412.286151 -308.074218) (xy 412.237296 -308.08015) (xy 412.188121 -308.078169) (xy 412.139902 -308.068325)
			(xy 412.093886 -308.050873) (xy 412.051265 -308.026266) (xy 412.013144 -307.995141) (xy 411.980509 -307.958304)
			(xy 411.954206 -307.916708) (xy 411.934915 -307.871432) (xy 411.923138 -307.823648) (xy 411.919178 -307.774594)
			(xy 411.580076 -307.774594) (xy 411.579581 -307.799201) (xy 411.571686 -307.847778) (xy 411.556102 -307.894459)
			(xy 411.533231 -307.938036) (xy 411.503666 -307.97738) (xy 411.468173 -308.011472) (xy 411.42767 -308.039428)
			(xy 411.383208 -308.060526) (xy 411.335937 -308.074218) (xy 411.287082 -308.08015) (xy 411.237907 -308.078169)
			(xy 411.189688 -308.068325) (xy 411.143672 -308.050873) (xy 411.101051 -308.026266) (xy 411.06293 -307.995141)
			(xy 411.030295 -307.958304) (xy 411.003992 -307.916708) (xy 410.984701 -307.871432) (xy 410.972924 -307.823648)
			(xy 410.968964 -307.774594) (xy 410.630111 -307.774594) (xy 410.630116 -307.774848) (xy 410.629621 -307.799455)
			(xy 410.621726 -307.848032) (xy 410.606142 -307.894713) (xy 410.583271 -307.93829) (xy 410.553706 -307.977634)
			(xy 410.518213 -308.011726) (xy 410.47771 -308.039682) (xy 410.433248 -308.06078) (xy 410.385977 -308.074472)
			(xy 410.337122 -308.080404) (xy 410.287947 -308.078423) (xy 410.239728 -308.068579) (xy 410.193712 -308.051127)
			(xy 410.151091 -308.02652) (xy 410.11297 -307.995395) (xy 410.080335 -307.958558) (xy 410.054032 -307.916962)
			(xy 410.034741 -307.871686) (xy 410.022964 -307.823902) (xy 410.019004 -307.774848) (xy 409.680156 -307.774848)
			(xy 409.679661 -307.799455) (xy 409.671766 -307.848032) (xy 409.656182 -307.894713) (xy 409.633311 -307.93829)
			(xy 409.603746 -307.977634) (xy 409.568253 -308.011726) (xy 409.52775 -308.039682) (xy 409.483288 -308.06078)
			(xy 409.436017 -308.074472) (xy 409.387162 -308.080404) (xy 409.337987 -308.078423) (xy 409.289768 -308.068579)
			(xy 409.243752 -308.051127) (xy 409.201131 -308.02652) (xy 409.16301 -307.995395) (xy 409.130375 -307.958558)
			(xy 409.104072 -307.916962) (xy 409.084781 -307.871686) (xy 409.073004 -307.823902) (xy 409.069044 -307.774848)
			(xy 408.730196 -307.774848) (xy 408.729701 -307.799455) (xy 408.721806 -307.848032) (xy 408.706222 -307.894713)
			(xy 408.683351 -307.93829) (xy 408.653786 -307.977634) (xy 408.618293 -308.011726) (xy 408.57779 -308.039682)
			(xy 408.533328 -308.06078) (xy 408.486057 -308.074472) (xy 408.437202 -308.080404) (xy 408.388027 -308.078423)
			(xy 408.339808 -308.068579) (xy 408.293792 -308.051127) (xy 408.251171 -308.02652) (xy 408.21305 -307.995395)
			(xy 408.180415 -307.958558) (xy 408.154112 -307.916962) (xy 408.134821 -307.871686) (xy 408.123044 -307.823902)
			(xy 408.119084 -307.774848) (xy 406.830276 -307.774848) (xy 406.829781 -307.799455) (xy 406.821886 -307.848032)
			(xy 406.806302 -307.894713) (xy 406.783431 -307.93829) (xy 406.753866 -307.977634) (xy 406.718373 -308.011726)
			(xy 406.67787 -308.039682) (xy 406.633408 -308.06078) (xy 406.586137 -308.074472) (xy 406.537282 -308.080404)
			(xy 406.488107 -308.078423) (xy 406.439888 -308.068579) (xy 406.393872 -308.051127) (xy 406.351251 -308.02652)
			(xy 406.31313 -307.995395) (xy 406.280495 -307.958558) (xy 406.254192 -307.916962) (xy 406.234901 -307.871686)
			(xy 406.223124 -307.823902) (xy 406.219164 -307.774848) (xy 405.880316 -307.774848) (xy 405.879821 -307.799455)
			(xy 405.871926 -307.848032) (xy 405.856342 -307.894713) (xy 405.833471 -307.93829) (xy 405.803906 -307.977634)
			(xy 405.768413 -308.011726) (xy 405.72791 -308.039682) (xy 405.683448 -308.06078) (xy 405.636177 -308.074472)
			(xy 405.587322 -308.080404) (xy 405.538147 -308.078423) (xy 405.489928 -308.068579) (xy 405.443912 -308.051127)
			(xy 405.401291 -308.02652) (xy 405.36317 -307.995395) (xy 405.330535 -307.958558) (xy 405.304232 -307.916962)
			(xy 405.284941 -307.871686) (xy 405.273164 -307.823902) (xy 405.269204 -307.774848) (xy 404.930356 -307.774848)
			(xy 404.929861 -307.799455) (xy 404.921966 -307.848032) (xy 404.906382 -307.894713) (xy 404.883511 -307.93829)
			(xy 404.853946 -307.977634) (xy 404.818453 -308.011726) (xy 404.77795 -308.039682) (xy 404.733488 -308.06078)
			(xy 404.686217 -308.074472) (xy 404.637362 -308.080404) (xy 404.588187 -308.078423) (xy 404.539968 -308.068579)
			(xy 404.493952 -308.051127) (xy 404.451331 -308.02652) (xy 404.41321 -307.995395) (xy 404.380575 -307.958558)
			(xy 404.354272 -307.916962) (xy 404.334981 -307.871686) (xy 404.323204 -307.823902) (xy 404.319244 -307.774848)
			(xy 403.980142 -307.774848) (xy 403.979647 -307.799455) (xy 403.971752 -307.848032) (xy 403.956168 -307.894713)
			(xy 403.933297 -307.93829) (xy 403.903732 -307.977634) (xy 403.868239 -308.011726) (xy 403.827736 -308.039682)
			(xy 403.783274 -308.06078) (xy 403.736003 -308.074472) (xy 403.687148 -308.080404) (xy 403.637973 -308.078423)
			(xy 403.589754 -308.068579) (xy 403.543738 -308.051127) (xy 403.501117 -308.02652) (xy 403.462996 -307.995395)
			(xy 403.430361 -307.958558) (xy 403.404058 -307.916962) (xy 403.384767 -307.871686) (xy 403.37299 -307.823902)
			(xy 403.36903 -307.774848) (xy 403.030182 -307.774848) (xy 403.029687 -307.799455) (xy 403.021792 -307.848032)
			(xy 403.006208 -307.894713) (xy 402.983337 -307.93829) (xy 402.953772 -307.977634) (xy 402.918279 -308.011726)
			(xy 402.877776 -308.039682) (xy 402.833314 -308.06078) (xy 402.786043 -308.074472) (xy 402.737188 -308.080404)
			(xy 402.688013 -308.078423) (xy 402.639794 -308.068579) (xy 402.593778 -308.051127) (xy 402.551157 -308.02652)
			(xy 402.513036 -307.995395) (xy 402.480401 -307.958558) (xy 402.454098 -307.916962) (xy 402.434807 -307.871686)
			(xy 402.42303 -307.823902) (xy 402.41907 -307.774848) (xy 402.080222 -307.774848) (xy 402.079727 -307.799455)
			(xy 402.071832 -307.848032) (xy 402.056248 -307.894713) (xy 402.033377 -307.93829) (xy 402.003812 -307.977634)
			(xy 401.968319 -308.011726) (xy 401.927816 -308.039682) (xy 401.883354 -308.06078) (xy 401.836083 -308.074472)
			(xy 401.787228 -308.080404) (xy 401.738053 -308.078423) (xy 401.689834 -308.068579) (xy 401.643818 -308.051127)
			(xy 401.601197 -308.02652) (xy 401.563076 -307.995395) (xy 401.530441 -307.958558) (xy 401.504138 -307.916962)
			(xy 401.484847 -307.871686) (xy 401.47307 -307.823902) (xy 401.46911 -307.774848) (xy 401.130262 -307.774848)
			(xy 401.129767 -307.799455) (xy 401.121872 -307.848032) (xy 401.106288 -307.894713) (xy 401.083417 -307.93829)
			(xy 401.053852 -307.977634) (xy 401.018359 -308.011726) (xy 400.977856 -308.039682) (xy 400.933394 -308.06078)
			(xy 400.886123 -308.074472) (xy 400.837268 -308.080404) (xy 400.788093 -308.078423) (xy 400.739874 -308.068579)
			(xy 400.693858 -308.051127) (xy 400.651237 -308.02652) (xy 400.613116 -307.995395) (xy 400.580481 -307.958558)
			(xy 400.554178 -307.916962) (xy 400.534887 -307.871686) (xy 400.52311 -307.823902) (xy 400.51915 -307.774848)
			(xy 400.180302 -307.774848) (xy 400.179807 -307.799455) (xy 400.171912 -307.848032) (xy 400.156328 -307.894713)
			(xy 400.133457 -307.93829) (xy 400.103892 -307.977634) (xy 400.068399 -308.011726) (xy 400.027896 -308.039682)
			(xy 399.983434 -308.06078) (xy 399.936163 -308.074472) (xy 399.887308 -308.080404) (xy 399.838133 -308.078423)
			(xy 399.789914 -308.068579) (xy 399.743898 -308.051127) (xy 399.701277 -308.02652) (xy 399.663156 -307.995395)
			(xy 399.630521 -307.958558) (xy 399.604218 -307.916962) (xy 399.584927 -307.871686) (xy 399.57315 -307.823902)
			(xy 399.56919 -307.774848) (xy 399.230342 -307.774848) (xy 399.229847 -307.799455) (xy 399.221952 -307.848032)
			(xy 399.206368 -307.894713) (xy 399.183497 -307.93829) (xy 399.153932 -307.977634) (xy 399.118439 -308.011726)
			(xy 399.077936 -308.039682) (xy 399.033474 -308.06078) (xy 398.986203 -308.074472) (xy 398.937348 -308.080404)
			(xy 398.888173 -308.078423) (xy 398.839954 -308.068579) (xy 398.793938 -308.051127) (xy 398.751317 -308.02652)
			(xy 398.713196 -307.995395) (xy 398.680561 -307.958558) (xy 398.654258 -307.916962) (xy 398.634967 -307.871686)
			(xy 398.62319 -307.823902) (xy 398.61923 -307.774848) (xy 398.341088 -307.774848) (xy 398.341088 -308.724808)
			(xy 398.61923 -308.724808) (xy 398.62319 -308.675754) (xy 398.634967 -308.62797) (xy 398.654258 -308.582694)
			(xy 398.680561 -308.541098) (xy 398.713196 -308.504261) (xy 398.751317 -308.473136) (xy 398.793938 -308.448529)
			(xy 398.839954 -308.431077) (xy 398.888173 -308.421233) (xy 398.937348 -308.419252) (xy 398.986203 -308.425184)
			(xy 399.033474 -308.438876) (xy 399.077936 -308.459974) (xy 399.118439 -308.48793) (xy 399.153932 -308.522022)
			(xy 399.183497 -308.561366) (xy 399.206368 -308.604943) (xy 399.221952 -308.651624) (xy 399.229847 -308.700201)
			(xy 399.230342 -308.724808) (xy 399.56919 -308.724808) (xy 399.57315 -308.675754) (xy 399.584927 -308.62797)
			(xy 399.604218 -308.582694) (xy 399.630521 -308.541098) (xy 399.663156 -308.504261) (xy 399.701277 -308.473136)
			(xy 399.743898 -308.448529) (xy 399.789914 -308.431077) (xy 399.838133 -308.421233) (xy 399.887308 -308.419252)
			(xy 399.936163 -308.425184) (xy 399.983434 -308.438876) (xy 400.027896 -308.459974) (xy 400.068399 -308.48793)
			(xy 400.103892 -308.522022) (xy 400.133457 -308.561366) (xy 400.156328 -308.604943) (xy 400.171912 -308.651624)
			(xy 400.179807 -308.700201) (xy 400.180302 -308.724808) (xy 400.51915 -308.724808) (xy 400.52311 -308.675754)
			(xy 400.534887 -308.62797) (xy 400.554178 -308.582694) (xy 400.580481 -308.541098) (xy 400.613116 -308.504261)
			(xy 400.651237 -308.473136) (xy 400.693858 -308.448529) (xy 400.739874 -308.431077) (xy 400.788093 -308.421233)
			(xy 400.837268 -308.419252) (xy 400.886123 -308.425184) (xy 400.933394 -308.438876) (xy 400.977856 -308.459974)
			(xy 401.018359 -308.48793) (xy 401.053852 -308.522022) (xy 401.083417 -308.561366) (xy 401.106288 -308.604943)
			(xy 401.121872 -308.651624) (xy 401.129767 -308.700201) (xy 401.130262 -308.724808) (xy 401.46911 -308.724808)
			(xy 401.47307 -308.675754) (xy 401.484847 -308.62797) (xy 401.504138 -308.582694) (xy 401.530441 -308.541098)
			(xy 401.563076 -308.504261) (xy 401.601197 -308.473136) (xy 401.643818 -308.448529) (xy 401.689834 -308.431077)
			(xy 401.738053 -308.421233) (xy 401.787228 -308.419252) (xy 401.836083 -308.425184) (xy 401.883354 -308.438876)
			(xy 401.927816 -308.459974) (xy 401.968319 -308.48793) (xy 402.003812 -308.522022) (xy 402.033377 -308.561366)
			(xy 402.056248 -308.604943) (xy 402.071832 -308.651624) (xy 402.079727 -308.700201) (xy 402.080222 -308.724808)
			(xy 402.41907 -308.724808) (xy 402.42303 -308.675754) (xy 402.434807 -308.62797) (xy 402.454098 -308.582694)
			(xy 402.480401 -308.541098) (xy 402.513036 -308.504261) (xy 402.551157 -308.473136) (xy 402.593778 -308.448529)
			(xy 402.639794 -308.431077) (xy 402.688013 -308.421233) (xy 402.737188 -308.419252) (xy 402.786043 -308.425184)
			(xy 402.833314 -308.438876) (xy 402.877776 -308.459974) (xy 402.918279 -308.48793) (xy 402.953772 -308.522022)
			(xy 402.983337 -308.561366) (xy 403.006208 -308.604943) (xy 403.021792 -308.651624) (xy 403.029687 -308.700201)
			(xy 403.030182 -308.724808) (xy 403.029687 -308.749415) (xy 403.021792 -308.797992) (xy 403.006208 -308.844673)
			(xy 402.983337 -308.88825) (xy 402.953772 -308.927594) (xy 402.918279 -308.961686) (xy 402.877776 -308.989642)
			(xy 402.833314 -309.01074) (xy 402.786043 -309.024432) (xy 402.737188 -309.030364) (xy 402.688013 -309.028383)
			(xy 402.639794 -309.018539) (xy 402.593778 -309.001087) (xy 402.551157 -308.97648) (xy 402.513036 -308.945355)
			(xy 402.480401 -308.908518) (xy 402.454098 -308.866922) (xy 402.434807 -308.821646) (xy 402.42303 -308.773862)
			(xy 402.41907 -308.724808) (xy 402.080222 -308.724808) (xy 402.079727 -308.749415) (xy 402.071832 -308.797992)
			(xy 402.056248 -308.844673) (xy 402.033377 -308.88825) (xy 402.003812 -308.927594) (xy 401.968319 -308.961686)
			(xy 401.927816 -308.989642) (xy 401.883354 -309.01074) (xy 401.836083 -309.024432) (xy 401.787228 -309.030364)
			(xy 401.738053 -309.028383) (xy 401.689834 -309.018539) (xy 401.643818 -309.001087) (xy 401.601197 -308.97648)
			(xy 401.563076 -308.945355) (xy 401.530441 -308.908518) (xy 401.504138 -308.866922) (xy 401.484847 -308.821646)
			(xy 401.47307 -308.773862) (xy 401.46911 -308.724808) (xy 401.130262 -308.724808) (xy 401.129767 -308.749415)
			(xy 401.121872 -308.797992) (xy 401.106288 -308.844673) (xy 401.083417 -308.88825) (xy 401.053852 -308.927594)
			(xy 401.018359 -308.961686) (xy 400.977856 -308.989642) (xy 400.933394 -309.01074) (xy 400.886123 -309.024432)
			(xy 400.837268 -309.030364) (xy 400.788093 -309.028383) (xy 400.739874 -309.018539) (xy 400.693858 -309.001087)
			(xy 400.651237 -308.97648) (xy 400.613116 -308.945355) (xy 400.580481 -308.908518) (xy 400.554178 -308.866922)
			(xy 400.534887 -308.821646) (xy 400.52311 -308.773862) (xy 400.51915 -308.724808) (xy 400.180302 -308.724808)
			(xy 400.179807 -308.749415) (xy 400.171912 -308.797992) (xy 400.156328 -308.844673) (xy 400.133457 -308.88825)
			(xy 400.103892 -308.927594) (xy 400.068399 -308.961686) (xy 400.027896 -308.989642) (xy 399.983434 -309.01074)
			(xy 399.936163 -309.024432) (xy 399.887308 -309.030364) (xy 399.838133 -309.028383) (xy 399.789914 -309.018539)
			(xy 399.743898 -309.001087) (xy 399.701277 -308.97648) (xy 399.663156 -308.945355) (xy 399.630521 -308.908518)
			(xy 399.604218 -308.866922) (xy 399.584927 -308.821646) (xy 399.57315 -308.773862) (xy 399.56919 -308.724808)
			(xy 399.230342 -308.724808) (xy 399.229847 -308.749415) (xy 399.221952 -308.797992) (xy 399.206368 -308.844673)
			(xy 399.183497 -308.88825) (xy 399.153932 -308.927594) (xy 399.118439 -308.961686) (xy 399.077936 -308.989642)
			(xy 399.033474 -309.01074) (xy 398.986203 -309.024432) (xy 398.937348 -309.030364) (xy 398.888173 -309.028383)
			(xy 398.839954 -309.018539) (xy 398.793938 -309.001087) (xy 398.751317 -308.97648) (xy 398.713196 -308.945355)
			(xy 398.680561 -308.908518) (xy 398.654258 -308.866922) (xy 398.634967 -308.821646) (xy 398.62319 -308.773862)
			(xy 398.61923 -308.724808) (xy 398.341088 -308.724808) (xy 398.341088 -309.22468) (xy 398.341525 -309.234744)
			(xy 398.349259 -309.253329) (xy 398.356074 -309.260748) (xy 398.541748 -309.446422) (xy 398.549257 -309.45333)
			(xy 398.568126 -309.461045) (xy 398.578324 -309.461408) (xy 398.641316 -309.460646) (xy 398.646421 -309.460444)
			(xy 398.656403 -309.458272) (xy 398.661128 -309.456328) (xy 398.670272 -309.452264) (xy 398.671288 -309.451756)
			(xy 398.671542 -309.451756) (xy 398.687798 -309.445152) (xy 398.69364 -309.438294) (xy 398.712292 -309.420741)
			(xy 398.754002 -309.391022) (xy 398.799793 -309.368083) (xy 398.848572 -309.352473) (xy 398.899173 -309.344564)
			(xy 398.92478 -309.34406) (xy 398.925034 -309.34406) (xy 398.95102 -309.344572) (xy 399.002353 -309.352707)
			(xy 399.051781 -309.36877) (xy 399.098088 -309.392367) (xy 399.140134 -309.422917) (xy 399.176884 -309.459668)
			(xy 399.207434 -309.501714) (xy 399.231031 -309.548021) (xy 399.247094 -309.597449) (xy 399.255228 -309.648782)
			(xy 399.255742 -309.674768) (xy 399.255742 -309.682642) (xy 399.255234 -309.697882) (xy 399.271998 -309.724298)
			(xy 399.286476 -309.730394) (xy 399.292318 -309.732934) (xy 399.302224 -309.737252) (xy 399.302478 -309.737252)
			(xy 399.324513 -309.746787) (xy 399.367712 -309.767754) (xy 399.388838 -309.779162) (xy 399.39468 -309.78221)
			(xy 399.408396 -309.785512) (xy 399.418288 -309.787451) (xy 399.43818 -309.784292) (xy 399.447004 -309.779416)
			(xy 399.513552 -309.738014) (xy 399.522696 -309.730902) (xy 399.529554 -309.724044) (xy 399.533166 -309.720275)
			(xy 399.538927 -309.71157) (xy 399.540984 -309.706772) (xy 399.544794 -309.696866) (xy 399.54454 -309.685436)
			(xy 399.54454 -309.685182) (xy 399.544286 -309.675022) (xy 399.544286 -309.674514) (xy 399.544817 -309.648541)
			(xy 399.552983 -309.597241) (xy 399.569069 -309.547848) (xy 399.59268 -309.501578) (xy 399.623235 -309.459568)
			(xy 399.659982 -309.422853) (xy 399.702017 -309.392333) (xy 399.748307 -309.368762) (xy 399.797714 -309.352717)
			(xy 399.849021 -309.344595) (xy 399.874994 -309.34406) (xy 399.900982 -309.344569) (xy 399.952319 -309.352699)
			(xy 400.001753 -309.368759) (xy 400.048066 -309.392354) (xy 400.090117 -309.422903) (xy 400.126872 -309.459654)
			(xy 400.157426 -309.501702) (xy 400.181027 -309.548012) (xy 400.197092 -309.597444) (xy 400.205228 -309.64878)
			(xy 400.205702 -309.674768) (xy 400.205448 -309.684674) (xy 400.205448 -309.691024) (xy 400.205781 -309.699666)
			(xy 400.211524 -309.715967) (xy 400.222378 -309.729416) (xy 400.229578 -309.734204) (xy 400.304 -309.779924)
			(xy 400.307302 -309.781956) (xy 400.310604 -309.78348) (xy 400.311874 -309.783988) (xy 400.317203 -309.786114)
			(xy 400.32849 -309.788168) (xy 400.334226 -309.788052) (xy 400.346926 -309.787544) (xy 400.35734 -309.781702)
			(xy 400.38125 -309.768624) (xy 400.430302 -309.744863) (xy 400.455384 -309.734204) (xy 400.462496 -309.731156)
			(xy 400.475704 -309.720234) (xy 400.484073 -309.712615) (xy 400.493704 -309.692169) (xy 400.494246 -309.680864)
			(xy 400.494246 -309.674768) (xy 400.494756 -309.648781) (xy 400.502886 -309.597446) (xy 400.518947 -309.548016)
			(xy 400.542543 -309.501706) (xy 400.573093 -309.459658) (xy 400.609844 -309.422907) (xy 400.651892 -309.392357)
			(xy 400.698202 -309.368761) (xy 400.747632 -309.3527) (xy 400.798967 -309.34457) (xy 400.850941 -309.34457)
			(xy 400.902276 -309.3527) (xy 400.951706 -309.368761) (xy 400.998016 -309.392357) (xy 401.040064 -309.422907)
			(xy 401.076815 -309.459658) (xy 401.107365 -309.501706) (xy 401.130961 -309.548016) (xy 401.147022 -309.597446)
			(xy 401.155152 -309.648781) (xy 401.155662 -309.674768) (xy 401.155662 -309.682642) (xy 401.155154 -309.697882)
			(xy 401.171918 -309.724298) (xy 401.186396 -309.730394) (xy 401.192238 -309.732934) (xy 401.202144 -309.737252)
			(xy 401.202398 -309.737252) (xy 401.224434 -309.746785) (xy 401.267634 -309.767749) (xy 401.288758 -309.779162)
			(xy 401.2946 -309.78221) (xy 401.308316 -309.785512) (xy 401.318211 -309.787467) (xy 401.33812 -309.784335)
			(xy 401.346924 -309.779416) (xy 401.413472 -309.738014) (xy 401.422616 -309.730902) (xy 401.429474 -309.724044)
			(xy 401.433085 -309.720274) (xy 401.438844 -309.711569) (xy 401.440904 -309.706772) (xy 401.444714 -309.696866)
			(xy 401.44446 -309.685436) (xy 401.44446 -309.685182) (xy 401.444206 -309.675022) (xy 401.444206 -309.674514)
			(xy 401.444737 -309.648542) (xy 401.452903 -309.597243) (xy 401.46899 -309.547851) (xy 401.492601 -309.501583)
			(xy 401.523156 -309.459575) (xy 401.559903 -309.422861) (xy 401.601939 -309.392344) (xy 401.648229 -309.368774)
			(xy 401.697635 -309.352733) (xy 401.748941 -309.344613) (xy 401.774914 -309.34406) (xy 401.800901 -309.344571)
			(xy 401.852236 -309.352703) (xy 401.901667 -309.368764) (xy 401.947977 -309.392361) (xy 401.990026 -309.42291)
			(xy 402.026778 -309.459661) (xy 402.05733 -309.501708) (xy 402.080929 -309.548017) (xy 402.096993 -309.597446)
			(xy 402.105128 -309.648781) (xy 402.105622 -309.674768) (xy 402.105368 -309.684674) (xy 402.105368 -309.691024)
			(xy 402.105702 -309.699665) (xy 402.111446 -309.715964) (xy 402.122302 -309.729411) (xy 402.129498 -309.734204)
			(xy 402.20392 -309.779924) (xy 402.207222 -309.781956) (xy 402.210524 -309.78348) (xy 402.211794 -309.783988)
			(xy 402.217124 -309.786112) (xy 402.22841 -309.788161) (xy 402.234146 -309.788052) (xy 402.246846 -309.787544)
			(xy 402.25726 -309.781702) (xy 402.281169 -309.768622) (xy 402.33022 -309.744857) (xy 402.355304 -309.734204)
			(xy 402.362416 -309.731156) (xy 402.375624 -309.720234) (xy 402.38399 -309.712614) (xy 402.393617 -309.692167)
			(xy 402.394166 -309.680864) (xy 402.394166 -309.674768) (xy 402.394676 -309.648781) (xy 402.402806 -309.597446)
			(xy 402.418867 -309.548016) (xy 402.442463 -309.501706) (xy 402.473013 -309.459658) (xy 402.509764 -309.422907)
			(xy 402.551812 -309.392357) (xy 402.598122 -309.368761) (xy 402.647552 -309.3527) (xy 402.698887 -309.34457)
			(xy 402.750861 -309.34457) (xy 402.802196 -309.3527) (xy 402.851626 -309.368761) (xy 402.897936 -309.392357)
			(xy 402.939984 -309.422907) (xy 402.976735 -309.459658) (xy 403.007285 -309.501706) (xy 403.030881 -309.548016)
			(xy 403.046942 -309.597446) (xy 403.055072 -309.648781) (xy 403.055582 -309.674768) (xy 403.055582 -309.682642)
			(xy 403.055074 -309.697882) (xy 403.071838 -309.724298) (xy 403.086316 -309.730394) (xy 403.092158 -309.732934)
			(xy 403.102064 -309.737252) (xy 403.102318 -309.737252) (xy 403.124354 -309.746786) (xy 403.167554 -309.76775)
			(xy 403.188678 -309.779162) (xy 403.19452 -309.78221) (xy 403.208236 -309.785512) (xy 403.21813 -309.787463)
			(xy 403.238035 -309.784324) (xy 403.246844 -309.779416) (xy 403.313392 -309.738014) (xy 403.322536 -309.730902)
			(xy 403.329394 -309.724044) (xy 403.333004 -309.720274) (xy 403.338761 -309.711567) (xy 403.340824 -309.706772)
			(xy 403.344634 -309.696866) (xy 403.34438 -309.685436) (xy 403.34438 -309.685182) (xy 403.344126 -309.675022)
			(xy 403.344126 -309.674514) (xy 403.344657 -309.648543) (xy 403.352823 -309.597245) (xy 403.36891 -309.547854)
			(xy 403.392521 -309.501587) (xy 403.423077 -309.459581) (xy 403.459824 -309.422869) (xy 403.50186 -309.392354)
			(xy 403.548151 -309.368787) (xy 403.597556 -309.352748) (xy 403.648862 -309.344632) (xy 403.674834 -309.34406)
			(xy 403.688361 -309.344239) (xy 403.715319 -309.346524) (xy 403.728682 -309.348632) (xy 403.74062 -309.350664)
			(xy 403.763226 -309.343806) (xy 403.831298 -309.279036) (xy 403.839363 -309.270541) (xy 403.847414 -309.248572)
			(xy 403.846792 -309.236872) (xy 403.846792 -309.235856) (xy 403.845758 -309.226938) (xy 403.844615 -309.209019)
			(xy 403.844506 -309.200042) (xy 403.844506 -309.199534) (xy 403.844724 -309.185543) (xy 403.847398 -309.157686)
			(xy 403.84984 -309.143908) (xy 403.84984 -309.1434) (xy 403.851351 -309.131164) (xy 403.844062 -309.107654)
			(xy 403.83587 -309.098442) (xy 403.77618 -309.038752) (xy 403.766937 -309.030614) (xy 403.743453 -309.02333)
			(xy 403.731222 -309.024782) (xy 403.730968 -309.024782) (xy 403.717066 -309.027257) (xy 403.688953 -309.029927)
			(xy 403.674834 -309.030116) (xy 403.650012 -309.029633) (xy 403.60102 -309.021606) (xy 403.553973 -309.00576)
			(xy 403.510109 -308.98251) (xy 403.470585 -308.95247) (xy 403.436441 -308.916432) (xy 403.408578 -308.875344)
			(xy 403.387729 -308.830289) (xy 403.374445 -308.782455) (xy 403.369074 -308.733102) (xy 403.371758 -308.68353)
			(xy 403.382427 -308.635046) (xy 403.4008 -308.588926) (xy 403.426393 -308.546387) (xy 403.45853 -308.508548)
			(xy 403.496366 -308.476408) (xy 403.538903 -308.450812) (xy 403.585021 -308.432435) (xy 403.633505 -308.421762)
			(xy 403.683076 -308.419073) (xy 403.73243 -308.42444) (xy 403.780265 -308.43772) (xy 403.825321 -308.458565)
			(xy 403.866411 -308.486425) (xy 403.902453 -308.520566) (xy 403.932496 -308.560087) (xy 403.955749 -308.603949)
			(xy 403.9716 -308.650995) (xy 403.979631 -308.699986) (xy 403.980142 -308.724808) (xy 403.979933 -308.738863)
			(xy 403.97726 -308.766847) (xy 403.974808 -308.780688) (xy 403.974808 -308.781196) (xy 403.97332 -308.793425)
			(xy 403.980635 -308.816907) (xy 403.988778 -308.826154) (xy 404.048468 -308.885844) (xy 404.057708 -308.893994)
			(xy 404.081197 -308.901301) (xy 404.093426 -308.899814) (xy 404.09368 -308.899814) (xy 404.107582 -308.897336)
			(xy 404.135694 -308.894662) (xy 404.149814 -308.89448) (xy 404.16406 -308.894656) (xy 404.192428 -308.897325)
			(xy 404.206456 -308.899814) (xy 404.218764 -308.901516) (xy 404.24248 -308.894205) (xy 404.251668 -308.885844)
			(xy 404.311104 -308.826408) (xy 404.319281 -308.817109) (xy 404.326578 -308.793487) (xy 404.325074 -308.781196)
			(xy 404.322588 -308.767231) (xy 404.319915 -308.738991) (xy 404.31974 -308.724808) (xy 404.320225 -308.699992)
			(xy 404.328253 -308.651013) (xy 404.344099 -308.603978) (xy 404.367346 -308.560126) (xy 404.39738 -308.520612)
			(xy 404.433412 -308.486478) (xy 404.474491 -308.458623) (xy 404.519535 -308.43778) (xy 404.567357 -308.424499)
			(xy 404.616698 -308.41913) (xy 404.666258 -308.421813) (xy 404.714731 -308.432479) (xy 404.76084 -308.450846)
			(xy 404.80337 -308.476431) (xy 404.841201 -308.508559) (xy 404.873336 -308.546384) (xy 404.898929 -308.588909)
			(xy 404.917304 -308.635015) (xy 404.927979 -308.683486) (xy 404.930224 -308.724808) (xy 406.219164 -308.724808)
			(xy 406.223124 -308.675754) (xy 406.234901 -308.62797) (xy 406.254192 -308.582694) (xy 406.280495 -308.541098)
			(xy 406.31313 -308.504261) (xy 406.351251 -308.473136) (xy 406.393872 -308.448529) (xy 406.439888 -308.431077)
			(xy 406.488107 -308.421233) (xy 406.537282 -308.419252) (xy 406.586137 -308.425184) (xy 406.633408 -308.438876)
			(xy 406.67787 -308.459974) (xy 406.718373 -308.48793) (xy 406.753866 -308.522022) (xy 406.783431 -308.561366)
			(xy 406.806302 -308.604943) (xy 406.821886 -308.651624) (xy 406.829781 -308.700201) (xy 406.830276 -308.724808)
			(xy 406.829781 -308.749415) (xy 406.821886 -308.797992) (xy 406.806302 -308.844673) (xy 406.783431 -308.88825)
			(xy 406.753866 -308.927594) (xy 406.718373 -308.961686) (xy 406.67787 -308.989642) (xy 406.633408 -309.01074)
			(xy 406.586137 -309.024432) (xy 406.537282 -309.030364) (xy 406.488107 -309.028383) (xy 406.439888 -309.018539)
			(xy 406.393872 -309.001087) (xy 406.351251 -308.97648) (xy 406.31313 -308.945355) (xy 406.280495 -308.908518)
			(xy 406.254192 -308.866922) (xy 406.234901 -308.821646) (xy 406.223124 -308.773862) (xy 406.219164 -308.724808)
			(xy 404.930224 -308.724808) (xy 404.930672 -308.733045) (xy 404.925311 -308.782388) (xy 404.912039 -308.830213)
			(xy 404.891205 -308.875261) (xy 404.863357 -308.916345) (xy 404.829229 -308.952382) (xy 404.789721 -308.982424)
			(xy 404.745874 -309.005679) (xy 404.698842 -309.021533) (xy 404.649864 -309.02957) (xy 404.625048 -309.030116)
			(xy 404.610802 -309.029938) (xy 404.582435 -309.027266) (xy 404.568406 -309.024782) (xy 404.556214 -309.022496)
			(xy 404.532084 -309.029862) (xy 404.463758 -309.098188) (xy 404.455585 -309.107489) (xy 404.448292 -309.131109)
			(xy 404.449788 -309.1434) (xy 404.452274 -309.157365) (xy 404.454947 -309.185605) (xy 404.455122 -309.199788)
			(xy 404.455017 -309.208829) (xy 404.453873 -309.226874) (xy 404.452836 -309.235856) (xy 404.452836 -309.236872)
			(xy 404.452188 -309.248572) (xy 404.460256 -309.270545) (xy 404.46833 -309.279036) (xy 404.536402 -309.343806)
			(xy 404.559008 -309.350664) (xy 404.570946 -309.348632) (xy 404.584309 -309.346523) (xy 404.611267 -309.344238)
			(xy 404.624794 -309.34406) (xy 404.650782 -309.344569) (xy 404.702119 -309.352699) (xy 404.751553 -309.368759)
			(xy 404.797866 -309.392354) (xy 404.839917 -309.422903) (xy 404.876672 -309.459654) (xy 404.907226 -309.501702)
			(xy 404.930827 -309.548012) (xy 404.946892 -309.597444) (xy 404.955028 -309.64878) (xy 404.955502 -309.674768)
			(xy 404.955502 -309.67807) (xy 404.955938 -309.688134) (xy 404.963671 -309.70672) (xy 404.970488 -309.714138)
			(xy 404.987506 -309.731156) (xy 404.996904 -309.734966) (xy 405.017986 -309.743856) (xy 405.036274 -309.752492)
			(xy 405.042116 -309.755286) (xy 405.069548 -309.769002) (xy 405.080724 -309.774844) (xy 405.080978 -309.774844)
			(xy 405.090122 -309.779924) (xy 405.09444 -309.78221) (xy 405.104771 -309.78695) (xy 405.127453 -309.787887)
			(xy 405.138128 -309.783988) (xy 405.14397 -309.781448) (xy 405.182832 -309.757572) (xy 405.209502 -309.741316)
			(xy 405.215063 -309.73759) (xy 405.2242 -309.727815) (xy 405.227536 -309.722012) (xy 405.238204 -309.7022)
			(xy 405.241025 -309.696571) (xy 405.244102 -309.684364) (xy 405.2443 -309.67807) (xy 405.2443 -309.674514)
			(xy 405.244831 -309.648542) (xy 405.252997 -309.597242) (xy 405.269083 -309.54785) (xy 405.292694 -309.501581)
			(xy 405.323249 -309.459573) (xy 405.359997 -309.422858) (xy 405.402032 -309.392341) (xy 405.448323 -309.368771)
			(xy 405.497729 -309.352728) (xy 405.549035 -309.344608) (xy 405.575008 -309.34406) (xy 405.600996 -309.34457)
			(xy 405.652331 -309.352701) (xy 405.701763 -309.368763) (xy 405.748073 -309.392359) (xy 405.790123 -309.422908)
			(xy 405.826877 -309.459659) (xy 405.857429 -309.501706) (xy 405.881028 -309.548015) (xy 405.897093 -309.597446)
			(xy 405.905228 -309.64878) (xy 405.905716 -309.674768) (xy 405.905462 -309.68569) (xy 405.905462 -309.69077)
			(xy 405.906132 -309.703415) (xy 405.918127 -309.725678) (xy 405.928322 -309.733188) (xy 405.92883 -309.733442)
			(xy 406.01646 -309.787798) (xy 406.044146 -309.78856) (xy 406.056338 -309.781702) (xy 406.084591 -309.766289)
			(xy 406.142805 -309.738832) (xy 406.17267 -309.726838) (xy 406.179528 -309.724044) (xy 406.191212 -309.7149)
			(xy 406.214834 -309.681626) (xy 406.21966 -309.668164) (xy 406.219914 -309.660544) (xy 406.221658 -309.634724)
			(xy 406.23274 -309.584178) (xy 406.252188 -309.536224) (xy 406.279443 -309.492237) (xy 406.313725 -309.453475)
			(xy 406.354052 -309.42105) (xy 406.39927 -309.395889) (xy 406.448084 -309.378714) (xy 406.499094 -309.370016)
			(xy 406.524968 -309.36946) (xy 406.550823 -309.370008) (xy 406.601792 -309.378727) (xy 406.650566 -309.395903)
			(xy 406.69575 -309.421047) (xy 406.736056 -309.453441) (xy 406.770332 -309.492159) (xy 406.797598 -309.536095)
			(xy 406.817077 -309.583996) (xy 406.828212 -309.634492) (xy 406.830022 -309.66029) (xy 406.830276 -309.66791)
			(xy 406.835102 -309.681118) (xy 406.85974 -309.715916) (xy 406.866221 -309.724205) (xy 406.884189 -309.735111)
			(xy 406.894538 -309.736998) (xy 406.905206 -309.738522) (xy 406.943761 -309.755578) (xy 407.018021 -309.795509)
			(xy 407.088503 -309.841781) (xy 407.121868 -309.867554) (xy 407.124154 -309.869332) (xy 407.133552 -309.875174)
			(xy 407.135838 -309.87619) (xy 407.157871 -309.887655) (xy 407.198212 -309.916623) (xy 407.233334 -309.951737)
			(xy 407.262311 -309.992072) (xy 407.27376 -310.014112) (xy 407.274776 -310.016398) (xy 407.280618 -310.025796)
			(xy 407.282396 -310.028082) (xy 407.312711 -310.067685) (xy 407.365901 -310.152059) (xy 407.388568 -310.196484)
			(xy 407.392656 -310.203986) (xy 407.40485 -310.215939) (xy 407.412444 -310.219852) (xy 407.432806 -310.229574)
			(xy 407.472701 -310.250663) (xy 407.4922 -310.262016) (xy 407.504392 -310.269128)
		)
		(stroke
			(width 0)
			(type solid)
		)
		(fill yes)
		(layer "In7.Cu")
		(net "P1V25_PEX3")
	)
	(gr_poly
		(pts
			(xy 84.474304 -318.305942) (xy 84.48191 -318.304429) (xy 84.495746 -318.297445) (xy 84.501482 -318.292226)
			(xy 86.870286 -315.923422) (xy 86.877688 -315.916587) (xy 86.896287 -315.90888) (xy 86.906354 -315.908436)
			(xy 93.28277 -315.908436) (xy 93.292834 -315.908873) (xy 93.311416 -315.916609) (xy 93.318838 -315.923422)
			(xy 95.061532 -317.666116) (xy 95.067882 -317.67145) (xy 95.067882 -317.671704) (xy 95.074522 -317.676068)
			(xy 95.089659 -317.680867) (xy 95.0976 -317.681102) (xy 117.229128 -317.681102) (xy 117.238212 -317.680728)
			(xy 117.255239 -317.674391) (xy 117.268993 -317.662521) (xy 117.277752 -317.646604) (xy 117.27942 -317.637668)
			(xy 117.283847 -317.610833) (xy 117.299311 -317.55869) (xy 117.322022 -317.509272) (xy 117.351521 -317.463579)
			(xy 117.387209 -317.422539) (xy 117.428364 -317.386983) (xy 117.474152 -317.357632) (xy 117.523643 -317.33508)
			(xy 117.575835 -317.319784) (xy 117.62967 -317.312056) (xy 117.656864 -317.311532) (xy 117.681122 -317.311909)
			(xy 117.729246 -317.318063) (xy 117.776199 -317.330274) (xy 117.79885 -317.338964) (xy 117.810534 -317.34379)
			(xy 117.83568 -317.340996) (xy 117.915944 -317.28664) (xy 117.925958 -317.279109) (xy 117.937666 -317.256992)
			(xy 117.938296 -317.244476) (xy 117.938296 -316.438534) (xy 117.937654 -316.426025) (xy 117.92594 -316.403917)
			(xy 117.915944 -316.39637) (xy 117.83568 -316.342014) (xy 117.810534 -316.33922) (xy 117.79885 -316.344046)
			(xy 117.776197 -316.352729) (xy 117.729244 -316.364943) (xy 117.681122 -316.371104) (xy 117.656864 -316.371478)
			(xy 117.629617 -316.370989) (xy 117.575677 -316.363229) (xy 117.523391 -316.347872) (xy 117.473822 -316.325231)
			(xy 117.42798 -316.295766) (xy 117.386797 -316.260077) (xy 117.351112 -316.218891) (xy 117.321652 -316.173046)
			(xy 117.299015 -316.123475) (xy 117.283663 -316.071188) (xy 117.275908 -316.017247) (xy 117.275908 -315.962753)
			(xy 117.283663 -315.908812) (xy 117.299015 -315.856525) (xy 117.321652 -315.806954) (xy 117.351112 -315.761109)
			(xy 117.386797 -315.719923) (xy 117.42798 -315.684234) (xy 117.473822 -315.654769) (xy 117.523391 -315.632128)
			(xy 117.575677 -315.616771) (xy 117.629617 -315.609011) (xy 117.656864 -315.608462) (xy 117.681122 -315.60884)
			(xy 117.729245 -315.614994) (xy 117.776198 -315.627206) (xy 117.79885 -315.635894) (xy 117.810534 -315.64072)
			(xy 117.83568 -315.637926) (xy 117.915944 -315.58357) (xy 117.925963 -315.576042) (xy 117.937684 -315.553924)
			(xy 117.938296 -315.541406) (xy 117.938296 -305.96078) (xy 117.937869 -305.950712) (xy 117.930149 -305.932113)
			(xy 117.92331 -305.924712) (xy 116.70792 -304.709322) (xy 116.701084 -304.70192) (xy 116.693375 -304.683322)
			(xy 116.692934 -304.673254) (xy 116.692934 -302.42002) (xy 116.693372 -302.409957) (xy 116.701111 -302.391377)
			(xy 116.70792 -302.383952) (xy 117.92331 -301.168562) (xy 117.923818 -301.168054) (xy 117.930405 -301.160675)
			(xy 117.937864 -301.142375) (xy 117.938296 -301.132494) (xy 117.938296 -294.43553) (xy 117.93786 -294.425466)
			(xy 117.930127 -294.40688) (xy 117.92331 -294.399462) (xy 117.505226 -293.981378) (xy 117.498114 -293.974012)
			(xy 117.479318 -293.966392) (xy 116.952522 -293.966392) (xy 116.947567 -293.966275) (xy 116.937844 -293.96436)
			(xy 116.933218 -293.962582) (xy 116.90731 -293.95166) (xy 100.996242 -293.95166) (xy 100.987136 -293.952032)
			(xy 100.970078 -293.958406) (xy 100.962968 -293.964106) (xy 100.953316 -293.972488) (xy 100.927385 -293.992796)
			(xy 100.871067 -294.026947) (xy 100.810634 -294.053138) (xy 100.747206 -294.070882) (xy 100.681956 -294.079853)
			(xy 100.649024 -294.080438) (xy 98.964242 -294.080438) (xy 98.964242 -294.080184) (xy 97.747074 -294.080184)
			(xy 97.718887 -294.079756) (xy 97.662903 -294.073133) (xy 97.608071 -294.060039) (xy 97.581466 -294.05072)
			(xy 97.548918 -294.038121) (xy 97.48754 -294.004898) (xy 97.431582 -293.963189) (xy 97.40646 -293.93896)
			(xy 94.96298 -291.49548) (xy 94.938749 -291.470361) (xy 94.897037 -291.414403) (xy 94.863818 -291.353023)
			(xy 94.85122 -291.320474) (xy 94.841845 -291.293709) (xy 94.828703 -291.238538) (xy 94.822119 -291.182207)
			(xy 94.821756 -291.15385) (xy 94.821756 -287.07207) (xy 94.822136 -287.043713) (xy 94.82872 -286.987385)
			(xy 94.841855 -286.932214) (xy 94.85122 -286.905446) (xy 94.863819 -286.872897) (xy 94.89704 -286.811519)
			(xy 94.938748 -286.755558) (xy 94.96298 -286.73044) (xy 97.006664 -284.686756) (xy 97.305368 -284.388306)
			(xy 97.311618 -284.38107) (xy 97.318672 -284.363314) (xy 97.319084 -284.353762) (xy 97.319084 -276.08022)
			(xy 97.318668 -276.070197) (xy 97.311001 -276.051676) (xy 97.296827 -276.037501) (xy 97.278307 -276.029833)
			(xy 97.268284 -276.02942) (xy 87.276178 -276.02942) (xy 87.266109 -276.028994) (xy 87.247509 -276.021276)
			(xy 87.24011 -276.014434) (xy 82.27949 -271.053814) (xy 82.272378 -271.046448) (xy 82.253582 -271.038828)
			(xy 59.881516 -271.038828) (xy 59.871453 -271.039267) (xy 59.852873 -271.047006) (xy 59.845448 -271.053814)
			(xy 59.36234 -271.536922) (xy 59.359632 -271.539701) (xy 59.355041 -271.545955) (xy 59.353196 -271.549368)
			(xy 59.34964 -271.556226) (xy 59.348116 -271.5641) (xy 59.348116 -271.564608) (xy 59.339047 -271.613039)
			(xy 59.312581 -271.707955) (xy 59.295284 -271.754092) (xy 59.291728 -271.762982) (xy 59.291728 -271.833086)
			(xy 59.291728 -271.834864) (xy 59.292414 -271.843684) (xy 59.299012 -271.860083) (xy 59.310803 -271.873252)
			(xy 59.318398 -271.87779) (xy 59.320684 -271.87906) (xy 59.41695 -271.92478) (xy 59.445906 -271.921224)
			(xy 59.457336 -271.91208) (xy 59.477882 -271.896116) (xy 59.523277 -271.870693) (xy 59.572322 -271.853327)
			(xy 59.6236 -271.844517) (xy 59.649614 -271.844008) (xy 59.674867 -271.844531) (xy 59.724685 -271.852846)
			(xy 59.772454 -271.869247) (xy 59.816872 -271.893287) (xy 59.856728 -271.92431) (xy 59.890935 -271.961469)
			(xy 59.918558 -272.003752) (xy 59.938846 -272.050005) (xy 59.951244 -272.098966) (xy 59.955415 -272.1493)
			(xy 59.955393 -272.14957) (xy 61.24373 -272.14957) (xy 61.24769 -272.100516) (xy 61.259467 -272.052732)
			(xy 61.278758 -272.007456) (xy 61.305061 -271.96586) (xy 61.337696 -271.929023) (xy 61.375817 -271.897898)
			(xy 61.418438 -271.873291) (xy 61.464454 -271.855839) (xy 61.512673 -271.845995) (xy 61.561848 -271.844014)
			(xy 61.610703 -271.849946) (xy 61.657974 -271.863638) (xy 61.702436 -271.884736) (xy 61.742939 -271.912692)
			(xy 61.778432 -271.946784) (xy 61.807997 -271.986128) (xy 61.830868 -272.029705) (xy 61.846452 -272.076386)
			(xy 61.854347 -272.124963) (xy 61.854842 -272.14957) (xy 63.143904 -272.14957) (xy 63.147864 -272.100516)
			(xy 63.159641 -272.052732) (xy 63.178932 -272.007456) (xy 63.205235 -271.96586) (xy 63.23787 -271.929023)
			(xy 63.275991 -271.897898) (xy 63.318612 -271.873291) (xy 63.364628 -271.855839) (xy 63.412847 -271.845995)
			(xy 63.462022 -271.844014) (xy 63.510877 -271.849946) (xy 63.558148 -271.863638) (xy 63.60261 -271.884736)
			(xy 63.643113 -271.912692) (xy 63.678606 -271.946784) (xy 63.708171 -271.986128) (xy 63.731042 -272.029705)
			(xy 63.746626 -272.076386) (xy 63.754521 -272.124963) (xy 63.755016 -272.14957) (xy 65.043824 -272.14957)
			(xy 65.047784 -272.100516) (xy 65.059561 -272.052732) (xy 65.078852 -272.007456) (xy 65.105155 -271.96586)
			(xy 65.13779 -271.929023) (xy 65.175911 -271.897898) (xy 65.218532 -271.873291) (xy 65.264548 -271.855839)
			(xy 65.312767 -271.845995) (xy 65.361942 -271.844014) (xy 65.410797 -271.849946) (xy 65.458068 -271.863638)
			(xy 65.50253 -271.884736) (xy 65.543033 -271.912692) (xy 65.578526 -271.946784) (xy 65.608091 -271.986128)
			(xy 65.630962 -272.029705) (xy 65.646546 -272.076386) (xy 65.654441 -272.124963) (xy 65.654936 -272.14957)
			(xy 66.943744 -272.14957) (xy 66.947704 -272.100516) (xy 66.959481 -272.052732) (xy 66.978772 -272.007456)
			(xy 67.005075 -271.96586) (xy 67.03771 -271.929023) (xy 67.075831 -271.897898) (xy 67.118452 -271.873291)
			(xy 67.164468 -271.855839) (xy 67.212687 -271.845995) (xy 67.261862 -271.844014) (xy 67.310717 -271.849946)
			(xy 67.357988 -271.863638) (xy 67.40245 -271.884736) (xy 67.442953 -271.912692) (xy 67.478446 -271.946784)
			(xy 67.508011 -271.986128) (xy 67.530882 -272.029705) (xy 67.546466 -272.076386) (xy 67.554361 -272.124963)
			(xy 67.554856 -272.14957) (xy 68.843918 -272.14957) (xy 68.847878 -272.100516) (xy 68.859655 -272.052732)
			(xy 68.878946 -272.007456) (xy 68.905249 -271.96586) (xy 68.937884 -271.929023) (xy 68.976005 -271.897898)
			(xy 69.018626 -271.873291) (xy 69.064642 -271.855839) (xy 69.112861 -271.845995) (xy 69.162036 -271.844014)
			(xy 69.210891 -271.849946) (xy 69.258162 -271.863638) (xy 69.302624 -271.884736) (xy 69.343127 -271.912692)
			(xy 69.37862 -271.946784) (xy 69.408185 -271.986128) (xy 69.431056 -272.029705) (xy 69.44664 -272.076386)
			(xy 69.454535 -272.124963) (xy 69.45503 -272.14957) (xy 70.743838 -272.14957) (xy 70.747798 -272.100516)
			(xy 70.759575 -272.052732) (xy 70.778866 -272.007456) (xy 70.805169 -271.96586) (xy 70.837804 -271.929023)
			(xy 70.875925 -271.897898) (xy 70.918546 -271.873291) (xy 70.964562 -271.855839) (xy 71.012781 -271.845995)
			(xy 71.061956 -271.844014) (xy 71.110811 -271.849946) (xy 71.158082 -271.863638) (xy 71.202544 -271.884736)
			(xy 71.243047 -271.912692) (xy 71.27854 -271.946784) (xy 71.308105 -271.986128) (xy 71.330976 -272.029705)
			(xy 71.34656 -272.076386) (xy 71.354455 -272.124963) (xy 71.35495 -272.14957) (xy 72.643758 -272.14957)
			(xy 72.647718 -272.100516) (xy 72.659495 -272.052732) (xy 72.678786 -272.007456) (xy 72.705089 -271.96586)
			(xy 72.737724 -271.929023) (xy 72.775845 -271.897898) (xy 72.818466 -271.873291) (xy 72.864482 -271.855839)
			(xy 72.912701 -271.845995) (xy 72.961876 -271.844014) (xy 73.010731 -271.849946) (xy 73.058002 -271.863638)
			(xy 73.102464 -271.884736) (xy 73.142967 -271.912692) (xy 73.17846 -271.946784) (xy 73.208025 -271.986128)
			(xy 73.230896 -272.029705) (xy 73.24648 -272.076386) (xy 73.254375 -272.124963) (xy 73.25487 -272.14957)
			(xy 74.543932 -272.14957) (xy 74.547892 -272.100516) (xy 74.559669 -272.052732) (xy 74.57896 -272.007456)
			(xy 74.605263 -271.96586) (xy 74.637898 -271.929023) (xy 74.676019 -271.897898) (xy 74.71864 -271.873291)
			(xy 74.764656 -271.855839) (xy 74.812875 -271.845995) (xy 74.86205 -271.844014) (xy 74.910905 -271.849946)
			(xy 74.958176 -271.863638) (xy 75.002638 -271.884736) (xy 75.043141 -271.912692) (xy 75.078634 -271.946784)
			(xy 75.108199 -271.986128) (xy 75.13107 -272.029705) (xy 75.146654 -272.076386) (xy 75.154549 -272.124963)
			(xy 75.155044 -272.14957) (xy 76.444106 -272.14957) (xy 76.448066 -272.100516) (xy 76.459843 -272.052732)
			(xy 76.479134 -272.007456) (xy 76.505437 -271.96586) (xy 76.538072 -271.929023) (xy 76.576193 -271.897898)
			(xy 76.618814 -271.873291) (xy 76.66483 -271.855839) (xy 76.713049 -271.845995) (xy 76.762224 -271.844014)
			(xy 76.811079 -271.849946) (xy 76.85835 -271.863638) (xy 76.902812 -271.884736) (xy 76.943315 -271.912692)
			(xy 76.978808 -271.946784) (xy 77.008373 -271.986128) (xy 77.031244 -272.029705) (xy 77.046828 -272.076386)
			(xy 77.054723 -272.124963) (xy 77.055218 -272.14957) (xy 78.344026 -272.14957) (xy 78.347986 -272.100516)
			(xy 78.359763 -272.052732) (xy 78.379054 -272.007456) (xy 78.405357 -271.96586) (xy 78.437992 -271.929023)
			(xy 78.476113 -271.897898) (xy 78.518734 -271.873291) (xy 78.56475 -271.855839) (xy 78.612969 -271.845995)
			(xy 78.662144 -271.844014) (xy 78.710999 -271.849946) (xy 78.75827 -271.863638) (xy 78.802732 -271.884736)
			(xy 78.843235 -271.912692) (xy 78.878728 -271.946784) (xy 78.908293 -271.986128) (xy 78.931164 -272.029705)
			(xy 78.946748 -272.076386) (xy 78.954643 -272.124963) (xy 78.955138 -272.14957) (xy 80.243946 -272.14957)
			(xy 80.247906 -272.100516) (xy 80.259683 -272.052732) (xy 80.278974 -272.007456) (xy 80.305277 -271.96586)
			(xy 80.337912 -271.929023) (xy 80.376033 -271.897898) (xy 80.418654 -271.873291) (xy 80.46467 -271.855839)
			(xy 80.512889 -271.845995) (xy 80.562064 -271.844014) (xy 80.610919 -271.849946) (xy 80.65819 -271.863638)
			(xy 80.702652 -271.884736) (xy 80.743155 -271.912692) (xy 80.778648 -271.946784) (xy 80.808213 -271.986128)
			(xy 80.831084 -272.029705) (xy 80.846668 -272.076386) (xy 80.854563 -272.124963) (xy 80.855058 -272.14957)
			(xy 80.854563 -272.174177) (xy 80.846668 -272.222754) (xy 80.831084 -272.269435) (xy 80.808213 -272.313012)
			(xy 80.778648 -272.352356) (xy 80.743155 -272.386448) (xy 80.702652 -272.414404) (xy 80.65819 -272.435502)
			(xy 80.610919 -272.449194) (xy 80.562064 -272.455126) (xy 80.512889 -272.453145) (xy 80.46467 -272.443301)
			(xy 80.418654 -272.425849) (xy 80.376033 -272.401242) (xy 80.337912 -272.370117) (xy 80.305277 -272.33328)
			(xy 80.278974 -272.291684) (xy 80.259683 -272.246408) (xy 80.247906 -272.198624) (xy 80.243946 -272.14957)
			(xy 78.955138 -272.14957) (xy 78.954643 -272.174177) (xy 78.946748 -272.222754) (xy 78.931164 -272.269435)
			(xy 78.908293 -272.313012) (xy 78.878728 -272.352356) (xy 78.843235 -272.386448) (xy 78.802732 -272.414404)
			(xy 78.75827 -272.435502) (xy 78.710999 -272.449194) (xy 78.662144 -272.455126) (xy 78.612969 -272.453145)
			(xy 78.56475 -272.443301) (xy 78.518734 -272.425849) (xy 78.476113 -272.401242) (xy 78.437992 -272.370117)
			(xy 78.405357 -272.33328) (xy 78.379054 -272.291684) (xy 78.359763 -272.246408) (xy 78.347986 -272.198624)
			(xy 78.344026 -272.14957) (xy 77.055218 -272.14957) (xy 77.054723 -272.174177) (xy 77.046828 -272.222754)
			(xy 77.031244 -272.269435) (xy 77.008373 -272.313012) (xy 76.978808 -272.352356) (xy 76.943315 -272.386448)
			(xy 76.902812 -272.414404) (xy 76.85835 -272.435502) (xy 76.811079 -272.449194) (xy 76.762224 -272.455126)
			(xy 76.713049 -272.453145) (xy 76.66483 -272.443301) (xy 76.618814 -272.425849) (xy 76.576193 -272.401242)
			(xy 76.538072 -272.370117) (xy 76.505437 -272.33328) (xy 76.479134 -272.291684) (xy 76.459843 -272.246408)
			(xy 76.448066 -272.198624) (xy 76.444106 -272.14957) (xy 75.155044 -272.14957) (xy 75.154549 -272.174177)
			(xy 75.146654 -272.222754) (xy 75.13107 -272.269435) (xy 75.108199 -272.313012) (xy 75.078634 -272.352356)
			(xy 75.043141 -272.386448) (xy 75.002638 -272.414404) (xy 74.958176 -272.435502) (xy 74.910905 -272.449194)
			(xy 74.86205 -272.455126) (xy 74.812875 -272.453145) (xy 74.764656 -272.443301) (xy 74.71864 -272.425849)
			(xy 74.676019 -272.401242) (xy 74.637898 -272.370117) (xy 74.605263 -272.33328) (xy 74.57896 -272.291684)
			(xy 74.559669 -272.246408) (xy 74.547892 -272.198624) (xy 74.543932 -272.14957) (xy 73.25487 -272.14957)
			(xy 73.254375 -272.174177) (xy 73.24648 -272.222754) (xy 73.230896 -272.269435) (xy 73.208025 -272.313012)
			(xy 73.17846 -272.352356) (xy 73.142967 -272.386448) (xy 73.102464 -272.414404) (xy 73.058002 -272.435502)
			(xy 73.010731 -272.449194) (xy 72.961876 -272.455126) (xy 72.912701 -272.453145) (xy 72.864482 -272.443301)
			(xy 72.818466 -272.425849) (xy 72.775845 -272.401242) (xy 72.737724 -272.370117) (xy 72.705089 -272.33328)
			(xy 72.678786 -272.291684) (xy 72.659495 -272.246408) (xy 72.647718 -272.198624) (xy 72.643758 -272.14957)
			(xy 71.35495 -272.14957) (xy 71.354455 -272.174177) (xy 71.34656 -272.222754) (xy 71.330976 -272.269435)
			(xy 71.308105 -272.313012) (xy 71.27854 -272.352356) (xy 71.243047 -272.386448) (xy 71.202544 -272.414404)
			(xy 71.158082 -272.435502) (xy 71.110811 -272.449194) (xy 71.061956 -272.455126) (xy 71.012781 -272.453145)
			(xy 70.964562 -272.443301) (xy 70.918546 -272.425849) (xy 70.875925 -272.401242) (xy 70.837804 -272.370117)
			(xy 70.805169 -272.33328) (xy 70.778866 -272.291684) (xy 70.759575 -272.246408) (xy 70.747798 -272.198624)
			(xy 70.743838 -272.14957) (xy 69.45503 -272.14957) (xy 69.454535 -272.174177) (xy 69.44664 -272.222754)
			(xy 69.431056 -272.269435) (xy 69.408185 -272.313012) (xy 69.37862 -272.352356) (xy 69.343127 -272.386448)
			(xy 69.302624 -272.414404) (xy 69.258162 -272.435502) (xy 69.210891 -272.449194) (xy 69.162036 -272.455126)
			(xy 69.112861 -272.453145) (xy 69.064642 -272.443301) (xy 69.018626 -272.425849) (xy 68.976005 -272.401242)
			(xy 68.937884 -272.370117) (xy 68.905249 -272.33328) (xy 68.878946 -272.291684) (xy 68.859655 -272.246408)
			(xy 68.847878 -272.198624) (xy 68.843918 -272.14957) (xy 67.554856 -272.14957) (xy 67.554361 -272.174177)
			(xy 67.546466 -272.222754) (xy 67.530882 -272.269435) (xy 67.508011 -272.313012) (xy 67.478446 -272.352356)
			(xy 67.442953 -272.386448) (xy 67.40245 -272.414404) (xy 67.357988 -272.435502) (xy 67.310717 -272.449194)
			(xy 67.261862 -272.455126) (xy 67.212687 -272.453145) (xy 67.164468 -272.443301) (xy 67.118452 -272.425849)
			(xy 67.075831 -272.401242) (xy 67.03771 -272.370117) (xy 67.005075 -272.33328) (xy 66.978772 -272.291684)
			(xy 66.959481 -272.246408) (xy 66.947704 -272.198624) (xy 66.943744 -272.14957) (xy 65.654936 -272.14957)
			(xy 65.654441 -272.174177) (xy 65.646546 -272.222754) (xy 65.630962 -272.269435) (xy 65.608091 -272.313012)
			(xy 65.578526 -272.352356) (xy 65.543033 -272.386448) (xy 65.50253 -272.414404) (xy 65.458068 -272.435502)
			(xy 65.410797 -272.449194) (xy 65.361942 -272.455126) (xy 65.312767 -272.453145) (xy 65.264548 -272.443301)
			(xy 65.218532 -272.425849) (xy 65.175911 -272.401242) (xy 65.13779 -272.370117) (xy 65.105155 -272.33328)
			(xy 65.078852 -272.291684) (xy 65.059561 -272.246408) (xy 65.047784 -272.198624) (xy 65.043824 -272.14957)
			(xy 63.755016 -272.14957) (xy 63.754521 -272.174177) (xy 63.746626 -272.222754) (xy 63.731042 -272.269435)
			(xy 63.708171 -272.313012) (xy 63.678606 -272.352356) (xy 63.643113 -272.386448) (xy 63.60261 -272.414404)
			(xy 63.558148 -272.435502) (xy 63.510877 -272.449194) (xy 63.462022 -272.455126) (xy 63.412847 -272.453145)
			(xy 63.364628 -272.443301) (xy 63.318612 -272.425849) (xy 63.275991 -272.401242) (xy 63.23787 -272.370117)
			(xy 63.205235 -272.33328) (xy 63.178932 -272.291684) (xy 63.159641 -272.246408) (xy 63.147864 -272.198624)
			(xy 63.143904 -272.14957) (xy 61.854842 -272.14957) (xy 61.854347 -272.174177) (xy 61.846452 -272.222754)
			(xy 61.830868 -272.269435) (xy 61.807997 -272.313012) (xy 61.778432 -272.352356) (xy 61.742939 -272.386448)
			(xy 61.702436 -272.414404) (xy 61.657974 -272.435502) (xy 61.610703 -272.449194) (xy 61.561848 -272.455126)
			(xy 61.512673 -272.453145) (xy 61.464454 -272.443301) (xy 61.418438 -272.425849) (xy 61.375817 -272.401242)
			(xy 61.337696 -272.370117) (xy 61.305061 -272.33328) (xy 61.278758 -272.291684) (xy 61.259467 -272.246408)
			(xy 61.24769 -272.198624) (xy 61.24373 -272.14957) (xy 59.955393 -272.14957) (xy 59.951244 -272.199634)
			(xy 59.938846 -272.248595) (xy 59.918558 -272.294848) (xy 59.890935 -272.337131) (xy 59.856728 -272.37429)
			(xy 59.816872 -272.405313) (xy 59.772454 -272.429353) (xy 59.724685 -272.445754) (xy 59.674867 -272.454069)
			(xy 59.649614 -272.454624) (xy 59.6236 -272.454102) (xy 59.572322 -272.445296) (xy 59.523276 -272.427936)
			(xy 59.477876 -272.402523) (xy 59.457336 -272.386552) (xy 59.445906 -272.377408) (xy 59.41695 -272.373852)
			(xy 59.320684 -272.419572) (xy 59.318398 -272.420842) (xy 59.310804 -272.425374) (xy 59.299036 -272.438557)
			(xy 59.292443 -272.454952) (xy 59.291728 -272.463768) (xy 59.291728 -272.755868) (xy 59.292342 -272.767193)
			(xy 59.302114 -272.787625) (xy 59.310524 -272.795238) (xy 59.314842 -272.798794) (xy 59.401202 -272.841974)
			(xy 59.409659 -272.845776) (xy 59.428086 -272.84769) (xy 59.445997 -272.842952) (xy 59.45378 -272.83791)
			(xy 59.454288 -272.837402) (xy 59.454542 -272.837148) (xy 59.475833 -272.821975) (xy 59.522226 -272.797876)
			(xy 59.571861 -272.781463) (xy 59.623475 -272.773151) (xy 59.649614 -272.772632) (xy 59.675299 -272.773137)
			(xy 59.726035 -272.781175) (xy 59.77489 -272.79705) (xy 59.82066 -272.820373) (xy 59.862218 -272.850568)
			(xy 59.898541 -272.886893) (xy 59.928734 -272.928452) (xy 59.952055 -272.974223) (xy 59.967929 -273.023078)
			(xy 59.975964 -273.073815) (xy 59.975964 -273.099784) (xy 60.294024 -273.099784) (xy 60.297984 -273.05073)
			(xy 60.309761 -273.002946) (xy 60.329052 -272.95767) (xy 60.355355 -272.916074) (xy 60.38799 -272.879237)
			(xy 60.426111 -272.848112) (xy 60.468732 -272.823505) (xy 60.514748 -272.806053) (xy 60.562967 -272.796209)
			(xy 60.612142 -272.794228) (xy 60.660997 -272.80016) (xy 60.708268 -272.813852) (xy 60.75273 -272.83495)
			(xy 60.793233 -272.862906) (xy 60.828726 -272.896998) (xy 60.858291 -272.936342) (xy 60.881162 -272.979919)
			(xy 60.896746 -273.0266) (xy 60.904641 -273.075177) (xy 60.905136 -273.099784) (xy 60.904641 -273.124391)
			(xy 60.904462 -273.125492) (xy 61.222886 -273.125492) (xy 61.222886 -273.074076) (xy 61.230929 -273.023294)
			(xy 61.246817 -272.974395) (xy 61.27016 -272.928583) (xy 61.300381 -272.886987) (xy 61.336737 -272.850631)
			(xy 61.378333 -272.82041) (xy 61.424145 -272.797067) (xy 61.473044 -272.781179) (xy 61.523826 -272.773136)
			(xy 61.575242 -272.773136) (xy 61.626024 -272.781179) (xy 61.674923 -272.797067) (xy 61.720735 -272.82041)
			(xy 61.762331 -272.850631) (xy 61.798687 -272.886987) (xy 61.828908 -272.928583) (xy 61.852251 -272.974395)
			(xy 61.868139 -273.023294) (xy 61.876182 -273.074076) (xy 61.876686 -273.099784) (xy 62.193944 -273.099784)
			(xy 62.197904 -273.05073) (xy 62.209681 -273.002946) (xy 62.228972 -272.95767) (xy 62.255275 -272.916074)
			(xy 62.28791 -272.879237) (xy 62.326031 -272.848112) (xy 62.368652 -272.823505) (xy 62.414668 -272.806053)
			(xy 62.462887 -272.796209) (xy 62.512062 -272.794228) (xy 62.560917 -272.80016) (xy 62.608188 -272.813852)
			(xy 62.65265 -272.83495) (xy 62.693153 -272.862906) (xy 62.728646 -272.896998) (xy 62.758211 -272.936342)
			(xy 62.781082 -272.979919) (xy 62.796666 -273.0266) (xy 62.804561 -273.075177) (xy 62.805056 -273.099784)
			(xy 62.804561 -273.124391) (xy 62.804382 -273.125492) (xy 63.12306 -273.125492) (xy 63.12306 -273.074076)
			(xy 63.131103 -273.023294) (xy 63.146991 -272.974395) (xy 63.170334 -272.928583) (xy 63.200555 -272.886987)
			(xy 63.236911 -272.850631) (xy 63.278507 -272.82041) (xy 63.324319 -272.797067) (xy 63.373218 -272.781179)
			(xy 63.424 -272.773136) (xy 63.475416 -272.773136) (xy 63.526198 -272.781179) (xy 63.575097 -272.797067)
			(xy 63.620909 -272.82041) (xy 63.662505 -272.850631) (xy 63.698861 -272.886987) (xy 63.729082 -272.928583)
			(xy 63.752425 -272.974395) (xy 63.768313 -273.023294) (xy 63.776356 -273.074076) (xy 63.77686 -273.099784)
			(xy 64.094118 -273.099784) (xy 64.098078 -273.05073) (xy 64.109855 -273.002946) (xy 64.129146 -272.95767)
			(xy 64.155449 -272.916074) (xy 64.188084 -272.879237) (xy 64.226205 -272.848112) (xy 64.268826 -272.823505)
			(xy 64.314842 -272.806053) (xy 64.363061 -272.796209) (xy 64.412236 -272.794228) (xy 64.461091 -272.80016)
			(xy 64.508362 -272.813852) (xy 64.552824 -272.83495) (xy 64.593327 -272.862906) (xy 64.62882 -272.896998)
			(xy 64.658385 -272.936342) (xy 64.681256 -272.979919) (xy 64.69684 -273.0266) (xy 64.704735 -273.075177)
			(xy 64.70523 -273.099784) (xy 64.704735 -273.124391) (xy 64.704556 -273.125492) (xy 65.02298 -273.125492)
			(xy 65.02298 -273.074076) (xy 65.031023 -273.023294) (xy 65.046911 -272.974395) (xy 65.070254 -272.928583)
			(xy 65.100475 -272.886987) (xy 65.136831 -272.850631) (xy 65.178427 -272.82041) (xy 65.224239 -272.797067)
			(xy 65.273138 -272.781179) (xy 65.32392 -272.773136) (xy 65.375336 -272.773136) (xy 65.426118 -272.781179)
			(xy 65.475017 -272.797067) (xy 65.520829 -272.82041) (xy 65.562425 -272.850631) (xy 65.598781 -272.886987)
			(xy 65.629002 -272.928583) (xy 65.652345 -272.974395) (xy 65.668233 -273.023294) (xy 65.676276 -273.074076)
			(xy 65.67678 -273.099784) (xy 65.994038 -273.099784) (xy 65.997998 -273.05073) (xy 66.009775 -273.002946)
			(xy 66.029066 -272.95767) (xy 66.055369 -272.916074) (xy 66.088004 -272.879237) (xy 66.126125 -272.848112)
			(xy 66.168746 -272.823505) (xy 66.214762 -272.806053) (xy 66.262981 -272.796209) (xy 66.312156 -272.794228)
			(xy 66.361011 -272.80016) (xy 66.408282 -272.813852) (xy 66.452744 -272.83495) (xy 66.493247 -272.862906)
			(xy 66.52874 -272.896998) (xy 66.558305 -272.936342) (xy 66.581176 -272.979919) (xy 66.59676 -273.0266)
			(xy 66.604655 -273.075177) (xy 66.60515 -273.099784) (xy 66.604655 -273.124391) (xy 66.604476 -273.125492)
			(xy 66.9229 -273.125492) (xy 66.9229 -273.074076) (xy 66.930943 -273.023294) (xy 66.946831 -272.974395)
			(xy 66.970174 -272.928583) (xy 67.000395 -272.886987) (xy 67.036751 -272.850631) (xy 67.078347 -272.82041)
			(xy 67.124159 -272.797067) (xy 67.173058 -272.781179) (xy 67.22384 -272.773136) (xy 67.275256 -272.773136)
			(xy 67.326038 -272.781179) (xy 67.374937 -272.797067) (xy 67.420749 -272.82041) (xy 67.462345 -272.850631)
			(xy 67.498701 -272.886987) (xy 67.528922 -272.928583) (xy 67.552265 -272.974395) (xy 67.568153 -273.023294)
			(xy 67.576196 -273.074076) (xy 67.5767 -273.099784) (xy 67.893958 -273.099784) (xy 67.897918 -273.05073)
			(xy 67.909695 -273.002946) (xy 67.928986 -272.95767) (xy 67.955289 -272.916074) (xy 67.987924 -272.879237)
			(xy 68.026045 -272.848112) (xy 68.068666 -272.823505) (xy 68.114682 -272.806053) (xy 68.162901 -272.796209)
			(xy 68.212076 -272.794228) (xy 68.260931 -272.80016) (xy 68.308202 -272.813852) (xy 68.352664 -272.83495)
			(xy 68.393167 -272.862906) (xy 68.42866 -272.896998) (xy 68.458225 -272.936342) (xy 68.481096 -272.979919)
			(xy 68.49668 -273.0266) (xy 68.504575 -273.075177) (xy 68.50507 -273.099784) (xy 68.504575 -273.124391)
			(xy 68.504396 -273.125492) (xy 68.823074 -273.125492) (xy 68.823074 -273.074076) (xy 68.831117 -273.023294)
			(xy 68.847005 -272.974395) (xy 68.870348 -272.928583) (xy 68.900569 -272.886987) (xy 68.936925 -272.850631)
			(xy 68.978521 -272.82041) (xy 69.024333 -272.797067) (xy 69.073232 -272.781179) (xy 69.124014 -272.773136)
			(xy 69.17543 -272.773136) (xy 69.226212 -272.781179) (xy 69.275111 -272.797067) (xy 69.320923 -272.82041)
			(xy 69.362519 -272.850631) (xy 69.398875 -272.886987) (xy 69.429096 -272.928583) (xy 69.452439 -272.974395)
			(xy 69.468327 -273.023294) (xy 69.47637 -273.074076) (xy 69.476874 -273.099784) (xy 69.794132 -273.099784)
			(xy 69.798092 -273.05073) (xy 69.809869 -273.002946) (xy 69.82916 -272.95767) (xy 69.855463 -272.916074)
			(xy 69.888098 -272.879237) (xy 69.926219 -272.848112) (xy 69.96884 -272.823505) (xy 70.014856 -272.806053)
			(xy 70.063075 -272.796209) (xy 70.11225 -272.794228) (xy 70.161105 -272.80016) (xy 70.208376 -272.813852)
			(xy 70.252838 -272.83495) (xy 70.293341 -272.862906) (xy 70.328834 -272.896998) (xy 70.358399 -272.936342)
			(xy 70.38127 -272.979919) (xy 70.396854 -273.0266) (xy 70.404749 -273.075177) (xy 70.405244 -273.099784)
			(xy 70.404749 -273.124391) (xy 70.40457 -273.125492) (xy 70.722994 -273.125492) (xy 70.722994 -273.074076)
			(xy 70.731037 -273.023294) (xy 70.746925 -272.974395) (xy 70.770268 -272.928583) (xy 70.800489 -272.886987)
			(xy 70.836845 -272.850631) (xy 70.878441 -272.82041) (xy 70.924253 -272.797067) (xy 70.973152 -272.781179)
			(xy 71.023934 -272.773136) (xy 71.07535 -272.773136) (xy 71.126132 -272.781179) (xy 71.175031 -272.797067)
			(xy 71.220843 -272.82041) (xy 71.262439 -272.850631) (xy 71.298795 -272.886987) (xy 71.329016 -272.928583)
			(xy 71.352359 -272.974395) (xy 71.368247 -273.023294) (xy 71.37629 -273.074076) (xy 71.376794 -273.099784)
			(xy 71.694052 -273.099784) (xy 71.698012 -273.05073) (xy 71.709789 -273.002946) (xy 71.72908 -272.95767)
			(xy 71.755383 -272.916074) (xy 71.788018 -272.879237) (xy 71.826139 -272.848112) (xy 71.86876 -272.823505)
			(xy 71.914776 -272.806053) (xy 71.962995 -272.796209) (xy 72.01217 -272.794228) (xy 72.061025 -272.80016)
			(xy 72.108296 -272.813852) (xy 72.152758 -272.83495) (xy 72.193261 -272.862906) (xy 72.228754 -272.896998)
			(xy 72.258319 -272.936342) (xy 72.28119 -272.979919) (xy 72.296774 -273.0266) (xy 72.304669 -273.075177)
			(xy 72.305164 -273.099784) (xy 72.304669 -273.124391) (xy 72.30449 -273.125492) (xy 72.622914 -273.125492)
			(xy 72.622914 -273.074076) (xy 72.630957 -273.023294) (xy 72.646845 -272.974395) (xy 72.670188 -272.928583)
			(xy 72.700409 -272.886987) (xy 72.736765 -272.850631) (xy 72.778361 -272.82041) (xy 72.824173 -272.797067)
			(xy 72.873072 -272.781179) (xy 72.923854 -272.773136) (xy 72.97527 -272.773136) (xy 73.026052 -272.781179)
			(xy 73.074951 -272.797067) (xy 73.120763 -272.82041) (xy 73.162359 -272.850631) (xy 73.198715 -272.886987)
			(xy 73.228936 -272.928583) (xy 73.252279 -272.974395) (xy 73.268167 -273.023294) (xy 73.27621 -273.074076)
			(xy 73.276714 -273.099784) (xy 73.593972 -273.099784) (xy 73.597932 -273.05073) (xy 73.609709 -273.002946)
			(xy 73.629 -272.95767) (xy 73.655303 -272.916074) (xy 73.687938 -272.879237) (xy 73.726059 -272.848112)
			(xy 73.76868 -272.823505) (xy 73.814696 -272.806053) (xy 73.862915 -272.796209) (xy 73.91209 -272.794228)
			(xy 73.960945 -272.80016) (xy 74.008216 -272.813852) (xy 74.052678 -272.83495) (xy 74.093181 -272.862906)
			(xy 74.128674 -272.896998) (xy 74.158239 -272.936342) (xy 74.18111 -272.979919) (xy 74.196694 -273.0266)
			(xy 74.204589 -273.075177) (xy 74.205084 -273.099784) (xy 74.204589 -273.124391) (xy 74.20441 -273.125492)
			(xy 74.523088 -273.125492) (xy 74.523088 -273.074076) (xy 74.531131 -273.023294) (xy 74.547019 -272.974395)
			(xy 74.570362 -272.928583) (xy 74.600583 -272.886987) (xy 74.636939 -272.850631) (xy 74.678535 -272.82041)
			(xy 74.724347 -272.797067) (xy 74.773246 -272.781179) (xy 74.824028 -272.773136) (xy 74.875444 -272.773136)
			(xy 74.926226 -272.781179) (xy 74.975125 -272.797067) (xy 75.020937 -272.82041) (xy 75.062533 -272.850631)
			(xy 75.098889 -272.886987) (xy 75.12911 -272.928583) (xy 75.152453 -272.974395) (xy 75.168341 -273.023294)
			(xy 75.176384 -273.074076) (xy 75.176888 -273.099784) (xy 75.494146 -273.099784) (xy 75.498106 -273.05073)
			(xy 75.509883 -273.002946) (xy 75.529174 -272.95767) (xy 75.555477 -272.916074) (xy 75.588112 -272.879237)
			(xy 75.626233 -272.848112) (xy 75.668854 -272.823505) (xy 75.71487 -272.806053) (xy 75.763089 -272.796209)
			(xy 75.812264 -272.794228) (xy 75.861119 -272.80016) (xy 75.90839 -272.813852) (xy 75.952852 -272.83495)
			(xy 75.993355 -272.862906) (xy 76.028848 -272.896998) (xy 76.058413 -272.936342) (xy 76.081284 -272.979919)
			(xy 76.096868 -273.0266) (xy 76.104763 -273.075177) (xy 76.105258 -273.099784) (xy 76.104763 -273.124391)
			(xy 76.104584 -273.125492) (xy 76.423008 -273.125492) (xy 76.423008 -273.074076) (xy 76.431051 -273.023294)
			(xy 76.446939 -272.974395) (xy 76.470282 -272.928583) (xy 76.500503 -272.886987) (xy 76.536859 -272.850631)
			(xy 76.578455 -272.82041) (xy 76.624267 -272.797067) (xy 76.673166 -272.781179) (xy 76.723948 -272.773136)
			(xy 76.775364 -272.773136) (xy 76.826146 -272.781179) (xy 76.875045 -272.797067) (xy 76.920857 -272.82041)
			(xy 76.962453 -272.850631) (xy 76.998809 -272.886987) (xy 77.02903 -272.928583) (xy 77.052373 -272.974395)
			(xy 77.068261 -273.023294) (xy 77.076304 -273.074076) (xy 77.076808 -273.099784) (xy 77.39432 -273.099784)
			(xy 77.39828 -273.05073) (xy 77.410057 -273.002946) (xy 77.429348 -272.95767) (xy 77.455651 -272.916074)
			(xy 77.488286 -272.879237) (xy 77.526407 -272.848112) (xy 77.569028 -272.823505) (xy 77.615044 -272.806053)
			(xy 77.663263 -272.796209) (xy 77.712438 -272.794228) (xy 77.761293 -272.80016) (xy 77.808564 -272.813852)
			(xy 77.853026 -272.83495) (xy 77.893529 -272.862906) (xy 77.929022 -272.896998) (xy 77.958587 -272.936342)
			(xy 77.981458 -272.979919) (xy 77.997042 -273.0266) (xy 78.004937 -273.075177) (xy 78.005432 -273.099784)
			(xy 78.004937 -273.124391) (xy 78.004758 -273.125492) (xy 78.322928 -273.125492) (xy 78.322928 -273.074076)
			(xy 78.330971 -273.023294) (xy 78.346859 -272.974395) (xy 78.370202 -272.928583) (xy 78.400423 -272.886987)
			(xy 78.436779 -272.850631) (xy 78.478375 -272.82041) (xy 78.524187 -272.797067) (xy 78.573086 -272.781179)
			(xy 78.623868 -272.773136) (xy 78.675284 -272.773136) (xy 78.726066 -272.781179) (xy 78.774965 -272.797067)
			(xy 78.820777 -272.82041) (xy 78.862373 -272.850631) (xy 78.898729 -272.886987) (xy 78.92895 -272.928583)
			(xy 78.952293 -272.974395) (xy 78.968181 -273.023294) (xy 78.976224 -273.074076) (xy 78.976728 -273.099784)
			(xy 79.29424 -273.099784) (xy 79.2982 -273.05073) (xy 79.309977 -273.002946) (xy 79.329268 -272.95767)
			(xy 79.355571 -272.916074) (xy 79.388206 -272.879237) (xy 79.426327 -272.848112) (xy 79.468948 -272.823505)
			(xy 79.514964 -272.806053) (xy 79.563183 -272.796209) (xy 79.612358 -272.794228) (xy 79.661213 -272.80016)
			(xy 79.708484 -272.813852) (xy 79.752946 -272.83495) (xy 79.793449 -272.862906) (xy 79.828942 -272.896998)
			(xy 79.858507 -272.936342) (xy 79.881378 -272.979919) (xy 79.896962 -273.0266) (xy 79.904857 -273.075177)
			(xy 79.905352 -273.099784) (xy 79.904857 -273.124391) (xy 79.904678 -273.125492) (xy 80.222848 -273.125492)
			(xy 80.222848 -273.074076) (xy 80.230891 -273.023294) (xy 80.246779 -272.974395) (xy 80.270122 -272.928583)
			(xy 80.300343 -272.886987) (xy 80.336699 -272.850631) (xy 80.378295 -272.82041) (xy 80.424107 -272.797067)
			(xy 80.473006 -272.781179) (xy 80.523788 -272.773136) (xy 80.575204 -272.773136) (xy 80.625986 -272.781179)
			(xy 80.674885 -272.797067) (xy 80.720697 -272.82041) (xy 80.762293 -272.850631) (xy 80.798649 -272.886987)
			(xy 80.82887 -272.928583) (xy 80.852213 -272.974395) (xy 80.868101 -273.023294) (xy 80.876144 -273.074076)
			(xy 80.876648 -273.099784) (xy 81.19416 -273.099784) (xy 81.19812 -273.05073) (xy 81.209897 -273.002946)
			(xy 81.229188 -272.95767) (xy 81.255491 -272.916074) (xy 81.288126 -272.879237) (xy 81.326247 -272.848112)
			(xy 81.368868 -272.823505) (xy 81.414884 -272.806053) (xy 81.463103 -272.796209) (xy 81.512278 -272.794228)
			(xy 81.561133 -272.80016) (xy 81.608404 -272.813852) (xy 81.652866 -272.83495) (xy 81.693369 -272.862906)
			(xy 81.728862 -272.896998) (xy 81.758427 -272.936342) (xy 81.781298 -272.979919) (xy 81.796882 -273.0266)
			(xy 81.804777 -273.075177) (xy 81.805272 -273.099784) (xy 81.804777 -273.124391) (xy 81.796882 -273.172968)
			(xy 81.781298 -273.219649) (xy 81.758427 -273.263226) (xy 81.728862 -273.30257) (xy 81.693369 -273.336662)
			(xy 81.652866 -273.364618) (xy 81.608404 -273.385716) (xy 81.561133 -273.399408) (xy 81.512278 -273.40534)
			(xy 81.463103 -273.403359) (xy 81.414884 -273.393515) (xy 81.368868 -273.376063) (xy 81.326247 -273.351456)
			(xy 81.288126 -273.320331) (xy 81.255491 -273.283494) (xy 81.229188 -273.241898) (xy 81.209897 -273.196622)
			(xy 81.19812 -273.148838) (xy 81.19416 -273.099784) (xy 80.876648 -273.099784) (xy 80.876144 -273.125492)
			(xy 80.868101 -273.176274) (xy 80.852213 -273.225173) (xy 80.82887 -273.270985) (xy 80.798649 -273.312581)
			(xy 80.762293 -273.348937) (xy 80.720697 -273.379158) (xy 80.674885 -273.402501) (xy 80.625986 -273.418389)
			(xy 80.575204 -273.426432) (xy 80.523788 -273.426432) (xy 80.473006 -273.418389) (xy 80.424107 -273.402501)
			(xy 80.378295 -273.379158) (xy 80.336699 -273.348937) (xy 80.300343 -273.312581) (xy 80.270122 -273.270985)
			(xy 80.246779 -273.225173) (xy 80.230891 -273.176274) (xy 80.222848 -273.125492) (xy 79.904678 -273.125492)
			(xy 79.896962 -273.172968) (xy 79.881378 -273.219649) (xy 79.858507 -273.263226) (xy 79.828942 -273.30257)
			(xy 79.793449 -273.336662) (xy 79.752946 -273.364618) (xy 79.708484 -273.385716) (xy 79.661213 -273.399408)
			(xy 79.612358 -273.40534) (xy 79.563183 -273.403359) (xy 79.514964 -273.393515) (xy 79.468948 -273.376063)
			(xy 79.426327 -273.351456) (xy 79.388206 -273.320331) (xy 79.355571 -273.283494) (xy 79.329268 -273.241898)
			(xy 79.309977 -273.196622) (xy 79.2982 -273.148838) (xy 79.29424 -273.099784) (xy 78.976728 -273.099784)
			(xy 78.976224 -273.125492) (xy 78.968181 -273.176274) (xy 78.952293 -273.225173) (xy 78.92895 -273.270985)
			(xy 78.898729 -273.312581) (xy 78.862373 -273.348937) (xy 78.820777 -273.379158) (xy 78.774965 -273.402501)
			(xy 78.726066 -273.418389) (xy 78.675284 -273.426432) (xy 78.623868 -273.426432) (xy 78.573086 -273.418389)
			(xy 78.524187 -273.402501) (xy 78.478375 -273.379158) (xy 78.436779 -273.348937) (xy 78.400423 -273.312581)
			(xy 78.370202 -273.270985) (xy 78.346859 -273.225173) (xy 78.330971 -273.176274) (xy 78.322928 -273.125492)
			(xy 78.004758 -273.125492) (xy 77.997042 -273.172968) (xy 77.981458 -273.219649) (xy 77.958587 -273.263226)
			(xy 77.929022 -273.30257) (xy 77.893529 -273.336662) (xy 77.853026 -273.364618) (xy 77.808564 -273.385716)
			(xy 77.761293 -273.399408) (xy 77.712438 -273.40534) (xy 77.663263 -273.403359) (xy 77.615044 -273.393515)
			(xy 77.569028 -273.376063) (xy 77.526407 -273.351456) (xy 77.488286 -273.320331) (xy 77.455651 -273.283494)
			(xy 77.429348 -273.241898) (xy 77.410057 -273.196622) (xy 77.39828 -273.148838) (xy 77.39432 -273.099784)
			(xy 77.076808 -273.099784) (xy 77.076304 -273.125492) (xy 77.068261 -273.176274) (xy 77.052373 -273.225173)
			(xy 77.02903 -273.270985) (xy 76.998809 -273.312581) (xy 76.962453 -273.348937) (xy 76.920857 -273.379158)
			(xy 76.875045 -273.402501) (xy 76.826146 -273.418389) (xy 76.775364 -273.426432) (xy 76.723948 -273.426432)
			(xy 76.673166 -273.418389) (xy 76.624267 -273.402501) (xy 76.578455 -273.379158) (xy 76.536859 -273.348937)
			(xy 76.500503 -273.312581) (xy 76.470282 -273.270985) (xy 76.446939 -273.225173) (xy 76.431051 -273.176274)
			(xy 76.423008 -273.125492) (xy 76.104584 -273.125492) (xy 76.096868 -273.172968) (xy 76.081284 -273.219649)
			(xy 76.058413 -273.263226) (xy 76.028848 -273.30257) (xy 75.993355 -273.336662) (xy 75.952852 -273.364618)
			(xy 75.90839 -273.385716) (xy 75.861119 -273.399408) (xy 75.812264 -273.40534) (xy 75.763089 -273.403359)
			(xy 75.71487 -273.393515) (xy 75.668854 -273.376063) (xy 75.626233 -273.351456) (xy 75.588112 -273.320331)
			(xy 75.555477 -273.283494) (xy 75.529174 -273.241898) (xy 75.509883 -273.196622) (xy 75.498106 -273.148838)
			(xy 75.494146 -273.099784) (xy 75.176888 -273.099784) (xy 75.176384 -273.125492) (xy 75.168341 -273.176274)
			(xy 75.152453 -273.225173) (xy 75.12911 -273.270985) (xy 75.098889 -273.312581) (xy 75.062533 -273.348937)
			(xy 75.020937 -273.379158) (xy 74.975125 -273.402501) (xy 74.926226 -273.418389) (xy 74.875444 -273.426432)
			(xy 74.824028 -273.426432) (xy 74.773246 -273.418389) (xy 74.724347 -273.402501) (xy 74.678535 -273.379158)
			(xy 74.636939 -273.348937) (xy 74.600583 -273.312581) (xy 74.570362 -273.270985) (xy 74.547019 -273.225173)
			(xy 74.531131 -273.176274) (xy 74.523088 -273.125492) (xy 74.20441 -273.125492) (xy 74.196694 -273.172968)
			(xy 74.18111 -273.219649) (xy 74.158239 -273.263226) (xy 74.128674 -273.30257) (xy 74.093181 -273.336662)
			(xy 74.052678 -273.364618) (xy 74.008216 -273.385716) (xy 73.960945 -273.399408) (xy 73.91209 -273.40534)
			(xy 73.862915 -273.403359) (xy 73.814696 -273.393515) (xy 73.76868 -273.376063) (xy 73.726059 -273.351456)
			(xy 73.687938 -273.320331) (xy 73.655303 -273.283494) (xy 73.629 -273.241898) (xy 73.609709 -273.196622)
			(xy 73.597932 -273.148838) (xy 73.593972 -273.099784) (xy 73.276714 -273.099784) (xy 73.27621 -273.125492)
			(xy 73.268167 -273.176274) (xy 73.252279 -273.225173) (xy 73.228936 -273.270985) (xy 73.198715 -273.312581)
			(xy 73.162359 -273.348937) (xy 73.120763 -273.379158) (xy 73.074951 -273.402501) (xy 73.026052 -273.418389)
			(xy 72.97527 -273.426432) (xy 72.923854 -273.426432) (xy 72.873072 -273.418389) (xy 72.824173 -273.402501)
			(xy 72.778361 -273.379158) (xy 72.736765 -273.348937) (xy 72.700409 -273.312581) (xy 72.670188 -273.270985)
			(xy 72.646845 -273.225173) (xy 72.630957 -273.176274) (xy 72.622914 -273.125492) (xy 72.30449 -273.125492)
			(xy 72.296774 -273.172968) (xy 72.28119 -273.219649) (xy 72.258319 -273.263226) (xy 72.228754 -273.30257)
			(xy 72.193261 -273.336662) (xy 72.152758 -273.364618) (xy 72.108296 -273.385716) (xy 72.061025 -273.399408)
			(xy 72.01217 -273.40534) (xy 71.962995 -273.403359) (xy 71.914776 -273.393515) (xy 71.86876 -273.376063)
			(xy 71.826139 -273.351456) (xy 71.788018 -273.320331) (xy 71.755383 -273.283494) (xy 71.72908 -273.241898)
			(xy 71.709789 -273.196622) (xy 71.698012 -273.148838) (xy 71.694052 -273.099784) (xy 71.376794 -273.099784)
			(xy 71.37629 -273.125492) (xy 71.368247 -273.176274) (xy 71.352359 -273.225173) (xy 71.329016 -273.270985)
			(xy 71.298795 -273.312581) (xy 71.262439 -273.348937) (xy 71.220843 -273.379158) (xy 71.175031 -273.402501)
			(xy 71.126132 -273.418389) (xy 71.07535 -273.426432) (xy 71.023934 -273.426432) (xy 70.973152 -273.418389)
			(xy 70.924253 -273.402501) (xy 70.878441 -273.379158) (xy 70.836845 -273.348937) (xy 70.800489 -273.312581)
			(xy 70.770268 -273.270985) (xy 70.746925 -273.225173) (xy 70.731037 -273.176274) (xy 70.722994 -273.125492)
			(xy 70.40457 -273.125492) (xy 70.396854 -273.172968) (xy 70.38127 -273.219649) (xy 70.358399 -273.263226)
			(xy 70.328834 -273.30257) (xy 70.293341 -273.336662) (xy 70.252838 -273.364618) (xy 70.208376 -273.385716)
			(xy 70.161105 -273.399408) (xy 70.11225 -273.40534) (xy 70.063075 -273.403359) (xy 70.014856 -273.393515)
			(xy 69.96884 -273.376063) (xy 69.926219 -273.351456) (xy 69.888098 -273.320331) (xy 69.855463 -273.283494)
			(xy 69.82916 -273.241898) (xy 69.809869 -273.196622) (xy 69.798092 -273.148838) (xy 69.794132 -273.099784)
			(xy 69.476874 -273.099784) (xy 69.47637 -273.125492) (xy 69.468327 -273.176274) (xy 69.452439 -273.225173)
			(xy 69.429096 -273.270985) (xy 69.398875 -273.312581) (xy 69.362519 -273.348937) (xy 69.320923 -273.379158)
			(xy 69.275111 -273.402501) (xy 69.226212 -273.418389) (xy 69.17543 -273.426432) (xy 69.124014 -273.426432)
			(xy 69.073232 -273.418389) (xy 69.024333 -273.402501) (xy 68.978521 -273.379158) (xy 68.936925 -273.348937)
			(xy 68.900569 -273.312581) (xy 68.870348 -273.270985) (xy 68.847005 -273.225173) (xy 68.831117 -273.176274)
			(xy 68.823074 -273.125492) (xy 68.504396 -273.125492) (xy 68.49668 -273.172968) (xy 68.481096 -273.219649)
			(xy 68.458225 -273.263226) (xy 68.42866 -273.30257) (xy 68.393167 -273.336662) (xy 68.352664 -273.364618)
			(xy 68.308202 -273.385716) (xy 68.260931 -273.399408) (xy 68.212076 -273.40534) (xy 68.162901 -273.403359)
			(xy 68.114682 -273.393515) (xy 68.068666 -273.376063) (xy 68.026045 -273.351456) (xy 67.987924 -273.320331)
			(xy 67.955289 -273.283494) (xy 67.928986 -273.241898) (xy 67.909695 -273.196622) (xy 67.897918 -273.148838)
			(xy 67.893958 -273.099784) (xy 67.5767 -273.099784) (xy 67.576196 -273.125492) (xy 67.568153 -273.176274)
			(xy 67.552265 -273.225173) (xy 67.528922 -273.270985) (xy 67.498701 -273.312581) (xy 67.462345 -273.348937)
			(xy 67.420749 -273.379158) (xy 67.374937 -273.402501) (xy 67.326038 -273.418389) (xy 67.275256 -273.426432)
			(xy 67.22384 -273.426432) (xy 67.173058 -273.418389) (xy 67.124159 -273.402501) (xy 67.078347 -273.379158)
			(xy 67.036751 -273.348937) (xy 67.000395 -273.312581) (xy 66.970174 -273.270985) (xy 66.946831 -273.225173)
			(xy 66.930943 -273.176274) (xy 66.9229 -273.125492) (xy 66.604476 -273.125492) (xy 66.59676 -273.172968)
			(xy 66.581176 -273.219649) (xy 66.558305 -273.263226) (xy 66.52874 -273.30257) (xy 66.493247 -273.336662)
			(xy 66.452744 -273.364618) (xy 66.408282 -273.385716) (xy 66.361011 -273.399408) (xy 66.312156 -273.40534)
			(xy 66.262981 -273.403359) (xy 66.214762 -273.393515) (xy 66.168746 -273.376063) (xy 66.126125 -273.351456)
			(xy 66.088004 -273.320331) (xy 66.055369 -273.283494) (xy 66.029066 -273.241898) (xy 66.009775 -273.196622)
			(xy 65.997998 -273.148838) (xy 65.994038 -273.099784) (xy 65.67678 -273.099784) (xy 65.676276 -273.125492)
			(xy 65.668233 -273.176274) (xy 65.652345 -273.225173) (xy 65.629002 -273.270985) (xy 65.598781 -273.312581)
			(xy 65.562425 -273.348937) (xy 65.520829 -273.379158) (xy 65.475017 -273.402501) (xy 65.426118 -273.418389)
			(xy 65.375336 -273.426432) (xy 65.32392 -273.426432) (xy 65.273138 -273.418389) (xy 65.224239 -273.402501)
			(xy 65.178427 -273.379158) (xy 65.136831 -273.348937) (xy 65.100475 -273.312581) (xy 65.070254 -273.270985)
			(xy 65.046911 -273.225173) (xy 65.031023 -273.176274) (xy 65.02298 -273.125492) (xy 64.704556 -273.125492)
			(xy 64.69684 -273.172968) (xy 64.681256 -273.219649) (xy 64.658385 -273.263226) (xy 64.62882 -273.30257)
			(xy 64.593327 -273.336662) (xy 64.552824 -273.364618) (xy 64.508362 -273.385716) (xy 64.461091 -273.399408)
			(xy 64.412236 -273.40534) (xy 64.363061 -273.403359) (xy 64.314842 -273.393515) (xy 64.268826 -273.376063)
			(xy 64.226205 -273.351456) (xy 64.188084 -273.320331) (xy 64.155449 -273.283494) (xy 64.129146 -273.241898)
			(xy 64.109855 -273.196622) (xy 64.098078 -273.148838) (xy 64.094118 -273.099784) (xy 63.77686 -273.099784)
			(xy 63.776356 -273.125492) (xy 63.768313 -273.176274) (xy 63.752425 -273.225173) (xy 63.729082 -273.270985)
			(xy 63.698861 -273.312581) (xy 63.662505 -273.348937) (xy 63.620909 -273.379158) (xy 63.575097 -273.402501)
			(xy 63.526198 -273.418389) (xy 63.475416 -273.426432) (xy 63.424 -273.426432) (xy 63.373218 -273.418389)
			(xy 63.324319 -273.402501) (xy 63.278507 -273.379158) (xy 63.236911 -273.348937) (xy 63.200555 -273.312581)
			(xy 63.170334 -273.270985) (xy 63.146991 -273.225173) (xy 63.131103 -273.176274) (xy 63.12306 -273.125492)
			(xy 62.804382 -273.125492) (xy 62.796666 -273.172968) (xy 62.781082 -273.219649) (xy 62.758211 -273.263226)
			(xy 62.728646 -273.30257) (xy 62.693153 -273.336662) (xy 62.65265 -273.364618) (xy 62.608188 -273.385716)
			(xy 62.560917 -273.399408) (xy 62.512062 -273.40534) (xy 62.462887 -273.403359) (xy 62.414668 -273.393515)
			(xy 62.368652 -273.376063) (xy 62.326031 -273.351456) (xy 62.28791 -273.320331) (xy 62.255275 -273.283494)
			(xy 62.228972 -273.241898) (xy 62.209681 -273.196622) (xy 62.197904 -273.148838) (xy 62.193944 -273.099784)
			(xy 61.876686 -273.099784) (xy 61.876182 -273.125492) (xy 61.868139 -273.176274) (xy 61.852251 -273.225173)
			(xy 61.828908 -273.270985) (xy 61.798687 -273.312581) (xy 61.762331 -273.348937) (xy 61.720735 -273.379158)
			(xy 61.674923 -273.402501) (xy 61.626024 -273.418389) (xy 61.575242 -273.426432) (xy 61.523826 -273.426432)
			(xy 61.473044 -273.418389) (xy 61.424145 -273.402501) (xy 61.378333 -273.379158) (xy 61.336737 -273.348937)
			(xy 61.300381 -273.312581) (xy 61.27016 -273.270985) (xy 61.246817 -273.225173) (xy 61.230929 -273.176274)
			(xy 61.222886 -273.125492) (xy 60.904462 -273.125492) (xy 60.896746 -273.172968) (xy 60.881162 -273.219649)
			(xy 60.858291 -273.263226) (xy 60.828726 -273.30257) (xy 60.793233 -273.336662) (xy 60.75273 -273.364618)
			(xy 60.708268 -273.385716) (xy 60.660997 -273.399408) (xy 60.612142 -273.40534) (xy 60.562967 -273.403359)
			(xy 60.514748 -273.393515) (xy 60.468732 -273.376063) (xy 60.426111 -273.351456) (xy 60.38799 -273.320331)
			(xy 60.355355 -273.283494) (xy 60.329052 -273.241898) (xy 60.309761 -273.196622) (xy 60.297984 -273.148838)
			(xy 60.294024 -273.099784) (xy 59.975964 -273.099784) (xy 59.975964 -273.125185) (xy 59.967929 -273.175922)
			(xy 59.952055 -273.224777) (xy 59.928734 -273.270548) (xy 59.898541 -273.312107) (xy 59.862218 -273.348432)
			(xy 59.82066 -273.378627) (xy 59.77489 -273.40195) (xy 59.726035 -273.417825) (xy 59.675299 -273.425863)
			(xy 59.649614 -273.426428) (xy 59.623474 -273.425918) (xy 59.571858 -273.417607) (xy 59.52222 -273.401195)
			(xy 59.475823 -273.3771) (xy 59.454542 -273.361912) (xy 59.454288 -273.361658) (xy 59.45378 -273.36115)
			(xy 59.446025 -273.356047) (xy 59.4281 -273.351278) (xy 59.409657 -273.353251) (xy 59.401202 -273.357086)
			(xy 59.319922 -273.397726) (xy 59.310524 -273.403822) (xy 59.302128 -273.41144) (xy 59.292374 -273.431873)
			(xy 59.291728 -273.443192) (xy 59.291728 -273.705828) (xy 59.292334 -273.717157) (xy 59.302096 -273.737602)
			(xy 59.310524 -273.745198) (xy 59.314842 -273.748754) (xy 59.401202 -273.791934) (xy 59.409658 -273.795739)
			(xy 59.428086 -273.797654) (xy 59.445997 -273.792912) (xy 59.45378 -273.78787) (xy 59.454288 -273.787362)
			(xy 59.454542 -273.787108) (xy 59.475832 -273.771932) (xy 59.522224 -273.747829) (xy 59.571859 -273.731413)
			(xy 59.623474 -273.723099) (xy 59.649614 -273.722592) (xy 59.675302 -273.723097) (xy 59.726045 -273.731136)
			(xy 59.774905 -273.747013) (xy 59.820681 -273.770339) (xy 59.862244 -273.800538) (xy 59.898571 -273.836867)
			(xy 59.928768 -273.878431) (xy 59.952092 -273.924208) (xy 59.967968 -273.973069) (xy 59.976004 -274.023812)
			(xy 59.976004 -274.049744) (xy 60.294024 -274.049744) (xy 60.297984 -274.00069) (xy 60.309761 -273.952906)
			(xy 60.329052 -273.90763) (xy 60.355355 -273.866034) (xy 60.38799 -273.829197) (xy 60.426111 -273.798072)
			(xy 60.468732 -273.773465) (xy 60.514748 -273.756013) (xy 60.562967 -273.746169) (xy 60.612142 -273.744188)
			(xy 60.660997 -273.75012) (xy 60.708268 -273.763812) (xy 60.75273 -273.78491) (xy 60.793233 -273.812866)
			(xy 60.828726 -273.846958) (xy 60.858291 -273.886302) (xy 60.881162 -273.929879) (xy 60.896746 -273.97656)
			(xy 60.904641 -274.025137) (xy 60.905136 -274.049744) (xy 60.904641 -274.074351) (xy 60.904462 -274.075452)
			(xy 61.222886 -274.075452) (xy 61.222886 -274.024036) (xy 61.230929 -273.973254) (xy 61.246817 -273.924355)
			(xy 61.27016 -273.878543) (xy 61.300381 -273.836947) (xy 61.336737 -273.800591) (xy 61.378333 -273.77037)
			(xy 61.424145 -273.747027) (xy 61.473044 -273.731139) (xy 61.523826 -273.723096) (xy 61.575242 -273.723096)
			(xy 61.626024 -273.731139) (xy 61.674923 -273.747027) (xy 61.720735 -273.77037) (xy 61.762331 -273.800591)
			(xy 61.798687 -273.836947) (xy 61.828908 -273.878543) (xy 61.852251 -273.924355) (xy 61.868139 -273.973254)
			(xy 61.876182 -274.024036) (xy 61.876686 -274.049744) (xy 62.193944 -274.049744) (xy 62.197904 -274.00069)
			(xy 62.209681 -273.952906) (xy 62.228972 -273.90763) (xy 62.255275 -273.866034) (xy 62.28791 -273.829197)
			(xy 62.326031 -273.798072) (xy 62.368652 -273.773465) (xy 62.414668 -273.756013) (xy 62.462887 -273.746169)
			(xy 62.512062 -273.744188) (xy 62.560917 -273.75012) (xy 62.608188 -273.763812) (xy 62.65265 -273.78491)
			(xy 62.693153 -273.812866) (xy 62.728646 -273.846958) (xy 62.758211 -273.886302) (xy 62.781082 -273.929879)
			(xy 62.796666 -273.97656) (xy 62.804561 -274.025137) (xy 62.805056 -274.049744) (xy 62.804561 -274.074351)
			(xy 62.804382 -274.075452) (xy 63.12306 -274.075452) (xy 63.12306 -274.024036) (xy 63.131103 -273.973254)
			(xy 63.146991 -273.924355) (xy 63.170334 -273.878543) (xy 63.200555 -273.836947) (xy 63.236911 -273.800591)
			(xy 63.278507 -273.77037) (xy 63.324319 -273.747027) (xy 63.373218 -273.731139) (xy 63.424 -273.723096)
			(xy 63.475416 -273.723096) (xy 63.526198 -273.731139) (xy 63.575097 -273.747027) (xy 63.620909 -273.77037)
			(xy 63.662505 -273.800591) (xy 63.698861 -273.836947) (xy 63.729082 -273.878543) (xy 63.752425 -273.924355)
			(xy 63.768313 -273.973254) (xy 63.776356 -274.024036) (xy 63.77686 -274.049744) (xy 64.094118 -274.049744)
			(xy 64.098078 -274.00069) (xy 64.109855 -273.952906) (xy 64.129146 -273.90763) (xy 64.155449 -273.866034)
			(xy 64.188084 -273.829197) (xy 64.226205 -273.798072) (xy 64.268826 -273.773465) (xy 64.314842 -273.756013)
			(xy 64.363061 -273.746169) (xy 64.412236 -273.744188) (xy 64.461091 -273.75012) (xy 64.508362 -273.763812)
			(xy 64.552824 -273.78491) (xy 64.593327 -273.812866) (xy 64.62882 -273.846958) (xy 64.658385 -273.886302)
			(xy 64.681256 -273.929879) (xy 64.69684 -273.97656) (xy 64.704735 -274.025137) (xy 64.70523 -274.049744)
			(xy 64.704735 -274.074351) (xy 64.704556 -274.075452) (xy 65.02298 -274.075452) (xy 65.02298 -274.024036)
			(xy 65.031023 -273.973254) (xy 65.046911 -273.924355) (xy 65.070254 -273.878543) (xy 65.100475 -273.836947)
			(xy 65.136831 -273.800591) (xy 65.178427 -273.77037) (xy 65.224239 -273.747027) (xy 65.273138 -273.731139)
			(xy 65.32392 -273.723096) (xy 65.375336 -273.723096) (xy 65.426118 -273.731139) (xy 65.475017 -273.747027)
			(xy 65.520829 -273.77037) (xy 65.562425 -273.800591) (xy 65.598781 -273.836947) (xy 65.629002 -273.878543)
			(xy 65.652345 -273.924355) (xy 65.668233 -273.973254) (xy 65.676276 -274.024036) (xy 65.67678 -274.049744)
			(xy 65.994038 -274.049744) (xy 65.997998 -274.00069) (xy 66.009775 -273.952906) (xy 66.029066 -273.90763)
			(xy 66.055369 -273.866034) (xy 66.088004 -273.829197) (xy 66.126125 -273.798072) (xy 66.168746 -273.773465)
			(xy 66.214762 -273.756013) (xy 66.262981 -273.746169) (xy 66.312156 -273.744188) (xy 66.361011 -273.75012)
			(xy 66.408282 -273.763812) (xy 66.452744 -273.78491) (xy 66.493247 -273.812866) (xy 66.52874 -273.846958)
			(xy 66.558305 -273.886302) (xy 66.581176 -273.929879) (xy 66.59676 -273.97656) (xy 66.604655 -274.025137)
			(xy 66.60515 -274.049744) (xy 66.604655 -274.074351) (xy 66.604476 -274.075452) (xy 66.9229 -274.075452)
			(xy 66.9229 -274.024036) (xy 66.930943 -273.973254) (xy 66.946831 -273.924355) (xy 66.970174 -273.878543)
			(xy 67.000395 -273.836947) (xy 67.036751 -273.800591) (xy 67.078347 -273.77037) (xy 67.124159 -273.747027)
			(xy 67.173058 -273.731139) (xy 67.22384 -273.723096) (xy 67.275256 -273.723096) (xy 67.326038 -273.731139)
			(xy 67.374937 -273.747027) (xy 67.420749 -273.77037) (xy 67.462345 -273.800591) (xy 67.498701 -273.836947)
			(xy 67.528922 -273.878543) (xy 67.552265 -273.924355) (xy 67.568153 -273.973254) (xy 67.576196 -274.024036)
			(xy 67.5767 -274.049744) (xy 67.893958 -274.049744) (xy 67.897918 -274.00069) (xy 67.909695 -273.952906)
			(xy 67.928986 -273.90763) (xy 67.955289 -273.866034) (xy 67.987924 -273.829197) (xy 68.026045 -273.798072)
			(xy 68.068666 -273.773465) (xy 68.114682 -273.756013) (xy 68.162901 -273.746169) (xy 68.212076 -273.744188)
			(xy 68.260931 -273.75012) (xy 68.308202 -273.763812) (xy 68.352664 -273.78491) (xy 68.393167 -273.812866)
			(xy 68.42866 -273.846958) (xy 68.458225 -273.886302) (xy 68.481096 -273.929879) (xy 68.49668 -273.97656)
			(xy 68.504575 -274.025137) (xy 68.50507 -274.049744) (xy 68.504575 -274.074351) (xy 68.504396 -274.075452)
			(xy 68.823074 -274.075452) (xy 68.823074 -274.024036) (xy 68.831117 -273.973254) (xy 68.847005 -273.924355)
			(xy 68.870348 -273.878543) (xy 68.900569 -273.836947) (xy 68.936925 -273.800591) (xy 68.978521 -273.77037)
			(xy 69.024333 -273.747027) (xy 69.073232 -273.731139) (xy 69.124014 -273.723096) (xy 69.17543 -273.723096)
			(xy 69.226212 -273.731139) (xy 69.275111 -273.747027) (xy 69.320923 -273.77037) (xy 69.362519 -273.800591)
			(xy 69.398875 -273.836947) (xy 69.429096 -273.878543) (xy 69.452439 -273.924355) (xy 69.468327 -273.973254)
			(xy 69.47637 -274.024036) (xy 69.476874 -274.049744) (xy 69.794132 -274.049744) (xy 69.798092 -274.00069)
			(xy 69.809869 -273.952906) (xy 69.82916 -273.90763) (xy 69.855463 -273.866034) (xy 69.888098 -273.829197)
			(xy 69.926219 -273.798072) (xy 69.96884 -273.773465) (xy 70.014856 -273.756013) (xy 70.063075 -273.746169)
			(xy 70.11225 -273.744188) (xy 70.161105 -273.75012) (xy 70.208376 -273.763812) (xy 70.252838 -273.78491)
			(xy 70.293341 -273.812866) (xy 70.328834 -273.846958) (xy 70.358399 -273.886302) (xy 70.38127 -273.929879)
			(xy 70.396854 -273.97656) (xy 70.404749 -274.025137) (xy 70.405244 -274.049744) (xy 70.404749 -274.074351)
			(xy 70.40457 -274.075452) (xy 70.722994 -274.075452) (xy 70.722994 -274.024036) (xy 70.731037 -273.973254)
			(xy 70.746925 -273.924355) (xy 70.770268 -273.878543) (xy 70.800489 -273.836947) (xy 70.836845 -273.800591)
			(xy 70.878441 -273.77037) (xy 70.924253 -273.747027) (xy 70.973152 -273.731139) (xy 71.023934 -273.723096)
			(xy 71.07535 -273.723096) (xy 71.126132 -273.731139) (xy 71.175031 -273.747027) (xy 71.220843 -273.77037)
			(xy 71.262439 -273.800591) (xy 71.298795 -273.836947) (xy 71.329016 -273.878543) (xy 71.352359 -273.924355)
			(xy 71.368247 -273.973254) (xy 71.37629 -274.024036) (xy 71.376794 -274.049744) (xy 71.694052 -274.049744)
			(xy 71.698012 -274.00069) (xy 71.709789 -273.952906) (xy 71.72908 -273.90763) (xy 71.755383 -273.866034)
			(xy 71.788018 -273.829197) (xy 71.826139 -273.798072) (xy 71.86876 -273.773465) (xy 71.914776 -273.756013)
			(xy 71.962995 -273.746169) (xy 72.01217 -273.744188) (xy 72.061025 -273.75012) (xy 72.108296 -273.763812)
			(xy 72.152758 -273.78491) (xy 72.193261 -273.812866) (xy 72.228754 -273.846958) (xy 72.258319 -273.886302)
			(xy 72.28119 -273.929879) (xy 72.296774 -273.97656) (xy 72.304669 -274.025137) (xy 72.305164 -274.049744)
			(xy 72.304669 -274.074351) (xy 72.30449 -274.075452) (xy 72.622914 -274.075452) (xy 72.622914 -274.024036)
			(xy 72.630957 -273.973254) (xy 72.646845 -273.924355) (xy 72.670188 -273.878543) (xy 72.700409 -273.836947)
			(xy 72.736765 -273.800591) (xy 72.778361 -273.77037) (xy 72.824173 -273.747027) (xy 72.873072 -273.731139)
			(xy 72.923854 -273.723096) (xy 72.97527 -273.723096) (xy 73.026052 -273.731139) (xy 73.074951 -273.747027)
			(xy 73.120763 -273.77037) (xy 73.162359 -273.800591) (xy 73.198715 -273.836947) (xy 73.228936 -273.878543)
			(xy 73.252279 -273.924355) (xy 73.268167 -273.973254) (xy 73.27621 -274.024036) (xy 73.276714 -274.049744)
			(xy 73.593972 -274.049744) (xy 73.597932 -274.00069) (xy 73.609709 -273.952906) (xy 73.629 -273.90763)
			(xy 73.655303 -273.866034) (xy 73.687938 -273.829197) (xy 73.726059 -273.798072) (xy 73.76868 -273.773465)
			(xy 73.814696 -273.756013) (xy 73.862915 -273.746169) (xy 73.91209 -273.744188) (xy 73.960945 -273.75012)
			(xy 74.008216 -273.763812) (xy 74.052678 -273.78491) (xy 74.093181 -273.812866) (xy 74.128674 -273.846958)
			(xy 74.158239 -273.886302) (xy 74.18111 -273.929879) (xy 74.196694 -273.97656) (xy 74.204589 -274.025137)
			(xy 74.205084 -274.049744) (xy 74.204589 -274.074351) (xy 74.20441 -274.075452) (xy 74.523088 -274.075452)
			(xy 74.523088 -274.024036) (xy 74.531131 -273.973254) (xy 74.547019 -273.924355) (xy 74.570362 -273.878543)
			(xy 74.600583 -273.836947) (xy 74.636939 -273.800591) (xy 74.678535 -273.77037) (xy 74.724347 -273.747027)
			(xy 74.773246 -273.731139) (xy 74.824028 -273.723096) (xy 74.875444 -273.723096) (xy 74.926226 -273.731139)
			(xy 74.975125 -273.747027) (xy 75.020937 -273.77037) (xy 75.062533 -273.800591) (xy 75.098889 -273.836947)
			(xy 75.12911 -273.878543) (xy 75.152453 -273.924355) (xy 75.168341 -273.973254) (xy 75.176384 -274.024036)
			(xy 75.176888 -274.049744) (xy 75.4944 -274.049744) (xy 75.49836 -274.00069) (xy 75.510137 -273.952906)
			(xy 75.529428 -273.90763) (xy 75.555731 -273.866034) (xy 75.588366 -273.829197) (xy 75.626487 -273.798072)
			(xy 75.669108 -273.773465) (xy 75.715124 -273.756013) (xy 75.763343 -273.746169) (xy 75.812518 -273.744188)
			(xy 75.861373 -273.75012) (xy 75.908644 -273.763812) (xy 75.953106 -273.78491) (xy 75.993609 -273.812866)
			(xy 76.029102 -273.846958) (xy 76.058667 -273.886302) (xy 76.081538 -273.929879) (xy 76.097122 -273.97656)
			(xy 76.105017 -274.025137) (xy 76.105512 -274.049744) (xy 76.105017 -274.074351) (xy 76.104838 -274.075452)
			(xy 76.423008 -274.075452) (xy 76.423008 -274.024036) (xy 76.431051 -273.973254) (xy 76.446939 -273.924355)
			(xy 76.470282 -273.878543) (xy 76.500503 -273.836947) (xy 76.536859 -273.800591) (xy 76.578455 -273.77037)
			(xy 76.624267 -273.747027) (xy 76.673166 -273.731139) (xy 76.723948 -273.723096) (xy 76.775364 -273.723096)
			(xy 76.826146 -273.731139) (xy 76.875045 -273.747027) (xy 76.920857 -273.77037) (xy 76.962453 -273.800591)
			(xy 76.998809 -273.836947) (xy 77.02903 -273.878543) (xy 77.052373 -273.924355) (xy 77.068261 -273.973254)
			(xy 77.076304 -274.024036) (xy 77.076808 -274.049744) (xy 77.39432 -274.049744) (xy 77.39828 -274.00069)
			(xy 77.410057 -273.952906) (xy 77.429348 -273.90763) (xy 77.455651 -273.866034) (xy 77.488286 -273.829197)
			(xy 77.526407 -273.798072) (xy 77.569028 -273.773465) (xy 77.615044 -273.756013) (xy 77.663263 -273.746169)
			(xy 77.712438 -273.744188) (xy 77.761293 -273.75012) (xy 77.808564 -273.763812) (xy 77.853026 -273.78491)
			(xy 77.893529 -273.812866) (xy 77.929022 -273.846958) (xy 77.958587 -273.886302) (xy 77.981458 -273.929879)
			(xy 77.997042 -273.97656) (xy 78.004937 -274.025137) (xy 78.005432 -274.049744) (xy 78.004937 -274.074351)
			(xy 78.004758 -274.075452) (xy 78.322928 -274.075452) (xy 78.322928 -274.024036) (xy 78.330971 -273.973254)
			(xy 78.346859 -273.924355) (xy 78.370202 -273.878543) (xy 78.400423 -273.836947) (xy 78.436779 -273.800591)
			(xy 78.478375 -273.77037) (xy 78.524187 -273.747027) (xy 78.573086 -273.731139) (xy 78.623868 -273.723096)
			(xy 78.675284 -273.723096) (xy 78.726066 -273.731139) (xy 78.774965 -273.747027) (xy 78.820777 -273.77037)
			(xy 78.862373 -273.800591) (xy 78.898729 -273.836947) (xy 78.92895 -273.878543) (xy 78.952293 -273.924355)
			(xy 78.968181 -273.973254) (xy 78.976224 -274.024036) (xy 78.976728 -274.049744) (xy 79.29424 -274.049744)
			(xy 79.2982 -274.00069) (xy 79.309977 -273.952906) (xy 79.329268 -273.90763) (xy 79.355571 -273.866034)
			(xy 79.388206 -273.829197) (xy 79.426327 -273.798072) (xy 79.468948 -273.773465) (xy 79.514964 -273.756013)
			(xy 79.563183 -273.746169) (xy 79.612358 -273.744188) (xy 79.661213 -273.75012) (xy 79.708484 -273.763812)
			(xy 79.752946 -273.78491) (xy 79.793449 -273.812866) (xy 79.828942 -273.846958) (xy 79.858507 -273.886302)
			(xy 79.881378 -273.929879) (xy 79.896962 -273.97656) (xy 79.904857 -274.025137) (xy 79.905352 -274.049744)
			(xy 79.904857 -274.074351) (xy 79.904678 -274.075452) (xy 80.222848 -274.075452) (xy 80.222848 -274.024036)
			(xy 80.230891 -273.973254) (xy 80.246779 -273.924355) (xy 80.270122 -273.878543) (xy 80.300343 -273.836947)
			(xy 80.336699 -273.800591) (xy 80.378295 -273.77037) (xy 80.424107 -273.747027) (xy 80.473006 -273.731139)
			(xy 80.523788 -273.723096) (xy 80.575204 -273.723096) (xy 80.625986 -273.731139) (xy 80.674885 -273.747027)
			(xy 80.720697 -273.77037) (xy 80.762293 -273.800591) (xy 80.798649 -273.836947) (xy 80.82887 -273.878543)
			(xy 80.852213 -273.924355) (xy 80.868101 -273.973254) (xy 80.876144 -274.024036) (xy 80.876648 -274.049744)
			(xy 81.19416 -274.049744) (xy 81.19812 -274.00069) (xy 81.209897 -273.952906) (xy 81.229188 -273.90763)
			(xy 81.255491 -273.866034) (xy 81.288126 -273.829197) (xy 81.326247 -273.798072) (xy 81.368868 -273.773465)
			(xy 81.414884 -273.756013) (xy 81.463103 -273.746169) (xy 81.512278 -273.744188) (xy 81.561133 -273.75012)
			(xy 81.608404 -273.763812) (xy 81.652866 -273.78491) (xy 81.693369 -273.812866) (xy 81.728862 -273.846958)
			(xy 81.758427 -273.886302) (xy 81.781298 -273.929879) (xy 81.796882 -273.97656) (xy 81.804777 -274.025137)
			(xy 81.805272 -274.049744) (xy 82.14412 -274.049744) (xy 82.14808 -274.00069) (xy 82.159857 -273.952906)
			(xy 82.179148 -273.90763) (xy 82.205451 -273.866034) (xy 82.238086 -273.829197) (xy 82.276207 -273.798072)
			(xy 82.318828 -273.773465) (xy 82.364844 -273.756013) (xy 82.413063 -273.746169) (xy 82.462238 -273.744188)
			(xy 82.511093 -273.75012) (xy 82.558364 -273.763812) (xy 82.602826 -273.78491) (xy 82.643329 -273.812866)
			(xy 82.678822 -273.846958) (xy 82.708387 -273.886302) (xy 82.731258 -273.929879) (xy 82.746842 -273.97656)
			(xy 82.754737 -274.025137) (xy 82.755232 -274.049744) (xy 82.754737 -274.074351) (xy 82.746842 -274.122928)
			(xy 82.731258 -274.169609) (xy 82.708387 -274.213186) (xy 82.678822 -274.25253) (xy 82.643329 -274.286622)
			(xy 82.602826 -274.314578) (xy 82.558364 -274.335676) (xy 82.511093 -274.349368) (xy 82.462238 -274.3553)
			(xy 82.413063 -274.353319) (xy 82.364844 -274.343475) (xy 82.318828 -274.326023) (xy 82.276207 -274.301416)
			(xy 82.238086 -274.270291) (xy 82.205451 -274.233454) (xy 82.179148 -274.191858) (xy 82.159857 -274.146582)
			(xy 82.14808 -274.098798) (xy 82.14412 -274.049744) (xy 81.805272 -274.049744) (xy 81.804777 -274.074351)
			(xy 81.796882 -274.122928) (xy 81.781298 -274.169609) (xy 81.758427 -274.213186) (xy 81.728862 -274.25253)
			(xy 81.693369 -274.286622) (xy 81.652866 -274.314578) (xy 81.608404 -274.335676) (xy 81.561133 -274.349368)
			(xy 81.512278 -274.3553) (xy 81.463103 -274.353319) (xy 81.414884 -274.343475) (xy 81.368868 -274.326023)
			(xy 81.326247 -274.301416) (xy 81.288126 -274.270291) (xy 81.255491 -274.233454) (xy 81.229188 -274.191858)
			(xy 81.209897 -274.146582) (xy 81.19812 -274.098798) (xy 81.19416 -274.049744) (xy 80.876648 -274.049744)
			(xy 80.876144 -274.075452) (xy 80.868101 -274.126234) (xy 80.852213 -274.175133) (xy 80.82887 -274.220945)
			(xy 80.798649 -274.262541) (xy 80.762293 -274.298897) (xy 80.720697 -274.329118) (xy 80.674885 -274.352461)
			(xy 80.625986 -274.368349) (xy 80.575204 -274.376392) (xy 80.523788 -274.376392) (xy 80.473006 -274.368349)
			(xy 80.424107 -274.352461) (xy 80.378295 -274.329118) (xy 80.336699 -274.298897) (xy 80.300343 -274.262541)
			(xy 80.270122 -274.220945) (xy 80.246779 -274.175133) (xy 80.230891 -274.126234) (xy 80.222848 -274.075452)
			(xy 79.904678 -274.075452) (xy 79.896962 -274.122928) (xy 79.881378 -274.169609) (xy 79.858507 -274.213186)
			(xy 79.828942 -274.25253) (xy 79.793449 -274.286622) (xy 79.752946 -274.314578) (xy 79.708484 -274.335676)
			(xy 79.661213 -274.349368) (xy 79.612358 -274.3553) (xy 79.563183 -274.353319) (xy 79.514964 -274.343475)
			(xy 79.468948 -274.326023) (xy 79.426327 -274.301416) (xy 79.388206 -274.270291) (xy 79.355571 -274.233454)
			(xy 79.329268 -274.191858) (xy 79.309977 -274.146582) (xy 79.2982 -274.098798) (xy 79.29424 -274.049744)
			(xy 78.976728 -274.049744) (xy 78.976224 -274.075452) (xy 78.968181 -274.126234) (xy 78.952293 -274.175133)
			(xy 78.92895 -274.220945) (xy 78.898729 -274.262541) (xy 78.862373 -274.298897) (xy 78.820777 -274.329118)
			(xy 78.774965 -274.352461) (xy 78.726066 -274.368349) (xy 78.675284 -274.376392) (xy 78.623868 -274.376392)
			(xy 78.573086 -274.368349) (xy 78.524187 -274.352461) (xy 78.478375 -274.329118) (xy 78.436779 -274.298897)
			(xy 78.400423 -274.262541) (xy 78.370202 -274.220945) (xy 78.346859 -274.175133) (xy 78.330971 -274.126234)
			(xy 78.322928 -274.075452) (xy 78.004758 -274.075452) (xy 77.997042 -274.122928) (xy 77.981458 -274.169609)
			(xy 77.958587 -274.213186) (xy 77.929022 -274.25253) (xy 77.893529 -274.286622) (xy 77.853026 -274.314578)
			(xy 77.808564 -274.335676) (xy 77.761293 -274.349368) (xy 77.712438 -274.3553) (xy 77.663263 -274.353319)
			(xy 77.615044 -274.343475) (xy 77.569028 -274.326023) (xy 77.526407 -274.301416) (xy 77.488286 -274.270291)
			(xy 77.455651 -274.233454) (xy 77.429348 -274.191858) (xy 77.410057 -274.146582) (xy 77.39828 -274.098798)
			(xy 77.39432 -274.049744) (xy 77.076808 -274.049744) (xy 77.076304 -274.075452) (xy 77.068261 -274.126234)
			(xy 77.052373 -274.175133) (xy 77.02903 -274.220945) (xy 76.998809 -274.262541) (xy 76.962453 -274.298897)
			(xy 76.920857 -274.329118) (xy 76.875045 -274.352461) (xy 76.826146 -274.368349) (xy 76.775364 -274.376392)
			(xy 76.723948 -274.376392) (xy 76.673166 -274.368349) (xy 76.624267 -274.352461) (xy 76.578455 -274.329118)
			(xy 76.536859 -274.298897) (xy 76.500503 -274.262541) (xy 76.470282 -274.220945) (xy 76.446939 -274.175133)
			(xy 76.431051 -274.126234) (xy 76.423008 -274.075452) (xy 76.104838 -274.075452) (xy 76.097122 -274.122928)
			(xy 76.081538 -274.169609) (xy 76.058667 -274.213186) (xy 76.029102 -274.25253) (xy 75.993609 -274.286622)
			(xy 75.953106 -274.314578) (xy 75.908644 -274.335676) (xy 75.861373 -274.349368) (xy 75.812518 -274.3553)
			(xy 75.763343 -274.353319) (xy 75.715124 -274.343475) (xy 75.669108 -274.326023) (xy 75.626487 -274.301416)
			(xy 75.588366 -274.270291) (xy 75.555731 -274.233454) (xy 75.529428 -274.191858) (xy 75.510137 -274.146582)
			(xy 75.49836 -274.098798) (xy 75.4944 -274.049744) (xy 75.176888 -274.049744) (xy 75.176384 -274.075452)
			(xy 75.168341 -274.126234) (xy 75.152453 -274.175133) (xy 75.12911 -274.220945) (xy 75.098889 -274.262541)
			(xy 75.062533 -274.298897) (xy 75.020937 -274.329118) (xy 74.975125 -274.352461) (xy 74.926226 -274.368349)
			(xy 74.875444 -274.376392) (xy 74.824028 -274.376392) (xy 74.773246 -274.368349) (xy 74.724347 -274.352461)
			(xy 74.678535 -274.329118) (xy 74.636939 -274.298897) (xy 74.600583 -274.262541) (xy 74.570362 -274.220945)
			(xy 74.547019 -274.175133) (xy 74.531131 -274.126234) (xy 74.523088 -274.075452) (xy 74.20441 -274.075452)
			(xy 74.196694 -274.122928) (xy 74.18111 -274.169609) (xy 74.158239 -274.213186) (xy 74.128674 -274.25253)
			(xy 74.093181 -274.286622) (xy 74.052678 -274.314578) (xy 74.008216 -274.335676) (xy 73.960945 -274.349368)
			(xy 73.91209 -274.3553) (xy 73.862915 -274.353319) (xy 73.814696 -274.343475) (xy 73.76868 -274.326023)
			(xy 73.726059 -274.301416) (xy 73.687938 -274.270291) (xy 73.655303 -274.233454) (xy 73.629 -274.191858)
			(xy 73.609709 -274.146582) (xy 73.597932 -274.098798) (xy 73.593972 -274.049744) (xy 73.276714 -274.049744)
			(xy 73.27621 -274.075452) (xy 73.268167 -274.126234) (xy 73.252279 -274.175133) (xy 73.228936 -274.220945)
			(xy 73.198715 -274.262541) (xy 73.162359 -274.298897) (xy 73.120763 -274.329118) (xy 73.074951 -274.352461)
			(xy 73.026052 -274.368349) (xy 72.97527 -274.376392) (xy 72.923854 -274.376392) (xy 72.873072 -274.368349)
			(xy 72.824173 -274.352461) (xy 72.778361 -274.329118) (xy 72.736765 -274.298897) (xy 72.700409 -274.262541)
			(xy 72.670188 -274.220945) (xy 72.646845 -274.175133) (xy 72.630957 -274.126234) (xy 72.622914 -274.075452)
			(xy 72.30449 -274.075452) (xy 72.296774 -274.122928) (xy 72.28119 -274.169609) (xy 72.258319 -274.213186)
			(xy 72.228754 -274.25253) (xy 72.193261 -274.286622) (xy 72.152758 -274.314578) (xy 72.108296 -274.335676)
			(xy 72.061025 -274.349368) (xy 72.01217 -274.3553) (xy 71.962995 -274.353319) (xy 71.914776 -274.343475)
			(xy 71.86876 -274.326023) (xy 71.826139 -274.301416) (xy 71.788018 -274.270291) (xy 71.755383 -274.233454)
			(xy 71.72908 -274.191858) (xy 71.709789 -274.146582) (xy 71.698012 -274.098798) (xy 71.694052 -274.049744)
			(xy 71.376794 -274.049744) (xy 71.37629 -274.075452) (xy 71.368247 -274.126234) (xy 71.352359 -274.175133)
			(xy 71.329016 -274.220945) (xy 71.298795 -274.262541) (xy 71.262439 -274.298897) (xy 71.220843 -274.329118)
			(xy 71.175031 -274.352461) (xy 71.126132 -274.368349) (xy 71.07535 -274.376392) (xy 71.023934 -274.376392)
			(xy 70.973152 -274.368349) (xy 70.924253 -274.352461) (xy 70.878441 -274.329118) (xy 70.836845 -274.298897)
			(xy 70.800489 -274.262541) (xy 70.770268 -274.220945) (xy 70.746925 -274.175133) (xy 70.731037 -274.126234)
			(xy 70.722994 -274.075452) (xy 70.40457 -274.075452) (xy 70.396854 -274.122928) (xy 70.38127 -274.169609)
			(xy 70.358399 -274.213186) (xy 70.328834 -274.25253) (xy 70.293341 -274.286622) (xy 70.252838 -274.314578)
			(xy 70.208376 -274.335676) (xy 70.161105 -274.349368) (xy 70.11225 -274.3553) (xy 70.063075 -274.353319)
			(xy 70.014856 -274.343475) (xy 69.96884 -274.326023) (xy 69.926219 -274.301416) (xy 69.888098 -274.270291)
			(xy 69.855463 -274.233454) (xy 69.82916 -274.191858) (xy 69.809869 -274.146582) (xy 69.798092 -274.098798)
			(xy 69.794132 -274.049744) (xy 69.476874 -274.049744) (xy 69.47637 -274.075452) (xy 69.468327 -274.126234)
			(xy 69.452439 -274.175133) (xy 69.429096 -274.220945) (xy 69.398875 -274.262541) (xy 69.362519 -274.298897)
			(xy 69.320923 -274.329118) (xy 69.275111 -274.352461) (xy 69.226212 -274.368349) (xy 69.17543 -274.376392)
			(xy 69.124014 -274.376392) (xy 69.073232 -274.368349) (xy 69.024333 -274.352461) (xy 68.978521 -274.329118)
			(xy 68.936925 -274.298897) (xy 68.900569 -274.262541) (xy 68.870348 -274.220945) (xy 68.847005 -274.175133)
			(xy 68.831117 -274.126234) (xy 68.823074 -274.075452) (xy 68.504396 -274.075452) (xy 68.49668 -274.122928)
			(xy 68.481096 -274.169609) (xy 68.458225 -274.213186) (xy 68.42866 -274.25253) (xy 68.393167 -274.286622)
			(xy 68.352664 -274.314578) (xy 68.308202 -274.335676) (xy 68.260931 -274.349368) (xy 68.212076 -274.3553)
			(xy 68.162901 -274.353319) (xy 68.114682 -274.343475) (xy 68.068666 -274.326023) (xy 68.026045 -274.301416)
			(xy 67.987924 -274.270291) (xy 67.955289 -274.233454) (xy 67.928986 -274.191858) (xy 67.909695 -274.146582)
			(xy 67.897918 -274.098798) (xy 67.893958 -274.049744) (xy 67.5767 -274.049744) (xy 67.576196 -274.075452)
			(xy 67.568153 -274.126234) (xy 67.552265 -274.175133) (xy 67.528922 -274.220945) (xy 67.498701 -274.262541)
			(xy 67.462345 -274.298897) (xy 67.420749 -274.329118) (xy 67.374937 -274.352461) (xy 67.326038 -274.368349)
			(xy 67.275256 -274.376392) (xy 67.22384 -274.376392) (xy 67.173058 -274.368349) (xy 67.124159 -274.352461)
			(xy 67.078347 -274.329118) (xy 67.036751 -274.298897) (xy 67.000395 -274.262541) (xy 66.970174 -274.220945)
			(xy 66.946831 -274.175133) (xy 66.930943 -274.126234) (xy 66.9229 -274.075452) (xy 66.604476 -274.075452)
			(xy 66.59676 -274.122928) (xy 66.581176 -274.169609) (xy 66.558305 -274.213186) (xy 66.52874 -274.25253)
			(xy 66.493247 -274.286622) (xy 66.452744 -274.314578) (xy 66.408282 -274.335676) (xy 66.361011 -274.349368)
			(xy 66.312156 -274.3553) (xy 66.262981 -274.353319) (xy 66.214762 -274.343475) (xy 66.168746 -274.326023)
			(xy 66.126125 -274.301416) (xy 66.088004 -274.270291) (xy 66.055369 -274.233454) (xy 66.029066 -274.191858)
			(xy 66.009775 -274.146582) (xy 65.997998 -274.098798) (xy 65.994038 -274.049744) (xy 65.67678 -274.049744)
			(xy 65.676276 -274.075452) (xy 65.668233 -274.126234) (xy 65.652345 -274.175133) (xy 65.629002 -274.220945)
			(xy 65.598781 -274.262541) (xy 65.562425 -274.298897) (xy 65.520829 -274.329118) (xy 65.475017 -274.352461)
			(xy 65.426118 -274.368349) (xy 65.375336 -274.376392) (xy 65.32392 -274.376392) (xy 65.273138 -274.368349)
			(xy 65.224239 -274.352461) (xy 65.178427 -274.329118) (xy 65.136831 -274.298897) (xy 65.100475 -274.262541)
			(xy 65.070254 -274.220945) (xy 65.046911 -274.175133) (xy 65.031023 -274.126234) (xy 65.02298 -274.075452)
			(xy 64.704556 -274.075452) (xy 64.69684 -274.122928) (xy 64.681256 -274.169609) (xy 64.658385 -274.213186)
			(xy 64.62882 -274.25253) (xy 64.593327 -274.286622) (xy 64.552824 -274.314578) (xy 64.508362 -274.335676)
			(xy 64.461091 -274.349368) (xy 64.412236 -274.3553) (xy 64.363061 -274.353319) (xy 64.314842 -274.343475)
			(xy 64.268826 -274.326023) (xy 64.226205 -274.301416) (xy 64.188084 -274.270291) (xy 64.155449 -274.233454)
			(xy 64.129146 -274.191858) (xy 64.109855 -274.146582) (xy 64.098078 -274.098798) (xy 64.094118 -274.049744)
			(xy 63.77686 -274.049744) (xy 63.776356 -274.075452) (xy 63.768313 -274.126234) (xy 63.752425 -274.175133)
			(xy 63.729082 -274.220945) (xy 63.698861 -274.262541) (xy 63.662505 -274.298897) (xy 63.620909 -274.329118)
			(xy 63.575097 -274.352461) (xy 63.526198 -274.368349) (xy 63.475416 -274.376392) (xy 63.424 -274.376392)
			(xy 63.373218 -274.368349) (xy 63.324319 -274.352461) (xy 63.278507 -274.329118) (xy 63.236911 -274.298897)
			(xy 63.200555 -274.262541) (xy 63.170334 -274.220945) (xy 63.146991 -274.175133) (xy 63.131103 -274.126234)
			(xy 63.12306 -274.075452) (xy 62.804382 -274.075452) (xy 62.796666 -274.122928) (xy 62.781082 -274.169609)
			(xy 62.758211 -274.213186) (xy 62.728646 -274.25253) (xy 62.693153 -274.286622) (xy 62.65265 -274.314578)
			(xy 62.608188 -274.335676) (xy 62.560917 -274.349368) (xy 62.512062 -274.3553) (xy 62.462887 -274.353319)
			(xy 62.414668 -274.343475) (xy 62.368652 -274.326023) (xy 62.326031 -274.301416) (xy 62.28791 -274.270291)
			(xy 62.255275 -274.233454) (xy 62.228972 -274.191858) (xy 62.209681 -274.146582) (xy 62.197904 -274.098798)
			(xy 62.193944 -274.049744) (xy 61.876686 -274.049744) (xy 61.876182 -274.075452) (xy 61.868139 -274.126234)
			(xy 61.852251 -274.175133) (xy 61.828908 -274.220945) (xy 61.798687 -274.262541) (xy 61.762331 -274.298897)
			(xy 61.720735 -274.329118) (xy 61.674923 -274.352461) (xy 61.626024 -274.368349) (xy 61.575242 -274.376392)
			(xy 61.523826 -274.376392) (xy 61.473044 -274.368349) (xy 61.424145 -274.352461) (xy 61.378333 -274.329118)
			(xy 61.336737 -274.298897) (xy 61.300381 -274.262541) (xy 61.27016 -274.220945) (xy 61.246817 -274.175133)
			(xy 61.230929 -274.126234) (xy 61.222886 -274.075452) (xy 60.904462 -274.075452) (xy 60.896746 -274.122928)
			(xy 60.881162 -274.169609) (xy 60.858291 -274.213186) (xy 60.828726 -274.25253) (xy 60.793233 -274.286622)
			(xy 60.75273 -274.314578) (xy 60.708268 -274.335676) (xy 60.660997 -274.349368) (xy 60.612142 -274.3553)
			(xy 60.562967 -274.353319) (xy 60.514748 -274.343475) (xy 60.468732 -274.326023) (xy 60.426111 -274.301416)
			(xy 60.38799 -274.270291) (xy 60.355355 -274.233454) (xy 60.329052 -274.191858) (xy 60.309761 -274.146582)
			(xy 60.297984 -274.098798) (xy 60.294024 -274.049744) (xy 59.976004 -274.049744) (xy 59.976004 -274.075188)
			(xy 59.967968 -274.125931) (xy 59.952092 -274.174792) (xy 59.928768 -274.220569) (xy 59.898571 -274.262133)
			(xy 59.862244 -274.298462) (xy 59.820681 -274.328661) (xy 59.774905 -274.351987) (xy 59.726045 -274.367864)
			(xy 59.675302 -274.375903) (xy 59.649614 -274.376388) (xy 59.640724 -274.376388) (xy 59.627008 -274.376134)
			(xy 59.61507 -274.382484) (xy 59.609302 -274.38588) (xy 59.599648 -274.395147) (xy 59.59602 -274.400772)
			(xy 59.543188 -274.487894) (xy 59.542426 -274.515072) (xy 59.549284 -274.527264) (xy 59.566929 -274.559729)
			(xy 59.59782 -274.626859) (xy 59.611006 -274.661376) (xy 59.614904 -274.670732) (xy 59.62868 -274.685576)
			(xy 59.647124 -274.693941) (xy 59.657234 -274.69465) (xy 59.680844 -274.69566) (xy 59.727346 -274.704062)
			(xy 59.771997 -274.719531) (xy 59.813732 -274.741696) (xy 59.851551 -274.770027) (xy 59.884553 -274.803849)
			(xy 59.911948 -274.842353) (xy 59.933082 -274.884619) (xy 59.94745 -274.929636) (xy 59.954708 -274.97633)
			(xy 59.955176 -274.999958) (xy 59.954651 -275.025412) (xy 60.272926 -275.025412) (xy 60.272926 -274.973996)
			(xy 60.280969 -274.923214) (xy 60.296857 -274.874315) (xy 60.3202 -274.828503) (xy 60.350421 -274.786907)
			(xy 60.386777 -274.750551) (xy 60.428373 -274.72033) (xy 60.474185 -274.696987) (xy 60.523084 -274.681099)
			(xy 60.573866 -274.673056) (xy 60.625282 -274.673056) (xy 60.676064 -274.681099) (xy 60.724963 -274.696987)
			(xy 60.770775 -274.72033) (xy 60.812371 -274.750551) (xy 60.848727 -274.786907) (xy 60.878948 -274.828503)
			(xy 60.902291 -274.874315) (xy 60.918179 -274.923214) (xy 60.926222 -274.973996) (xy 60.926726 -274.999704)
			(xy 60.926721 -274.999958) (xy 61.243984 -274.999958) (xy 61.247944 -274.950904) (xy 61.259721 -274.90312)
			(xy 61.279012 -274.857844) (xy 61.305315 -274.816248) (xy 61.33795 -274.779411) (xy 61.376071 -274.748286)
			(xy 61.418692 -274.723679) (xy 61.464708 -274.706227) (xy 61.512927 -274.696383) (xy 61.562102 -274.694402)
			(xy 61.610957 -274.700334) (xy 61.658228 -274.714026) (xy 61.70269 -274.735124) (xy 61.743193 -274.76308)
			(xy 61.778686 -274.797172) (xy 61.808251 -274.836516) (xy 61.831122 -274.880093) (xy 61.846706 -274.926774)
			(xy 61.854601 -274.975351) (xy 61.855096 -274.999958) (xy 61.854601 -275.024565) (xy 61.854422 -275.025666)
			(xy 62.172846 -275.025666) (xy 62.172846 -274.97425) (xy 62.180889 -274.923468) (xy 62.196777 -274.874569)
			(xy 62.22012 -274.828757) (xy 62.250341 -274.787161) (xy 62.286697 -274.750805) (xy 62.328293 -274.720584)
			(xy 62.374105 -274.697241) (xy 62.423004 -274.681353) (xy 62.473786 -274.67331) (xy 62.525202 -274.67331)
			(xy 62.575984 -274.681353) (xy 62.624883 -274.697241) (xy 62.670695 -274.720584) (xy 62.712291 -274.750805)
			(xy 62.748647 -274.787161) (xy 62.778868 -274.828757) (xy 62.802211 -274.874569) (xy 62.818099 -274.923468)
			(xy 62.826142 -274.97425) (xy 62.826646 -274.999958) (xy 63.144158 -274.999958) (xy 63.148118 -274.950904)
			(xy 63.159895 -274.90312) (xy 63.179186 -274.857844) (xy 63.205489 -274.816248) (xy 63.238124 -274.779411)
			(xy 63.276245 -274.748286) (xy 63.318866 -274.723679) (xy 63.364882 -274.706227) (xy 63.413101 -274.696383)
			(xy 63.462276 -274.694402) (xy 63.511131 -274.700334) (xy 63.558402 -274.714026) (xy 63.602864 -274.735124)
			(xy 63.643367 -274.76308) (xy 63.67886 -274.797172) (xy 63.708425 -274.836516) (xy 63.731296 -274.880093)
			(xy 63.74688 -274.926774) (xy 63.754775 -274.975351) (xy 63.75527 -274.999958) (xy 63.754775 -275.024565)
			(xy 63.754637 -275.025412) (xy 64.07302 -275.025412) (xy 64.07302 -274.973996) (xy 64.081063 -274.923214)
			(xy 64.096951 -274.874315) (xy 64.120294 -274.828503) (xy 64.150515 -274.786907) (xy 64.186871 -274.750551)
			(xy 64.228467 -274.72033) (xy 64.274279 -274.696987) (xy 64.323178 -274.681099) (xy 64.37396 -274.673056)
			(xy 64.425376 -274.673056) (xy 64.476158 -274.681099) (xy 64.525057 -274.696987) (xy 64.570869 -274.72033)
			(xy 64.612465 -274.750551) (xy 64.648821 -274.786907) (xy 64.679042 -274.828503) (xy 64.702385 -274.874315)
			(xy 64.718273 -274.923214) (xy 64.726316 -274.973996) (xy 64.72682 -274.999704) (xy 64.726815 -274.999958)
			(xy 65.044078 -274.999958) (xy 65.048038 -274.950904) (xy 65.059815 -274.90312) (xy 65.079106 -274.857844)
			(xy 65.105409 -274.816248) (xy 65.138044 -274.779411) (xy 65.176165 -274.748286) (xy 65.218786 -274.723679)
			(xy 65.264802 -274.706227) (xy 65.313021 -274.696383) (xy 65.362196 -274.694402) (xy 65.411051 -274.700334)
			(xy 65.458322 -274.714026) (xy 65.502784 -274.735124) (xy 65.543287 -274.76308) (xy 65.57878 -274.797172)
			(xy 65.608345 -274.836516) (xy 65.631216 -274.880093) (xy 65.6468 -274.926774) (xy 65.654695 -274.975351)
			(xy 65.65519 -274.999958) (xy 65.654695 -275.024565) (xy 65.654516 -275.025666) (xy 65.97294 -275.025666)
			(xy 65.97294 -274.97425) (xy 65.980983 -274.923468) (xy 65.996871 -274.874569) (xy 66.020214 -274.828757)
			(xy 66.050435 -274.787161) (xy 66.086791 -274.750805) (xy 66.128387 -274.720584) (xy 66.174199 -274.697241)
			(xy 66.223098 -274.681353) (xy 66.27388 -274.67331) (xy 66.325296 -274.67331) (xy 66.376078 -274.681353)
			(xy 66.424977 -274.697241) (xy 66.470789 -274.720584) (xy 66.512385 -274.750805) (xy 66.548741 -274.787161)
			(xy 66.578962 -274.828757) (xy 66.602305 -274.874569) (xy 66.618193 -274.923468) (xy 66.626236 -274.97425)
			(xy 66.62674 -274.999958) (xy 66.943998 -274.999958) (xy 66.947958 -274.950904) (xy 66.959735 -274.90312)
			(xy 66.979026 -274.857844) (xy 67.005329 -274.816248) (xy 67.037964 -274.779411) (xy 67.076085 -274.748286)
			(xy 67.118706 -274.723679) (xy 67.164722 -274.706227) (xy 67.212941 -274.696383) (xy 67.262116 -274.694402)
			(xy 67.310971 -274.700334) (xy 67.358242 -274.714026) (xy 67.402704 -274.735124) (xy 67.443207 -274.76308)
			(xy 67.4787 -274.797172) (xy 67.508265 -274.836516) (xy 67.531136 -274.880093) (xy 67.54672 -274.926774)
			(xy 67.554615 -274.975351) (xy 67.55511 -274.999958) (xy 67.554615 -275.024565) (xy 67.554477 -275.025412)
			(xy 67.87286 -275.025412) (xy 67.87286 -274.973996) (xy 67.880903 -274.923214) (xy 67.896791 -274.874315)
			(xy 67.920134 -274.828503) (xy 67.950355 -274.786907) (xy 67.986711 -274.750551) (xy 68.028307 -274.72033)
			(xy 68.074119 -274.696987) (xy 68.123018 -274.681099) (xy 68.1738 -274.673056) (xy 68.225216 -274.673056)
			(xy 68.275998 -274.681099) (xy 68.324897 -274.696987) (xy 68.370709 -274.72033) (xy 68.412305 -274.750551)
			(xy 68.448661 -274.786907) (xy 68.478882 -274.828503) (xy 68.502225 -274.874315) (xy 68.518113 -274.923214)
			(xy 68.526156 -274.973996) (xy 68.52666 -274.999704) (xy 68.526655 -274.999958) (xy 68.844172 -274.999958)
			(xy 68.848132 -274.950904) (xy 68.859909 -274.90312) (xy 68.8792 -274.857844) (xy 68.905503 -274.816248)
			(xy 68.938138 -274.779411) (xy 68.976259 -274.748286) (xy 69.01888 -274.723679) (xy 69.064896 -274.706227)
			(xy 69.113115 -274.696383) (xy 69.16229 -274.694402) (xy 69.211145 -274.700334) (xy 69.258416 -274.714026)
			(xy 69.302878 -274.735124) (xy 69.343381 -274.76308) (xy 69.378874 -274.797172) (xy 69.408439 -274.836516)
			(xy 69.43131 -274.880093) (xy 69.446894 -274.926774) (xy 69.454789 -274.975351) (xy 69.455284 -274.999958)
			(xy 69.454789 -275.024565) (xy 69.45461 -275.025666) (xy 69.77278 -275.025666) (xy 69.77278 -274.97425)
			(xy 69.780823 -274.923468) (xy 69.796711 -274.874569) (xy 69.820054 -274.828757) (xy 69.850275 -274.787161)
			(xy 69.886631 -274.750805) (xy 69.928227 -274.720584) (xy 69.974039 -274.697241) (xy 70.022938 -274.681353)
			(xy 70.07372 -274.67331) (xy 70.125136 -274.67331) (xy 70.175918 -274.681353) (xy 70.224817 -274.697241)
			(xy 70.270629 -274.720584) (xy 70.312225 -274.750805) (xy 70.348581 -274.787161) (xy 70.378802 -274.828757)
			(xy 70.402145 -274.874569) (xy 70.418033 -274.923468) (xy 70.426076 -274.97425) (xy 70.42658 -274.999958)
			(xy 70.744092 -274.999958) (xy 70.748052 -274.950904) (xy 70.759829 -274.90312) (xy 70.77912 -274.857844)
			(xy 70.805423 -274.816248) (xy 70.838058 -274.779411) (xy 70.876179 -274.748286) (xy 70.9188 -274.723679)
			(xy 70.964816 -274.706227) (xy 71.013035 -274.696383) (xy 71.06221 -274.694402) (xy 71.111065 -274.700334)
			(xy 71.158336 -274.714026) (xy 71.202798 -274.735124) (xy 71.243301 -274.76308) (xy 71.278794 -274.797172)
			(xy 71.308359 -274.836516) (xy 71.33123 -274.880093) (xy 71.346814 -274.926774) (xy 71.354709 -274.975351)
			(xy 71.355204 -274.999958) (xy 71.354709 -275.024565) (xy 71.354571 -275.025412) (xy 71.672954 -275.025412)
			(xy 71.672954 -274.973996) (xy 71.680997 -274.923214) (xy 71.696885 -274.874315) (xy 71.720228 -274.828503)
			(xy 71.750449 -274.786907) (xy 71.786805 -274.750551) (xy 71.828401 -274.72033) (xy 71.874213 -274.696987)
			(xy 71.923112 -274.681099) (xy 71.973894 -274.673056) (xy 72.02531 -274.673056) (xy 72.076092 -274.681099)
			(xy 72.124991 -274.696987) (xy 72.170803 -274.72033) (xy 72.212399 -274.750551) (xy 72.248755 -274.786907)
			(xy 72.278976 -274.828503) (xy 72.302319 -274.874315) (xy 72.318207 -274.923214) (xy 72.32625 -274.973996)
			(xy 72.326754 -274.999704) (xy 72.326749 -274.999958) (xy 72.644012 -274.999958) (xy 72.647972 -274.950904)
			(xy 72.659749 -274.90312) (xy 72.67904 -274.857844) (xy 72.705343 -274.816248) (xy 72.737978 -274.779411)
			(xy 72.776099 -274.748286) (xy 72.81872 -274.723679) (xy 72.864736 -274.706227) (xy 72.912955 -274.696383)
			(xy 72.96213 -274.694402) (xy 73.010985 -274.700334) (xy 73.058256 -274.714026) (xy 73.102718 -274.735124)
			(xy 73.143221 -274.76308) (xy 73.178714 -274.797172) (xy 73.208279 -274.836516) (xy 73.23115 -274.880093)
			(xy 73.246734 -274.926774) (xy 73.254629 -274.975351) (xy 73.255124 -274.999958) (xy 73.254629 -275.024565)
			(xy 73.25445 -275.025666) (xy 73.572874 -275.025666) (xy 73.572874 -274.97425) (xy 73.580917 -274.923468)
			(xy 73.596805 -274.874569) (xy 73.620148 -274.828757) (xy 73.650369 -274.787161) (xy 73.686725 -274.750805)
			(xy 73.728321 -274.720584) (xy 73.774133 -274.697241) (xy 73.823032 -274.681353) (xy 73.873814 -274.67331)
			(xy 73.92523 -274.67331) (xy 73.976012 -274.681353) (xy 74.024911 -274.697241) (xy 74.070723 -274.720584)
			(xy 74.112319 -274.750805) (xy 74.148675 -274.787161) (xy 74.178896 -274.828757) (xy 74.202239 -274.874569)
			(xy 74.218127 -274.923468) (xy 74.22617 -274.97425) (xy 74.226674 -274.999958) (xy 74.543932 -274.999958)
			(xy 74.547892 -274.950904) (xy 74.559669 -274.90312) (xy 74.57896 -274.857844) (xy 74.605263 -274.816248)
			(xy 74.637898 -274.779411) (xy 74.676019 -274.748286) (xy 74.71864 -274.723679) (xy 74.764656 -274.706227)
			(xy 74.812875 -274.696383) (xy 74.86205 -274.694402) (xy 74.910905 -274.700334) (xy 74.958176 -274.714026)
			(xy 75.002638 -274.735124) (xy 75.043141 -274.76308) (xy 75.078634 -274.797172) (xy 75.108199 -274.836516)
			(xy 75.13107 -274.880093) (xy 75.146654 -274.926774) (xy 75.154549 -274.975351) (xy 75.155044 -274.999958)
			(xy 75.154549 -275.024565) (xy 75.154411 -275.025412) (xy 75.473048 -275.025412) (xy 75.473048 -274.973996)
			(xy 75.481091 -274.923214) (xy 75.496979 -274.874315) (xy 75.520322 -274.828503) (xy 75.550543 -274.786907)
			(xy 75.586899 -274.750551) (xy 75.628495 -274.72033) (xy 75.674307 -274.696987) (xy 75.723206 -274.681099)
			(xy 75.773988 -274.673056) (xy 75.825404 -274.673056) (xy 75.876186 -274.681099) (xy 75.925085 -274.696987)
			(xy 75.970897 -274.72033) (xy 76.012493 -274.750551) (xy 76.048849 -274.786907) (xy 76.07907 -274.828503)
			(xy 76.102413 -274.874315) (xy 76.118301 -274.923214) (xy 76.126344 -274.973996) (xy 76.126848 -274.999704)
			(xy 76.126843 -274.999958) (xy 76.443852 -274.999958) (xy 76.447812 -274.950904) (xy 76.459589 -274.90312)
			(xy 76.47888 -274.857844) (xy 76.505183 -274.816248) (xy 76.537818 -274.779411) (xy 76.575939 -274.748286)
			(xy 76.61856 -274.723679) (xy 76.664576 -274.706227) (xy 76.712795 -274.696383) (xy 76.76197 -274.694402)
			(xy 76.810825 -274.700334) (xy 76.858096 -274.714026) (xy 76.902558 -274.735124) (xy 76.943061 -274.76308)
			(xy 76.978554 -274.797172) (xy 77.008119 -274.836516) (xy 77.03099 -274.880093) (xy 77.046574 -274.926774)
			(xy 77.054469 -274.975351) (xy 77.054964 -274.999958) (xy 77.054469 -275.024565) (xy 77.05429 -275.025666)
			(xy 77.372968 -275.025666) (xy 77.372968 -274.97425) (xy 77.381011 -274.923468) (xy 77.396899 -274.874569)
			(xy 77.420242 -274.828757) (xy 77.450463 -274.787161) (xy 77.486819 -274.750805) (xy 77.528415 -274.720584)
			(xy 77.574227 -274.697241) (xy 77.623126 -274.681353) (xy 77.673908 -274.67331) (xy 77.725324 -274.67331)
			(xy 77.776106 -274.681353) (xy 77.825005 -274.697241) (xy 77.870817 -274.720584) (xy 77.912413 -274.750805)
			(xy 77.948769 -274.787161) (xy 77.97899 -274.828757) (xy 78.002333 -274.874569) (xy 78.018221 -274.923468)
			(xy 78.026264 -274.97425) (xy 78.026768 -274.999958) (xy 78.343772 -274.999958) (xy 78.347732 -274.950904)
			(xy 78.359509 -274.90312) (xy 78.3788 -274.857844) (xy 78.405103 -274.816248) (xy 78.437738 -274.779411)
			(xy 78.475859 -274.748286) (xy 78.51848 -274.723679) (xy 78.564496 -274.706227) (xy 78.612715 -274.696383)
			(xy 78.66189 -274.694402) (xy 78.710745 -274.700334) (xy 78.758016 -274.714026) (xy 78.802478 -274.735124)
			(xy 78.842981 -274.76308) (xy 78.878474 -274.797172) (xy 78.908039 -274.836516) (xy 78.93091 -274.880093)
			(xy 78.946494 -274.926774) (xy 78.954389 -274.975351) (xy 78.954884 -274.999958) (xy 78.954389 -275.024565)
			(xy 78.95421 -275.025666) (xy 79.272888 -275.025666) (xy 79.272888 -274.97425) (xy 79.280931 -274.923468)
			(xy 79.296819 -274.874569) (xy 79.320162 -274.828757) (xy 79.350383 -274.787161) (xy 79.386739 -274.750805)
			(xy 79.428335 -274.720584) (xy 79.474147 -274.697241) (xy 79.523046 -274.681353) (xy 79.573828 -274.67331)
			(xy 79.625244 -274.67331) (xy 79.676026 -274.681353) (xy 79.724925 -274.697241) (xy 79.770737 -274.720584)
			(xy 79.812333 -274.750805) (xy 79.848689 -274.787161) (xy 79.87891 -274.828757) (xy 79.902253 -274.874569)
			(xy 79.918141 -274.923468) (xy 79.926184 -274.97425) (xy 79.926688 -274.999958) (xy 80.243946 -274.999958)
			(xy 80.247906 -274.950904) (xy 80.259683 -274.90312) (xy 80.278974 -274.857844) (xy 80.305277 -274.816248)
			(xy 80.337912 -274.779411) (xy 80.376033 -274.748286) (xy 80.418654 -274.723679) (xy 80.46467 -274.706227)
			(xy 80.512889 -274.696383) (xy 80.562064 -274.694402) (xy 80.610919 -274.700334) (xy 80.65819 -274.714026)
			(xy 80.702652 -274.735124) (xy 80.743155 -274.76308) (xy 80.778648 -274.797172) (xy 80.808213 -274.836516)
			(xy 80.831084 -274.880093) (xy 80.846668 -274.926774) (xy 80.854563 -274.975351) (xy 80.855058 -274.999958)
			(xy 80.854563 -275.024565) (xy 80.854425 -275.025412) (xy 81.173316 -275.025412) (xy 81.173316 -274.973996)
			(xy 81.181359 -274.923214) (xy 81.197247 -274.874315) (xy 81.22059 -274.828503) (xy 81.250811 -274.786907)
			(xy 81.287167 -274.750551) (xy 81.328763 -274.72033) (xy 81.374575 -274.696987) (xy 81.423474 -274.681099)
			(xy 81.474256 -274.673056) (xy 81.525672 -274.673056) (xy 81.576454 -274.681099) (xy 81.625353 -274.696987)
			(xy 81.671165 -274.72033) (xy 81.712761 -274.750551) (xy 81.749117 -274.786907) (xy 81.779338 -274.828503)
			(xy 81.802681 -274.874315) (xy 81.818569 -274.923214) (xy 81.826612 -274.973996) (xy 81.827116 -274.999704)
			(xy 81.826612 -275.025412) (xy 82.123276 -275.025412) (xy 82.123276 -274.973996) (xy 82.131319 -274.923214)
			(xy 82.147207 -274.874315) (xy 82.17055 -274.828503) (xy 82.200771 -274.786907) (xy 82.237127 -274.750551)
			(xy 82.278723 -274.72033) (xy 82.324535 -274.696987) (xy 82.373434 -274.681099) (xy 82.424216 -274.673056)
			(xy 82.475632 -274.673056) (xy 82.526414 -274.681099) (xy 82.575313 -274.696987) (xy 82.621125 -274.72033)
			(xy 82.662721 -274.750551) (xy 82.699077 -274.786907) (xy 82.729298 -274.828503) (xy 82.752641 -274.874315)
			(xy 82.768529 -274.923214) (xy 82.776572 -274.973996) (xy 82.777076 -274.999704) (xy 82.777071 -274.999958)
			(xy 83.094334 -274.999958) (xy 83.098294 -274.950904) (xy 83.110071 -274.90312) (xy 83.129362 -274.857844)
			(xy 83.155665 -274.816248) (xy 83.1883 -274.779411) (xy 83.226421 -274.748286) (xy 83.269042 -274.723679)
			(xy 83.315058 -274.706227) (xy 83.363277 -274.696383) (xy 83.412452 -274.694402) (xy 83.461307 -274.700334)
			(xy 83.508578 -274.714026) (xy 83.55304 -274.735124) (xy 83.593543 -274.76308) (xy 83.629036 -274.797172)
			(xy 83.658601 -274.836516) (xy 83.681472 -274.880093) (xy 83.697056 -274.926774) (xy 83.704951 -274.975351)
			(xy 83.705446 -274.999958) (xy 83.704951 -275.024565) (xy 83.697056 -275.073142) (xy 83.681472 -275.119823)
			(xy 83.658601 -275.1634) (xy 83.629036 -275.202744) (xy 83.593543 -275.236836) (xy 83.55304 -275.264792)
			(xy 83.508578 -275.28589) (xy 83.461307 -275.299582) (xy 83.412452 -275.305514) (xy 83.363277 -275.303533)
			(xy 83.315058 -275.293689) (xy 83.269042 -275.276237) (xy 83.226421 -275.25163) (xy 83.1883 -275.220505)
			(xy 83.155665 -275.183668) (xy 83.129362 -275.142072) (xy 83.110071 -275.096796) (xy 83.098294 -275.049012)
			(xy 83.094334 -274.999958) (xy 82.777071 -274.999958) (xy 82.776572 -275.025412) (xy 82.768529 -275.076194)
			(xy 82.752641 -275.125093) (xy 82.729298 -275.170905) (xy 82.699077 -275.212501) (xy 82.662721 -275.248857)
			(xy 82.621125 -275.279078) (xy 82.575313 -275.302421) (xy 82.526414 -275.318309) (xy 82.475632 -275.326352)
			(xy 82.424216 -275.326352) (xy 82.373434 -275.318309) (xy 82.324535 -275.302421) (xy 82.278723 -275.279078)
			(xy 82.237127 -275.248857) (xy 82.200771 -275.212501) (xy 82.17055 -275.170905) (xy 82.147207 -275.125093)
			(xy 82.131319 -275.076194) (xy 82.123276 -275.025412) (xy 81.826612 -275.025412) (xy 81.818569 -275.076194)
			(xy 81.802681 -275.125093) (xy 81.779338 -275.170905) (xy 81.749117 -275.212501) (xy 81.712761 -275.248857)
			(xy 81.671165 -275.279078) (xy 81.625353 -275.302421) (xy 81.576454 -275.318309) (xy 81.525672 -275.326352)
			(xy 81.474256 -275.326352) (xy 81.423474 -275.318309) (xy 81.374575 -275.302421) (xy 81.328763 -275.279078)
			(xy 81.287167 -275.248857) (xy 81.250811 -275.212501) (xy 81.22059 -275.170905) (xy 81.197247 -275.125093)
			(xy 81.181359 -275.076194) (xy 81.173316 -275.025412) (xy 80.854425 -275.025412) (xy 80.846668 -275.073142)
			(xy 80.831084 -275.119823) (xy 80.808213 -275.1634) (xy 80.778648 -275.202744) (xy 80.743155 -275.236836)
			(xy 80.702652 -275.264792) (xy 80.65819 -275.28589) (xy 80.610919 -275.299582) (xy 80.562064 -275.305514)
			(xy 80.512889 -275.303533) (xy 80.46467 -275.293689) (xy 80.418654 -275.276237) (xy 80.376033 -275.25163)
			(xy 80.337912 -275.220505) (xy 80.305277 -275.183668) (xy 80.278974 -275.142072) (xy 80.259683 -275.096796)
			(xy 80.247906 -275.049012) (xy 80.243946 -274.999958) (xy 79.926688 -274.999958) (xy 79.926184 -275.025666)
			(xy 79.918141 -275.076448) (xy 79.902253 -275.125347) (xy 79.87891 -275.171159) (xy 79.848689 -275.212755)
			(xy 79.812333 -275.249111) (xy 79.770737 -275.279332) (xy 79.724925 -275.302675) (xy 79.676026 -275.318563)
			(xy 79.625244 -275.326606) (xy 79.573828 -275.326606) (xy 79.523046 -275.318563) (xy 79.474147 -275.302675)
			(xy 79.428335 -275.279332) (xy 79.386739 -275.249111) (xy 79.350383 -275.212755) (xy 79.320162 -275.171159)
			(xy 79.296819 -275.125347) (xy 79.280931 -275.076448) (xy 79.272888 -275.025666) (xy 78.95421 -275.025666)
			(xy 78.946494 -275.073142) (xy 78.93091 -275.119823) (xy 78.908039 -275.1634) (xy 78.878474 -275.202744)
			(xy 78.842981 -275.236836) (xy 78.802478 -275.264792) (xy 78.758016 -275.28589) (xy 78.710745 -275.299582)
			(xy 78.66189 -275.305514) (xy 78.612715 -275.303533) (xy 78.564496 -275.293689) (xy 78.51848 -275.276237)
			(xy 78.475859 -275.25163) (xy 78.437738 -275.220505) (xy 78.405103 -275.183668) (xy 78.3788 -275.142072)
			(xy 78.359509 -275.096796) (xy 78.347732 -275.049012) (xy 78.343772 -274.999958) (xy 78.026768 -274.999958)
			(xy 78.026264 -275.025666) (xy 78.018221 -275.076448) (xy 78.002333 -275.125347) (xy 77.97899 -275.171159)
			(xy 77.948769 -275.212755) (xy 77.912413 -275.249111) (xy 77.870817 -275.279332) (xy 77.825005 -275.302675)
			(xy 77.776106 -275.318563) (xy 77.725324 -275.326606) (xy 77.673908 -275.326606) (xy 77.623126 -275.318563)
			(xy 77.574227 -275.302675) (xy 77.528415 -275.279332) (xy 77.486819 -275.249111) (xy 77.450463 -275.212755)
			(xy 77.420242 -275.171159) (xy 77.396899 -275.125347) (xy 77.381011 -275.076448) (xy 77.372968 -275.025666)
			(xy 77.05429 -275.025666) (xy 77.046574 -275.073142) (xy 77.03099 -275.119823) (xy 77.008119 -275.1634)
			(xy 76.978554 -275.202744) (xy 76.943061 -275.236836) (xy 76.902558 -275.264792) (xy 76.858096 -275.28589)
			(xy 76.810825 -275.299582) (xy 76.76197 -275.305514) (xy 76.712795 -275.303533) (xy 76.664576 -275.293689)
			(xy 76.61856 -275.276237) (xy 76.575939 -275.25163) (xy 76.537818 -275.220505) (xy 76.505183 -275.183668)
			(xy 76.47888 -275.142072) (xy 76.459589 -275.096796) (xy 76.447812 -275.049012) (xy 76.443852 -274.999958)
			(xy 76.126843 -274.999958) (xy 76.126344 -275.025412) (xy 76.118301 -275.076194) (xy 76.102413 -275.125093)
			(xy 76.07907 -275.170905) (xy 76.048849 -275.212501) (xy 76.012493 -275.248857) (xy 75.970897 -275.279078)
			(xy 75.925085 -275.302421) (xy 75.876186 -275.318309) (xy 75.825404 -275.326352) (xy 75.773988 -275.326352)
			(xy 75.723206 -275.318309) (xy 75.674307 -275.302421) (xy 75.628495 -275.279078) (xy 75.586899 -275.248857)
			(xy 75.550543 -275.212501) (xy 75.520322 -275.170905) (xy 75.496979 -275.125093) (xy 75.481091 -275.076194)
			(xy 75.473048 -275.025412) (xy 75.154411 -275.025412) (xy 75.146654 -275.073142) (xy 75.13107 -275.119823)
			(xy 75.108199 -275.1634) (xy 75.078634 -275.202744) (xy 75.043141 -275.236836) (xy 75.002638 -275.264792)
			(xy 74.958176 -275.28589) (xy 74.910905 -275.299582) (xy 74.86205 -275.305514) (xy 74.812875 -275.303533)
			(xy 74.764656 -275.293689) (xy 74.71864 -275.276237) (xy 74.676019 -275.25163) (xy 74.637898 -275.220505)
			(xy 74.605263 -275.183668) (xy 74.57896 -275.142072) (xy 74.559669 -275.096796) (xy 74.547892 -275.049012)
			(xy 74.543932 -274.999958) (xy 74.226674 -274.999958) (xy 74.22617 -275.025666) (xy 74.218127 -275.076448)
			(xy 74.202239 -275.125347) (xy 74.178896 -275.171159) (xy 74.148675 -275.212755) (xy 74.112319 -275.249111)
			(xy 74.070723 -275.279332) (xy 74.024911 -275.302675) (xy 73.976012 -275.318563) (xy 73.92523 -275.326606)
			(xy 73.873814 -275.326606) (xy 73.823032 -275.318563) (xy 73.774133 -275.302675) (xy 73.728321 -275.279332)
			(xy 73.686725 -275.249111) (xy 73.650369 -275.212755) (xy 73.620148 -275.171159) (xy 73.596805 -275.125347)
			(xy 73.580917 -275.076448) (xy 73.572874 -275.025666) (xy 73.25445 -275.025666) (xy 73.246734 -275.073142)
			(xy 73.23115 -275.119823) (xy 73.208279 -275.1634) (xy 73.178714 -275.202744) (xy 73.143221 -275.236836)
			(xy 73.102718 -275.264792) (xy 73.058256 -275.28589) (xy 73.010985 -275.299582) (xy 72.96213 -275.305514)
			(xy 72.912955 -275.303533) (xy 72.864736 -275.293689) (xy 72.81872 -275.276237) (xy 72.776099 -275.25163)
			(xy 72.737978 -275.220505) (xy 72.705343 -275.183668) (xy 72.67904 -275.142072) (xy 72.659749 -275.096796)
			(xy 72.647972 -275.049012) (xy 72.644012 -274.999958) (xy 72.326749 -274.999958) (xy 72.32625 -275.025412)
			(xy 72.318207 -275.076194) (xy 72.302319 -275.125093) (xy 72.278976 -275.170905) (xy 72.248755 -275.212501)
			(xy 72.212399 -275.248857) (xy 72.170803 -275.279078) (xy 72.124991 -275.302421) (xy 72.076092 -275.318309)
			(xy 72.02531 -275.326352) (xy 71.973894 -275.326352) (xy 71.923112 -275.318309) (xy 71.874213 -275.302421)
			(xy 71.828401 -275.279078) (xy 71.786805 -275.248857) (xy 71.750449 -275.212501) (xy 71.720228 -275.170905)
			(xy 71.696885 -275.125093) (xy 71.680997 -275.076194) (xy 71.672954 -275.025412) (xy 71.354571 -275.025412)
			(xy 71.346814 -275.073142) (xy 71.33123 -275.119823) (xy 71.308359 -275.1634) (xy 71.278794 -275.202744)
			(xy 71.243301 -275.236836) (xy 71.202798 -275.264792) (xy 71.158336 -275.28589) (xy 71.111065 -275.299582)
			(xy 71.06221 -275.305514) (xy 71.013035 -275.303533) (xy 70.964816 -275.293689) (xy 70.9188 -275.276237)
			(xy 70.876179 -275.25163) (xy 70.838058 -275.220505) (xy 70.805423 -275.183668) (xy 70.77912 -275.142072)
			(xy 70.759829 -275.096796) (xy 70.748052 -275.049012) (xy 70.744092 -274.999958) (xy 70.42658 -274.999958)
			(xy 70.426076 -275.025666) (xy 70.418033 -275.076448) (xy 70.402145 -275.125347) (xy 70.378802 -275.171159)
			(xy 70.348581 -275.212755) (xy 70.312225 -275.249111) (xy 70.270629 -275.279332) (xy 70.224817 -275.302675)
			(xy 70.175918 -275.318563) (xy 70.125136 -275.326606) (xy 70.07372 -275.326606) (xy 70.022938 -275.318563)
			(xy 69.974039 -275.302675) (xy 69.928227 -275.279332) (xy 69.886631 -275.249111) (xy 69.850275 -275.212755)
			(xy 69.820054 -275.171159) (xy 69.796711 -275.125347) (xy 69.780823 -275.076448) (xy 69.77278 -275.025666)
			(xy 69.45461 -275.025666) (xy 69.446894 -275.073142) (xy 69.43131 -275.119823) (xy 69.408439 -275.1634)
			(xy 69.378874 -275.202744) (xy 69.343381 -275.236836) (xy 69.302878 -275.264792) (xy 69.258416 -275.28589)
			(xy 69.211145 -275.299582) (xy 69.16229 -275.305514) (xy 69.113115 -275.303533) (xy 69.064896 -275.293689)
			(xy 69.01888 -275.276237) (xy 68.976259 -275.25163) (xy 68.938138 -275.220505) (xy 68.905503 -275.183668)
			(xy 68.8792 -275.142072) (xy 68.859909 -275.096796) (xy 68.848132 -275.049012) (xy 68.844172 -274.999958)
			(xy 68.526655 -274.999958) (xy 68.526156 -275.025412) (xy 68.518113 -275.076194) (xy 68.502225 -275.125093)
			(xy 68.478882 -275.170905) (xy 68.448661 -275.212501) (xy 68.412305 -275.248857) (xy 68.370709 -275.279078)
			(xy 68.324897 -275.302421) (xy 68.275998 -275.318309) (xy 68.225216 -275.326352) (xy 68.1738 -275.326352)
			(xy 68.123018 -275.318309) (xy 68.074119 -275.302421) (xy 68.028307 -275.279078) (xy 67.986711 -275.248857)
			(xy 67.950355 -275.212501) (xy 67.920134 -275.170905) (xy 67.896791 -275.125093) (xy 67.880903 -275.076194)
			(xy 67.87286 -275.025412) (xy 67.554477 -275.025412) (xy 67.54672 -275.073142) (xy 67.531136 -275.119823)
			(xy 67.508265 -275.1634) (xy 67.4787 -275.202744) (xy 67.443207 -275.236836) (xy 67.402704 -275.264792)
			(xy 67.358242 -275.28589) (xy 67.310971 -275.299582) (xy 67.262116 -275.305514) (xy 67.212941 -275.303533)
			(xy 67.164722 -275.293689) (xy 67.118706 -275.276237) (xy 67.076085 -275.25163) (xy 67.037964 -275.220505)
			(xy 67.005329 -275.183668) (xy 66.979026 -275.142072) (xy 66.959735 -275.096796) (xy 66.947958 -275.049012)
			(xy 66.943998 -274.999958) (xy 66.62674 -274.999958) (xy 66.626236 -275.025666) (xy 66.618193 -275.076448)
			(xy 66.602305 -275.125347) (xy 66.578962 -275.171159) (xy 66.548741 -275.212755) (xy 66.512385 -275.249111)
			(xy 66.470789 -275.279332) (xy 66.424977 -275.302675) (xy 66.376078 -275.318563) (xy 66.325296 -275.326606)
			(xy 66.27388 -275.326606) (xy 66.223098 -275.318563) (xy 66.174199 -275.302675) (xy 66.128387 -275.279332)
			(xy 66.086791 -275.249111) (xy 66.050435 -275.212755) (xy 66.020214 -275.171159) (xy 65.996871 -275.125347)
			(xy 65.980983 -275.076448) (xy 65.97294 -275.025666) (xy 65.654516 -275.025666) (xy 65.6468 -275.073142)
			(xy 65.631216 -275.119823) (xy 65.608345 -275.1634) (xy 65.57878 -275.202744) (xy 65.543287 -275.236836)
			(xy 65.502784 -275.264792) (xy 65.458322 -275.28589) (xy 65.411051 -275.299582) (xy 65.362196 -275.305514)
			(xy 65.313021 -275.303533) (xy 65.264802 -275.293689) (xy 65.218786 -275.276237) (xy 65.176165 -275.25163)
			(xy 65.138044 -275.220505) (xy 65.105409 -275.183668) (xy 65.079106 -275.142072) (xy 65.059815 -275.096796)
			(xy 65.048038 -275.049012) (xy 65.044078 -274.999958) (xy 64.726815 -274.999958) (xy 64.726316 -275.025412)
			(xy 64.718273 -275.076194) (xy 64.702385 -275.125093) (xy 64.679042 -275.170905) (xy 64.648821 -275.212501)
			(xy 64.612465 -275.248857) (xy 64.570869 -275.279078) (xy 64.525057 -275.302421) (xy 64.476158 -275.318309)
			(xy 64.425376 -275.326352) (xy 64.37396 -275.326352) (xy 64.323178 -275.318309) (xy 64.274279 -275.302421)
			(xy 64.228467 -275.279078) (xy 64.186871 -275.248857) (xy 64.150515 -275.212501) (xy 64.120294 -275.170905)
			(xy 64.096951 -275.125093) (xy 64.081063 -275.076194) (xy 64.07302 -275.025412) (xy 63.754637 -275.025412)
			(xy 63.74688 -275.073142) (xy 63.731296 -275.119823) (xy 63.708425 -275.1634) (xy 63.67886 -275.202744)
			(xy 63.643367 -275.236836) (xy 63.602864 -275.264792) (xy 63.558402 -275.28589) (xy 63.511131 -275.299582)
			(xy 63.462276 -275.305514) (xy 63.413101 -275.303533) (xy 63.364882 -275.293689) (xy 63.318866 -275.276237)
			(xy 63.276245 -275.25163) (xy 63.238124 -275.220505) (xy 63.205489 -275.183668) (xy 63.179186 -275.142072)
			(xy 63.159895 -275.096796) (xy 63.148118 -275.049012) (xy 63.144158 -274.999958) (xy 62.826646 -274.999958)
			(xy 62.826142 -275.025666) (xy 62.818099 -275.076448) (xy 62.802211 -275.125347) (xy 62.778868 -275.171159)
			(xy 62.748647 -275.212755) (xy 62.712291 -275.249111) (xy 62.670695 -275.279332) (xy 62.624883 -275.302675)
			(xy 62.575984 -275.318563) (xy 62.525202 -275.326606) (xy 62.473786 -275.326606) (xy 62.423004 -275.318563)
			(xy 62.374105 -275.302675) (xy 62.328293 -275.279332) (xy 62.286697 -275.249111) (xy 62.250341 -275.212755)
			(xy 62.22012 -275.171159) (xy 62.196777 -275.125347) (xy 62.180889 -275.076448) (xy 62.172846 -275.025666)
			(xy 61.854422 -275.025666) (xy 61.846706 -275.073142) (xy 61.831122 -275.119823) (xy 61.808251 -275.1634)
			(xy 61.778686 -275.202744) (xy 61.743193 -275.236836) (xy 61.70269 -275.264792) (xy 61.658228 -275.28589)
			(xy 61.610957 -275.299582) (xy 61.562102 -275.305514) (xy 61.512927 -275.303533) (xy 61.464708 -275.293689)
			(xy 61.418692 -275.276237) (xy 61.376071 -275.25163) (xy 61.33795 -275.220505) (xy 61.305315 -275.183668)
			(xy 61.279012 -275.142072) (xy 61.259721 -275.096796) (xy 61.247944 -275.049012) (xy 61.243984 -274.999958)
			(xy 60.926721 -274.999958) (xy 60.926222 -275.025412) (xy 60.918179 -275.076194) (xy 60.902291 -275.125093)
			(xy 60.878948 -275.170905) (xy 60.848727 -275.212501) (xy 60.812371 -275.248857) (xy 60.770775 -275.279078)
			(xy 60.724963 -275.302421) (xy 60.676064 -275.318309) (xy 60.625282 -275.326352) (xy 60.573866 -275.326352)
			(xy 60.523084 -275.318309) (xy 60.474185 -275.302421) (xy 60.428373 -275.279078) (xy 60.386777 -275.248857)
			(xy 60.350421 -275.212501) (xy 60.3202 -275.170905) (xy 60.296857 -275.125093) (xy 60.280969 -275.076194)
			(xy 60.272926 -275.025412) (xy 59.954651 -275.025412) (xy 59.954634 -275.026212) (xy 59.94566 -275.077948)
			(xy 59.927969 -275.127386) (xy 59.902084 -275.17307) (xy 59.868766 -275.213653) (xy 59.828997 -275.247939)
			(xy 59.78395 -275.274919) (xy 59.734953 -275.293795) (xy 59.709304 -275.299424) (xy 59.698665 -275.302086)
			(xy 59.680923 -275.314939) (xy 59.670162 -275.334023) (xy 59.668664 -275.34489) (xy 59.665921 -275.375016)
			(xy 59.657155 -275.434878) (xy 59.651138 -275.464524) (xy 59.650195 -275.469689) (xy 59.650203 -275.480186)
			(xy 59.651138 -275.485352) (xy 59.65715 -275.514999) (xy 59.66592 -275.57486) (xy 59.668664 -275.604986)
			(xy 59.670133 -275.615853) (xy 59.680927 -275.634917) (xy 59.698671 -275.647765) (xy 59.709304 -275.650452)
			(xy 59.734949 -275.656096) (xy 59.783946 -275.674971) (xy 59.828993 -275.701948) (xy 59.868762 -275.736233)
			(xy 59.902081 -275.776813) (xy 59.927969 -275.822495) (xy 59.945662 -275.871931) (xy 59.954639 -275.923665)
			(xy 59.955176 -275.949918) (xy 59.954733 -275.973545) (xy 59.954448 -275.975372) (xy 60.272926 -275.975372)
			(xy 60.272926 -275.923956) (xy 60.280969 -275.873174) (xy 60.296857 -275.824275) (xy 60.3202 -275.778463)
			(xy 60.350421 -275.736867) (xy 60.386777 -275.700511) (xy 60.428373 -275.67029) (xy 60.474185 -275.646947)
			(xy 60.523084 -275.631059) (xy 60.573866 -275.623016) (xy 60.625282 -275.623016) (xy 60.676064 -275.631059)
			(xy 60.724963 -275.646947) (xy 60.770775 -275.67029) (xy 60.812371 -275.700511) (xy 60.848727 -275.736867)
			(xy 60.878948 -275.778463) (xy 60.902291 -275.824275) (xy 60.918179 -275.873174) (xy 60.926222 -275.923956)
			(xy 60.926726 -275.949664) (xy 60.926721 -275.949918) (xy 61.243984 -275.949918) (xy 61.247944 -275.900864)
			(xy 61.259721 -275.85308) (xy 61.279012 -275.807804) (xy 61.305315 -275.766208) (xy 61.33795 -275.729371)
			(xy 61.376071 -275.698246) (xy 61.418692 -275.673639) (xy 61.464708 -275.656187) (xy 61.512927 -275.646343)
			(xy 61.562102 -275.644362) (xy 61.610957 -275.650294) (xy 61.658228 -275.663986) (xy 61.70269 -275.685084)
			(xy 61.743193 -275.71304) (xy 61.778686 -275.747132) (xy 61.808251 -275.786476) (xy 61.831122 -275.830053)
			(xy 61.846706 -275.876734) (xy 61.854601 -275.925311) (xy 61.855096 -275.949918) (xy 61.854601 -275.974525)
			(xy 61.854422 -275.975626) (xy 62.172846 -275.975626) (xy 62.172846 -275.92421) (xy 62.180889 -275.873428)
			(xy 62.196777 -275.824529) (xy 62.22012 -275.778717) (xy 62.250341 -275.737121) (xy 62.286697 -275.700765)
			(xy 62.328293 -275.670544) (xy 62.374105 -275.647201) (xy 62.423004 -275.631313) (xy 62.473786 -275.62327)
			(xy 62.525202 -275.62327) (xy 62.575984 -275.631313) (xy 62.624883 -275.647201) (xy 62.670695 -275.670544)
			(xy 62.712291 -275.700765) (xy 62.748647 -275.737121) (xy 62.778868 -275.778717) (xy 62.802211 -275.824529)
			(xy 62.818099 -275.873428) (xy 62.826142 -275.92421) (xy 62.826646 -275.949918) (xy 63.144158 -275.949918)
			(xy 63.148118 -275.900864) (xy 63.159895 -275.85308) (xy 63.179186 -275.807804) (xy 63.205489 -275.766208)
			(xy 63.238124 -275.729371) (xy 63.276245 -275.698246) (xy 63.318866 -275.673639) (xy 63.364882 -275.656187)
			(xy 63.413101 -275.646343) (xy 63.462276 -275.644362) (xy 63.511131 -275.650294) (xy 63.558402 -275.663986)
			(xy 63.602864 -275.685084) (xy 63.643367 -275.71304) (xy 63.67886 -275.747132) (xy 63.708425 -275.786476)
			(xy 63.731296 -275.830053) (xy 63.74688 -275.876734) (xy 63.754775 -275.925311) (xy 63.75527 -275.949918)
			(xy 63.754775 -275.974525) (xy 63.754637 -275.975372) (xy 64.07302 -275.975372) (xy 64.07302 -275.923956)
			(xy 64.081063 -275.873174) (xy 64.096951 -275.824275) (xy 64.120294 -275.778463) (xy 64.150515 -275.736867)
			(xy 64.186871 -275.700511) (xy 64.228467 -275.67029) (xy 64.274279 -275.646947) (xy 64.323178 -275.631059)
			(xy 64.37396 -275.623016) (xy 64.425376 -275.623016) (xy 64.476158 -275.631059) (xy 64.525057 -275.646947)
			(xy 64.570869 -275.67029) (xy 64.612465 -275.700511) (xy 64.648821 -275.736867) (xy 64.679042 -275.778463)
			(xy 64.702385 -275.824275) (xy 64.718273 -275.873174) (xy 64.726316 -275.923956) (xy 64.72682 -275.949664)
			(xy 64.726815 -275.949918) (xy 65.044078 -275.949918) (xy 65.048038 -275.900864) (xy 65.059815 -275.85308)
			(xy 65.079106 -275.807804) (xy 65.105409 -275.766208) (xy 65.138044 -275.729371) (xy 65.176165 -275.698246)
			(xy 65.218786 -275.673639) (xy 65.264802 -275.656187) (xy 65.313021 -275.646343) (xy 65.362196 -275.644362)
			(xy 65.411051 -275.650294) (xy 65.458322 -275.663986) (xy 65.502784 -275.685084) (xy 65.543287 -275.71304)
			(xy 65.57878 -275.747132) (xy 65.608345 -275.786476) (xy 65.631216 -275.830053) (xy 65.6468 -275.876734)
			(xy 65.654695 -275.925311) (xy 65.65519 -275.949918) (xy 65.654695 -275.974525) (xy 65.654516 -275.975626)
			(xy 65.97294 -275.975626) (xy 65.97294 -275.92421) (xy 65.980983 -275.873428) (xy 65.996871 -275.824529)
			(xy 66.020214 -275.778717) (xy 66.050435 -275.737121) (xy 66.086791 -275.700765) (xy 66.128387 -275.670544)
			(xy 66.174199 -275.647201) (xy 66.223098 -275.631313) (xy 66.27388 -275.62327) (xy 66.325296 -275.62327)
			(xy 66.376078 -275.631313) (xy 66.424977 -275.647201) (xy 66.470789 -275.670544) (xy 66.512385 -275.700765)
			(xy 66.548741 -275.737121) (xy 66.578962 -275.778717) (xy 66.602305 -275.824529) (xy 66.618193 -275.873428)
			(xy 66.626236 -275.92421) (xy 66.62674 -275.949918) (xy 66.943998 -275.949918) (xy 66.947958 -275.900864)
			(xy 66.959735 -275.85308) (xy 66.979026 -275.807804) (xy 67.005329 -275.766208) (xy 67.037964 -275.729371)
			(xy 67.076085 -275.698246) (xy 67.118706 -275.673639) (xy 67.164722 -275.656187) (xy 67.212941 -275.646343)
			(xy 67.262116 -275.644362) (xy 67.310971 -275.650294) (xy 67.358242 -275.663986) (xy 67.402704 -275.685084)
			(xy 67.443207 -275.71304) (xy 67.4787 -275.747132) (xy 67.508265 -275.786476) (xy 67.531136 -275.830053)
			(xy 67.54672 -275.876734) (xy 67.554615 -275.925311) (xy 67.55511 -275.949918) (xy 67.554615 -275.974525)
			(xy 67.554477 -275.975372) (xy 67.87286 -275.975372) (xy 67.87286 -275.923956) (xy 67.880903 -275.873174)
			(xy 67.896791 -275.824275) (xy 67.920134 -275.778463) (xy 67.950355 -275.736867) (xy 67.986711 -275.700511)
			(xy 68.028307 -275.67029) (xy 68.074119 -275.646947) (xy 68.123018 -275.631059) (xy 68.1738 -275.623016)
			(xy 68.225216 -275.623016) (xy 68.275998 -275.631059) (xy 68.324897 -275.646947) (xy 68.370709 -275.67029)
			(xy 68.412305 -275.700511) (xy 68.448661 -275.736867) (xy 68.478882 -275.778463) (xy 68.502225 -275.824275)
			(xy 68.518113 -275.873174) (xy 68.526156 -275.923956) (xy 68.52666 -275.949664) (xy 68.526655 -275.949918)
			(xy 68.844172 -275.949918) (xy 68.848132 -275.900864) (xy 68.859909 -275.85308) (xy 68.8792 -275.807804)
			(xy 68.905503 -275.766208) (xy 68.938138 -275.729371) (xy 68.976259 -275.698246) (xy 69.01888 -275.673639)
			(xy 69.064896 -275.656187) (xy 69.113115 -275.646343) (xy 69.16229 -275.644362) (xy 69.211145 -275.650294)
			(xy 69.258416 -275.663986) (xy 69.302878 -275.685084) (xy 69.343381 -275.71304) (xy 69.378874 -275.747132)
			(xy 69.408439 -275.786476) (xy 69.43131 -275.830053) (xy 69.446894 -275.876734) (xy 69.454789 -275.925311)
			(xy 69.455284 -275.949918) (xy 69.454789 -275.974525) (xy 69.45461 -275.975626) (xy 69.77278 -275.975626)
			(xy 69.77278 -275.92421) (xy 69.780823 -275.873428) (xy 69.796711 -275.824529) (xy 69.820054 -275.778717)
			(xy 69.850275 -275.737121) (xy 69.886631 -275.700765) (xy 69.928227 -275.670544) (xy 69.974039 -275.647201)
			(xy 70.022938 -275.631313) (xy 70.07372 -275.62327) (xy 70.125136 -275.62327) (xy 70.175918 -275.631313)
			(xy 70.224817 -275.647201) (xy 70.270629 -275.670544) (xy 70.312225 -275.700765) (xy 70.348581 -275.737121)
			(xy 70.378802 -275.778717) (xy 70.402145 -275.824529) (xy 70.418033 -275.873428) (xy 70.426076 -275.92421)
			(xy 70.42658 -275.949918) (xy 70.744092 -275.949918) (xy 70.748052 -275.900864) (xy 70.759829 -275.85308)
			(xy 70.77912 -275.807804) (xy 70.805423 -275.766208) (xy 70.838058 -275.729371) (xy 70.876179 -275.698246)
			(xy 70.9188 -275.673639) (xy 70.964816 -275.656187) (xy 71.013035 -275.646343) (xy 71.06221 -275.644362)
			(xy 71.111065 -275.650294) (xy 71.158336 -275.663986) (xy 71.202798 -275.685084) (xy 71.243301 -275.71304)
			(xy 71.278794 -275.747132) (xy 71.308359 -275.786476) (xy 71.33123 -275.830053) (xy 71.346814 -275.876734)
			(xy 71.354709 -275.925311) (xy 71.355204 -275.949918) (xy 71.354709 -275.974525) (xy 71.354571 -275.975372)
			(xy 71.672954 -275.975372) (xy 71.672954 -275.923956) (xy 71.680997 -275.873174) (xy 71.696885 -275.824275)
			(xy 71.720228 -275.778463) (xy 71.750449 -275.736867) (xy 71.786805 -275.700511) (xy 71.828401 -275.67029)
			(xy 71.874213 -275.646947) (xy 71.923112 -275.631059) (xy 71.973894 -275.623016) (xy 72.02531 -275.623016)
			(xy 72.076092 -275.631059) (xy 72.124991 -275.646947) (xy 72.170803 -275.67029) (xy 72.212399 -275.700511)
			(xy 72.248755 -275.736867) (xy 72.278976 -275.778463) (xy 72.302319 -275.824275) (xy 72.318207 -275.873174)
			(xy 72.32625 -275.923956) (xy 72.326754 -275.949664) (xy 72.326749 -275.949918) (xy 72.644012 -275.949918)
			(xy 72.647972 -275.900864) (xy 72.659749 -275.85308) (xy 72.67904 -275.807804) (xy 72.705343 -275.766208)
			(xy 72.737978 -275.729371) (xy 72.776099 -275.698246) (xy 72.81872 -275.673639) (xy 72.864736 -275.656187)
			(xy 72.912955 -275.646343) (xy 72.96213 -275.644362) (xy 73.010985 -275.650294) (xy 73.058256 -275.663986)
			(xy 73.102718 -275.685084) (xy 73.143221 -275.71304) (xy 73.178714 -275.747132) (xy 73.208279 -275.786476)
			(xy 73.23115 -275.830053) (xy 73.246734 -275.876734) (xy 73.254629 -275.925311) (xy 73.255124 -275.949918)
			(xy 73.254629 -275.974525) (xy 73.25445 -275.975626) (xy 73.572874 -275.975626) (xy 73.572874 -275.92421)
			(xy 73.580917 -275.873428) (xy 73.596805 -275.824529) (xy 73.620148 -275.778717) (xy 73.650369 -275.737121)
			(xy 73.686725 -275.700765) (xy 73.728321 -275.670544) (xy 73.774133 -275.647201) (xy 73.823032 -275.631313)
			(xy 73.873814 -275.62327) (xy 73.92523 -275.62327) (xy 73.976012 -275.631313) (xy 74.024911 -275.647201)
			(xy 74.070723 -275.670544) (xy 74.112319 -275.700765) (xy 74.148675 -275.737121) (xy 74.178896 -275.778717)
			(xy 74.202239 -275.824529) (xy 74.218127 -275.873428) (xy 74.22617 -275.92421) (xy 74.226674 -275.949918)
			(xy 74.544186 -275.949918) (xy 74.548146 -275.900864) (xy 74.559923 -275.85308) (xy 74.579214 -275.807804)
			(xy 74.605517 -275.766208) (xy 74.638152 -275.729371) (xy 74.676273 -275.698246) (xy 74.718894 -275.673639)
			(xy 74.76491 -275.656187) (xy 74.813129 -275.646343) (xy 74.862304 -275.644362) (xy 74.911159 -275.650294)
			(xy 74.95843 -275.663986) (xy 75.002892 -275.685084) (xy 75.043395 -275.71304) (xy 75.078888 -275.747132)
			(xy 75.108453 -275.786476) (xy 75.131324 -275.830053) (xy 75.146908 -275.876734) (xy 75.154803 -275.925311)
			(xy 75.155298 -275.949918) (xy 75.154803 -275.974525) (xy 75.154665 -275.975372) (xy 75.473048 -275.975372)
			(xy 75.473048 -275.923956) (xy 75.481091 -275.873174) (xy 75.496979 -275.824275) (xy 75.520322 -275.778463)
			(xy 75.550543 -275.736867) (xy 75.586899 -275.700511) (xy 75.628495 -275.67029) (xy 75.674307 -275.646947)
			(xy 75.723206 -275.631059) (xy 75.773988 -275.623016) (xy 75.825404 -275.623016) (xy 75.876186 -275.631059)
			(xy 75.925085 -275.646947) (xy 75.970897 -275.67029) (xy 76.012493 -275.700511) (xy 76.048849 -275.736867)
			(xy 76.07907 -275.778463) (xy 76.102413 -275.824275) (xy 76.118301 -275.873174) (xy 76.126344 -275.923956)
			(xy 76.126848 -275.949664) (xy 76.126843 -275.949918) (xy 76.444106 -275.949918) (xy 76.448066 -275.900864)
			(xy 76.459843 -275.85308) (xy 76.479134 -275.807804) (xy 76.505437 -275.766208) (xy 76.538072 -275.729371)
			(xy 76.576193 -275.698246) (xy 76.618814 -275.673639) (xy 76.66483 -275.656187) (xy 76.713049 -275.646343)
			(xy 76.762224 -275.644362) (xy 76.811079 -275.650294) (xy 76.85835 -275.663986) (xy 76.902812 -275.685084)
			(xy 76.943315 -275.71304) (xy 76.978808 -275.747132) (xy 77.008373 -275.786476) (xy 77.031244 -275.830053)
			(xy 77.046828 -275.876734) (xy 77.054723 -275.925311) (xy 77.055218 -275.949918) (xy 77.054723 -275.974525)
			(xy 77.054544 -275.975626) (xy 77.372968 -275.975626) (xy 77.372968 -275.92421) (xy 77.381011 -275.873428)
			(xy 77.396899 -275.824529) (xy 77.420242 -275.778717) (xy 77.450463 -275.737121) (xy 77.486819 -275.700765)
			(xy 77.528415 -275.670544) (xy 77.574227 -275.647201) (xy 77.623126 -275.631313) (xy 77.673908 -275.62327)
			(xy 77.725324 -275.62327) (xy 77.776106 -275.631313) (xy 77.825005 -275.647201) (xy 77.870817 -275.670544)
			(xy 77.912413 -275.700765) (xy 77.948769 -275.737121) (xy 77.97899 -275.778717) (xy 78.002333 -275.824529)
			(xy 78.018221 -275.873428) (xy 78.026264 -275.92421) (xy 78.026768 -275.949918) (xy 78.344026 -275.949918)
			(xy 78.347986 -275.900864) (xy 78.359763 -275.85308) (xy 78.379054 -275.807804) (xy 78.405357 -275.766208)
			(xy 78.437992 -275.729371) (xy 78.476113 -275.698246) (xy 78.518734 -275.673639) (xy 78.56475 -275.656187)
			(xy 78.612969 -275.646343) (xy 78.662144 -275.644362) (xy 78.710999 -275.650294) (xy 78.75827 -275.663986)
			(xy 78.802732 -275.685084) (xy 78.843235 -275.71304) (xy 78.878728 -275.747132) (xy 78.908293 -275.786476)
			(xy 78.931164 -275.830053) (xy 78.946748 -275.876734) (xy 78.954643 -275.925311) (xy 78.955138 -275.949918)
			(xy 78.954643 -275.974525) (xy 78.954464 -275.975626) (xy 79.272888 -275.975626) (xy 79.272888 -275.92421)
			(xy 79.280931 -275.873428) (xy 79.296819 -275.824529) (xy 79.320162 -275.778717) (xy 79.350383 -275.737121)
			(xy 79.386739 -275.700765) (xy 79.428335 -275.670544) (xy 79.474147 -275.647201) (xy 79.523046 -275.631313)
			(xy 79.573828 -275.62327) (xy 79.625244 -275.62327) (xy 79.676026 -275.631313) (xy 79.724925 -275.647201)
			(xy 79.770737 -275.670544) (xy 79.812333 -275.700765) (xy 79.848689 -275.737121) (xy 79.87891 -275.778717)
			(xy 79.902253 -275.824529) (xy 79.918141 -275.873428) (xy 79.926184 -275.92421) (xy 79.926688 -275.949918)
			(xy 80.2442 -275.949918) (xy 80.24816 -275.900864) (xy 80.259937 -275.85308) (xy 80.279228 -275.807804)
			(xy 80.305531 -275.766208) (xy 80.338166 -275.729371) (xy 80.376287 -275.698246) (xy 80.418908 -275.673639)
			(xy 80.464924 -275.656187) (xy 80.513143 -275.646343) (xy 80.562318 -275.644362) (xy 80.611173 -275.650294)
			(xy 80.658444 -275.663986) (xy 80.702906 -275.685084) (xy 80.743409 -275.71304) (xy 80.778902 -275.747132)
			(xy 80.808467 -275.786476) (xy 80.831338 -275.830053) (xy 80.846922 -275.876734) (xy 80.854817 -275.925311)
			(xy 80.855312 -275.949918) (xy 81.19416 -275.949918) (xy 81.19812 -275.900864) (xy 81.209897 -275.85308)
			(xy 81.229188 -275.807804) (xy 81.255491 -275.766208) (xy 81.288126 -275.729371) (xy 81.326247 -275.698246)
			(xy 81.368868 -275.673639) (xy 81.414884 -275.656187) (xy 81.463103 -275.646343) (xy 81.512278 -275.644362)
			(xy 81.561133 -275.650294) (xy 81.608404 -275.663986) (xy 81.652866 -275.685084) (xy 81.693369 -275.71304)
			(xy 81.728862 -275.747132) (xy 81.758427 -275.786476) (xy 81.781298 -275.830053) (xy 81.796882 -275.876734)
			(xy 81.804777 -275.925311) (xy 81.805272 -275.949918) (xy 82.14412 -275.949918) (xy 82.14808 -275.900864)
			(xy 82.159857 -275.85308) (xy 82.179148 -275.807804) (xy 82.205451 -275.766208) (xy 82.238086 -275.729371)
			(xy 82.276207 -275.698246) (xy 82.318828 -275.673639) (xy 82.364844 -275.656187) (xy 82.413063 -275.646343)
			(xy 82.462238 -275.644362) (xy 82.511093 -275.650294) (xy 82.558364 -275.663986) (xy 82.602826 -275.685084)
			(xy 82.643329 -275.71304) (xy 82.678822 -275.747132) (xy 82.708387 -275.786476) (xy 82.731258 -275.830053)
			(xy 82.746842 -275.876734) (xy 82.754737 -275.925311) (xy 82.755232 -275.949918) (xy 82.754737 -275.974525)
			(xy 82.746842 -276.023102) (xy 82.731258 -276.069783) (xy 82.708387 -276.11336) (xy 82.678822 -276.152704)
			(xy 82.643329 -276.186796) (xy 82.602826 -276.214752) (xy 82.558364 -276.23585) (xy 82.511093 -276.249542)
			(xy 82.462238 -276.255474) (xy 82.413063 -276.253493) (xy 82.364844 -276.243649) (xy 82.318828 -276.226197)
			(xy 82.276207 -276.20159) (xy 82.238086 -276.170465) (xy 82.205451 -276.133628) (xy 82.179148 -276.092032)
			(xy 82.159857 -276.046756) (xy 82.14808 -275.998972) (xy 82.14412 -275.949918) (xy 81.805272 -275.949918)
			(xy 81.804777 -275.974525) (xy 81.796882 -276.023102) (xy 81.781298 -276.069783) (xy 81.758427 -276.11336)
			(xy 81.728862 -276.152704) (xy 81.693369 -276.186796) (xy 81.652866 -276.214752) (xy 81.608404 -276.23585)
			(xy 81.561133 -276.249542) (xy 81.512278 -276.255474) (xy 81.463103 -276.253493) (xy 81.414884 -276.243649)
			(xy 81.368868 -276.226197) (xy 81.326247 -276.20159) (xy 81.288126 -276.170465) (xy 81.255491 -276.133628)
			(xy 81.229188 -276.092032) (xy 81.209897 -276.046756) (xy 81.19812 -275.998972) (xy 81.19416 -275.949918)
			(xy 80.855312 -275.949918) (xy 80.854817 -275.974525) (xy 80.846922 -276.023102) (xy 80.831338 -276.069783)
			(xy 80.808467 -276.11336) (xy 80.778902 -276.152704) (xy 80.743409 -276.186796) (xy 80.702906 -276.214752)
			(xy 80.658444 -276.23585) (xy 80.611173 -276.249542) (xy 80.562318 -276.255474) (xy 80.513143 -276.253493)
			(xy 80.464924 -276.243649) (xy 80.418908 -276.226197) (xy 80.376287 -276.20159) (xy 80.338166 -276.170465)
			(xy 80.305531 -276.133628) (xy 80.279228 -276.092032) (xy 80.259937 -276.046756) (xy 80.24816 -275.998972)
			(xy 80.2442 -275.949918) (xy 79.926688 -275.949918) (xy 79.926184 -275.975626) (xy 79.918141 -276.026408)
			(xy 79.902253 -276.075307) (xy 79.87891 -276.121119) (xy 79.848689 -276.162715) (xy 79.812333 -276.199071)
			(xy 79.770737 -276.229292) (xy 79.724925 -276.252635) (xy 79.676026 -276.268523) (xy 79.625244 -276.276566)
			(xy 79.573828 -276.276566) (xy 79.523046 -276.268523) (xy 79.474147 -276.252635) (xy 79.428335 -276.229292)
			(xy 79.386739 -276.199071) (xy 79.350383 -276.162715) (xy 79.320162 -276.121119) (xy 79.296819 -276.075307)
			(xy 79.280931 -276.026408) (xy 79.272888 -275.975626) (xy 78.954464 -275.975626) (xy 78.946748 -276.023102)
			(xy 78.931164 -276.069783) (xy 78.908293 -276.11336) (xy 78.878728 -276.152704) (xy 78.843235 -276.186796)
			(xy 78.802732 -276.214752) (xy 78.75827 -276.23585) (xy 78.710999 -276.249542) (xy 78.662144 -276.255474)
			(xy 78.612969 -276.253493) (xy 78.56475 -276.243649) (xy 78.518734 -276.226197) (xy 78.476113 -276.20159)
			(xy 78.437992 -276.170465) (xy 78.405357 -276.133628) (xy 78.379054 -276.092032) (xy 78.359763 -276.046756)
			(xy 78.347986 -275.998972) (xy 78.344026 -275.949918) (xy 78.026768 -275.949918) (xy 78.026264 -275.975626)
			(xy 78.018221 -276.026408) (xy 78.002333 -276.075307) (xy 77.97899 -276.121119) (xy 77.948769 -276.162715)
			(xy 77.912413 -276.199071) (xy 77.870817 -276.229292) (xy 77.825005 -276.252635) (xy 77.776106 -276.268523)
			(xy 77.725324 -276.276566) (xy 77.673908 -276.276566) (xy 77.623126 -276.268523) (xy 77.574227 -276.252635)
			(xy 77.528415 -276.229292) (xy 77.486819 -276.199071) (xy 77.450463 -276.162715) (xy 77.420242 -276.121119)
			(xy 77.396899 -276.075307) (xy 77.381011 -276.026408) (xy 77.372968 -275.975626) (xy 77.054544 -275.975626)
			(xy 77.046828 -276.023102) (xy 77.031244 -276.069783) (xy 77.008373 -276.11336) (xy 76.978808 -276.152704)
			(xy 76.943315 -276.186796) (xy 76.902812 -276.214752) (xy 76.85835 -276.23585) (xy 76.811079 -276.249542)
			(xy 76.762224 -276.255474) (xy 76.713049 -276.253493) (xy 76.66483 -276.243649) (xy 76.618814 -276.226197)
			(xy 76.576193 -276.20159) (xy 76.538072 -276.170465) (xy 76.505437 -276.133628) (xy 76.479134 -276.092032)
			(xy 76.459843 -276.046756) (xy 76.448066 -275.998972) (xy 76.444106 -275.949918) (xy 76.126843 -275.949918)
			(xy 76.126344 -275.975372) (xy 76.118301 -276.026154) (xy 76.102413 -276.075053) (xy 76.07907 -276.120865)
			(xy 76.048849 -276.162461) (xy 76.012493 -276.198817) (xy 75.970897 -276.229038) (xy 75.925085 -276.252381)
			(xy 75.876186 -276.268269) (xy 75.825404 -276.276312) (xy 75.773988 -276.276312) (xy 75.723206 -276.268269)
			(xy 75.674307 -276.252381) (xy 75.628495 -276.229038) (xy 75.586899 -276.198817) (xy 75.550543 -276.162461)
			(xy 75.520322 -276.120865) (xy 75.496979 -276.075053) (xy 75.481091 -276.026154) (xy 75.473048 -275.975372)
			(xy 75.154665 -275.975372) (xy 75.146908 -276.023102) (xy 75.131324 -276.069783) (xy 75.108453 -276.11336)
			(xy 75.078888 -276.152704) (xy 75.043395 -276.186796) (xy 75.002892 -276.214752) (xy 74.95843 -276.23585)
			(xy 74.911159 -276.249542) (xy 74.862304 -276.255474) (xy 74.813129 -276.253493) (xy 74.76491 -276.243649)
			(xy 74.718894 -276.226197) (xy 74.676273 -276.20159) (xy 74.638152 -276.170465) (xy 74.605517 -276.133628)
			(xy 74.579214 -276.092032) (xy 74.559923 -276.046756) (xy 74.548146 -275.998972) (xy 74.544186 -275.949918)
			(xy 74.226674 -275.949918) (xy 74.22617 -275.975626) (xy 74.218127 -276.026408) (xy 74.202239 -276.075307)
			(xy 74.178896 -276.121119) (xy 74.148675 -276.162715) (xy 74.112319 -276.199071) (xy 74.070723 -276.229292)
			(xy 74.024911 -276.252635) (xy 73.976012 -276.268523) (xy 73.92523 -276.276566) (xy 73.873814 -276.276566)
			(xy 73.823032 -276.268523) (xy 73.774133 -276.252635) (xy 73.728321 -276.229292) (xy 73.686725 -276.199071)
			(xy 73.650369 -276.162715) (xy 73.620148 -276.121119) (xy 73.596805 -276.075307) (xy 73.580917 -276.026408)
			(xy 73.572874 -275.975626) (xy 73.25445 -275.975626) (xy 73.246734 -276.023102) (xy 73.23115 -276.069783)
			(xy 73.208279 -276.11336) (xy 73.178714 -276.152704) (xy 73.143221 -276.186796) (xy 73.102718 -276.214752)
			(xy 73.058256 -276.23585) (xy 73.010985 -276.249542) (xy 72.96213 -276.255474) (xy 72.912955 -276.253493)
			(xy 72.864736 -276.243649) (xy 72.81872 -276.226197) (xy 72.776099 -276.20159) (xy 72.737978 -276.170465)
			(xy 72.705343 -276.133628) (xy 72.67904 -276.092032) (xy 72.659749 -276.046756) (xy 72.647972 -275.998972)
			(xy 72.644012 -275.949918) (xy 72.326749 -275.949918) (xy 72.32625 -275.975372) (xy 72.318207 -276.026154)
			(xy 72.302319 -276.075053) (xy 72.278976 -276.120865) (xy 72.248755 -276.162461) (xy 72.212399 -276.198817)
			(xy 72.170803 -276.229038) (xy 72.124991 -276.252381) (xy 72.076092 -276.268269) (xy 72.02531 -276.276312)
			(xy 71.973894 -276.276312) (xy 71.923112 -276.268269) (xy 71.874213 -276.252381) (xy 71.828401 -276.229038)
			(xy 71.786805 -276.198817) (xy 71.750449 -276.162461) (xy 71.720228 -276.120865) (xy 71.696885 -276.075053)
			(xy 71.680997 -276.026154) (xy 71.672954 -275.975372) (xy 71.354571 -275.975372) (xy 71.346814 -276.023102)
			(xy 71.33123 -276.069783) (xy 71.308359 -276.11336) (xy 71.278794 -276.152704) (xy 71.243301 -276.186796)
			(xy 71.202798 -276.214752) (xy 71.158336 -276.23585) (xy 71.111065 -276.249542) (xy 71.06221 -276.255474)
			(xy 71.013035 -276.253493) (xy 70.964816 -276.243649) (xy 70.9188 -276.226197) (xy 70.876179 -276.20159)
			(xy 70.838058 -276.170465) (xy 70.805423 -276.133628) (xy 70.77912 -276.092032) (xy 70.759829 -276.046756)
			(xy 70.748052 -275.998972) (xy 70.744092 -275.949918) (xy 70.42658 -275.949918) (xy 70.426076 -275.975626)
			(xy 70.418033 -276.026408) (xy 70.402145 -276.075307) (xy 70.378802 -276.121119) (xy 70.348581 -276.162715)
			(xy 70.312225 -276.199071) (xy 70.270629 -276.229292) (xy 70.224817 -276.252635) (xy 70.175918 -276.268523)
			(xy 70.125136 -276.276566) (xy 70.07372 -276.276566) (xy 70.022938 -276.268523) (xy 69.974039 -276.252635)
			(xy 69.928227 -276.229292) (xy 69.886631 -276.199071) (xy 69.850275 -276.162715) (xy 69.820054 -276.121119)
			(xy 69.796711 -276.075307) (xy 69.780823 -276.026408) (xy 69.77278 -275.975626) (xy 69.45461 -275.975626)
			(xy 69.446894 -276.023102) (xy 69.43131 -276.069783) (xy 69.408439 -276.11336) (xy 69.378874 -276.152704)
			(xy 69.343381 -276.186796) (xy 69.302878 -276.214752) (xy 69.258416 -276.23585) (xy 69.211145 -276.249542)
			(xy 69.16229 -276.255474) (xy 69.113115 -276.253493) (xy 69.064896 -276.243649) (xy 69.01888 -276.226197)
			(xy 68.976259 -276.20159) (xy 68.938138 -276.170465) (xy 68.905503 -276.133628) (xy 68.8792 -276.092032)
			(xy 68.859909 -276.046756) (xy 68.848132 -275.998972) (xy 68.844172 -275.949918) (xy 68.526655 -275.949918)
			(xy 68.526156 -275.975372) (xy 68.518113 -276.026154) (xy 68.502225 -276.075053) (xy 68.478882 -276.120865)
			(xy 68.448661 -276.162461) (xy 68.412305 -276.198817) (xy 68.370709 -276.229038) (xy 68.324897 -276.252381)
			(xy 68.275998 -276.268269) (xy 68.225216 -276.276312) (xy 68.1738 -276.276312) (xy 68.123018 -276.268269)
			(xy 68.074119 -276.252381) (xy 68.028307 -276.229038) (xy 67.986711 -276.198817) (xy 67.950355 -276.162461)
			(xy 67.920134 -276.120865) (xy 67.896791 -276.075053) (xy 67.880903 -276.026154) (xy 67.87286 -275.975372)
			(xy 67.554477 -275.975372) (xy 67.54672 -276.023102) (xy 67.531136 -276.069783) (xy 67.508265 -276.11336)
			(xy 67.4787 -276.152704) (xy 67.443207 -276.186796) (xy 67.402704 -276.214752) (xy 67.358242 -276.23585)
			(xy 67.310971 -276.249542) (xy 67.262116 -276.255474) (xy 67.212941 -276.253493) (xy 67.164722 -276.243649)
			(xy 67.118706 -276.226197) (xy 67.076085 -276.20159) (xy 67.037964 -276.170465) (xy 67.005329 -276.133628)
			(xy 66.979026 -276.092032) (xy 66.959735 -276.046756) (xy 66.947958 -275.998972) (xy 66.943998 -275.949918)
			(xy 66.62674 -275.949918) (xy 66.626236 -275.975626) (xy 66.618193 -276.026408) (xy 66.602305 -276.075307)
			(xy 66.578962 -276.121119) (xy 66.548741 -276.162715) (xy 66.512385 -276.199071) (xy 66.470789 -276.229292)
			(xy 66.424977 -276.252635) (xy 66.376078 -276.268523) (xy 66.325296 -276.276566) (xy 66.27388 -276.276566)
			(xy 66.223098 -276.268523) (xy 66.174199 -276.252635) (xy 66.128387 -276.229292) (xy 66.086791 -276.199071)
			(xy 66.050435 -276.162715) (xy 66.020214 -276.121119) (xy 65.996871 -276.075307) (xy 65.980983 -276.026408)
			(xy 65.97294 -275.975626) (xy 65.654516 -275.975626) (xy 65.6468 -276.023102) (xy 65.631216 -276.069783)
			(xy 65.608345 -276.11336) (xy 65.57878 -276.152704) (xy 65.543287 -276.186796) (xy 65.502784 -276.214752)
			(xy 65.458322 -276.23585) (xy 65.411051 -276.249542) (xy 65.362196 -276.255474) (xy 65.313021 -276.253493)
			(xy 65.264802 -276.243649) (xy 65.218786 -276.226197) (xy 65.176165 -276.20159) (xy 65.138044 -276.170465)
			(xy 65.105409 -276.133628) (xy 65.079106 -276.092032) (xy 65.059815 -276.046756) (xy 65.048038 -275.998972)
			(xy 65.044078 -275.949918) (xy 64.726815 -275.949918) (xy 64.726316 -275.975372) (xy 64.718273 -276.026154)
			(xy 64.702385 -276.075053) (xy 64.679042 -276.120865) (xy 64.648821 -276.162461) (xy 64.612465 -276.198817)
			(xy 64.570869 -276.229038) (xy 64.525057 -276.252381) (xy 64.476158 -276.268269) (xy 64.425376 -276.276312)
			(xy 64.37396 -276.276312) (xy 64.323178 -276.268269) (xy 64.274279 -276.252381) (xy 64.228467 -276.229038)
			(xy 64.186871 -276.198817) (xy 64.150515 -276.162461) (xy 64.120294 -276.120865) (xy 64.096951 -276.075053)
			(xy 64.081063 -276.026154) (xy 64.07302 -275.975372) (xy 63.754637 -275.975372) (xy 63.74688 -276.023102)
			(xy 63.731296 -276.069783) (xy 63.708425 -276.11336) (xy 63.67886 -276.152704) (xy 63.643367 -276.186796)
			(xy 63.602864 -276.214752) (xy 63.558402 -276.23585) (xy 63.511131 -276.249542) (xy 63.462276 -276.255474)
			(xy 63.413101 -276.253493) (xy 63.364882 -276.243649) (xy 63.318866 -276.226197) (xy 63.276245 -276.20159)
			(xy 63.238124 -276.170465) (xy 63.205489 -276.133628) (xy 63.179186 -276.092032) (xy 63.159895 -276.046756)
			(xy 63.148118 -275.998972) (xy 63.144158 -275.949918) (xy 62.826646 -275.949918) (xy 62.826142 -275.975626)
			(xy 62.818099 -276.026408) (xy 62.802211 -276.075307) (xy 62.778868 -276.121119) (xy 62.748647 -276.162715)
			(xy 62.712291 -276.199071) (xy 62.670695 -276.229292) (xy 62.624883 -276.252635) (xy 62.575984 -276.268523)
			(xy 62.525202 -276.276566) (xy 62.473786 -276.276566) (xy 62.423004 -276.268523) (xy 62.374105 -276.252635)
			(xy 62.328293 -276.229292) (xy 62.286697 -276.199071) (xy 62.250341 -276.162715) (xy 62.22012 -276.121119)
			(xy 62.196777 -276.075307) (xy 62.180889 -276.026408) (xy 62.172846 -275.975626) (xy 61.854422 -275.975626)
			(xy 61.846706 -276.023102) (xy 61.831122 -276.069783) (xy 61.808251 -276.11336) (xy 61.778686 -276.152704)
			(xy 61.743193 -276.186796) (xy 61.70269 -276.214752) (xy 61.658228 -276.23585) (xy 61.610957 -276.249542)
			(xy 61.562102 -276.255474) (xy 61.512927 -276.253493) (xy 61.464708 -276.243649) (xy 61.418692 -276.226197)
			(xy 61.376071 -276.20159) (xy 61.33795 -276.170465) (xy 61.305315 -276.133628) (xy 61.279012 -276.092032)
			(xy 61.259721 -276.046756) (xy 61.247944 -275.998972) (xy 61.243984 -275.949918) (xy 60.926721 -275.949918)
			(xy 60.926222 -275.975372) (xy 60.918179 -276.026154) (xy 60.902291 -276.075053) (xy 60.878948 -276.120865)
			(xy 60.848727 -276.162461) (xy 60.812371 -276.198817) (xy 60.770775 -276.229038) (xy 60.724963 -276.252381)
			(xy 60.676064 -276.268269) (xy 60.625282 -276.276312) (xy 60.573866 -276.276312) (xy 60.523084 -276.268269)
			(xy 60.474185 -276.252381) (xy 60.428373 -276.229038) (xy 60.386777 -276.198817) (xy 60.350421 -276.162461)
			(xy 60.3202 -276.120865) (xy 60.296857 -276.075053) (xy 60.280969 -276.026154) (xy 60.272926 -275.975372)
			(xy 59.954448 -275.975372) (xy 59.947454 -276.020236) (xy 59.933071 -276.065248) (xy 59.911929 -276.107509)
			(xy 59.88453 -276.14601) (xy 59.85153 -276.179833) (xy 59.813715 -276.208171) (xy 59.771987 -276.230347)
			(xy 59.727342 -276.245833) (xy 59.680845 -276.254259) (xy 59.657234 -276.255226) (xy 59.647148 -276.255904)
			(xy 59.628716 -276.264166) (xy 59.614931 -276.278929) (xy 59.611006 -276.288246) (xy 59.595762 -276.328009)
			(xy 59.559256 -276.404953) (xy 59.538108 -276.441916) (xy 59.537854 -276.44217) (xy 59.5376 -276.442678)
			(xy 59.533447 -276.450719) (xy 59.530525 -276.468568) (xy 59.53398 -276.486321) (xy 59.538362 -276.49424)
			(xy 59.592718 -276.582886) (xy 59.617356 -276.59584) (xy 59.63158 -276.595078) (xy 59.649868 -276.59457)
			(xy 59.674692 -276.595053) (xy 59.723686 -276.603081) (xy 59.770735 -276.618929) (xy 59.814601 -276.64218)
			(xy 59.854127 -276.672222) (xy 59.888272 -276.708263) (xy 59.916136 -276.749354) (xy 59.936985 -276.794411)
			(xy 59.95027 -276.842248) (xy 59.95564 -276.891603) (xy 59.955192 -276.899878) (xy 60.294024 -276.899878)
			(xy 60.297984 -276.850824) (xy 60.309761 -276.80304) (xy 60.329052 -276.757764) (xy 60.355355 -276.716168)
			(xy 60.38799 -276.679331) (xy 60.426111 -276.648206) (xy 60.468732 -276.623599) (xy 60.514748 -276.606147)
			(xy 60.562967 -276.596303) (xy 60.612142 -276.594322) (xy 60.660997 -276.600254) (xy 60.708268 -276.613946)
			(xy 60.75273 -276.635044) (xy 60.793233 -276.663) (xy 60.828726 -276.697092) (xy 60.858291 -276.736436)
			(xy 60.881162 -276.780013) (xy 60.896746 -276.826694) (xy 60.904641 -276.875271) (xy 60.905136 -276.899878)
			(xy 61.243984 -276.899878) (xy 61.247944 -276.850824) (xy 61.259721 -276.80304) (xy 61.279012 -276.757764)
			(xy 61.305315 -276.716168) (xy 61.33795 -276.679331) (xy 61.376071 -276.648206) (xy 61.418692 -276.623599)
			(xy 61.464708 -276.606147) (xy 61.512927 -276.596303) (xy 61.562102 -276.594322) (xy 61.610957 -276.600254)
			(xy 61.658228 -276.613946) (xy 61.70269 -276.635044) (xy 61.743193 -276.663) (xy 61.778686 -276.697092)
			(xy 61.808251 -276.736436) (xy 61.831122 -276.780013) (xy 61.846706 -276.826694) (xy 61.854601 -276.875271)
			(xy 61.855096 -276.899878) (xy 62.193944 -276.899878) (xy 62.197904 -276.850824) (xy 62.209681 -276.80304)
			(xy 62.228972 -276.757764) (xy 62.255275 -276.716168) (xy 62.28791 -276.679331) (xy 62.326031 -276.648206)
			(xy 62.368652 -276.623599) (xy 62.414668 -276.606147) (xy 62.462887 -276.596303) (xy 62.512062 -276.594322)
			(xy 62.560917 -276.600254) (xy 62.608188 -276.613946) (xy 62.65265 -276.635044) (xy 62.693153 -276.663)
			(xy 62.728646 -276.697092) (xy 62.758211 -276.736436) (xy 62.781082 -276.780013) (xy 62.796666 -276.826694)
			(xy 62.804561 -276.875271) (xy 62.805056 -276.899878) (xy 63.144158 -276.899878) (xy 63.148118 -276.850824)
			(xy 63.159895 -276.80304) (xy 63.179186 -276.757764) (xy 63.205489 -276.716168) (xy 63.238124 -276.679331)
			(xy 63.276245 -276.648206) (xy 63.318866 -276.623599) (xy 63.364882 -276.606147) (xy 63.413101 -276.596303)
			(xy 63.462276 -276.594322) (xy 63.511131 -276.600254) (xy 63.558402 -276.613946) (xy 63.602864 -276.635044)
			(xy 63.643367 -276.663) (xy 63.67886 -276.697092) (xy 63.708425 -276.736436) (xy 63.731296 -276.780013)
			(xy 63.74688 -276.826694) (xy 63.754775 -276.875271) (xy 63.75527 -276.899878) (xy 64.094118 -276.899878)
			(xy 64.098078 -276.850824) (xy 64.109855 -276.80304) (xy 64.129146 -276.757764) (xy 64.155449 -276.716168)
			(xy 64.188084 -276.679331) (xy 64.226205 -276.648206) (xy 64.268826 -276.623599) (xy 64.314842 -276.606147)
			(xy 64.363061 -276.596303) (xy 64.412236 -276.594322) (xy 64.461091 -276.600254) (xy 64.508362 -276.613946)
			(xy 64.552824 -276.635044) (xy 64.593327 -276.663) (xy 64.62882 -276.697092) (xy 64.658385 -276.736436)
			(xy 64.681256 -276.780013) (xy 64.69684 -276.826694) (xy 64.704735 -276.875271) (xy 64.70523 -276.899878)
			(xy 65.044078 -276.899878) (xy 65.048038 -276.850824) (xy 65.059815 -276.80304) (xy 65.079106 -276.757764)
			(xy 65.105409 -276.716168) (xy 65.138044 -276.679331) (xy 65.176165 -276.648206) (xy 65.218786 -276.623599)
			(xy 65.264802 -276.606147) (xy 65.313021 -276.596303) (xy 65.362196 -276.594322) (xy 65.411051 -276.600254)
			(xy 65.458322 -276.613946) (xy 65.502784 -276.635044) (xy 65.543287 -276.663) (xy 65.57878 -276.697092)
			(xy 65.608345 -276.736436) (xy 65.631216 -276.780013) (xy 65.6468 -276.826694) (xy 65.654695 -276.875271)
			(xy 65.65519 -276.899878) (xy 65.994038 -276.899878) (xy 65.997998 -276.850824) (xy 66.009775 -276.80304)
			(xy 66.029066 -276.757764) (xy 66.055369 -276.716168) (xy 66.088004 -276.679331) (xy 66.126125 -276.648206)
			(xy 66.168746 -276.623599) (xy 66.214762 -276.606147) (xy 66.262981 -276.596303) (xy 66.312156 -276.594322)
			(xy 66.361011 -276.600254) (xy 66.408282 -276.613946) (xy 66.452744 -276.635044) (xy 66.493247 -276.663)
			(xy 66.52874 -276.697092) (xy 66.558305 -276.736436) (xy 66.581176 -276.780013) (xy 66.59676 -276.826694)
			(xy 66.604655 -276.875271) (xy 66.60515 -276.899878) (xy 66.943998 -276.899878) (xy 66.947958 -276.850824)
			(xy 66.959735 -276.80304) (xy 66.979026 -276.757764) (xy 67.005329 -276.716168) (xy 67.037964 -276.679331)
			(xy 67.076085 -276.648206) (xy 67.118706 -276.623599) (xy 67.164722 -276.606147) (xy 67.212941 -276.596303)
			(xy 67.262116 -276.594322) (xy 67.310971 -276.600254) (xy 67.358242 -276.613946) (xy 67.402704 -276.635044)
			(xy 67.443207 -276.663) (xy 67.4787 -276.697092) (xy 67.508265 -276.736436) (xy 67.531136 -276.780013)
			(xy 67.54672 -276.826694) (xy 67.554615 -276.875271) (xy 67.55511 -276.899878) (xy 67.893958 -276.899878)
			(xy 67.897918 -276.850824) (xy 67.909695 -276.80304) (xy 67.928986 -276.757764) (xy 67.955289 -276.716168)
			(xy 67.987924 -276.679331) (xy 68.026045 -276.648206) (xy 68.068666 -276.623599) (xy 68.114682 -276.606147)
			(xy 68.162901 -276.596303) (xy 68.212076 -276.594322) (xy 68.260931 -276.600254) (xy 68.308202 -276.613946)
			(xy 68.352664 -276.635044) (xy 68.393167 -276.663) (xy 68.42866 -276.697092) (xy 68.458225 -276.736436)
			(xy 68.481096 -276.780013) (xy 68.49668 -276.826694) (xy 68.504575 -276.875271) (xy 68.50507 -276.899878)
			(xy 68.844172 -276.899878) (xy 68.848132 -276.850824) (xy 68.859909 -276.80304) (xy 68.8792 -276.757764)
			(xy 68.905503 -276.716168) (xy 68.938138 -276.679331) (xy 68.976259 -276.648206) (xy 69.01888 -276.623599)
			(xy 69.064896 -276.606147) (xy 69.113115 -276.596303) (xy 69.16229 -276.594322) (xy 69.211145 -276.600254)
			(xy 69.258416 -276.613946) (xy 69.302878 -276.635044) (xy 69.343381 -276.663) (xy 69.378874 -276.697092)
			(xy 69.408439 -276.736436) (xy 69.43131 -276.780013) (xy 69.446894 -276.826694) (xy 69.454789 -276.875271)
			(xy 69.455284 -276.899878) (xy 69.794132 -276.899878) (xy 69.798092 -276.850824) (xy 69.809869 -276.80304)
			(xy 69.82916 -276.757764) (xy 69.855463 -276.716168) (xy 69.888098 -276.679331) (xy 69.926219 -276.648206)
			(xy 69.96884 -276.623599) (xy 70.014856 -276.606147) (xy 70.063075 -276.596303) (xy 70.11225 -276.594322)
			(xy 70.161105 -276.600254) (xy 70.208376 -276.613946) (xy 70.252838 -276.635044) (xy 70.293341 -276.663)
			(xy 70.328834 -276.697092) (xy 70.358399 -276.736436) (xy 70.38127 -276.780013) (xy 70.396854 -276.826694)
			(xy 70.404749 -276.875271) (xy 70.405244 -276.899878) (xy 70.744092 -276.899878) (xy 70.748052 -276.850824)
			(xy 70.759829 -276.80304) (xy 70.77912 -276.757764) (xy 70.805423 -276.716168) (xy 70.838058 -276.679331)
			(xy 70.876179 -276.648206) (xy 70.9188 -276.623599) (xy 70.964816 -276.606147) (xy 71.013035 -276.596303)
			(xy 71.06221 -276.594322) (xy 71.111065 -276.600254) (xy 71.158336 -276.613946) (xy 71.202798 -276.635044)
			(xy 71.243301 -276.663) (xy 71.278794 -276.697092) (xy 71.308359 -276.736436) (xy 71.33123 -276.780013)
			(xy 71.346814 -276.826694) (xy 71.354709 -276.875271) (xy 71.355204 -276.899878) (xy 71.694052 -276.899878)
			(xy 71.698012 -276.850824) (xy 71.709789 -276.80304) (xy 71.72908 -276.757764) (xy 71.755383 -276.716168)
			(xy 71.788018 -276.679331) (xy 71.826139 -276.648206) (xy 71.86876 -276.623599) (xy 71.914776 -276.606147)
			(xy 71.962995 -276.596303) (xy 72.01217 -276.594322) (xy 72.061025 -276.600254) (xy 72.108296 -276.613946)
			(xy 72.152758 -276.635044) (xy 72.193261 -276.663) (xy 72.228754 -276.697092) (xy 72.258319 -276.736436)
			(xy 72.28119 -276.780013) (xy 72.296774 -276.826694) (xy 72.304669 -276.875271) (xy 72.305164 -276.899878)
			(xy 72.644012 -276.899878) (xy 72.647972 -276.850824) (xy 72.659749 -276.80304) (xy 72.67904 -276.757764)
			(xy 72.705343 -276.716168) (xy 72.737978 -276.679331) (xy 72.776099 -276.648206) (xy 72.81872 -276.623599)
			(xy 72.864736 -276.606147) (xy 72.912955 -276.596303) (xy 72.96213 -276.594322) (xy 73.010985 -276.600254)
			(xy 73.058256 -276.613946) (xy 73.102718 -276.635044) (xy 73.143221 -276.663) (xy 73.178714 -276.697092)
			(xy 73.208279 -276.736436) (xy 73.23115 -276.780013) (xy 73.246734 -276.826694) (xy 73.254629 -276.875271)
			(xy 73.255124 -276.899878) (xy 73.593718 -276.899878) (xy 73.597678 -276.850824) (xy 73.609455 -276.80304)
			(xy 73.628746 -276.757764) (xy 73.655049 -276.716168) (xy 73.687684 -276.679331) (xy 73.725805 -276.648206)
			(xy 73.768426 -276.623599) (xy 73.814442 -276.606147) (xy 73.862661 -276.596303) (xy 73.911836 -276.594322)
			(xy 73.960691 -276.600254) (xy 74.007962 -276.613946) (xy 74.052424 -276.635044) (xy 74.092927 -276.663)
			(xy 74.12842 -276.697092) (xy 74.157985 -276.736436) (xy 74.180856 -276.780013) (xy 74.19644 -276.826694)
			(xy 74.204335 -276.875271) (xy 74.20483 -276.899878) (xy 74.543932 -276.899878) (xy 74.547892 -276.850824)
			(xy 74.559669 -276.80304) (xy 74.57896 -276.757764) (xy 74.605263 -276.716168) (xy 74.637898 -276.679331)
			(xy 74.676019 -276.648206) (xy 74.71864 -276.623599) (xy 74.764656 -276.606147) (xy 74.812875 -276.596303)
			(xy 74.86205 -276.594322) (xy 74.910905 -276.600254) (xy 74.958176 -276.613946) (xy 75.002638 -276.635044)
			(xy 75.043141 -276.663) (xy 75.078634 -276.697092) (xy 75.108199 -276.736436) (xy 75.13107 -276.780013)
			(xy 75.146654 -276.826694) (xy 75.154549 -276.875271) (xy 75.155044 -276.899878) (xy 75.493892 -276.899878)
			(xy 75.497852 -276.850824) (xy 75.509629 -276.80304) (xy 75.52892 -276.757764) (xy 75.555223 -276.716168)
			(xy 75.587858 -276.679331) (xy 75.625979 -276.648206) (xy 75.6686 -276.623599) (xy 75.714616 -276.606147)
			(xy 75.762835 -276.596303) (xy 75.81201 -276.594322) (xy 75.860865 -276.600254) (xy 75.908136 -276.613946)
			(xy 75.952598 -276.635044) (xy 75.993101 -276.663) (xy 76.028594 -276.697092) (xy 76.058159 -276.736436)
			(xy 76.08103 -276.780013) (xy 76.096614 -276.826694) (xy 76.104509 -276.875271) (xy 76.105004 -276.899878)
			(xy 76.443852 -276.899878) (xy 76.447812 -276.850824) (xy 76.459589 -276.80304) (xy 76.47888 -276.757764)
			(xy 76.505183 -276.716168) (xy 76.537818 -276.679331) (xy 76.575939 -276.648206) (xy 76.61856 -276.623599)
			(xy 76.664576 -276.606147) (xy 76.712795 -276.596303) (xy 76.76197 -276.594322) (xy 76.810825 -276.600254)
			(xy 76.858096 -276.613946) (xy 76.902558 -276.635044) (xy 76.943061 -276.663) (xy 76.978554 -276.697092)
			(xy 77.008119 -276.736436) (xy 77.03099 -276.780013) (xy 77.046574 -276.826694) (xy 77.054469 -276.875271)
			(xy 77.054964 -276.899878) (xy 77.393812 -276.899878) (xy 77.397772 -276.850824) (xy 77.409549 -276.80304)
			(xy 77.42884 -276.757764) (xy 77.455143 -276.716168) (xy 77.487778 -276.679331) (xy 77.525899 -276.648206)
			(xy 77.56852 -276.623599) (xy 77.614536 -276.606147) (xy 77.662755 -276.596303) (xy 77.71193 -276.594322)
			(xy 77.760785 -276.600254) (xy 77.808056 -276.613946) (xy 77.852518 -276.635044) (xy 77.893021 -276.663)
			(xy 77.928514 -276.697092) (xy 77.958079 -276.736436) (xy 77.98095 -276.780013) (xy 77.996534 -276.826694)
			(xy 78.004429 -276.875271) (xy 78.004924 -276.899878) (xy 78.343772 -276.899878) (xy 78.347732 -276.850824)
			(xy 78.359509 -276.80304) (xy 78.3788 -276.757764) (xy 78.405103 -276.716168) (xy 78.437738 -276.679331)
			(xy 78.475859 -276.648206) (xy 78.51848 -276.623599) (xy 78.564496 -276.606147) (xy 78.612715 -276.596303)
			(xy 78.66189 -276.594322) (xy 78.710745 -276.600254) (xy 78.758016 -276.613946) (xy 78.802478 -276.635044)
			(xy 78.842981 -276.663) (xy 78.878474 -276.697092) (xy 78.908039 -276.736436) (xy 78.93091 -276.780013)
			(xy 78.946494 -276.826694) (xy 78.954389 -276.875271) (xy 78.954884 -276.899878) (xy 79.293732 -276.899878)
			(xy 79.297692 -276.850824) (xy 79.309469 -276.80304) (xy 79.32876 -276.757764) (xy 79.355063 -276.716168)
			(xy 79.387698 -276.679331) (xy 79.425819 -276.648206) (xy 79.46844 -276.623599) (xy 79.514456 -276.606147)
			(xy 79.562675 -276.596303) (xy 79.61185 -276.594322) (xy 79.660705 -276.600254) (xy 79.707976 -276.613946)
			(xy 79.752438 -276.635044) (xy 79.792941 -276.663) (xy 79.828434 -276.697092) (xy 79.857999 -276.736436)
			(xy 79.88087 -276.780013) (xy 79.896454 -276.826694) (xy 79.904349 -276.875271) (xy 79.904844 -276.899878)
			(xy 80.243946 -276.899878) (xy 80.247906 -276.850824) (xy 80.259683 -276.80304) (xy 80.278974 -276.757764)
			(xy 80.305277 -276.716168) (xy 80.337912 -276.679331) (xy 80.376033 -276.648206) (xy 80.418654 -276.623599)
			(xy 80.46467 -276.606147) (xy 80.512889 -276.596303) (xy 80.562064 -276.594322) (xy 80.610919 -276.600254)
			(xy 80.65819 -276.613946) (xy 80.702652 -276.635044) (xy 80.743155 -276.663) (xy 80.778648 -276.697092)
			(xy 80.808213 -276.736436) (xy 80.831084 -276.780013) (xy 80.846668 -276.826694) (xy 80.854563 -276.875271)
			(xy 80.855058 -276.899878) (xy 81.19416 -276.899878) (xy 81.19812 -276.850824) (xy 81.209897 -276.80304)
			(xy 81.229188 -276.757764) (xy 81.255491 -276.716168) (xy 81.288126 -276.679331) (xy 81.326247 -276.648206)
			(xy 81.368868 -276.623599) (xy 81.414884 -276.606147) (xy 81.463103 -276.596303) (xy 81.512278 -276.594322)
			(xy 81.561133 -276.600254) (xy 81.608404 -276.613946) (xy 81.652866 -276.635044) (xy 81.693369 -276.663)
			(xy 81.728862 -276.697092) (xy 81.758427 -276.736436) (xy 81.781298 -276.780013) (xy 81.796882 -276.826694)
			(xy 81.804777 -276.875271) (xy 81.805272 -276.899878) (xy 82.14412 -276.899878) (xy 82.14808 -276.850824)
			(xy 82.159857 -276.80304) (xy 82.179148 -276.757764) (xy 82.205451 -276.716168) (xy 82.238086 -276.679331)
			(xy 82.276207 -276.648206) (xy 82.318828 -276.623599) (xy 82.364844 -276.606147) (xy 82.413063 -276.596303)
			(xy 82.462238 -276.594322) (xy 82.511093 -276.600254) (xy 82.558364 -276.613946) (xy 82.602826 -276.635044)
			(xy 82.643329 -276.663) (xy 82.678822 -276.697092) (xy 82.708387 -276.736436) (xy 82.731258 -276.780013)
			(xy 82.746842 -276.826694) (xy 82.754737 -276.875271) (xy 82.755232 -276.899878) (xy 82.755227 -276.900132)
			(xy 83.094334 -276.900132) (xy 83.098294 -276.851078) (xy 83.110071 -276.803294) (xy 83.129362 -276.758018)
			(xy 83.155665 -276.716422) (xy 83.1883 -276.679585) (xy 83.226421 -276.64846) (xy 83.269042 -276.623853)
			(xy 83.315058 -276.606401) (xy 83.363277 -276.596557) (xy 83.412452 -276.594576) (xy 83.461307 -276.600508)
			(xy 83.508578 -276.6142) (xy 83.55304 -276.635298) (xy 83.593543 -276.663254) (xy 83.629036 -276.697346)
			(xy 83.658601 -276.73669) (xy 83.681472 -276.780267) (xy 83.697056 -276.826948) (xy 83.704951 -276.875525)
			(xy 83.705446 -276.900132) (xy 83.704951 -276.924739) (xy 83.697056 -276.973316) (xy 83.681472 -277.019997)
			(xy 83.658601 -277.063574) (xy 83.629036 -277.102918) (xy 83.593543 -277.13701) (xy 83.55304 -277.164966)
			(xy 83.508578 -277.186064) (xy 83.461307 -277.199756) (xy 83.412452 -277.205688) (xy 83.363277 -277.203707)
			(xy 83.315058 -277.193863) (xy 83.269042 -277.176411) (xy 83.226421 -277.151804) (xy 83.1883 -277.120679)
			(xy 83.155665 -277.083842) (xy 83.129362 -277.042246) (xy 83.110071 -276.99697) (xy 83.098294 -276.949186)
			(xy 83.094334 -276.900132) (xy 82.755227 -276.900132) (xy 82.754737 -276.924485) (xy 82.746842 -276.973062)
			(xy 82.731258 -277.019743) (xy 82.708387 -277.06332) (xy 82.678822 -277.102664) (xy 82.643329 -277.136756)
			(xy 82.602826 -277.164712) (xy 82.558364 -277.18581) (xy 82.511093 -277.199502) (xy 82.462238 -277.205434)
			(xy 82.413063 -277.203453) (xy 82.364844 -277.193609) (xy 82.318828 -277.176157) (xy 82.276207 -277.15155)
			(xy 82.238086 -277.120425) (xy 82.205451 -277.083588) (xy 82.179148 -277.041992) (xy 82.159857 -276.996716)
			(xy 82.14808 -276.948932) (xy 82.14412 -276.899878) (xy 81.805272 -276.899878) (xy 81.804777 -276.924485)
			(xy 81.796882 -276.973062) (xy 81.781298 -277.019743) (xy 81.758427 -277.06332) (xy 81.728862 -277.102664)
			(xy 81.693369 -277.136756) (xy 81.652866 -277.164712) (xy 81.608404 -277.18581) (xy 81.561133 -277.199502)
			(xy 81.512278 -277.205434) (xy 81.463103 -277.203453) (xy 81.414884 -277.193609) (xy 81.368868 -277.176157)
			(xy 81.326247 -277.15155) (xy 81.288126 -277.120425) (xy 81.255491 -277.083588) (xy 81.229188 -277.041992)
			(xy 81.209897 -276.996716) (xy 81.19812 -276.948932) (xy 81.19416 -276.899878) (xy 80.855058 -276.899878)
			(xy 80.854563 -276.924485) (xy 80.846668 -276.973062) (xy 80.831084 -277.019743) (xy 80.808213 -277.06332)
			(xy 80.778648 -277.102664) (xy 80.743155 -277.136756) (xy 80.702652 -277.164712) (xy 80.65819 -277.18581)
			(xy 80.610919 -277.199502) (xy 80.562064 -277.205434) (xy 80.512889 -277.203453) (xy 80.46467 -277.193609)
			(xy 80.418654 -277.176157) (xy 80.376033 -277.15155) (xy 80.337912 -277.120425) (xy 80.305277 -277.083588)
			(xy 80.278974 -277.041992) (xy 80.259683 -276.996716) (xy 80.247906 -276.948932) (xy 80.243946 -276.899878)
			(xy 79.904844 -276.899878) (xy 79.904349 -276.924485) (xy 79.896454 -276.973062) (xy 79.88087 -277.019743)
			(xy 79.857999 -277.06332) (xy 79.828434 -277.102664) (xy 79.792941 -277.136756) (xy 79.752438 -277.164712)
			(xy 79.707976 -277.18581) (xy 79.660705 -277.199502) (xy 79.61185 -277.205434) (xy 79.562675 -277.203453)
			(xy 79.514456 -277.193609) (xy 79.46844 -277.176157) (xy 79.425819 -277.15155) (xy 79.387698 -277.120425)
			(xy 79.355063 -277.083588) (xy 79.32876 -277.041992) (xy 79.309469 -276.996716) (xy 79.297692 -276.948932)
			(xy 79.293732 -276.899878) (xy 78.954884 -276.899878) (xy 78.954389 -276.924485) (xy 78.946494 -276.973062)
			(xy 78.93091 -277.019743) (xy 78.908039 -277.06332) (xy 78.878474 -277.102664) (xy 78.842981 -277.136756)
			(xy 78.802478 -277.164712) (xy 78.758016 -277.18581) (xy 78.710745 -277.199502) (xy 78.66189 -277.205434)
			(xy 78.612715 -277.203453) (xy 78.564496 -277.193609) (xy 78.51848 -277.176157) (xy 78.475859 -277.15155)
			(xy 78.437738 -277.120425) (xy 78.405103 -277.083588) (xy 78.3788 -277.041992) (xy 78.359509 -276.996716)
			(xy 78.347732 -276.948932) (xy 78.343772 -276.899878) (xy 78.004924 -276.899878) (xy 78.004429 -276.924485)
			(xy 77.996534 -276.973062) (xy 77.98095 -277.019743) (xy 77.958079 -277.06332) (xy 77.928514 -277.102664)
			(xy 77.893021 -277.136756) (xy 77.852518 -277.164712) (xy 77.808056 -277.18581) (xy 77.760785 -277.199502)
			(xy 77.71193 -277.205434) (xy 77.662755 -277.203453) (xy 77.614536 -277.193609) (xy 77.56852 -277.176157)
			(xy 77.525899 -277.15155) (xy 77.487778 -277.120425) (xy 77.455143 -277.083588) (xy 77.42884 -277.041992)
			(xy 77.409549 -276.996716) (xy 77.397772 -276.948932) (xy 77.393812 -276.899878) (xy 77.054964 -276.899878)
			(xy 77.054469 -276.924485) (xy 77.046574 -276.973062) (xy 77.03099 -277.019743) (xy 77.008119 -277.06332)
			(xy 76.978554 -277.102664) (xy 76.943061 -277.136756) (xy 76.902558 -277.164712) (xy 76.858096 -277.18581)
			(xy 76.810825 -277.199502) (xy 76.76197 -277.205434) (xy 76.712795 -277.203453) (xy 76.664576 -277.193609)
			(xy 76.61856 -277.176157) (xy 76.575939 -277.15155) (xy 76.537818 -277.120425) (xy 76.505183 -277.083588)
			(xy 76.47888 -277.041992) (xy 76.459589 -276.996716) (xy 76.447812 -276.948932) (xy 76.443852 -276.899878)
			(xy 76.105004 -276.899878) (xy 76.104509 -276.924485) (xy 76.096614 -276.973062) (xy 76.08103 -277.019743)
			(xy 76.058159 -277.06332) (xy 76.028594 -277.102664) (xy 75.993101 -277.136756) (xy 75.952598 -277.164712)
			(xy 75.908136 -277.18581) (xy 75.860865 -277.199502) (xy 75.81201 -277.205434) (xy 75.762835 -277.203453)
			(xy 75.714616 -277.193609) (xy 75.6686 -277.176157) (xy 75.625979 -277.15155) (xy 75.587858 -277.120425)
			(xy 75.555223 -277.083588) (xy 75.52892 -277.041992) (xy 75.509629 -276.996716) (xy 75.497852 -276.948932)
			(xy 75.493892 -276.899878) (xy 75.155044 -276.899878) (xy 75.154549 -276.924485) (xy 75.146654 -276.973062)
			(xy 75.13107 -277.019743) (xy 75.108199 -277.06332) (xy 75.078634 -277.102664) (xy 75.043141 -277.136756)
			(xy 75.002638 -277.164712) (xy 74.958176 -277.18581) (xy 74.910905 -277.199502) (xy 74.86205 -277.205434)
			(xy 74.812875 -277.203453) (xy 74.764656 -277.193609) (xy 74.71864 -277.176157) (xy 74.676019 -277.15155)
			(xy 74.637898 -277.120425) (xy 74.605263 -277.083588) (xy 74.57896 -277.041992) (xy 74.559669 -276.996716)
			(xy 74.547892 -276.948932) (xy 74.543932 -276.899878) (xy 74.20483 -276.899878) (xy 74.204335 -276.924485)
			(xy 74.19644 -276.973062) (xy 74.180856 -277.019743) (xy 74.157985 -277.06332) (xy 74.12842 -277.102664)
			(xy 74.092927 -277.136756) (xy 74.052424 -277.164712) (xy 74.007962 -277.18581) (xy 73.960691 -277.199502)
			(xy 73.911836 -277.205434) (xy 73.862661 -277.203453) (xy 73.814442 -277.193609) (xy 73.768426 -277.176157)
			(xy 73.725805 -277.15155) (xy 73.687684 -277.120425) (xy 73.655049 -277.083588) (xy 73.628746 -277.041992)
			(xy 73.609455 -276.996716) (xy 73.597678 -276.948932) (xy 73.593718 -276.899878) (xy 73.255124 -276.899878)
			(xy 73.254629 -276.924485) (xy 73.246734 -276.973062) (xy 73.23115 -277.019743) (xy 73.208279 -277.06332)
			(xy 73.178714 -277.102664) (xy 73.143221 -277.136756) (xy 73.102718 -277.164712) (xy 73.058256 -277.18581)
			(xy 73.010985 -277.199502) (xy 72.96213 -277.205434) (xy 72.912955 -277.203453) (xy 72.864736 -277.193609)
			(xy 72.81872 -277.176157) (xy 72.776099 -277.15155) (xy 72.737978 -277.120425) (xy 72.705343 -277.083588)
			(xy 72.67904 -277.041992) (xy 72.659749 -276.996716) (xy 72.647972 -276.948932) (xy 72.644012 -276.899878)
			(xy 72.305164 -276.899878) (xy 72.304669 -276.924485) (xy 72.296774 -276.973062) (xy 72.28119 -277.019743)
			(xy 72.258319 -277.06332) (xy 72.228754 -277.102664) (xy 72.193261 -277.136756) (xy 72.152758 -277.164712)
			(xy 72.108296 -277.18581) (xy 72.061025 -277.199502) (xy 72.01217 -277.205434) (xy 71.962995 -277.203453)
			(xy 71.914776 -277.193609) (xy 71.86876 -277.176157) (xy 71.826139 -277.15155) (xy 71.788018 -277.120425)
			(xy 71.755383 -277.083588) (xy 71.72908 -277.041992) (xy 71.709789 -276.996716) (xy 71.698012 -276.948932)
			(xy 71.694052 -276.899878) (xy 71.355204 -276.899878) (xy 71.354709 -276.924485) (xy 71.346814 -276.973062)
			(xy 71.33123 -277.019743) (xy 71.308359 -277.06332) (xy 71.278794 -277.102664) (xy 71.243301 -277.136756)
			(xy 71.202798 -277.164712) (xy 71.158336 -277.18581) (xy 71.111065 -277.199502) (xy 71.06221 -277.205434)
			(xy 71.013035 -277.203453) (xy 70.964816 -277.193609) (xy 70.9188 -277.176157) (xy 70.876179 -277.15155)
			(xy 70.838058 -277.120425) (xy 70.805423 -277.083588) (xy 70.77912 -277.041992) (xy 70.759829 -276.996716)
			(xy 70.748052 -276.948932) (xy 70.744092 -276.899878) (xy 70.405244 -276.899878) (xy 70.404749 -276.924485)
			(xy 70.396854 -276.973062) (xy 70.38127 -277.019743) (xy 70.358399 -277.06332) (xy 70.328834 -277.102664)
			(xy 70.293341 -277.136756) (xy 70.252838 -277.164712) (xy 70.208376 -277.18581) (xy 70.161105 -277.199502)
			(xy 70.11225 -277.205434) (xy 70.063075 -277.203453) (xy 70.014856 -277.193609) (xy 69.96884 -277.176157)
			(xy 69.926219 -277.15155) (xy 69.888098 -277.120425) (xy 69.855463 -277.083588) (xy 69.82916 -277.041992)
			(xy 69.809869 -276.996716) (xy 69.798092 -276.948932) (xy 69.794132 -276.899878) (xy 69.455284 -276.899878)
			(xy 69.454789 -276.924485) (xy 69.446894 -276.973062) (xy 69.43131 -277.019743) (xy 69.408439 -277.06332)
			(xy 69.378874 -277.102664) (xy 69.343381 -277.136756) (xy 69.302878 -277.164712) (xy 69.258416 -277.18581)
			(xy 69.211145 -277.199502) (xy 69.16229 -277.205434) (xy 69.113115 -277.203453) (xy 69.064896 -277.193609)
			(xy 69.01888 -277.176157) (xy 68.976259 -277.15155) (xy 68.938138 -277.120425) (xy 68.905503 -277.083588)
			(xy 68.8792 -277.041992) (xy 68.859909 -276.996716) (xy 68.848132 -276.948932) (xy 68.844172 -276.899878)
			(xy 68.50507 -276.899878) (xy 68.504575 -276.924485) (xy 68.49668 -276.973062) (xy 68.481096 -277.019743)
			(xy 68.458225 -277.06332) (xy 68.42866 -277.102664) (xy 68.393167 -277.136756) (xy 68.352664 -277.164712)
			(xy 68.308202 -277.18581) (xy 68.260931 -277.199502) (xy 68.212076 -277.205434) (xy 68.162901 -277.203453)
			(xy 68.114682 -277.193609) (xy 68.068666 -277.176157) (xy 68.026045 -277.15155) (xy 67.987924 -277.120425)
			(xy 67.955289 -277.083588) (xy 67.928986 -277.041992) (xy 67.909695 -276.996716) (xy 67.897918 -276.948932)
			(xy 67.893958 -276.899878) (xy 67.55511 -276.899878) (xy 67.554615 -276.924485) (xy 67.54672 -276.973062)
			(xy 67.531136 -277.019743) (xy 67.508265 -277.06332) (xy 67.4787 -277.102664) (xy 67.443207 -277.136756)
			(xy 67.402704 -277.164712) (xy 67.358242 -277.18581) (xy 67.310971 -277.199502) (xy 67.262116 -277.205434)
			(xy 67.212941 -277.203453) (xy 67.164722 -277.193609) (xy 67.118706 -277.176157) (xy 67.076085 -277.15155)
			(xy 67.037964 -277.120425) (xy 67.005329 -277.083588) (xy 66.979026 -277.041992) (xy 66.959735 -276.996716)
			(xy 66.947958 -276.948932) (xy 66.943998 -276.899878) (xy 66.60515 -276.899878) (xy 66.604655 -276.924485)
			(xy 66.59676 -276.973062) (xy 66.581176 -277.019743) (xy 66.558305 -277.06332) (xy 66.52874 -277.102664)
			(xy 66.493247 -277.136756) (xy 66.452744 -277.164712) (xy 66.408282 -277.18581) (xy 66.361011 -277.199502)
			(xy 66.312156 -277.205434) (xy 66.262981 -277.203453) (xy 66.214762 -277.193609) (xy 66.168746 -277.176157)
			(xy 66.126125 -277.15155) (xy 66.088004 -277.120425) (xy 66.055369 -277.083588) (xy 66.029066 -277.041992)
			(xy 66.009775 -276.996716) (xy 65.997998 -276.948932) (xy 65.994038 -276.899878) (xy 65.65519 -276.899878)
			(xy 65.654695 -276.924485) (xy 65.6468 -276.973062) (xy 65.631216 -277.019743) (xy 65.608345 -277.06332)
			(xy 65.57878 -277.102664) (xy 65.543287 -277.136756) (xy 65.502784 -277.164712) (xy 65.458322 -277.18581)
			(xy 65.411051 -277.199502) (xy 65.362196 -277.205434) (xy 65.313021 -277.203453) (xy 65.264802 -277.193609)
			(xy 65.218786 -277.176157) (xy 65.176165 -277.15155) (xy 65.138044 -277.120425) (xy 65.105409 -277.083588)
			(xy 65.079106 -277.041992) (xy 65.059815 -276.996716) (xy 65.048038 -276.948932) (xy 65.044078 -276.899878)
			(xy 64.70523 -276.899878) (xy 64.704735 -276.924485) (xy 64.69684 -276.973062) (xy 64.681256 -277.019743)
			(xy 64.658385 -277.06332) (xy 64.62882 -277.102664) (xy 64.593327 -277.136756) (xy 64.552824 -277.164712)
			(xy 64.508362 -277.18581) (xy 64.461091 -277.199502) (xy 64.412236 -277.205434) (xy 64.363061 -277.203453)
			(xy 64.314842 -277.193609) (xy 64.268826 -277.176157) (xy 64.226205 -277.15155) (xy 64.188084 -277.120425)
			(xy 64.155449 -277.083588) (xy 64.129146 -277.041992) (xy 64.109855 -276.996716) (xy 64.098078 -276.948932)
			(xy 64.094118 -276.899878) (xy 63.75527 -276.899878) (xy 63.754775 -276.924485) (xy 63.74688 -276.973062)
			(xy 63.731296 -277.019743) (xy 63.708425 -277.06332) (xy 63.67886 -277.102664) (xy 63.643367 -277.136756)
			(xy 63.602864 -277.164712) (xy 63.558402 -277.18581) (xy 63.511131 -277.199502) (xy 63.462276 -277.205434)
			(xy 63.413101 -277.203453) (xy 63.364882 -277.193609) (xy 63.318866 -277.176157) (xy 63.276245 -277.15155)
			(xy 63.238124 -277.120425) (xy 63.205489 -277.083588) (xy 63.179186 -277.041992) (xy 63.159895 -276.996716)
			(xy 63.148118 -276.948932) (xy 63.144158 -276.899878) (xy 62.805056 -276.899878) (xy 62.804561 -276.924485)
			(xy 62.796666 -276.973062) (xy 62.781082 -277.019743) (xy 62.758211 -277.06332) (xy 62.728646 -277.102664)
			(xy 62.693153 -277.136756) (xy 62.65265 -277.164712) (xy 62.608188 -277.18581) (xy 62.560917 -277.199502)
			(xy 62.512062 -277.205434) (xy 62.462887 -277.203453) (xy 62.414668 -277.193609) (xy 62.368652 -277.176157)
			(xy 62.326031 -277.15155) (xy 62.28791 -277.120425) (xy 62.255275 -277.083588) (xy 62.228972 -277.041992)
			(xy 62.209681 -276.996716) (xy 62.197904 -276.948932) (xy 62.193944 -276.899878) (xy 61.855096 -276.899878)
			(xy 61.854601 -276.924485) (xy 61.846706 -276.973062) (xy 61.831122 -277.019743) (xy 61.808251 -277.06332)
			(xy 61.778686 -277.102664) (xy 61.743193 -277.136756) (xy 61.70269 -277.164712) (xy 61.658228 -277.18581)
			(xy 61.610957 -277.199502) (xy 61.562102 -277.205434) (xy 61.512927 -277.203453) (xy 61.464708 -277.193609)
			(xy 61.418692 -277.176157) (xy 61.376071 -277.15155) (xy 61.33795 -277.120425) (xy 61.305315 -277.083588)
			(xy 61.279012 -277.041992) (xy 61.259721 -276.996716) (xy 61.247944 -276.948932) (xy 61.243984 -276.899878)
			(xy 60.905136 -276.899878) (xy 60.904641 -276.924485) (xy 60.896746 -276.973062) (xy 60.881162 -277.019743)
			(xy 60.858291 -277.06332) (xy 60.828726 -277.102664) (xy 60.793233 -277.136756) (xy 60.75273 -277.164712)
			(xy 60.708268 -277.18581) (xy 60.660997 -277.199502) (xy 60.612142 -277.205434) (xy 60.562967 -277.203453)
			(xy 60.514748 -277.193609) (xy 60.468732 -277.176157) (xy 60.426111 -277.15155) (xy 60.38799 -277.120425)
			(xy 60.355355 -277.083588) (xy 60.329052 -277.041992) (xy 60.309761 -276.996716) (xy 60.297984 -276.948932)
			(xy 60.294024 -276.899878) (xy 59.955192 -276.899878) (xy 59.952955 -276.941178) (xy 59.942284 -276.989665)
			(xy 59.923909 -277.035786) (xy 59.898314 -277.078327) (xy 59.866174 -277.116167) (xy 59.828336 -277.148309)
			(xy 59.785795 -277.173905) (xy 59.739674 -277.192281) (xy 59.691188 -277.202953) (xy 59.641613 -277.205641)
			(xy 59.592257 -277.200272) (xy 59.54442 -277.186989) (xy 59.499362 -277.166141) (xy 59.458271 -277.138279)
			(xy 59.422229 -277.104135) (xy 59.392185 -277.06461) (xy 59.368933 -277.020744) (xy 59.353083 -276.973695)
			(xy 59.345054 -276.924702) (xy 59.34456 -276.899878) (xy 59.345303 -276.869526) (xy 59.357325 -276.810023)
			(xy 59.368436 -276.781768) (xy 59.371745 -276.772817) (xy 59.372155 -276.753751) (xy 59.365568 -276.735855)
			(xy 59.352895 -276.721606) (xy 59.33589 -276.712976) (xy 59.316907 -276.711159) (xy 59.298573 -276.716407)
			(xy 59.290712 -276.721824) (xy 59.242706 -276.756368) (xy 59.232646 -276.763886) (xy 59.220788 -276.785993)
			(xy 59.2201 -276.798532) (xy 59.2201 -277.572978) (xy 59.219662 -277.583042) (xy 59.211928 -277.601626)
			(xy 59.205114 -277.609046) (xy 59.01944 -277.79472) (xy 59.015776 -277.798592) (xy 59.010013 -277.807559)
			(xy 59.00801 -277.8125) (xy 59.0042 -277.822406) (xy 59.004708 -277.833328) (xy 59.004708 -277.833582)
			(xy 59.005216 -277.849838) (xy 59.34381 -277.849838) (xy 59.34777 -277.800784) (xy 59.359547 -277.753)
			(xy 59.378838 -277.707724) (xy 59.405141 -277.666128) (xy 59.437776 -277.629291) (xy 59.475897 -277.598166)
			(xy 59.518518 -277.573559) (xy 59.564534 -277.556107) (xy 59.612753 -277.546263) (xy 59.661928 -277.544282)
			(xy 59.710783 -277.550214) (xy 59.758054 -277.563906) (xy 59.802516 -277.585004) (xy 59.843019 -277.61296)
			(xy 59.878512 -277.647052) (xy 59.908077 -277.686396) (xy 59.930948 -277.729973) (xy 59.946532 -277.776654)
			(xy 59.954427 -277.825231) (xy 59.954922 -277.849838) (xy 60.294024 -277.849838) (xy 60.297984 -277.800784)
			(xy 60.309761 -277.753) (xy 60.329052 -277.707724) (xy 60.355355 -277.666128) (xy 60.38799 -277.629291)
			(xy 60.426111 -277.598166) (xy 60.468732 -277.573559) (xy 60.514748 -277.556107) (xy 60.562967 -277.546263)
			(xy 60.612142 -277.544282) (xy 60.660997 -277.550214) (xy 60.708268 -277.563906) (xy 60.75273 -277.585004)
			(xy 60.793233 -277.61296) (xy 60.828726 -277.647052) (xy 60.858291 -277.686396) (xy 60.881162 -277.729973)
			(xy 60.896746 -277.776654) (xy 60.904641 -277.825231) (xy 60.905136 -277.849838) (xy 61.24373 -277.849838)
			(xy 61.24769 -277.800784) (xy 61.259467 -277.753) (xy 61.278758 -277.707724) (xy 61.305061 -277.666128)
			(xy 61.337696 -277.629291) (xy 61.375817 -277.598166) (xy 61.418438 -277.573559) (xy 61.464454 -277.556107)
			(xy 61.512673 -277.546263) (xy 61.561848 -277.544282) (xy 61.610703 -277.550214) (xy 61.657974 -277.563906)
			(xy 61.702436 -277.585004) (xy 61.742939 -277.61296) (xy 61.778432 -277.647052) (xy 61.807997 -277.686396)
			(xy 61.830868 -277.729973) (xy 61.846452 -277.776654) (xy 61.854347 -277.825231) (xy 61.854842 -277.849838)
			(xy 62.193944 -277.849838) (xy 62.197904 -277.800784) (xy 62.209681 -277.753) (xy 62.228972 -277.707724)
			(xy 62.255275 -277.666128) (xy 62.28791 -277.629291) (xy 62.326031 -277.598166) (xy 62.368652 -277.573559)
			(xy 62.414668 -277.556107) (xy 62.462887 -277.546263) (xy 62.512062 -277.544282) (xy 62.560917 -277.550214)
			(xy 62.608188 -277.563906) (xy 62.65265 -277.585004) (xy 62.693153 -277.61296) (xy 62.728646 -277.647052)
			(xy 62.758211 -277.686396) (xy 62.781082 -277.729973) (xy 62.796666 -277.776654) (xy 62.804561 -277.825231)
			(xy 62.805056 -277.849838) (xy 63.143904 -277.849838) (xy 63.147864 -277.800784) (xy 63.159641 -277.753)
			(xy 63.178932 -277.707724) (xy 63.205235 -277.666128) (xy 63.23787 -277.629291) (xy 63.275991 -277.598166)
			(xy 63.318612 -277.573559) (xy 63.364628 -277.556107) (xy 63.412847 -277.546263) (xy 63.462022 -277.544282)
			(xy 63.510877 -277.550214) (xy 63.558148 -277.563906) (xy 63.60261 -277.585004) (xy 63.643113 -277.61296)
			(xy 63.678606 -277.647052) (xy 63.708171 -277.686396) (xy 63.731042 -277.729973) (xy 63.746626 -277.776654)
			(xy 63.754521 -277.825231) (xy 63.755016 -277.849838) (xy 64.094118 -277.849838) (xy 64.098078 -277.800784)
			(xy 64.109855 -277.753) (xy 64.129146 -277.707724) (xy 64.155449 -277.666128) (xy 64.188084 -277.629291)
			(xy 64.226205 -277.598166) (xy 64.268826 -277.573559) (xy 64.314842 -277.556107) (xy 64.363061 -277.546263)
			(xy 64.412236 -277.544282) (xy 64.461091 -277.550214) (xy 64.508362 -277.563906) (xy 64.552824 -277.585004)
			(xy 64.593327 -277.61296) (xy 64.62882 -277.647052) (xy 64.658385 -277.686396) (xy 64.681256 -277.729973)
			(xy 64.69684 -277.776654) (xy 64.704735 -277.825231) (xy 64.70523 -277.849838) (xy 65.043824 -277.849838)
			(xy 65.047784 -277.800784) (xy 65.059561 -277.753) (xy 65.078852 -277.707724) (xy 65.105155 -277.666128)
			(xy 65.13779 -277.629291) (xy 65.175911 -277.598166) (xy 65.218532 -277.573559) (xy 65.264548 -277.556107)
			(xy 65.312767 -277.546263) (xy 65.361942 -277.544282) (xy 65.410797 -277.550214) (xy 65.458068 -277.563906)
			(xy 65.50253 -277.585004) (xy 65.543033 -277.61296) (xy 65.578526 -277.647052) (xy 65.608091 -277.686396)
			(xy 65.630962 -277.729973) (xy 65.646546 -277.776654) (xy 65.654441 -277.825231) (xy 65.654936 -277.849838)
			(xy 65.994038 -277.849838) (xy 65.997998 -277.800784) (xy 66.009775 -277.753) (xy 66.029066 -277.707724)
			(xy 66.055369 -277.666128) (xy 66.088004 -277.629291) (xy 66.126125 -277.598166) (xy 66.168746 -277.573559)
			(xy 66.214762 -277.556107) (xy 66.262981 -277.546263) (xy 66.312156 -277.544282) (xy 66.361011 -277.550214)
			(xy 66.408282 -277.563906) (xy 66.452744 -277.585004) (xy 66.493247 -277.61296) (xy 66.52874 -277.647052)
			(xy 66.558305 -277.686396) (xy 66.581176 -277.729973) (xy 66.59676 -277.776654) (xy 66.604655 -277.825231)
			(xy 66.60515 -277.849838) (xy 66.943744 -277.849838) (xy 66.947704 -277.800784) (xy 66.959481 -277.753)
			(xy 66.978772 -277.707724) (xy 67.005075 -277.666128) (xy 67.03771 -277.629291) (xy 67.075831 -277.598166)
			(xy 67.118452 -277.573559) (xy 67.164468 -277.556107) (xy 67.212687 -277.546263) (xy 67.261862 -277.544282)
			(xy 67.310717 -277.550214) (xy 67.357988 -277.563906) (xy 67.40245 -277.585004) (xy 67.442953 -277.61296)
			(xy 67.478446 -277.647052) (xy 67.508011 -277.686396) (xy 67.530882 -277.729973) (xy 67.546466 -277.776654)
			(xy 67.554361 -277.825231) (xy 67.554856 -277.849838) (xy 67.893958 -277.849838) (xy 67.897918 -277.800784)
			(xy 67.909695 -277.753) (xy 67.928986 -277.707724) (xy 67.955289 -277.666128) (xy 67.987924 -277.629291)
			(xy 68.026045 -277.598166) (xy 68.068666 -277.573559) (xy 68.114682 -277.556107) (xy 68.162901 -277.546263)
			(xy 68.212076 -277.544282) (xy 68.260931 -277.550214) (xy 68.308202 -277.563906) (xy 68.352664 -277.585004)
			(xy 68.393167 -277.61296) (xy 68.42866 -277.647052) (xy 68.458225 -277.686396) (xy 68.481096 -277.729973)
			(xy 68.49668 -277.776654) (xy 68.504575 -277.825231) (xy 68.50507 -277.849838) (xy 68.843918 -277.849838)
			(xy 68.847878 -277.800784) (xy 68.859655 -277.753) (xy 68.878946 -277.707724) (xy 68.905249 -277.666128)
			(xy 68.937884 -277.629291) (xy 68.976005 -277.598166) (xy 69.018626 -277.573559) (xy 69.064642 -277.556107)
			(xy 69.112861 -277.546263) (xy 69.162036 -277.544282) (xy 69.210891 -277.550214) (xy 69.258162 -277.563906)
			(xy 69.302624 -277.585004) (xy 69.343127 -277.61296) (xy 69.37862 -277.647052) (xy 69.408185 -277.686396)
			(xy 69.431056 -277.729973) (xy 69.44664 -277.776654) (xy 69.454535 -277.825231) (xy 69.45503 -277.849838)
			(xy 69.794132 -277.849838) (xy 69.798092 -277.800784) (xy 69.809869 -277.753) (xy 69.82916 -277.707724)
			(xy 69.855463 -277.666128) (xy 69.888098 -277.629291) (xy 69.926219 -277.598166) (xy 69.96884 -277.573559)
			(xy 70.014856 -277.556107) (xy 70.063075 -277.546263) (xy 70.11225 -277.544282) (xy 70.161105 -277.550214)
			(xy 70.208376 -277.563906) (xy 70.252838 -277.585004) (xy 70.293341 -277.61296) (xy 70.328834 -277.647052)
			(xy 70.358399 -277.686396) (xy 70.38127 -277.729973) (xy 70.396854 -277.776654) (xy 70.404749 -277.825231)
			(xy 70.405244 -277.849838) (xy 70.743838 -277.849838) (xy 70.747798 -277.800784) (xy 70.759575 -277.753)
			(xy 70.778866 -277.707724) (xy 70.805169 -277.666128) (xy 70.837804 -277.629291) (xy 70.875925 -277.598166)
			(xy 70.918546 -277.573559) (xy 70.964562 -277.556107) (xy 71.012781 -277.546263) (xy 71.061956 -277.544282)
			(xy 71.110811 -277.550214) (xy 71.158082 -277.563906) (xy 71.202544 -277.585004) (xy 71.243047 -277.61296)
			(xy 71.27854 -277.647052) (xy 71.308105 -277.686396) (xy 71.330976 -277.729973) (xy 71.34656 -277.776654)
			(xy 71.354455 -277.825231) (xy 71.35495 -277.849838) (xy 71.694052 -277.849838) (xy 71.698012 -277.800784)
			(xy 71.709789 -277.753) (xy 71.72908 -277.707724) (xy 71.755383 -277.666128) (xy 71.788018 -277.629291)
			(xy 71.826139 -277.598166) (xy 71.86876 -277.573559) (xy 71.914776 -277.556107) (xy 71.962995 -277.546263)
			(xy 72.01217 -277.544282) (xy 72.061025 -277.550214) (xy 72.108296 -277.563906) (xy 72.152758 -277.585004)
			(xy 72.193261 -277.61296) (xy 72.228754 -277.647052) (xy 72.258319 -277.686396) (xy 72.28119 -277.729973)
			(xy 72.296774 -277.776654) (xy 72.304669 -277.825231) (xy 72.305164 -277.849838) (xy 72.643758 -277.849838)
			(xy 72.647718 -277.800784) (xy 72.659495 -277.753) (xy 72.678786 -277.707724) (xy 72.705089 -277.666128)
			(xy 72.737724 -277.629291) (xy 72.775845 -277.598166) (xy 72.818466 -277.573559) (xy 72.864482 -277.556107)
			(xy 72.912701 -277.546263) (xy 72.961876 -277.544282) (xy 73.010731 -277.550214) (xy 73.058002 -277.563906)
			(xy 73.102464 -277.585004) (xy 73.142967 -277.61296) (xy 73.17846 -277.647052) (xy 73.208025 -277.686396)
			(xy 73.230896 -277.729973) (xy 73.24648 -277.776654) (xy 73.254375 -277.825231) (xy 73.25487 -277.849838)
			(xy 73.593972 -277.849838) (xy 73.597932 -277.800784) (xy 73.609709 -277.753) (xy 73.629 -277.707724)
			(xy 73.655303 -277.666128) (xy 73.687938 -277.629291) (xy 73.726059 -277.598166) (xy 73.76868 -277.573559)
			(xy 73.814696 -277.556107) (xy 73.862915 -277.546263) (xy 73.91209 -277.544282) (xy 73.960945 -277.550214)
			(xy 74.008216 -277.563906) (xy 74.052678 -277.585004) (xy 74.093181 -277.61296) (xy 74.128674 -277.647052)
			(xy 74.158239 -277.686396) (xy 74.18111 -277.729973) (xy 74.196694 -277.776654) (xy 74.204589 -277.825231)
			(xy 74.205084 -277.849838) (xy 74.543932 -277.849838) (xy 74.547892 -277.800784) (xy 74.559669 -277.753)
			(xy 74.57896 -277.707724) (xy 74.605263 -277.666128) (xy 74.637898 -277.629291) (xy 74.676019 -277.598166)
			(xy 74.71864 -277.573559) (xy 74.764656 -277.556107) (xy 74.812875 -277.546263) (xy 74.86205 -277.544282)
			(xy 74.910905 -277.550214) (xy 74.958176 -277.563906) (xy 75.002638 -277.585004) (xy 75.043141 -277.61296)
			(xy 75.078634 -277.647052) (xy 75.108199 -277.686396) (xy 75.13107 -277.729973) (xy 75.146654 -277.776654)
			(xy 75.154549 -277.825231) (xy 75.155044 -277.849838) (xy 75.494146 -277.849838) (xy 75.498106 -277.800784)
			(xy 75.509883 -277.753) (xy 75.529174 -277.707724) (xy 75.555477 -277.666128) (xy 75.588112 -277.629291)
			(xy 75.626233 -277.598166) (xy 75.668854 -277.573559) (xy 75.71487 -277.556107) (xy 75.763089 -277.546263)
			(xy 75.812264 -277.544282) (xy 75.861119 -277.550214) (xy 75.90839 -277.563906) (xy 75.952852 -277.585004)
			(xy 75.993355 -277.61296) (xy 76.028848 -277.647052) (xy 76.058413 -277.686396) (xy 76.081284 -277.729973)
			(xy 76.096868 -277.776654) (xy 76.104763 -277.825231) (xy 76.105258 -277.849838) (xy 76.443852 -277.849838)
			(xy 76.447812 -277.800784) (xy 76.459589 -277.753) (xy 76.47888 -277.707724) (xy 76.505183 -277.666128)
			(xy 76.537818 -277.629291) (xy 76.575939 -277.598166) (xy 76.61856 -277.573559) (xy 76.664576 -277.556107)
			(xy 76.712795 -277.546263) (xy 76.76197 -277.544282) (xy 76.810825 -277.550214) (xy 76.858096 -277.563906)
			(xy 76.902558 -277.585004) (xy 76.943061 -277.61296) (xy 76.978554 -277.647052) (xy 77.008119 -277.686396)
			(xy 77.03099 -277.729973) (xy 77.046574 -277.776654) (xy 77.054469 -277.825231) (xy 77.054964 -277.849838)
			(xy 77.394066 -277.849838) (xy 77.398026 -277.800784) (xy 77.409803 -277.753) (xy 77.429094 -277.707724)
			(xy 77.455397 -277.666128) (xy 77.488032 -277.629291) (xy 77.526153 -277.598166) (xy 77.568774 -277.573559)
			(xy 77.61479 -277.556107) (xy 77.663009 -277.546263) (xy 77.712184 -277.544282) (xy 77.761039 -277.550214)
			(xy 77.80831 -277.563906) (xy 77.852772 -277.585004) (xy 77.893275 -277.61296) (xy 77.928768 -277.647052)
			(xy 77.958333 -277.686396) (xy 77.981204 -277.729973) (xy 77.996788 -277.776654) (xy 78.004683 -277.825231)
			(xy 78.005178 -277.849838) (xy 78.343772 -277.849838) (xy 78.347732 -277.800784) (xy 78.359509 -277.753)
			(xy 78.3788 -277.707724) (xy 78.405103 -277.666128) (xy 78.437738 -277.629291) (xy 78.475859 -277.598166)
			(xy 78.51848 -277.573559) (xy 78.564496 -277.556107) (xy 78.612715 -277.546263) (xy 78.66189 -277.544282)
			(xy 78.710745 -277.550214) (xy 78.758016 -277.563906) (xy 78.802478 -277.585004) (xy 78.842981 -277.61296)
			(xy 78.878474 -277.647052) (xy 78.908039 -277.686396) (xy 78.93091 -277.729973) (xy 78.946494 -277.776654)
			(xy 78.954389 -277.825231) (xy 78.954884 -277.849838) (xy 79.293986 -277.849838) (xy 79.297946 -277.800784)
			(xy 79.309723 -277.753) (xy 79.329014 -277.707724) (xy 79.355317 -277.666128) (xy 79.387952 -277.629291)
			(xy 79.426073 -277.598166) (xy 79.468694 -277.573559) (xy 79.51471 -277.556107) (xy 79.562929 -277.546263)
			(xy 79.612104 -277.544282) (xy 79.660959 -277.550214) (xy 79.70823 -277.563906) (xy 79.752692 -277.585004)
			(xy 79.793195 -277.61296) (xy 79.828688 -277.647052) (xy 79.858253 -277.686396) (xy 79.881124 -277.729973)
			(xy 79.896708 -277.776654) (xy 79.904603 -277.825231) (xy 79.905098 -277.849838) (xy 80.243946 -277.849838)
			(xy 80.247906 -277.800784) (xy 80.259683 -277.753) (xy 80.278974 -277.707724) (xy 80.305277 -277.666128)
			(xy 80.337912 -277.629291) (xy 80.376033 -277.598166) (xy 80.418654 -277.573559) (xy 80.46467 -277.556107)
			(xy 80.512889 -277.546263) (xy 80.562064 -277.544282) (xy 80.610919 -277.550214) (xy 80.65819 -277.563906)
			(xy 80.702652 -277.585004) (xy 80.743155 -277.61296) (xy 80.778648 -277.647052) (xy 80.808213 -277.686396)
			(xy 80.831084 -277.729973) (xy 80.846668 -277.776654) (xy 80.854563 -277.825231) (xy 80.855058 -277.849838)
			(xy 81.19416 -277.849838) (xy 81.19812 -277.800784) (xy 81.209897 -277.753) (xy 81.229188 -277.707724)
			(xy 81.255491 -277.666128) (xy 81.288126 -277.629291) (xy 81.326247 -277.598166) (xy 81.368868 -277.573559)
			(xy 81.414884 -277.556107) (xy 81.463103 -277.546263) (xy 81.512278 -277.544282) (xy 81.561133 -277.550214)
			(xy 81.608404 -277.563906) (xy 81.652866 -277.585004) (xy 81.693369 -277.61296) (xy 81.728862 -277.647052)
			(xy 81.758427 -277.686396) (xy 81.781298 -277.729973) (xy 81.796882 -277.776654) (xy 81.804777 -277.825231)
			(xy 81.805272 -277.849838) (xy 82.14412 -277.849838) (xy 82.14808 -277.800784) (xy 82.159857 -277.753)
			(xy 82.179148 -277.707724) (xy 82.205451 -277.666128) (xy 82.238086 -277.629291) (xy 82.276207 -277.598166)
			(xy 82.318828 -277.573559) (xy 82.364844 -277.556107) (xy 82.413063 -277.546263) (xy 82.462238 -277.544282)
			(xy 82.511093 -277.550214) (xy 82.558364 -277.563906) (xy 82.602826 -277.585004) (xy 82.643329 -277.61296)
			(xy 82.678822 -277.647052) (xy 82.708387 -277.686396) (xy 82.731258 -277.729973) (xy 82.746842 -277.776654)
			(xy 82.754737 -277.825231) (xy 82.755232 -277.849838) (xy 82.754737 -277.874445) (xy 82.746842 -277.923022)
			(xy 82.731258 -277.969703) (xy 82.708387 -278.01328) (xy 82.678822 -278.052624) (xy 82.643329 -278.086716)
			(xy 82.602826 -278.114672) (xy 82.558364 -278.13577) (xy 82.511093 -278.149462) (xy 82.462238 -278.155394)
			(xy 82.413063 -278.153413) (xy 82.364844 -278.143569) (xy 82.318828 -278.126117) (xy 82.276207 -278.10151)
			(xy 82.238086 -278.070385) (xy 82.205451 -278.033548) (xy 82.179148 -277.991952) (xy 82.159857 -277.946676)
			(xy 82.14808 -277.898892) (xy 82.14412 -277.849838) (xy 81.805272 -277.849838) (xy 81.804777 -277.874445)
			(xy 81.796882 -277.923022) (xy 81.781298 -277.969703) (xy 81.758427 -278.01328) (xy 81.728862 -278.052624)
			(xy 81.693369 -278.086716) (xy 81.652866 -278.114672) (xy 81.608404 -278.13577) (xy 81.561133 -278.149462)
			(xy 81.512278 -278.155394) (xy 81.463103 -278.153413) (xy 81.414884 -278.143569) (xy 81.368868 -278.126117)
			(xy 81.326247 -278.10151) (xy 81.288126 -278.070385) (xy 81.255491 -278.033548) (xy 81.229188 -277.991952)
			(xy 81.209897 -277.946676) (xy 81.19812 -277.898892) (xy 81.19416 -277.849838) (xy 80.855058 -277.849838)
			(xy 80.854563 -277.874445) (xy 80.846668 -277.923022) (xy 80.831084 -277.969703) (xy 80.808213 -278.01328)
			(xy 80.778648 -278.052624) (xy 80.743155 -278.086716) (xy 80.702652 -278.114672) (xy 80.65819 -278.13577)
			(xy 80.610919 -278.149462) (xy 80.562064 -278.155394) (xy 80.512889 -278.153413) (xy 80.46467 -278.143569)
			(xy 80.418654 -278.126117) (xy 80.376033 -278.10151) (xy 80.337912 -278.070385) (xy 80.305277 -278.033548)
			(xy 80.278974 -277.991952) (xy 80.259683 -277.946676) (xy 80.247906 -277.898892) (xy 80.243946 -277.849838)
			(xy 79.905098 -277.849838) (xy 79.904603 -277.874445) (xy 79.896708 -277.923022) (xy 79.881124 -277.969703)
			(xy 79.858253 -278.01328) (xy 79.828688 -278.052624) (xy 79.793195 -278.086716) (xy 79.752692 -278.114672)
			(xy 79.70823 -278.13577) (xy 79.660959 -278.149462) (xy 79.612104 -278.155394) (xy 79.562929 -278.153413)
			(xy 79.51471 -278.143569) (xy 79.468694 -278.126117) (xy 79.426073 -278.10151) (xy 79.387952 -278.070385)
			(xy 79.355317 -278.033548) (xy 79.329014 -277.991952) (xy 79.309723 -277.946676) (xy 79.297946 -277.898892)
			(xy 79.293986 -277.849838) (xy 78.954884 -277.849838) (xy 78.954389 -277.874445) (xy 78.946494 -277.923022)
			(xy 78.93091 -277.969703) (xy 78.908039 -278.01328) (xy 78.878474 -278.052624) (xy 78.842981 -278.086716)
			(xy 78.802478 -278.114672) (xy 78.758016 -278.13577) (xy 78.710745 -278.149462) (xy 78.66189 -278.155394)
			(xy 78.612715 -278.153413) (xy 78.564496 -278.143569) (xy 78.51848 -278.126117) (xy 78.475859 -278.10151)
			(xy 78.437738 -278.070385) (xy 78.405103 -278.033548) (xy 78.3788 -277.991952) (xy 78.359509 -277.946676)
			(xy 78.347732 -277.898892) (xy 78.343772 -277.849838) (xy 78.005178 -277.849838) (xy 78.004683 -277.874445)
			(xy 77.996788 -277.923022) (xy 77.981204 -277.969703) (xy 77.958333 -278.01328) (xy 77.928768 -278.052624)
			(xy 77.893275 -278.086716) (xy 77.852772 -278.114672) (xy 77.80831 -278.13577) (xy 77.761039 -278.149462)
			(xy 77.712184 -278.155394) (xy 77.663009 -278.153413) (xy 77.61479 -278.143569) (xy 77.568774 -278.126117)
			(xy 77.526153 -278.10151) (xy 77.488032 -278.070385) (xy 77.455397 -278.033548) (xy 77.429094 -277.991952)
			(xy 77.409803 -277.946676) (xy 77.398026 -277.898892) (xy 77.394066 -277.849838) (xy 77.054964 -277.849838)
			(xy 77.054469 -277.874445) (xy 77.046574 -277.923022) (xy 77.03099 -277.969703) (xy 77.008119 -278.01328)
			(xy 76.978554 -278.052624) (xy 76.943061 -278.086716) (xy 76.902558 -278.114672) (xy 76.858096 -278.13577)
			(xy 76.810825 -278.149462) (xy 76.76197 -278.155394) (xy 76.712795 -278.153413) (xy 76.664576 -278.143569)
			(xy 76.61856 -278.126117) (xy 76.575939 -278.10151) (xy 76.537818 -278.070385) (xy 76.505183 -278.033548)
			(xy 76.47888 -277.991952) (xy 76.459589 -277.946676) (xy 76.447812 -277.898892) (xy 76.443852 -277.849838)
			(xy 76.105258 -277.849838) (xy 76.104763 -277.874445) (xy 76.096868 -277.923022) (xy 76.081284 -277.969703)
			(xy 76.058413 -278.01328) (xy 76.028848 -278.052624) (xy 75.993355 -278.086716) (xy 75.952852 -278.114672)
			(xy 75.90839 -278.13577) (xy 75.861119 -278.149462) (xy 75.812264 -278.155394) (xy 75.763089 -278.153413)
			(xy 75.71487 -278.143569) (xy 75.668854 -278.126117) (xy 75.626233 -278.10151) (xy 75.588112 -278.070385)
			(xy 75.555477 -278.033548) (xy 75.529174 -277.991952) (xy 75.509883 -277.946676) (xy 75.498106 -277.898892)
			(xy 75.494146 -277.849838) (xy 75.155044 -277.849838) (xy 75.154549 -277.874445) (xy 75.146654 -277.923022)
			(xy 75.13107 -277.969703) (xy 75.108199 -278.01328) (xy 75.078634 -278.052624) (xy 75.043141 -278.086716)
			(xy 75.002638 -278.114672) (xy 74.958176 -278.13577) (xy 74.910905 -278.149462) (xy 74.86205 -278.155394)
			(xy 74.812875 -278.153413) (xy 74.764656 -278.143569) (xy 74.71864 -278.126117) (xy 74.676019 -278.10151)
			(xy 74.637898 -278.070385) (xy 74.605263 -278.033548) (xy 74.57896 -277.991952) (xy 74.559669 -277.946676)
			(xy 74.547892 -277.898892) (xy 74.543932 -277.849838) (xy 74.205084 -277.849838) (xy 74.204589 -277.874445)
			(xy 74.196694 -277.923022) (xy 74.18111 -277.969703) (xy 74.158239 -278.01328) (xy 74.128674 -278.052624)
			(xy 74.093181 -278.086716) (xy 74.052678 -278.114672) (xy 74.008216 -278.13577) (xy 73.960945 -278.149462)
			(xy 73.91209 -278.155394) (xy 73.862915 -278.153413) (xy 73.814696 -278.143569) (xy 73.76868 -278.126117)
			(xy 73.726059 -278.10151) (xy 73.687938 -278.070385) (xy 73.655303 -278.033548) (xy 73.629 -277.991952)
			(xy 73.609709 -277.946676) (xy 73.597932 -277.898892) (xy 73.593972 -277.849838) (xy 73.25487 -277.849838)
			(xy 73.254375 -277.874445) (xy 73.24648 -277.923022) (xy 73.230896 -277.969703) (xy 73.208025 -278.01328)
			(xy 73.17846 -278.052624) (xy 73.142967 -278.086716) (xy 73.102464 -278.114672) (xy 73.058002 -278.13577)
			(xy 73.010731 -278.149462) (xy 72.961876 -278.155394) (xy 72.912701 -278.153413) (xy 72.864482 -278.143569)
			(xy 72.818466 -278.126117) (xy 72.775845 -278.10151) (xy 72.737724 -278.070385) (xy 72.705089 -278.033548)
			(xy 72.678786 -277.991952) (xy 72.659495 -277.946676) (xy 72.647718 -277.898892) (xy 72.643758 -277.849838)
			(xy 72.305164 -277.849838) (xy 72.304669 -277.874445) (xy 72.296774 -277.923022) (xy 72.28119 -277.969703)
			(xy 72.258319 -278.01328) (xy 72.228754 -278.052624) (xy 72.193261 -278.086716) (xy 72.152758 -278.114672)
			(xy 72.108296 -278.13577) (xy 72.061025 -278.149462) (xy 72.01217 -278.155394) (xy 71.962995 -278.153413)
			(xy 71.914776 -278.143569) (xy 71.86876 -278.126117) (xy 71.826139 -278.10151) (xy 71.788018 -278.070385)
			(xy 71.755383 -278.033548) (xy 71.72908 -277.991952) (xy 71.709789 -277.946676) (xy 71.698012 -277.898892)
			(xy 71.694052 -277.849838) (xy 71.35495 -277.849838) (xy 71.354455 -277.874445) (xy 71.34656 -277.923022)
			(xy 71.330976 -277.969703) (xy 71.308105 -278.01328) (xy 71.27854 -278.052624) (xy 71.243047 -278.086716)
			(xy 71.202544 -278.114672) (xy 71.158082 -278.13577) (xy 71.110811 -278.149462) (xy 71.061956 -278.155394)
			(xy 71.012781 -278.153413) (xy 70.964562 -278.143569) (xy 70.918546 -278.126117) (xy 70.875925 -278.10151)
			(xy 70.837804 -278.070385) (xy 70.805169 -278.033548) (xy 70.778866 -277.991952) (xy 70.759575 -277.946676)
			(xy 70.747798 -277.898892) (xy 70.743838 -277.849838) (xy 70.405244 -277.849838) (xy 70.404749 -277.874445)
			(xy 70.396854 -277.923022) (xy 70.38127 -277.969703) (xy 70.358399 -278.01328) (xy 70.328834 -278.052624)
			(xy 70.293341 -278.086716) (xy 70.252838 -278.114672) (xy 70.208376 -278.13577) (xy 70.161105 -278.149462)
			(xy 70.11225 -278.155394) (xy 70.063075 -278.153413) (xy 70.014856 -278.143569) (xy 69.96884 -278.126117)
			(xy 69.926219 -278.10151) (xy 69.888098 -278.070385) (xy 69.855463 -278.033548) (xy 69.82916 -277.991952)
			(xy 69.809869 -277.946676) (xy 69.798092 -277.898892) (xy 69.794132 -277.849838) (xy 69.45503 -277.849838)
			(xy 69.454535 -277.874445) (xy 69.44664 -277.923022) (xy 69.431056 -277.969703) (xy 69.408185 -278.01328)
			(xy 69.37862 -278.052624) (xy 69.343127 -278.086716) (xy 69.302624 -278.114672) (xy 69.258162 -278.13577)
			(xy 69.210891 -278.149462) (xy 69.162036 -278.155394) (xy 69.112861 -278.153413) (xy 69.064642 -278.143569)
			(xy 69.018626 -278.126117) (xy 68.976005 -278.10151) (xy 68.937884 -278.070385) (xy 68.905249 -278.033548)
			(xy 68.878946 -277.991952) (xy 68.859655 -277.946676) (xy 68.847878 -277.898892) (xy 68.843918 -277.849838)
			(xy 68.50507 -277.849838) (xy 68.504575 -277.874445) (xy 68.49668 -277.923022) (xy 68.481096 -277.969703)
			(xy 68.458225 -278.01328) (xy 68.42866 -278.052624) (xy 68.393167 -278.086716) (xy 68.352664 -278.114672)
			(xy 68.308202 -278.13577) (xy 68.260931 -278.149462) (xy 68.212076 -278.155394) (xy 68.162901 -278.153413)
			(xy 68.114682 -278.143569) (xy 68.068666 -278.126117) (xy 68.026045 -278.10151) (xy 67.987924 -278.070385)
			(xy 67.955289 -278.033548) (xy 67.928986 -277.991952) (xy 67.909695 -277.946676) (xy 67.897918 -277.898892)
			(xy 67.893958 -277.849838) (xy 67.554856 -277.849838) (xy 67.554361 -277.874445) (xy 67.546466 -277.923022)
			(xy 67.530882 -277.969703) (xy 67.508011 -278.01328) (xy 67.478446 -278.052624) (xy 67.442953 -278.086716)
			(xy 67.40245 -278.114672) (xy 67.357988 -278.13577) (xy 67.310717 -278.149462) (xy 67.261862 -278.155394)
			(xy 67.212687 -278.153413) (xy 67.164468 -278.143569) (xy 67.118452 -278.126117) (xy 67.075831 -278.10151)
			(xy 67.03771 -278.070385) (xy 67.005075 -278.033548) (xy 66.978772 -277.991952) (xy 66.959481 -277.946676)
			(xy 66.947704 -277.898892) (xy 66.943744 -277.849838) (xy 66.60515 -277.849838) (xy 66.604655 -277.874445)
			(xy 66.59676 -277.923022) (xy 66.581176 -277.969703) (xy 66.558305 -278.01328) (xy 66.52874 -278.052624)
			(xy 66.493247 -278.086716) (xy 66.452744 -278.114672) (xy 66.408282 -278.13577) (xy 66.361011 -278.149462)
			(xy 66.312156 -278.155394) (xy 66.262981 -278.153413) (xy 66.214762 -278.143569) (xy 66.168746 -278.126117)
			(xy 66.126125 -278.10151) (xy 66.088004 -278.070385) (xy 66.055369 -278.033548) (xy 66.029066 -277.991952)
			(xy 66.009775 -277.946676) (xy 65.997998 -277.898892) (xy 65.994038 -277.849838) (xy 65.654936 -277.849838)
			(xy 65.654441 -277.874445) (xy 65.646546 -277.923022) (xy 65.630962 -277.969703) (xy 65.608091 -278.01328)
			(xy 65.578526 -278.052624) (xy 65.543033 -278.086716) (xy 65.50253 -278.114672) (xy 65.458068 -278.13577)
			(xy 65.410797 -278.149462) (xy 65.361942 -278.155394) (xy 65.312767 -278.153413) (xy 65.264548 -278.143569)
			(xy 65.218532 -278.126117) (xy 65.175911 -278.10151) (xy 65.13779 -278.070385) (xy 65.105155 -278.033548)
			(xy 65.078852 -277.991952) (xy 65.059561 -277.946676) (xy 65.047784 -277.898892) (xy 65.043824 -277.849838)
			(xy 64.70523 -277.849838) (xy 64.704735 -277.874445) (xy 64.69684 -277.923022) (xy 64.681256 -277.969703)
			(xy 64.658385 -278.01328) (xy 64.62882 -278.052624) (xy 64.593327 -278.086716) (xy 64.552824 -278.114672)
			(xy 64.508362 -278.13577) (xy 64.461091 -278.149462) (xy 64.412236 -278.155394) (xy 64.363061 -278.153413)
			(xy 64.314842 -278.143569) (xy 64.268826 -278.126117) (xy 64.226205 -278.10151) (xy 64.188084 -278.070385)
			(xy 64.155449 -278.033548) (xy 64.129146 -277.991952) (xy 64.109855 -277.946676) (xy 64.098078 -277.898892)
			(xy 64.094118 -277.849838) (xy 63.755016 -277.849838) (xy 63.754521 -277.874445) (xy 63.746626 -277.923022)
			(xy 63.731042 -277.969703) (xy 63.708171 -278.01328) (xy 63.678606 -278.052624) (xy 63.643113 -278.086716)
			(xy 63.60261 -278.114672) (xy 63.558148 -278.13577) (xy 63.510877 -278.149462) (xy 63.462022 -278.155394)
			(xy 63.412847 -278.153413) (xy 63.364628 -278.143569) (xy 63.318612 -278.126117) (xy 63.275991 -278.10151)
			(xy 63.23787 -278.070385) (xy 63.205235 -278.033548) (xy 63.178932 -277.991952) (xy 63.159641 -277.946676)
			(xy 63.147864 -277.898892) (xy 63.143904 -277.849838) (xy 62.805056 -277.849838) (xy 62.804561 -277.874445)
			(xy 62.796666 -277.923022) (xy 62.781082 -277.969703) (xy 62.758211 -278.01328) (xy 62.728646 -278.052624)
			(xy 62.693153 -278.086716) (xy 62.65265 -278.114672) (xy 62.608188 -278.13577) (xy 62.560917 -278.149462)
			(xy 62.512062 -278.155394) (xy 62.462887 -278.153413) (xy 62.414668 -278.143569) (xy 62.368652 -278.126117)
			(xy 62.326031 -278.10151) (xy 62.28791 -278.070385) (xy 62.255275 -278.033548) (xy 62.228972 -277.991952)
			(xy 62.209681 -277.946676) (xy 62.197904 -277.898892) (xy 62.193944 -277.849838) (xy 61.854842 -277.849838)
			(xy 61.854347 -277.874445) (xy 61.846452 -277.923022) (xy 61.830868 -277.969703) (xy 61.807997 -278.01328)
			(xy 61.778432 -278.052624) (xy 61.742939 -278.086716) (xy 61.702436 -278.114672) (xy 61.657974 -278.13577)
			(xy 61.610703 -278.149462) (xy 61.561848 -278.155394) (xy 61.512673 -278.153413) (xy 61.464454 -278.143569)
			(xy 61.418438 -278.126117) (xy 61.375817 -278.10151) (xy 61.337696 -278.070385) (xy 61.305061 -278.033548)
			(xy 61.278758 -277.991952) (xy 61.259467 -277.946676) (xy 61.24769 -277.898892) (xy 61.24373 -277.849838)
			(xy 60.905136 -277.849838) (xy 60.904641 -277.874445) (xy 60.896746 -277.923022) (xy 60.881162 -277.969703)
			(xy 60.858291 -278.01328) (xy 60.828726 -278.052624) (xy 60.793233 -278.086716) (xy 60.75273 -278.114672)
			(xy 60.708268 -278.13577) (xy 60.660997 -278.149462) (xy 60.612142 -278.155394) (xy 60.562967 -278.153413)
			(xy 60.514748 -278.143569) (xy 60.468732 -278.126117) (xy 60.426111 -278.10151) (xy 60.38799 -278.070385)
			(xy 60.355355 -278.033548) (xy 60.329052 -277.991952) (xy 60.309761 -277.946676) (xy 60.297984 -277.898892)
			(xy 60.294024 -277.849838) (xy 59.954922 -277.849838) (xy 59.954427 -277.874445) (xy 59.946532 -277.923022)
			(xy 59.930948 -277.969703) (xy 59.908077 -278.01328) (xy 59.878512 -278.052624) (xy 59.843019 -278.086716)
			(xy 59.802516 -278.114672) (xy 59.758054 -278.13577) (xy 59.710783 -278.149462) (xy 59.661928 -278.155394)
			(xy 59.612753 -278.153413) (xy 59.564534 -278.143569) (xy 59.518518 -278.126117) (xy 59.475897 -278.10151)
			(xy 59.437776 -278.070385) (xy 59.405141 -278.033548) (xy 59.378838 -277.991952) (xy 59.359547 -277.946676)
			(xy 59.34777 -277.898892) (xy 59.34381 -277.849838) (xy 59.005216 -277.849838) (xy 59.004743 -277.873827)
			(xy 58.997232 -277.921215) (xy 58.982401 -277.966845) (xy 58.960616 -278.009592) (xy 58.932412 -278.048407)
			(xy 58.898484 -278.082331) (xy 58.859667 -278.110531) (xy 58.816917 -278.132313) (xy 58.771286 -278.147139)
			(xy 58.723898 -278.154645) (xy 58.699908 -278.155146) (xy 58.685789 -278.154949) (xy 58.657676 -278.152282)
			(xy 58.643774 -278.149812) (xy 58.631328 -278.147526) (xy 58.607452 -278.154892) (xy 58.529982 -278.232362)
			(xy 58.522616 -278.256238) (xy 58.524902 -278.268684) (xy 58.527375 -278.282586) (xy 58.530043 -278.310699)
			(xy 58.530236 -278.324818) (xy 58.530236 -278.327612) (xy 58.529935 -278.341031) (xy 58.527264 -278.36774)
			(xy 58.524902 -278.380952) (xy 58.522616 -278.393398) (xy 58.529982 -278.417274) (xy 58.607452 -278.494744)
			(xy 58.631328 -278.50211) (xy 58.643774 -278.499824) (xy 58.657676 -278.497346) (xy 58.685788 -278.494671)
			(xy 58.699908 -278.49449) (xy 58.724729 -278.494977) (xy 58.773717 -278.503009) (xy 58.820759 -278.518861)
			(xy 58.864618 -278.542115) (xy 58.904137 -278.572157) (xy 58.938275 -278.608198) (xy 58.966132 -278.649287)
			(xy 58.986975 -278.694341) (xy 59.000255 -278.742173) (xy 59.005621 -278.791524) (xy 59.005172 -278.799798)
			(xy 59.34381 -278.799798) (xy 59.34777 -278.750744) (xy 59.359547 -278.70296) (xy 59.378838 -278.657684)
			(xy 59.405141 -278.616088) (xy 59.437776 -278.579251) (xy 59.475897 -278.548126) (xy 59.518518 -278.523519)
			(xy 59.564534 -278.506067) (xy 59.612753 -278.496223) (xy 59.661928 -278.494242) (xy 59.710783 -278.500174)
			(xy 59.758054 -278.513866) (xy 59.802516 -278.534964) (xy 59.843019 -278.56292) (xy 59.878512 -278.597012)
			(xy 59.908077 -278.636356) (xy 59.930948 -278.679933) (xy 59.946532 -278.726614) (xy 59.954427 -278.775191)
			(xy 59.954922 -278.799798) (xy 60.294024 -278.799798) (xy 60.297984 -278.750744) (xy 60.309761 -278.70296)
			(xy 60.329052 -278.657684) (xy 60.355355 -278.616088) (xy 60.38799 -278.579251) (xy 60.426111 -278.548126)
			(xy 60.468732 -278.523519) (xy 60.514748 -278.506067) (xy 60.562967 -278.496223) (xy 60.612142 -278.494242)
			(xy 60.660997 -278.500174) (xy 60.708268 -278.513866) (xy 60.75273 -278.534964) (xy 60.793233 -278.56292)
			(xy 60.828726 -278.597012) (xy 60.858291 -278.636356) (xy 60.881162 -278.679933) (xy 60.896746 -278.726614)
			(xy 60.904641 -278.775191) (xy 60.905136 -278.799798) (xy 61.24373 -278.799798) (xy 61.24769 -278.750744)
			(xy 61.259467 -278.70296) (xy 61.278758 -278.657684) (xy 61.305061 -278.616088) (xy 61.337696 -278.579251)
			(xy 61.375817 -278.548126) (xy 61.418438 -278.523519) (xy 61.464454 -278.506067) (xy 61.512673 -278.496223)
			(xy 61.561848 -278.494242) (xy 61.610703 -278.500174) (xy 61.657974 -278.513866) (xy 61.702436 -278.534964)
			(xy 61.742939 -278.56292) (xy 61.778432 -278.597012) (xy 61.807997 -278.636356) (xy 61.830868 -278.679933)
			(xy 61.846452 -278.726614) (xy 61.854347 -278.775191) (xy 61.854842 -278.799798) (xy 62.193944 -278.799798)
			(xy 62.197904 -278.750744) (xy 62.209681 -278.70296) (xy 62.228972 -278.657684) (xy 62.255275 -278.616088)
			(xy 62.28791 -278.579251) (xy 62.326031 -278.548126) (xy 62.368652 -278.523519) (xy 62.414668 -278.506067)
			(xy 62.462887 -278.496223) (xy 62.512062 -278.494242) (xy 62.560917 -278.500174) (xy 62.608188 -278.513866)
			(xy 62.65265 -278.534964) (xy 62.693153 -278.56292) (xy 62.728646 -278.597012) (xy 62.758211 -278.636356)
			(xy 62.781082 -278.679933) (xy 62.796666 -278.726614) (xy 62.804561 -278.775191) (xy 62.805056 -278.799798)
			(xy 63.143904 -278.799798) (xy 63.147864 -278.750744) (xy 63.159641 -278.70296) (xy 63.178932 -278.657684)
			(xy 63.205235 -278.616088) (xy 63.23787 -278.579251) (xy 63.275991 -278.548126) (xy 63.318612 -278.523519)
			(xy 63.364628 -278.506067) (xy 63.412847 -278.496223) (xy 63.462022 -278.494242) (xy 63.510877 -278.500174)
			(xy 63.558148 -278.513866) (xy 63.60261 -278.534964) (xy 63.643113 -278.56292) (xy 63.678606 -278.597012)
			(xy 63.708171 -278.636356) (xy 63.731042 -278.679933) (xy 63.746626 -278.726614) (xy 63.754521 -278.775191)
			(xy 63.755016 -278.799798) (xy 64.094118 -278.799798) (xy 64.098078 -278.750744) (xy 64.109855 -278.70296)
			(xy 64.129146 -278.657684) (xy 64.155449 -278.616088) (xy 64.188084 -278.579251) (xy 64.226205 -278.548126)
			(xy 64.268826 -278.523519) (xy 64.314842 -278.506067) (xy 64.363061 -278.496223) (xy 64.412236 -278.494242)
			(xy 64.461091 -278.500174) (xy 64.508362 -278.513866) (xy 64.552824 -278.534964) (xy 64.593327 -278.56292)
			(xy 64.62882 -278.597012) (xy 64.658385 -278.636356) (xy 64.681256 -278.679933) (xy 64.69684 -278.726614)
			(xy 64.704735 -278.775191) (xy 64.70523 -278.799798) (xy 65.043824 -278.799798) (xy 65.047784 -278.750744)
			(xy 65.059561 -278.70296) (xy 65.078852 -278.657684) (xy 65.105155 -278.616088) (xy 65.13779 -278.579251)
			(xy 65.175911 -278.548126) (xy 65.218532 -278.523519) (xy 65.264548 -278.506067) (xy 65.312767 -278.496223)
			(xy 65.361942 -278.494242) (xy 65.410797 -278.500174) (xy 65.458068 -278.513866) (xy 65.50253 -278.534964)
			(xy 65.543033 -278.56292) (xy 65.578526 -278.597012) (xy 65.608091 -278.636356) (xy 65.630962 -278.679933)
			(xy 65.646546 -278.726614) (xy 65.654441 -278.775191) (xy 65.654936 -278.799798) (xy 65.994038 -278.799798)
			(xy 65.997998 -278.750744) (xy 66.009775 -278.70296) (xy 66.029066 -278.657684) (xy 66.055369 -278.616088)
			(xy 66.088004 -278.579251) (xy 66.126125 -278.548126) (xy 66.168746 -278.523519) (xy 66.214762 -278.506067)
			(xy 66.262981 -278.496223) (xy 66.312156 -278.494242) (xy 66.361011 -278.500174) (xy 66.408282 -278.513866)
			(xy 66.452744 -278.534964) (xy 66.493247 -278.56292) (xy 66.52874 -278.597012) (xy 66.558305 -278.636356)
			(xy 66.581176 -278.679933) (xy 66.59676 -278.726614) (xy 66.604655 -278.775191) (xy 66.60515 -278.799798)
			(xy 66.943744 -278.799798) (xy 66.947704 -278.750744) (xy 66.959481 -278.70296) (xy 66.978772 -278.657684)
			(xy 67.005075 -278.616088) (xy 67.03771 -278.579251) (xy 67.075831 -278.548126) (xy 67.118452 -278.523519)
			(xy 67.164468 -278.506067) (xy 67.212687 -278.496223) (xy 67.261862 -278.494242) (xy 67.310717 -278.500174)
			(xy 67.357988 -278.513866) (xy 67.40245 -278.534964) (xy 67.442953 -278.56292) (xy 67.478446 -278.597012)
			(xy 67.508011 -278.636356) (xy 67.530882 -278.679933) (xy 67.546466 -278.726614) (xy 67.554361 -278.775191)
			(xy 67.554856 -278.799798) (xy 67.893958 -278.799798) (xy 67.897918 -278.750744) (xy 67.909695 -278.70296)
			(xy 67.928986 -278.657684) (xy 67.955289 -278.616088) (xy 67.987924 -278.579251) (xy 68.026045 -278.548126)
			(xy 68.068666 -278.523519) (xy 68.114682 -278.506067) (xy 68.162901 -278.496223) (xy 68.212076 -278.494242)
			(xy 68.260931 -278.500174) (xy 68.308202 -278.513866) (xy 68.352664 -278.534964) (xy 68.393167 -278.56292)
			(xy 68.42866 -278.597012) (xy 68.458225 -278.636356) (xy 68.481096 -278.679933) (xy 68.49668 -278.726614)
			(xy 68.504575 -278.775191) (xy 68.50507 -278.799798) (xy 68.843918 -278.799798) (xy 68.847878 -278.750744)
			(xy 68.859655 -278.70296) (xy 68.878946 -278.657684) (xy 68.905249 -278.616088) (xy 68.937884 -278.579251)
			(xy 68.976005 -278.548126) (xy 69.018626 -278.523519) (xy 69.064642 -278.506067) (xy 69.112861 -278.496223)
			(xy 69.162036 -278.494242) (xy 69.210891 -278.500174) (xy 69.258162 -278.513866) (xy 69.302624 -278.534964)
			(xy 69.343127 -278.56292) (xy 69.37862 -278.597012) (xy 69.408185 -278.636356) (xy 69.431056 -278.679933)
			(xy 69.44664 -278.726614) (xy 69.454535 -278.775191) (xy 69.45503 -278.799798) (xy 69.794132 -278.799798)
			(xy 69.798092 -278.750744) (xy 69.809869 -278.70296) (xy 69.82916 -278.657684) (xy 69.855463 -278.616088)
			(xy 69.888098 -278.579251) (xy 69.926219 -278.548126) (xy 69.96884 -278.523519) (xy 70.014856 -278.506067)
			(xy 70.063075 -278.496223) (xy 70.11225 -278.494242) (xy 70.161105 -278.500174) (xy 70.208376 -278.513866)
			(xy 70.252838 -278.534964) (xy 70.293341 -278.56292) (xy 70.328834 -278.597012) (xy 70.358399 -278.636356)
			(xy 70.38127 -278.679933) (xy 70.396854 -278.726614) (xy 70.404749 -278.775191) (xy 70.405244 -278.799798)
			(xy 70.743838 -278.799798) (xy 70.747798 -278.750744) (xy 70.759575 -278.70296) (xy 70.778866 -278.657684)
			(xy 70.805169 -278.616088) (xy 70.837804 -278.579251) (xy 70.875925 -278.548126) (xy 70.918546 -278.523519)
			(xy 70.964562 -278.506067) (xy 71.012781 -278.496223) (xy 71.061956 -278.494242) (xy 71.110811 -278.500174)
			(xy 71.158082 -278.513866) (xy 71.202544 -278.534964) (xy 71.243047 -278.56292) (xy 71.27854 -278.597012)
			(xy 71.308105 -278.636356) (xy 71.330976 -278.679933) (xy 71.34656 -278.726614) (xy 71.354455 -278.775191)
			(xy 71.35495 -278.799798) (xy 71.694052 -278.799798) (xy 71.698012 -278.750744) (xy 71.709789 -278.70296)
			(xy 71.72908 -278.657684) (xy 71.755383 -278.616088) (xy 71.788018 -278.579251) (xy 71.826139 -278.548126)
			(xy 71.86876 -278.523519) (xy 71.914776 -278.506067) (xy 71.962995 -278.496223) (xy 72.01217 -278.494242)
			(xy 72.061025 -278.500174) (xy 72.108296 -278.513866) (xy 72.152758 -278.534964) (xy 72.193261 -278.56292)
			(xy 72.228754 -278.597012) (xy 72.258319 -278.636356) (xy 72.28119 -278.679933) (xy 72.296774 -278.726614)
			(xy 72.304669 -278.775191) (xy 72.305164 -278.799798) (xy 72.643758 -278.799798) (xy 72.647718 -278.750744)
			(xy 72.659495 -278.70296) (xy 72.678786 -278.657684) (xy 72.705089 -278.616088) (xy 72.737724 -278.579251)
			(xy 72.775845 -278.548126) (xy 72.818466 -278.523519) (xy 72.864482 -278.506067) (xy 72.912701 -278.496223)
			(xy 72.961876 -278.494242) (xy 73.010731 -278.500174) (xy 73.058002 -278.513866) (xy 73.102464 -278.534964)
			(xy 73.142967 -278.56292) (xy 73.17846 -278.597012) (xy 73.208025 -278.636356) (xy 73.230896 -278.679933)
			(xy 73.24648 -278.726614) (xy 73.254375 -278.775191) (xy 73.25487 -278.799798) (xy 73.593972 -278.799798)
			(xy 73.597932 -278.750744) (xy 73.609709 -278.70296) (xy 73.629 -278.657684) (xy 73.655303 -278.616088)
			(xy 73.687938 -278.579251) (xy 73.726059 -278.548126) (xy 73.76868 -278.523519) (xy 73.814696 -278.506067)
			(xy 73.862915 -278.496223) (xy 73.91209 -278.494242) (xy 73.960945 -278.500174) (xy 74.008216 -278.513866)
			(xy 74.052678 -278.534964) (xy 74.093181 -278.56292) (xy 74.128674 -278.597012) (xy 74.158239 -278.636356)
			(xy 74.18111 -278.679933) (xy 74.196694 -278.726614) (xy 74.204589 -278.775191) (xy 74.205084 -278.799798)
			(xy 74.543932 -278.799798) (xy 74.547892 -278.750744) (xy 74.559669 -278.70296) (xy 74.57896 -278.657684)
			(xy 74.605263 -278.616088) (xy 74.637898 -278.579251) (xy 74.676019 -278.548126) (xy 74.71864 -278.523519)
			(xy 74.764656 -278.506067) (xy 74.812875 -278.496223) (xy 74.86205 -278.494242) (xy 74.910905 -278.500174)
			(xy 74.958176 -278.513866) (xy 75.002638 -278.534964) (xy 75.043141 -278.56292) (xy 75.078634 -278.597012)
			(xy 75.108199 -278.636356) (xy 75.13107 -278.679933) (xy 75.146654 -278.726614) (xy 75.154549 -278.775191)
			(xy 75.155044 -278.799798) (xy 75.494146 -278.799798) (xy 75.498106 -278.750744) (xy 75.509883 -278.70296)
			(xy 75.529174 -278.657684) (xy 75.555477 -278.616088) (xy 75.588112 -278.579251) (xy 75.626233 -278.548126)
			(xy 75.668854 -278.523519) (xy 75.71487 -278.506067) (xy 75.763089 -278.496223) (xy 75.812264 -278.494242)
			(xy 75.861119 -278.500174) (xy 75.90839 -278.513866) (xy 75.952852 -278.534964) (xy 75.993355 -278.56292)
			(xy 76.028848 -278.597012) (xy 76.058413 -278.636356) (xy 76.081284 -278.679933) (xy 76.096868 -278.726614)
			(xy 76.104763 -278.775191) (xy 76.105258 -278.799798) (xy 76.443852 -278.799798) (xy 76.447812 -278.750744)
			(xy 76.459589 -278.70296) (xy 76.47888 -278.657684) (xy 76.505183 -278.616088) (xy 76.537818 -278.579251)
			(xy 76.575939 -278.548126) (xy 76.61856 -278.523519) (xy 76.664576 -278.506067) (xy 76.712795 -278.496223)
			(xy 76.76197 -278.494242) (xy 76.810825 -278.500174) (xy 76.858096 -278.513866) (xy 76.902558 -278.534964)
			(xy 76.943061 -278.56292) (xy 76.978554 -278.597012) (xy 77.008119 -278.636356) (xy 77.03099 -278.679933)
			(xy 77.046574 -278.726614) (xy 77.054469 -278.775191) (xy 77.054964 -278.799798) (xy 77.394066 -278.799798)
			(xy 77.398026 -278.750744) (xy 77.409803 -278.70296) (xy 77.429094 -278.657684) (xy 77.455397 -278.616088)
			(xy 77.488032 -278.579251) (xy 77.526153 -278.548126) (xy 77.568774 -278.523519) (xy 77.61479 -278.506067)
			(xy 77.663009 -278.496223) (xy 77.712184 -278.494242) (xy 77.761039 -278.500174) (xy 77.80831 -278.513866)
			(xy 77.852772 -278.534964) (xy 77.893275 -278.56292) (xy 77.928768 -278.597012) (xy 77.958333 -278.636356)
			(xy 77.981204 -278.679933) (xy 77.996788 -278.726614) (xy 78.004683 -278.775191) (xy 78.005178 -278.799798)
			(xy 78.343772 -278.799798) (xy 78.347732 -278.750744) (xy 78.359509 -278.70296) (xy 78.3788 -278.657684)
			(xy 78.405103 -278.616088) (xy 78.437738 -278.579251) (xy 78.475859 -278.548126) (xy 78.51848 -278.523519)
			(xy 78.564496 -278.506067) (xy 78.612715 -278.496223) (xy 78.66189 -278.494242) (xy 78.710745 -278.500174)
			(xy 78.758016 -278.513866) (xy 78.802478 -278.534964) (xy 78.842981 -278.56292) (xy 78.878474 -278.597012)
			(xy 78.908039 -278.636356) (xy 78.93091 -278.679933) (xy 78.946494 -278.726614) (xy 78.954389 -278.775191)
			(xy 78.954884 -278.799798) (xy 79.293986 -278.799798) (xy 79.297946 -278.750744) (xy 79.309723 -278.70296)
			(xy 79.329014 -278.657684) (xy 79.355317 -278.616088) (xy 79.387952 -278.579251) (xy 79.426073 -278.548126)
			(xy 79.468694 -278.523519) (xy 79.51471 -278.506067) (xy 79.562929 -278.496223) (xy 79.612104 -278.494242)
			(xy 79.660959 -278.500174) (xy 79.70823 -278.513866) (xy 79.752692 -278.534964) (xy 79.793195 -278.56292)
			(xy 79.828688 -278.597012) (xy 79.858253 -278.636356) (xy 79.881124 -278.679933) (xy 79.896708 -278.726614)
			(xy 79.904603 -278.775191) (xy 79.905098 -278.799798) (xy 80.243946 -278.799798) (xy 80.247906 -278.750744)
			(xy 80.259683 -278.70296) (xy 80.278974 -278.657684) (xy 80.305277 -278.616088) (xy 80.337912 -278.579251)
			(xy 80.376033 -278.548126) (xy 80.418654 -278.523519) (xy 80.46467 -278.506067) (xy 80.512889 -278.496223)
			(xy 80.562064 -278.494242) (xy 80.610919 -278.500174) (xy 80.65819 -278.513866) (xy 80.702652 -278.534964)
			(xy 80.743155 -278.56292) (xy 80.778648 -278.597012) (xy 80.808213 -278.636356) (xy 80.831084 -278.679933)
			(xy 80.846668 -278.726614) (xy 80.854563 -278.775191) (xy 80.855058 -278.799798) (xy 81.19416 -278.799798)
			(xy 81.19812 -278.750744) (xy 81.209897 -278.70296) (xy 81.229188 -278.657684) (xy 81.255491 -278.616088)
			(xy 81.288126 -278.579251) (xy 81.326247 -278.548126) (xy 81.368868 -278.523519) (xy 81.414884 -278.506067)
			(xy 81.463103 -278.496223) (xy 81.512278 -278.494242) (xy 81.561133 -278.500174) (xy 81.608404 -278.513866)
			(xy 81.652866 -278.534964) (xy 81.693369 -278.56292) (xy 81.728862 -278.597012) (xy 81.758427 -278.636356)
			(xy 81.781298 -278.679933) (xy 81.796882 -278.726614) (xy 81.804777 -278.775191) (xy 81.805272 -278.799798)
			(xy 82.14412 -278.799798) (xy 82.14808 -278.750744) (xy 82.159857 -278.70296) (xy 82.179148 -278.657684)
			(xy 82.205451 -278.616088) (xy 82.238086 -278.579251) (xy 82.276207 -278.548126) (xy 82.318828 -278.523519)
			(xy 82.364844 -278.506067) (xy 82.413063 -278.496223) (xy 82.462238 -278.494242) (xy 82.511093 -278.500174)
			(xy 82.558364 -278.513866) (xy 82.602826 -278.534964) (xy 82.643329 -278.56292) (xy 82.678822 -278.597012)
			(xy 82.708387 -278.636356) (xy 82.731258 -278.679933) (xy 82.746842 -278.726614) (xy 82.754737 -278.775191)
			(xy 82.755232 -278.799798) (xy 82.754737 -278.824405) (xy 82.746842 -278.872982) (xy 82.731258 -278.919663)
			(xy 82.708387 -278.96324) (xy 82.678822 -279.002584) (xy 82.643329 -279.036676) (xy 82.602826 -279.064632)
			(xy 82.558364 -279.08573) (xy 82.511093 -279.099422) (xy 82.462238 -279.105354) (xy 82.413063 -279.103373)
			(xy 82.364844 -279.093529) (xy 82.318828 -279.076077) (xy 82.276207 -279.05147) (xy 82.238086 -279.020345)
			(xy 82.205451 -278.983508) (xy 82.179148 -278.941912) (xy 82.159857 -278.896636) (xy 82.14808 -278.848852)
			(xy 82.14412 -278.799798) (xy 81.805272 -278.799798) (xy 81.804777 -278.824405) (xy 81.796882 -278.872982)
			(xy 81.781298 -278.919663) (xy 81.758427 -278.96324) (xy 81.728862 -279.002584) (xy 81.693369 -279.036676)
			(xy 81.652866 -279.064632) (xy 81.608404 -279.08573) (xy 81.561133 -279.099422) (xy 81.512278 -279.105354)
			(xy 81.463103 -279.103373) (xy 81.414884 -279.093529) (xy 81.368868 -279.076077) (xy 81.326247 -279.05147)
			(xy 81.288126 -279.020345) (xy 81.255491 -278.983508) (xy 81.229188 -278.941912) (xy 81.209897 -278.896636)
			(xy 81.19812 -278.848852) (xy 81.19416 -278.799798) (xy 80.855058 -278.799798) (xy 80.854563 -278.824405)
			(xy 80.846668 -278.872982) (xy 80.831084 -278.919663) (xy 80.808213 -278.96324) (xy 80.778648 -279.002584)
			(xy 80.743155 -279.036676) (xy 80.702652 -279.064632) (xy 80.65819 -279.08573) (xy 80.610919 -279.099422)
			(xy 80.562064 -279.105354) (xy 80.512889 -279.103373) (xy 80.46467 -279.093529) (xy 80.418654 -279.076077)
			(xy 80.376033 -279.05147) (xy 80.337912 -279.020345) (xy 80.305277 -278.983508) (xy 80.278974 -278.941912)
			(xy 80.259683 -278.896636) (xy 80.247906 -278.848852) (xy 80.243946 -278.799798) (xy 79.905098 -278.799798)
			(xy 79.904603 -278.824405) (xy 79.896708 -278.872982) (xy 79.881124 -278.919663) (xy 79.858253 -278.96324)
			(xy 79.828688 -279.002584) (xy 79.793195 -279.036676) (xy 79.752692 -279.064632) (xy 79.70823 -279.08573)
			(xy 79.660959 -279.099422) (xy 79.612104 -279.105354) (xy 79.562929 -279.103373) (xy 79.51471 -279.093529)
			(xy 79.468694 -279.076077) (xy 79.426073 -279.05147) (xy 79.387952 -279.020345) (xy 79.355317 -278.983508)
			(xy 79.329014 -278.941912) (xy 79.309723 -278.896636) (xy 79.297946 -278.848852) (xy 79.293986 -278.799798)
			(xy 78.954884 -278.799798) (xy 78.954389 -278.824405) (xy 78.946494 -278.872982) (xy 78.93091 -278.919663)
			(xy 78.908039 -278.96324) (xy 78.878474 -279.002584) (xy 78.842981 -279.036676) (xy 78.802478 -279.064632)
			(xy 78.758016 -279.08573) (xy 78.710745 -279.099422) (xy 78.66189 -279.105354) (xy 78.612715 -279.103373)
			(xy 78.564496 -279.093529) (xy 78.51848 -279.076077) (xy 78.475859 -279.05147) (xy 78.437738 -279.020345)
			(xy 78.405103 -278.983508) (xy 78.3788 -278.941912) (xy 78.359509 -278.896636) (xy 78.347732 -278.848852)
			(xy 78.343772 -278.799798) (xy 78.005178 -278.799798) (xy 78.004683 -278.824405) (xy 77.996788 -278.872982)
			(xy 77.981204 -278.919663) (xy 77.958333 -278.96324) (xy 77.928768 -279.002584) (xy 77.893275 -279.036676)
			(xy 77.852772 -279.064632) (xy 77.80831 -279.08573) (xy 77.761039 -279.099422) (xy 77.712184 -279.105354)
			(xy 77.663009 -279.103373) (xy 77.61479 -279.093529) (xy 77.568774 -279.076077) (xy 77.526153 -279.05147)
			(xy 77.488032 -279.020345) (xy 77.455397 -278.983508) (xy 77.429094 -278.941912) (xy 77.409803 -278.896636)
			(xy 77.398026 -278.848852) (xy 77.394066 -278.799798) (xy 77.054964 -278.799798) (xy 77.054469 -278.824405)
			(xy 77.046574 -278.872982) (xy 77.03099 -278.919663) (xy 77.008119 -278.96324) (xy 76.978554 -279.002584)
			(xy 76.943061 -279.036676) (xy 76.902558 -279.064632) (xy 76.858096 -279.08573) (xy 76.810825 -279.099422)
			(xy 76.76197 -279.105354) (xy 76.712795 -279.103373) (xy 76.664576 -279.093529) (xy 76.61856 -279.076077)
			(xy 76.575939 -279.05147) (xy 76.537818 -279.020345) (xy 76.505183 -278.983508) (xy 76.47888 -278.941912)
			(xy 76.459589 -278.896636) (xy 76.447812 -278.848852) (xy 76.443852 -278.799798) (xy 76.105258 -278.799798)
			(xy 76.104763 -278.824405) (xy 76.096868 -278.872982) (xy 76.081284 -278.919663) (xy 76.058413 -278.96324)
			(xy 76.028848 -279.002584) (xy 75.993355 -279.036676) (xy 75.952852 -279.064632) (xy 75.90839 -279.08573)
			(xy 75.861119 -279.099422) (xy 75.812264 -279.105354) (xy 75.763089 -279.103373) (xy 75.71487 -279.093529)
			(xy 75.668854 -279.076077) (xy 75.626233 -279.05147) (xy 75.588112 -279.020345) (xy 75.555477 -278.983508)
			(xy 75.529174 -278.941912) (xy 75.509883 -278.896636) (xy 75.498106 -278.848852) (xy 75.494146 -278.799798)
			(xy 75.155044 -278.799798) (xy 75.154549 -278.824405) (xy 75.146654 -278.872982) (xy 75.13107 -278.919663)
			(xy 75.108199 -278.96324) (xy 75.078634 -279.002584) (xy 75.043141 -279.036676) (xy 75.002638 -279.064632)
			(xy 74.958176 -279.08573) (xy 74.910905 -279.099422) (xy 74.86205 -279.105354) (xy 74.812875 -279.103373)
			(xy 74.764656 -279.093529) (xy 74.71864 -279.076077) (xy 74.676019 -279.05147) (xy 74.637898 -279.020345)
			(xy 74.605263 -278.983508) (xy 74.57896 -278.941912) (xy 74.559669 -278.896636) (xy 74.547892 -278.848852)
			(xy 74.543932 -278.799798) (xy 74.205084 -278.799798) (xy 74.204589 -278.824405) (xy 74.196694 -278.872982)
			(xy 74.18111 -278.919663) (xy 74.158239 -278.96324) (xy 74.128674 -279.002584) (xy 74.093181 -279.036676)
			(xy 74.052678 -279.064632) (xy 74.008216 -279.08573) (xy 73.960945 -279.099422) (xy 73.91209 -279.105354)
			(xy 73.862915 -279.103373) (xy 73.814696 -279.093529) (xy 73.76868 -279.076077) (xy 73.726059 -279.05147)
			(xy 73.687938 -279.020345) (xy 73.655303 -278.983508) (xy 73.629 -278.941912) (xy 73.609709 -278.896636)
			(xy 73.597932 -278.848852) (xy 73.593972 -278.799798) (xy 73.25487 -278.799798) (xy 73.254375 -278.824405)
			(xy 73.24648 -278.872982) (xy 73.230896 -278.919663) (xy 73.208025 -278.96324) (xy 73.17846 -279.002584)
			(xy 73.142967 -279.036676) (xy 73.102464 -279.064632) (xy 73.058002 -279.08573) (xy 73.010731 -279.099422)
			(xy 72.961876 -279.105354) (xy 72.912701 -279.103373) (xy 72.864482 -279.093529) (xy 72.818466 -279.076077)
			(xy 72.775845 -279.05147) (xy 72.737724 -279.020345) (xy 72.705089 -278.983508) (xy 72.678786 -278.941912)
			(xy 72.659495 -278.896636) (xy 72.647718 -278.848852) (xy 72.643758 -278.799798) (xy 72.305164 -278.799798)
			(xy 72.304669 -278.824405) (xy 72.296774 -278.872982) (xy 72.28119 -278.919663) (xy 72.258319 -278.96324)
			(xy 72.228754 -279.002584) (xy 72.193261 -279.036676) (xy 72.152758 -279.064632) (xy 72.108296 -279.08573)
			(xy 72.061025 -279.099422) (xy 72.01217 -279.105354) (xy 71.962995 -279.103373) (xy 71.914776 -279.093529)
			(xy 71.86876 -279.076077) (xy 71.826139 -279.05147) (xy 71.788018 -279.020345) (xy 71.755383 -278.983508)
			(xy 71.72908 -278.941912) (xy 71.709789 -278.896636) (xy 71.698012 -278.848852) (xy 71.694052 -278.799798)
			(xy 71.35495 -278.799798) (xy 71.354455 -278.824405) (xy 71.34656 -278.872982) (xy 71.330976 -278.919663)
			(xy 71.308105 -278.96324) (xy 71.27854 -279.002584) (xy 71.243047 -279.036676) (xy 71.202544 -279.064632)
			(xy 71.158082 -279.08573) (xy 71.110811 -279.099422) (xy 71.061956 -279.105354) (xy 71.012781 -279.103373)
			(xy 70.964562 -279.093529) (xy 70.918546 -279.076077) (xy 70.875925 -279.05147) (xy 70.837804 -279.020345)
			(xy 70.805169 -278.983508) (xy 70.778866 -278.941912) (xy 70.759575 -278.896636) (xy 70.747798 -278.848852)
			(xy 70.743838 -278.799798) (xy 70.405244 -278.799798) (xy 70.404749 -278.824405) (xy 70.396854 -278.872982)
			(xy 70.38127 -278.919663) (xy 70.358399 -278.96324) (xy 70.328834 -279.002584) (xy 70.293341 -279.036676)
			(xy 70.252838 -279.064632) (xy 70.208376 -279.08573) (xy 70.161105 -279.099422) (xy 70.11225 -279.105354)
			(xy 70.063075 -279.103373) (xy 70.014856 -279.093529) (xy 69.96884 -279.076077) (xy 69.926219 -279.05147)
			(xy 69.888098 -279.020345) (xy 69.855463 -278.983508) (xy 69.82916 -278.941912) (xy 69.809869 -278.896636)
			(xy 69.798092 -278.848852) (xy 69.794132 -278.799798) (xy 69.45503 -278.799798) (xy 69.454535 -278.824405)
			(xy 69.44664 -278.872982) (xy 69.431056 -278.919663) (xy 69.408185 -278.96324) (xy 69.37862 -279.002584)
			(xy 69.343127 -279.036676) (xy 69.302624 -279.064632) (xy 69.258162 -279.08573) (xy 69.210891 -279.099422)
			(xy 69.162036 -279.105354) (xy 69.112861 -279.103373) (xy 69.064642 -279.093529) (xy 69.018626 -279.076077)
			(xy 68.976005 -279.05147) (xy 68.937884 -279.020345) (xy 68.905249 -278.983508) (xy 68.878946 -278.941912)
			(xy 68.859655 -278.896636) (xy 68.847878 -278.848852) (xy 68.843918 -278.799798) (xy 68.50507 -278.799798)
			(xy 68.504575 -278.824405) (xy 68.49668 -278.872982) (xy 68.481096 -278.919663) (xy 68.458225 -278.96324)
			(xy 68.42866 -279.002584) (xy 68.393167 -279.036676) (xy 68.352664 -279.064632) (xy 68.308202 -279.08573)
			(xy 68.260931 -279.099422) (xy 68.212076 -279.105354) (xy 68.162901 -279.103373) (xy 68.114682 -279.093529)
			(xy 68.068666 -279.076077) (xy 68.026045 -279.05147) (xy 67.987924 -279.020345) (xy 67.955289 -278.983508)
			(xy 67.928986 -278.941912) (xy 67.909695 -278.896636) (xy 67.897918 -278.848852) (xy 67.893958 -278.799798)
			(xy 67.554856 -278.799798) (xy 67.554361 -278.824405) (xy 67.546466 -278.872982) (xy 67.530882 -278.919663)
			(xy 67.508011 -278.96324) (xy 67.478446 -279.002584) (xy 67.442953 -279.036676) (xy 67.40245 -279.064632)
			(xy 67.357988 -279.08573) (xy 67.310717 -279.099422) (xy 67.261862 -279.105354) (xy 67.212687 -279.103373)
			(xy 67.164468 -279.093529) (xy 67.118452 -279.076077) (xy 67.075831 -279.05147) (xy 67.03771 -279.020345)
			(xy 67.005075 -278.983508) (xy 66.978772 -278.941912) (xy 66.959481 -278.896636) (xy 66.947704 -278.848852)
			(xy 66.943744 -278.799798) (xy 66.60515 -278.799798) (xy 66.604655 -278.824405) (xy 66.59676 -278.872982)
			(xy 66.581176 -278.919663) (xy 66.558305 -278.96324) (xy 66.52874 -279.002584) (xy 66.493247 -279.036676)
			(xy 66.452744 -279.064632) (xy 66.408282 -279.08573) (xy 66.361011 -279.099422) (xy 66.312156 -279.105354)
			(xy 66.262981 -279.103373) (xy 66.214762 -279.093529) (xy 66.168746 -279.076077) (xy 66.126125 -279.05147)
			(xy 66.088004 -279.020345) (xy 66.055369 -278.983508) (xy 66.029066 -278.941912) (xy 66.009775 -278.896636)
			(xy 65.997998 -278.848852) (xy 65.994038 -278.799798) (xy 65.654936 -278.799798) (xy 65.654441 -278.824405)
			(xy 65.646546 -278.872982) (xy 65.630962 -278.919663) (xy 65.608091 -278.96324) (xy 65.578526 -279.002584)
			(xy 65.543033 -279.036676) (xy 65.50253 -279.064632) (xy 65.458068 -279.08573) (xy 65.410797 -279.099422)
			(xy 65.361942 -279.105354) (xy 65.312767 -279.103373) (xy 65.264548 -279.093529) (xy 65.218532 -279.076077)
			(xy 65.175911 -279.05147) (xy 65.13779 -279.020345) (xy 65.105155 -278.983508) (xy 65.078852 -278.941912)
			(xy 65.059561 -278.896636) (xy 65.047784 -278.848852) (xy 65.043824 -278.799798) (xy 64.70523 -278.799798)
			(xy 64.704735 -278.824405) (xy 64.69684 -278.872982) (xy 64.681256 -278.919663) (xy 64.658385 -278.96324)
			(xy 64.62882 -279.002584) (xy 64.593327 -279.036676) (xy 64.552824 -279.064632) (xy 64.508362 -279.08573)
			(xy 64.461091 -279.099422) (xy 64.412236 -279.105354) (xy 64.363061 -279.103373) (xy 64.314842 -279.093529)
			(xy 64.268826 -279.076077) (xy 64.226205 -279.05147) (xy 64.188084 -279.020345) (xy 64.155449 -278.983508)
			(xy 64.129146 -278.941912) (xy 64.109855 -278.896636) (xy 64.098078 -278.848852) (xy 64.094118 -278.799798)
			(xy 63.755016 -278.799798) (xy 63.754521 -278.824405) (xy 63.746626 -278.872982) (xy 63.731042 -278.919663)
			(xy 63.708171 -278.96324) (xy 63.678606 -279.002584) (xy 63.643113 -279.036676) (xy 63.60261 -279.064632)
			(xy 63.558148 -279.08573) (xy 63.510877 -279.099422) (xy 63.462022 -279.105354) (xy 63.412847 -279.103373)
			(xy 63.364628 -279.093529) (xy 63.318612 -279.076077) (xy 63.275991 -279.05147) (xy 63.23787 -279.020345)
			(xy 63.205235 -278.983508) (xy 63.178932 -278.941912) (xy 63.159641 -278.896636) (xy 63.147864 -278.848852)
			(xy 63.143904 -278.799798) (xy 62.805056 -278.799798) (xy 62.804561 -278.824405) (xy 62.796666 -278.872982)
			(xy 62.781082 -278.919663) (xy 62.758211 -278.96324) (xy 62.728646 -279.002584) (xy 62.693153 -279.036676)
			(xy 62.65265 -279.064632) (xy 62.608188 -279.08573) (xy 62.560917 -279.099422) (xy 62.512062 -279.105354)
			(xy 62.462887 -279.103373) (xy 62.414668 -279.093529) (xy 62.368652 -279.076077) (xy 62.326031 -279.05147)
			(xy 62.28791 -279.020345) (xy 62.255275 -278.983508) (xy 62.228972 -278.941912) (xy 62.209681 -278.896636)
			(xy 62.197904 -278.848852) (xy 62.193944 -278.799798) (xy 61.854842 -278.799798) (xy 61.854347 -278.824405)
			(xy 61.846452 -278.872982) (xy 61.830868 -278.919663) (xy 61.807997 -278.96324) (xy 61.778432 -279.002584)
			(xy 61.742939 -279.036676) (xy 61.702436 -279.064632) (xy 61.657974 -279.08573) (xy 61.610703 -279.099422)
			(xy 61.561848 -279.105354) (xy 61.512673 -279.103373) (xy 61.464454 -279.093529) (xy 61.418438 -279.076077)
			(xy 61.375817 -279.05147) (xy 61.337696 -279.020345) (xy 61.305061 -278.983508) (xy 61.278758 -278.941912)
			(xy 61.259467 -278.896636) (xy 61.24769 -278.848852) (xy 61.24373 -278.799798) (xy 60.905136 -278.799798)
			(xy 60.904641 -278.824405) (xy 60.896746 -278.872982) (xy 60.881162 -278.919663) (xy 60.858291 -278.96324)
			(xy 60.828726 -279.002584) (xy 60.793233 -279.036676) (xy 60.75273 -279.064632) (xy 60.708268 -279.08573)
			(xy 60.660997 -279.099422) (xy 60.612142 -279.105354) (xy 60.562967 -279.103373) (xy 60.514748 -279.093529)
			(xy 60.468732 -279.076077) (xy 60.426111 -279.05147) (xy 60.38799 -279.020345) (xy 60.355355 -278.983508)
			(xy 60.329052 -278.941912) (xy 60.309761 -278.896636) (xy 60.297984 -278.848852) (xy 60.294024 -278.799798)
			(xy 59.954922 -278.799798) (xy 59.954427 -278.824405) (xy 59.946532 -278.872982) (xy 59.930948 -278.919663)
			(xy 59.908077 -278.96324) (xy 59.878512 -279.002584) (xy 59.843019 -279.036676) (xy 59.802516 -279.064632)
			(xy 59.758054 -279.08573) (xy 59.710783 -279.099422) (xy 59.661928 -279.105354) (xy 59.612753 -279.103373)
			(xy 59.564534 -279.093529) (xy 59.518518 -279.076077) (xy 59.475897 -279.05147) (xy 59.437776 -279.020345)
			(xy 59.405141 -278.983508) (xy 59.378838 -278.941912) (xy 59.359547 -278.896636) (xy 59.34777 -278.848852)
			(xy 59.34381 -278.799798) (xy 59.005172 -278.799798) (xy 59.002932 -278.841093) (xy 58.99226 -278.889574)
			(xy 58.973885 -278.93569) (xy 58.948291 -278.978226) (xy 58.916153 -279.01606) (xy 58.878317 -279.048197)
			(xy 58.835781 -279.073789) (xy 58.789665 -279.092163) (xy 58.741183 -279.102834) (xy 58.691614 -279.105521)
			(xy 58.642264 -279.100153) (xy 58.594431 -279.086872) (xy 58.549378 -279.066027) (xy 58.50829 -279.038168)
			(xy 58.472251 -279.004029) (xy 58.442209 -278.96451) (xy 58.418957 -278.92065) (xy 58.403107 -278.873607)
			(xy 58.395076 -278.824619) (xy 58.3946 -278.799798) (xy 58.394798 -278.785679) (xy 58.397465 -278.757567)
			(xy 58.399934 -278.743664) (xy 58.40222 -278.731218) (xy 58.394854 -278.707342) (xy 58.317384 -278.629872)
			(xy 58.293508 -278.622506) (xy 58.281062 -278.624792) (xy 58.26716 -278.627267) (xy 58.239047 -278.629936)
			(xy 58.224928 -278.630126) (xy 58.224674 -278.630126) (xy 58.202552 -278.629713) (xy 58.158775 -278.623296)
			(xy 58.116377 -278.610645) (xy 58.09615 -278.601678) (xy 58.095642 -278.601678) (xy 58.093356 -278.600662)
			(xy 58.092848 -278.600408) (xy 58.088506 -278.598453) (xy 58.079301 -278.596022) (xy 58.07456 -278.595582)
			(xy 58.065337 -278.595332) (xy 58.047682 -278.600637) (xy 58.033053 -278.611854) (xy 58.027824 -278.619458)
			(xy 58.020966 -278.630634) (xy 58.019696 -278.656542) (xy 58.025284 -278.668226) (xy 58.0347 -278.688871)
			(xy 58.048019 -278.732246) (xy 58.05479 -278.777112) (xy 58.055256 -278.799798) (xy 58.054734 -278.825053)
			(xy 58.046421 -278.874875) (xy 58.03002 -278.922649) (xy 58.005979 -278.967072) (xy 57.974955 -279.006932)
			(xy 57.937793 -279.041142) (xy 57.895507 -279.068768) (xy 57.849251 -279.089058) (xy 57.800286 -279.101458)
			(xy 57.749948 -279.105629) (xy 57.69961 -279.101458) (xy 57.650645 -279.089058) (xy 57.604389 -279.068768)
			(xy 57.562103 -279.041142) (xy 57.524941 -279.006932) (xy 57.493917 -278.967072) (xy 57.469876 -278.922649)
			(xy 57.453475 -278.874875) (xy 57.445162 -278.825053) (xy 57.44464 -278.799798) (xy 57.444749 -278.790821)
			(xy 57.445891 -278.772902) (xy 57.446926 -278.763984) (xy 57.446926 -278.762714) (xy 57.447511 -278.751084)
			(xy 57.439427 -278.729273) (xy 57.431432 -278.720804) (xy 57.363614 -278.656034) (xy 57.341008 -278.649176)
			(xy 57.32907 -278.651208) (xy 57.315456 -278.653355) (xy 57.287988 -278.655644) (xy 57.274206 -278.65578)
			(xy 57.273952 -278.65578) (xy 57.260557 -278.655646) (xy 57.233854 -278.653485) (xy 57.220612 -278.651462)
			(xy 57.220358 -278.651462) (xy 57.20856 -278.650126) (xy 57.185919 -278.657169) (xy 57.176924 -278.664924)
			(xy 57.109614 -278.72944) (xy 57.10174 -278.751538) (xy 57.103264 -278.76373) (xy 57.104248 -278.772714)
			(xy 57.105267 -278.79076) (xy 57.105296 -278.799798) (xy 57.104774 -278.825053) (xy 57.096461 -278.874875)
			(xy 57.08006 -278.922649) (xy 57.056019 -278.967072) (xy 57.024995 -279.006932) (xy 56.987833 -279.041142)
			(xy 56.945547 -279.068768) (xy 56.899291 -279.089058) (xy 56.850326 -279.101458) (xy 56.799988 -279.105629)
			(xy 56.74965 -279.101458) (xy 56.700685 -279.089058) (xy 56.654429 -279.068768) (xy 56.612143 -279.041142)
			(xy 56.574981 -279.006932) (xy 56.543957 -278.967072) (xy 56.519916 -278.922649) (xy 56.503515 -278.874875)
			(xy 56.495202 -278.825053) (xy 56.49468 -278.799798) (xy 56.494798 -278.786458) (xy 56.497085 -278.759876)
			(xy 56.499252 -278.746712) (xy 56.501538 -278.73452) (xy 56.493918 -278.71039) (xy 56.425846 -278.64308)
			(xy 56.416608 -278.634924) (xy 56.393117 -278.627607) (xy 56.380888 -278.62911) (xy 56.367042 -278.631495)
			(xy 56.339058 -278.634035) (xy 56.325008 -278.63419) (xy 56.324754 -278.63419) (xy 56.310705 -278.634031)
			(xy 56.282721 -278.631488) (xy 56.268874 -278.62911) (xy 56.256428 -278.626824) (xy 56.232806 -278.63419)
			(xy 56.155844 -278.710644) (xy 56.148224 -278.734266) (xy 56.15051 -278.746712) (xy 56.152664 -278.759877)
			(xy 56.154956 -278.786458) (xy 56.155082 -278.799798) (xy 56.15456 -278.825053) (xy 56.146247 -278.874875)
			(xy 56.129846 -278.922649) (xy 56.105805 -278.967072) (xy 56.074781 -279.006932) (xy 56.037619 -279.041142)
			(xy 55.995333 -279.068768) (xy 55.949077 -279.089058) (xy 55.900112 -279.101458) (xy 55.849774 -279.105629)
			(xy 55.799436 -279.101458) (xy 55.750471 -279.089058) (xy 55.704215 -279.068768) (xy 55.661929 -279.041142)
			(xy 55.624767 -279.006932) (xy 55.593743 -278.967072) (xy 55.569702 -278.922649) (xy 55.553301 -278.874875)
			(xy 55.544988 -278.825053) (xy 55.544466 -278.799798) (xy 55.544575 -278.790821) (xy 55.545717 -278.772902)
			(xy 55.546752 -278.763984) (xy 55.546752 -278.762714) (xy 55.547406 -278.751108) (xy 55.53946 -278.729289)
			(xy 55.531512 -278.720804) (xy 55.472584 -278.66467) (xy 55.463591 -278.656921) (xy 55.440946 -278.649888)
			(xy 55.42915 -278.651208) (xy 55.428896 -278.651208) (xy 55.415345 -278.653344) (xy 55.388004 -278.65563)
			(xy 55.374286 -278.65578) (xy 55.360764 -278.655663) (xy 55.333806 -278.653504) (xy 55.320438 -278.651462)
			(xy 55.3085 -278.64943) (xy 55.285894 -278.656288) (xy 55.21833 -278.72055) (xy 55.210191 -278.729301)
			(xy 55.202243 -278.75181) (xy 55.20309 -278.76373) (xy 55.204074 -278.772714) (xy 55.205093 -278.79076)
			(xy 55.205122 -278.799798) (xy 55.2046 -278.825053) (xy 55.196287 -278.874875) (xy 55.179886 -278.922649)
			(xy 55.155845 -278.967072) (xy 55.124821 -279.006932) (xy 55.087659 -279.041142) (xy 55.045373 -279.068768)
			(xy 54.999117 -279.089058) (xy 54.950152 -279.101458) (xy 54.899814 -279.105629) (xy 54.849476 -279.101458)
			(xy 54.800511 -279.089058) (xy 54.754255 -279.068768) (xy 54.711969 -279.041142) (xy 54.674807 -279.006932)
			(xy 54.643783 -278.967072) (xy 54.619742 -278.922649) (xy 54.603341 -278.874875) (xy 54.595028 -278.825053)
			(xy 54.594506 -278.799798) (xy 54.594624 -278.786458) (xy 54.596911 -278.759876) (xy 54.599078 -278.746712)
			(xy 54.601364 -278.734266) (xy 54.593744 -278.710644) (xy 54.516782 -278.63419) (xy 54.49316 -278.626824)
			(xy 54.480714 -278.62911) (xy 54.466868 -278.631496) (xy 54.438884 -278.634038) (xy 54.424834 -278.63419)
			(xy 54.410785 -278.63403) (xy 54.382802 -278.631485) (xy 54.368954 -278.62911) (xy 54.356508 -278.626824)
			(xy 54.332886 -278.63419) (xy 54.255924 -278.710644) (xy 54.248304 -278.734266) (xy 54.25059 -278.746712)
			(xy 54.252744 -278.759877) (xy 54.255036 -278.786458) (xy 54.255162 -278.799798) (xy 54.25464 -278.825053)
			(xy 54.246327 -278.874875) (xy 54.229926 -278.922649) (xy 54.205885 -278.967072) (xy 54.174861 -279.006932)
			(xy 54.137699 -279.041142) (xy 54.095413 -279.068768) (xy 54.049157 -279.089058) (xy 54.000192 -279.101458)
			(xy 53.949854 -279.105629) (xy 53.899516 -279.101458) (xy 53.850551 -279.089058) (xy 53.804295 -279.068768)
			(xy 53.762009 -279.041142) (xy 53.724847 -279.006932) (xy 53.693823 -278.967072) (xy 53.669782 -278.922649)
			(xy 53.653381 -278.874875) (xy 53.645068 -278.825053) (xy 53.644546 -278.799798) (xy 53.644655 -278.790821)
			(xy 53.645797 -278.772902) (xy 53.646832 -278.763984) (xy 53.646832 -278.763476) (xy 53.648102 -278.751284)
			(xy 53.644292 -278.740362) (xy 53.642128 -278.734783) (xy 53.635582 -278.724769) (xy 53.631338 -278.72055)
			(xy 53.56352 -278.656034) (xy 53.540914 -278.649176) (xy 53.528976 -278.651208) (xy 53.515362 -278.653355)
			(xy 53.487894 -278.655644) (xy 53.474112 -278.65578) (xy 53.473604 -278.65578) (xy 53.460209 -278.655649)
			(xy 53.433505 -278.653491) (xy 53.420264 -278.651462) (xy 53.408326 -278.64943) (xy 53.38572 -278.656542)
			(xy 53.309774 -278.729186) (xy 53.301646 -278.751792) (xy 53.30317 -278.76373) (xy 53.304154 -278.772714)
			(xy 53.305173 -278.79076) (xy 53.305202 -278.799798) (xy 53.30468 -278.825053) (xy 53.296367 -278.874875)
			(xy 53.279966 -278.922649) (xy 53.255925 -278.967072) (xy 53.224901 -279.006932) (xy 53.187739 -279.041142)
			(xy 53.145453 -279.068768) (xy 53.099197 -279.089058) (xy 53.050232 -279.101458) (xy 52.999894 -279.105629)
			(xy 52.949556 -279.101458) (xy 52.900591 -279.089058) (xy 52.854335 -279.068768) (xy 52.812049 -279.041142)
			(xy 52.774887 -279.006932) (xy 52.743863 -278.967072) (xy 52.719822 -278.922649) (xy 52.703421 -278.874875)
			(xy 52.695108 -278.825053) (xy 52.694586 -278.799798) (xy 52.694704 -278.786458) (xy 52.696991 -278.759876)
			(xy 52.699158 -278.746712) (xy 52.701444 -278.734266) (xy 52.693824 -278.710644) (xy 52.616862 -278.63419)
			(xy 52.59324 -278.626824) (xy 52.580794 -278.62911) (xy 52.566948 -278.631495) (xy 52.538964 -278.634035)
			(xy 52.524914 -278.63419) (xy 52.510865 -278.634029) (xy 52.482882 -278.631483) (xy 52.469034 -278.62911)
			(xy 52.456588 -278.626824) (xy 52.432966 -278.63419) (xy 52.356004 -278.710644) (xy 52.348384 -278.734266)
			(xy 52.35067 -278.746712) (xy 52.352824 -278.759877) (xy 52.355116 -278.786458) (xy 52.355242 -278.799798)
			(xy 52.35472 -278.825053) (xy 52.346407 -278.874875) (xy 52.330006 -278.922649) (xy 52.305965 -278.967072)
			(xy 52.274941 -279.006932) (xy 52.237779 -279.041142) (xy 52.195493 -279.068768) (xy 52.149237 -279.089058)
			(xy 52.100272 -279.101458) (xy 52.049934 -279.105629) (xy 51.999596 -279.101458) (xy 51.950631 -279.089058)
			(xy 51.904375 -279.068768) (xy 51.862089 -279.041142) (xy 51.824927 -279.006932) (xy 51.793903 -278.967072)
			(xy 51.769862 -278.922649) (xy 51.753461 -278.874875) (xy 51.745148 -278.825053) (xy 51.744626 -278.799798)
			(xy 51.744735 -278.790821) (xy 51.745877 -278.772902) (xy 51.746912 -278.763984) (xy 51.746912 -278.763476)
			(xy 51.748182 -278.751284) (xy 51.744372 -278.740362) (xy 51.742207 -278.734783) (xy 51.73566 -278.724771)
			(xy 51.731418 -278.72055) (xy 51.6636 -278.656034) (xy 51.640994 -278.649176) (xy 51.629056 -278.651208)
			(xy 51.615442 -278.653354) (xy 51.587974 -278.655642) (xy 51.574192 -278.65578) (xy 51.573684 -278.65578)
			(xy 51.560289 -278.655648) (xy 51.533586 -278.653488) (xy 51.520344 -278.651462) (xy 51.508406 -278.64943)
			(xy 51.4858 -278.656542) (xy 51.409854 -278.729186) (xy 51.401726 -278.751792) (xy 51.40325 -278.76373)
			(xy 51.404234 -278.772714) (xy 51.405253 -278.79076) (xy 51.405282 -278.799798) (xy 51.40476 -278.825053)
			(xy 51.396447 -278.874875) (xy 51.380046 -278.922649) (xy 51.356005 -278.967072) (xy 51.324981 -279.006932)
			(xy 51.287819 -279.041142) (xy 51.245533 -279.068768) (xy 51.199277 -279.089058) (xy 51.150312 -279.101458)
			(xy 51.099974 -279.105629) (xy 51.049636 -279.101458) (xy 51.000671 -279.089058) (xy 50.954415 -279.068768)
			(xy 50.912129 -279.041142) (xy 50.874967 -279.006932) (xy 50.843943 -278.967072) (xy 50.819902 -278.922649)
			(xy 50.803501 -278.874875) (xy 50.795188 -278.825053) (xy 50.794666 -278.799798) (xy 50.794784 -278.786458)
			(xy 50.797071 -278.759876) (xy 50.799238 -278.746712) (xy 50.801524 -278.734266) (xy 50.793904 -278.710644)
			(xy 50.716942 -278.63419) (xy 50.69332 -278.626824) (xy 50.680874 -278.62911) (xy 50.667028 -278.631499)
			(xy 50.639044 -278.634046) (xy 50.624994 -278.63419) (xy 50.62474 -278.63419) (xy 50.610691 -278.63403)
			(xy 50.582708 -278.631486) (xy 50.56886 -278.62911) (xy 50.556626 -278.627609) (xy 50.533126 -278.634906)
			(xy 50.523902 -278.64308) (xy 50.45583 -278.71039) (xy 50.44821 -278.73452) (xy 50.450496 -278.746712)
			(xy 50.45265 -278.759877) (xy 50.454942 -278.786458) (xy 50.455068 -278.799798) (xy 50.454546 -278.825053)
			(xy 50.446233 -278.874875) (xy 50.429832 -278.922649) (xy 50.405791 -278.967072) (xy 50.374767 -279.006932)
			(xy 50.337605 -279.041142) (xy 50.295319 -279.068768) (xy 50.249063 -279.089058) (xy 50.200098 -279.101458)
			(xy 50.14976 -279.105629) (xy 50.099422 -279.101458) (xy 50.050457 -279.089058) (xy 50.004201 -279.068768)
			(xy 49.961915 -279.041142) (xy 49.924753 -279.006932) (xy 49.893729 -278.967072) (xy 49.869688 -278.922649)
			(xy 49.853287 -278.874875) (xy 49.844974 -278.825053) (xy 49.844452 -278.799798) (xy 49.844561 -278.790821)
			(xy 49.845703 -278.772902) (xy 49.846738 -278.763984) (xy 49.846738 -278.762714) (xy 49.847323 -278.751084)
			(xy 49.83924 -278.729272) (xy 49.831244 -278.720804) (xy 49.763426 -278.656034) (xy 49.74082 -278.649176)
			(xy 49.728882 -278.651208) (xy 49.715268 -278.653355) (xy 49.6878 -278.655645) (xy 49.674018 -278.65578)
			(xy 49.673764 -278.65578) (xy 49.660369 -278.655647) (xy 49.633666 -278.653486) (xy 49.620424 -278.651462)
			(xy 49.62017 -278.651462) (xy 49.608371 -278.650123) (xy 49.585726 -278.657162) (xy 49.576736 -278.664924)
			(xy 49.509426 -278.72944) (xy 49.501552 -278.751538) (xy 49.503076 -278.76373) (xy 49.50406 -278.772714)
			(xy 49.505079 -278.79076) (xy 49.505108 -278.799798) (xy 49.504586 -278.825053) (xy 49.496273 -278.874875)
			(xy 49.479872 -278.922649) (xy 49.455831 -278.967072) (xy 49.424807 -279.006932) (xy 49.387645 -279.041142)
			(xy 49.345359 -279.068768) (xy 49.299103 -279.089058) (xy 49.250138 -279.101458) (xy 49.1998 -279.105629)
			(xy 49.149462 -279.101458) (xy 49.100497 -279.089058) (xy 49.054241 -279.068768) (xy 49.011955 -279.041142)
			(xy 48.974793 -279.006932) (xy 48.943769 -278.967072) (xy 48.919728 -278.922649) (xy 48.903327 -278.874875)
			(xy 48.895014 -278.825053) (xy 48.894492 -278.799798) (xy 48.894667 -278.786002) (xy 48.897212 -278.758528)
			(xy 48.899572 -278.744934) (xy 48.901858 -278.732488) (xy 48.894492 -278.708866) (xy 48.817276 -278.631904)
			(xy 48.793654 -278.624538) (xy 48.781208 -278.626824) (xy 48.767236 -278.62923) (xy 48.738997 -278.631771)
			(xy 48.72482 -278.631904) (xy 48.710643 -278.631778) (xy 48.682403 -278.629239) (xy 48.668432 -278.626824)
			(xy 48.655986 -278.624538) (xy 48.632364 -278.631904) (xy 48.555148 -278.708866) (xy 48.547782 -278.732488)
			(xy 48.550068 -278.744934) (xy 48.552415 -278.758529) (xy 48.554959 -278.786003) (xy 48.555148 -278.799798)
			(xy 48.554678 -278.82379) (xy 48.547172 -278.871185) (xy 48.532345 -278.916822) (xy 48.510562 -278.959577)
			(xy 48.48236 -278.9984) (xy 48.448432 -279.032332) (xy 48.409613 -279.06054) (xy 48.36686 -279.082329)
			(xy 48.321226 -279.097162) (xy 48.273832 -279.104674) (xy 48.24984 -279.105106) (xy 48.249586 -279.105106)
			(xy 48.220887 -279.104452) (xy 48.164504 -279.093707) (xy 48.137572 -279.08377) (xy 48.128682 -279.080214)
			(xy 48.11903 -279.080214) (xy 48.109006 -279.080628) (xy 48.090481 -279.088294) (xy 48.076303 -279.102467)
			(xy 48.068632 -279.12099) (xy 48.06823 -279.131014) (xy 48.06823 -279.183338) (xy 48.070008 -279.196546)
			(xy 48.07077 -279.199594) (xy 48.075156 -279.218016) (xy 48.079866 -279.25559) (xy 48.080168 -279.274524)
			(xy 48.080168 -279.275032) (xy 48.079914 -279.284176) (xy 48.079914 -279.291542) (xy 48.079914 -279.295098)
			(xy 48.07966 -279.296876) (xy 48.07966 -279.297892) (xy 48.078412 -279.312102) (xy 48.073581 -279.340216)
			(xy 48.070008 -279.354026) (xy 48.06823 -279.36063) (xy 48.06823 -279.418542) (xy 48.068726 -279.428542)
			(xy 48.076394 -279.447014) (xy 48.090546 -279.461147) (xy 48.109029 -279.468789) (xy 48.11903 -279.469342)
			(xy 48.128682 -279.469342) (xy 48.137572 -279.465786) (xy 48.164509 -279.455869) (xy 48.22089 -279.445133)
			(xy 48.249586 -279.44445) (xy 48.24984 -279.44445) (xy 48.275097 -279.444975) (xy 48.32492 -279.453295)
			(xy 48.372695 -279.469702) (xy 48.417118 -279.493747) (xy 48.456978 -279.524776) (xy 48.491187 -279.561942)
			(xy 48.518813 -279.604232) (xy 48.539103 -279.650491) (xy 48.551502 -279.699459) (xy 48.555648 -279.749504)
			(xy 48.893996 -279.749504) (xy 48.897956 -279.70045) (xy 48.909733 -279.652666) (xy 48.929024 -279.60739)
			(xy 48.955327 -279.565794) (xy 48.987962 -279.528957) (xy 49.026083 -279.497832) (xy 49.068704 -279.473225)
			(xy 49.11472 -279.455773) (xy 49.162939 -279.445929) (xy 49.212114 -279.443948) (xy 49.260969 -279.44988)
			(xy 49.30824 -279.463572) (xy 49.352702 -279.48467) (xy 49.393205 -279.512626) (xy 49.428698 -279.546718)
			(xy 49.458263 -279.586062) (xy 49.481134 -279.629639) (xy 49.496718 -279.67632) (xy 49.504613 -279.724897)
			(xy 49.505108 -279.749504) (xy 49.505103 -279.749758) (xy 49.843956 -279.749758) (xy 49.847916 -279.700704)
			(xy 49.859693 -279.65292) (xy 49.878984 -279.607644) (xy 49.905287 -279.566048) (xy 49.937922 -279.529211)
			(xy 49.976043 -279.498086) (xy 50.018664 -279.473479) (xy 50.06468 -279.456027) (xy 50.112899 -279.446183)
			(xy 50.162074 -279.444202) (xy 50.210929 -279.450134) (xy 50.2582 -279.463826) (xy 50.302662 -279.484924)
			(xy 50.343165 -279.51288) (xy 50.378658 -279.546972) (xy 50.408223 -279.586316) (xy 50.431094 -279.629893)
			(xy 50.446678 -279.676574) (xy 50.454573 -279.725151) (xy 50.455063 -279.749504) (xy 50.79417 -279.749504)
			(xy 50.79813 -279.70045) (xy 50.809907 -279.652666) (xy 50.829198 -279.60739) (xy 50.855501 -279.565794)
			(xy 50.888136 -279.528957) (xy 50.926257 -279.497832) (xy 50.968878 -279.473225) (xy 51.014894 -279.455773)
			(xy 51.063113 -279.445929) (xy 51.112288 -279.443948) (xy 51.161143 -279.44988) (xy 51.208414 -279.463572)
			(xy 51.252876 -279.48467) (xy 51.293379 -279.512626) (xy 51.328872 -279.546718) (xy 51.358437 -279.586062)
			(xy 51.381308 -279.629639) (xy 51.396892 -279.67632) (xy 51.404787 -279.724897) (xy 51.405282 -279.749504)
			(xy 51.405277 -279.749758) (xy 51.74413 -279.749758) (xy 51.74809 -279.700704) (xy 51.759867 -279.65292)
			(xy 51.779158 -279.607644) (xy 51.805461 -279.566048) (xy 51.838096 -279.529211) (xy 51.876217 -279.498086)
			(xy 51.918838 -279.473479) (xy 51.964854 -279.456027) (xy 52.013073 -279.446183) (xy 52.062248 -279.444202)
			(xy 52.111103 -279.450134) (xy 52.158374 -279.463826) (xy 52.202836 -279.484924) (xy 52.243339 -279.51288)
			(xy 52.278832 -279.546972) (xy 52.308397 -279.586316) (xy 52.331268 -279.629893) (xy 52.346852 -279.676574)
			(xy 52.354747 -279.725151) (xy 52.355237 -279.749504) (xy 52.69409 -279.749504) (xy 52.69805 -279.70045)
			(xy 52.709827 -279.652666) (xy 52.729118 -279.60739) (xy 52.755421 -279.565794) (xy 52.788056 -279.528957)
			(xy 52.826177 -279.497832) (xy 52.868798 -279.473225) (xy 52.914814 -279.455773) (xy 52.963033 -279.445929)
			(xy 53.012208 -279.443948) (xy 53.061063 -279.44988) (xy 53.108334 -279.463572) (xy 53.152796 -279.48467)
			(xy 53.193299 -279.512626) (xy 53.228792 -279.546718) (xy 53.258357 -279.586062) (xy 53.281228 -279.629639)
			(xy 53.296812 -279.67632) (xy 53.304707 -279.724897) (xy 53.305202 -279.749504) (xy 53.305197 -279.749758)
			(xy 53.64405 -279.749758) (xy 53.64801 -279.700704) (xy 53.659787 -279.65292) (xy 53.679078 -279.607644)
			(xy 53.705381 -279.566048) (xy 53.738016 -279.529211) (xy 53.776137 -279.498086) (xy 53.818758 -279.473479)
			(xy 53.864774 -279.456027) (xy 53.912993 -279.446183) (xy 53.962168 -279.444202) (xy 54.011023 -279.450134)
			(xy 54.058294 -279.463826) (xy 54.102756 -279.484924) (xy 54.143259 -279.51288) (xy 54.178752 -279.546972)
			(xy 54.208317 -279.586316) (xy 54.231188 -279.629893) (xy 54.246772 -279.676574) (xy 54.254667 -279.725151)
			(xy 54.255157 -279.749504) (xy 54.59401 -279.749504) (xy 54.59797 -279.70045) (xy 54.609747 -279.652666)
			(xy 54.629038 -279.60739) (xy 54.655341 -279.565794) (xy 54.687976 -279.528957) (xy 54.726097 -279.497832)
			(xy 54.768718 -279.473225) (xy 54.814734 -279.455773) (xy 54.862953 -279.445929) (xy 54.912128 -279.443948)
			(xy 54.960983 -279.44988) (xy 55.008254 -279.463572) (xy 55.052716 -279.48467) (xy 55.093219 -279.512626)
			(xy 55.128712 -279.546718) (xy 55.158277 -279.586062) (xy 55.181148 -279.629639) (xy 55.196732 -279.67632)
			(xy 55.204627 -279.724897) (xy 55.205122 -279.749504) (xy 55.205117 -279.749758) (xy 55.54397 -279.749758)
			(xy 55.54793 -279.700704) (xy 55.559707 -279.65292) (xy 55.578998 -279.607644) (xy 55.605301 -279.566048)
			(xy 55.637936 -279.529211) (xy 55.676057 -279.498086) (xy 55.718678 -279.473479) (xy 55.764694 -279.456027)
			(xy 55.812913 -279.446183) (xy 55.862088 -279.444202) (xy 55.910943 -279.450134) (xy 55.958214 -279.463826)
			(xy 56.002676 -279.484924) (xy 56.043179 -279.51288) (xy 56.078672 -279.546972) (xy 56.108237 -279.586316)
			(xy 56.131108 -279.629893) (xy 56.146692 -279.676574) (xy 56.154587 -279.725151) (xy 56.155077 -279.749504)
			(xy 56.49393 -279.749504) (xy 56.49789 -279.70045) (xy 56.509667 -279.652666) (xy 56.528958 -279.60739)
			(xy 56.555261 -279.565794) (xy 56.587896 -279.528957) (xy 56.626017 -279.497832) (xy 56.668638 -279.473225)
			(xy 56.714654 -279.455773) (xy 56.762873 -279.445929) (xy 56.812048 -279.443948) (xy 56.860903 -279.44988)
			(xy 56.908174 -279.463572) (xy 56.952636 -279.48467) (xy 56.993139 -279.512626) (xy 57.028632 -279.546718)
			(xy 57.058197 -279.586062) (xy 57.081068 -279.629639) (xy 57.096652 -279.67632) (xy 57.104547 -279.724897)
			(xy 57.105042 -279.749504) (xy 57.105037 -279.749758) (xy 57.444144 -279.749758) (xy 57.448104 -279.700704)
			(xy 57.459881 -279.65292) (xy 57.479172 -279.607644) (xy 57.505475 -279.566048) (xy 57.53811 -279.529211)
			(xy 57.576231 -279.498086) (xy 57.618852 -279.473479) (xy 57.664868 -279.456027) (xy 57.713087 -279.446183)
			(xy 57.762262 -279.444202) (xy 57.811117 -279.450134) (xy 57.858388 -279.463826) (xy 57.90285 -279.484924)
			(xy 57.943353 -279.51288) (xy 57.978846 -279.546972) (xy 58.008411 -279.586316) (xy 58.031282 -279.629893)
			(xy 58.046866 -279.676574) (xy 58.054761 -279.725151) (xy 58.055251 -279.749504) (xy 58.394104 -279.749504)
			(xy 58.398064 -279.70045) (xy 58.409841 -279.652666) (xy 58.429132 -279.60739) (xy 58.455435 -279.565794)
			(xy 58.48807 -279.528957) (xy 58.526191 -279.497832) (xy 58.568812 -279.473225) (xy 58.614828 -279.455773)
			(xy 58.663047 -279.445929) (xy 58.712222 -279.443948) (xy 58.761077 -279.44988) (xy 58.808348 -279.463572)
			(xy 58.85281 -279.48467) (xy 58.893313 -279.512626) (xy 58.928806 -279.546718) (xy 58.958371 -279.586062)
			(xy 58.981242 -279.629639) (xy 58.996826 -279.67632) (xy 59.004721 -279.724897) (xy 59.005216 -279.749504)
			(xy 59.005211 -279.749758) (xy 59.344064 -279.749758) (xy 59.348024 -279.700704) (xy 59.359801 -279.65292)
			(xy 59.379092 -279.607644) (xy 59.405395 -279.566048) (xy 59.43803 -279.529211) (xy 59.476151 -279.498086)
			(xy 59.518772 -279.473479) (xy 59.564788 -279.456027) (xy 59.613007 -279.446183) (xy 59.662182 -279.444202)
			(xy 59.711037 -279.450134) (xy 59.758308 -279.463826) (xy 59.80277 -279.484924) (xy 59.843273 -279.51288)
			(xy 59.878766 -279.546972) (xy 59.908331 -279.586316) (xy 59.931202 -279.629893) (xy 59.946786 -279.676574)
			(xy 59.954681 -279.725151) (xy 59.955171 -279.749504) (xy 60.294024 -279.749504) (xy 60.297984 -279.70045)
			(xy 60.309761 -279.652666) (xy 60.329052 -279.60739) (xy 60.355355 -279.565794) (xy 60.38799 -279.528957)
			(xy 60.426111 -279.497832) (xy 60.468732 -279.473225) (xy 60.514748 -279.455773) (xy 60.562967 -279.445929)
			(xy 60.612142 -279.443948) (xy 60.660997 -279.44988) (xy 60.708268 -279.463572) (xy 60.75273 -279.48467)
			(xy 60.793233 -279.512626) (xy 60.828726 -279.546718) (xy 60.858291 -279.586062) (xy 60.881162 -279.629639)
			(xy 60.896746 -279.67632) (xy 60.904641 -279.724897) (xy 60.905136 -279.749504) (xy 60.905131 -279.749758)
			(xy 61.243984 -279.749758) (xy 61.247944 -279.700704) (xy 61.259721 -279.65292) (xy 61.279012 -279.607644)
			(xy 61.305315 -279.566048) (xy 61.33795 -279.529211) (xy 61.376071 -279.498086) (xy 61.418692 -279.473479)
			(xy 61.464708 -279.456027) (xy 61.512927 -279.446183) (xy 61.562102 -279.444202) (xy 61.610957 -279.450134)
			(xy 61.658228 -279.463826) (xy 61.70269 -279.484924) (xy 61.743193 -279.51288) (xy 61.778686 -279.546972)
			(xy 61.808251 -279.586316) (xy 61.831122 -279.629893) (xy 61.846706 -279.676574) (xy 61.854601 -279.725151)
			(xy 61.855091 -279.749504) (xy 62.193944 -279.749504) (xy 62.197904 -279.70045) (xy 62.209681 -279.652666)
			(xy 62.228972 -279.60739) (xy 62.255275 -279.565794) (xy 62.28791 -279.528957) (xy 62.326031 -279.497832)
			(xy 62.368652 -279.473225) (xy 62.414668 -279.455773) (xy 62.462887 -279.445929) (xy 62.512062 -279.443948)
			(xy 62.560917 -279.44988) (xy 62.608188 -279.463572) (xy 62.65265 -279.48467) (xy 62.693153 -279.512626)
			(xy 62.728646 -279.546718) (xy 62.758211 -279.586062) (xy 62.781082 -279.629639) (xy 62.796666 -279.67632)
			(xy 62.804561 -279.724897) (xy 62.805056 -279.749504) (xy 62.805051 -279.749758) (xy 63.144158 -279.749758)
			(xy 63.148118 -279.700704) (xy 63.159895 -279.65292) (xy 63.179186 -279.607644) (xy 63.205489 -279.566048)
			(xy 63.238124 -279.529211) (xy 63.276245 -279.498086) (xy 63.318866 -279.473479) (xy 63.364882 -279.456027)
			(xy 63.413101 -279.446183) (xy 63.462276 -279.444202) (xy 63.511131 -279.450134) (xy 63.558402 -279.463826)
			(xy 63.602864 -279.484924) (xy 63.643367 -279.51288) (xy 63.67886 -279.546972) (xy 63.708425 -279.586316)
			(xy 63.731296 -279.629893) (xy 63.74688 -279.676574) (xy 63.754775 -279.725151) (xy 63.755265 -279.749504)
			(xy 64.094118 -279.749504) (xy 64.098078 -279.70045) (xy 64.109855 -279.652666) (xy 64.129146 -279.60739)
			(xy 64.155449 -279.565794) (xy 64.188084 -279.528957) (xy 64.226205 -279.497832) (xy 64.268826 -279.473225)
			(xy 64.314842 -279.455773) (xy 64.363061 -279.445929) (xy 64.412236 -279.443948) (xy 64.461091 -279.44988)
			(xy 64.508362 -279.463572) (xy 64.552824 -279.48467) (xy 64.593327 -279.512626) (xy 64.62882 -279.546718)
			(xy 64.658385 -279.586062) (xy 64.681256 -279.629639) (xy 64.69684 -279.67632) (xy 64.704735 -279.724897)
			(xy 64.70523 -279.749504) (xy 64.705225 -279.749758) (xy 65.044078 -279.749758) (xy 65.048038 -279.700704)
			(xy 65.059815 -279.65292) (xy 65.079106 -279.607644) (xy 65.105409 -279.566048) (xy 65.138044 -279.529211)
			(xy 65.176165 -279.498086) (xy 65.218786 -279.473479) (xy 65.264802 -279.456027) (xy 65.313021 -279.446183)
			(xy 65.362196 -279.444202) (xy 65.411051 -279.450134) (xy 65.458322 -279.463826) (xy 65.502784 -279.484924)
			(xy 65.543287 -279.51288) (xy 65.57878 -279.546972) (xy 65.608345 -279.586316) (xy 65.631216 -279.629893)
			(xy 65.6468 -279.676574) (xy 65.654695 -279.725151) (xy 65.655185 -279.749504) (xy 65.994038 -279.749504)
			(xy 65.997998 -279.70045) (xy 66.009775 -279.652666) (xy 66.029066 -279.60739) (xy 66.055369 -279.565794)
			(xy 66.088004 -279.528957) (xy 66.126125 -279.497832) (xy 66.168746 -279.473225) (xy 66.214762 -279.455773)
			(xy 66.262981 -279.445929) (xy 66.312156 -279.443948) (xy 66.361011 -279.44988) (xy 66.408282 -279.463572)
			(xy 66.452744 -279.48467) (xy 66.493247 -279.512626) (xy 66.52874 -279.546718) (xy 66.558305 -279.586062)
			(xy 66.581176 -279.629639) (xy 66.59676 -279.67632) (xy 66.604655 -279.724897) (xy 66.60515 -279.749504)
			(xy 66.605145 -279.749758) (xy 66.943998 -279.749758) (xy 66.947958 -279.700704) (xy 66.959735 -279.65292)
			(xy 66.979026 -279.607644) (xy 67.005329 -279.566048) (xy 67.037964 -279.529211) (xy 67.076085 -279.498086)
			(xy 67.118706 -279.473479) (xy 67.164722 -279.456027) (xy 67.212941 -279.446183) (xy 67.262116 -279.444202)
			(xy 67.310971 -279.450134) (xy 67.358242 -279.463826) (xy 67.402704 -279.484924) (xy 67.443207 -279.51288)
			(xy 67.4787 -279.546972) (xy 67.508265 -279.586316) (xy 67.531136 -279.629893) (xy 67.54672 -279.676574)
			(xy 67.554615 -279.725151) (xy 67.555105 -279.749504) (xy 67.893958 -279.749504) (xy 67.897918 -279.70045)
			(xy 67.909695 -279.652666) (xy 67.928986 -279.60739) (xy 67.955289 -279.565794) (xy 67.987924 -279.528957)
			(xy 68.026045 -279.497832) (xy 68.068666 -279.473225) (xy 68.114682 -279.455773) (xy 68.162901 -279.445929)
			(xy 68.212076 -279.443948) (xy 68.260931 -279.44988) (xy 68.308202 -279.463572) (xy 68.352664 -279.48467)
			(xy 68.393167 -279.512626) (xy 68.42866 -279.546718) (xy 68.458225 -279.586062) (xy 68.481096 -279.629639)
			(xy 68.49668 -279.67632) (xy 68.504575 -279.724897) (xy 68.50507 -279.749504) (xy 68.505065 -279.749758)
			(xy 68.844172 -279.749758) (xy 68.848132 -279.700704) (xy 68.859909 -279.65292) (xy 68.8792 -279.607644)
			(xy 68.905503 -279.566048) (xy 68.938138 -279.529211) (xy 68.976259 -279.498086) (xy 69.01888 -279.473479)
			(xy 69.064896 -279.456027) (xy 69.113115 -279.446183) (xy 69.16229 -279.444202) (xy 69.211145 -279.450134)
			(xy 69.258416 -279.463826) (xy 69.302878 -279.484924) (xy 69.343381 -279.51288) (xy 69.378874 -279.546972)
			(xy 69.408439 -279.586316) (xy 69.43131 -279.629893) (xy 69.446894 -279.676574) (xy 69.454789 -279.725151)
			(xy 69.455279 -279.749504) (xy 69.794132 -279.749504) (xy 69.798092 -279.70045) (xy 69.809869 -279.652666)
			(xy 69.82916 -279.60739) (xy 69.855463 -279.565794) (xy 69.888098 -279.528957) (xy 69.926219 -279.497832)
			(xy 69.96884 -279.473225) (xy 70.014856 -279.455773) (xy 70.063075 -279.445929) (xy 70.11225 -279.443948)
			(xy 70.161105 -279.44988) (xy 70.208376 -279.463572) (xy 70.252838 -279.48467) (xy 70.293341 -279.512626)
			(xy 70.328834 -279.546718) (xy 70.358399 -279.586062) (xy 70.38127 -279.629639) (xy 70.396854 -279.67632)
			(xy 70.404749 -279.724897) (xy 70.405244 -279.749504) (xy 70.405239 -279.749758) (xy 70.744092 -279.749758)
			(xy 70.748052 -279.700704) (xy 70.759829 -279.65292) (xy 70.77912 -279.607644) (xy 70.805423 -279.566048)
			(xy 70.838058 -279.529211) (xy 70.876179 -279.498086) (xy 70.9188 -279.473479) (xy 70.964816 -279.456027)
			(xy 71.013035 -279.446183) (xy 71.06221 -279.444202) (xy 71.111065 -279.450134) (xy 71.158336 -279.463826)
			(xy 71.202798 -279.484924) (xy 71.243301 -279.51288) (xy 71.278794 -279.546972) (xy 71.308359 -279.586316)
			(xy 71.33123 -279.629893) (xy 71.346814 -279.676574) (xy 71.354709 -279.725151) (xy 71.355199 -279.749504)
			(xy 71.694052 -279.749504) (xy 71.698012 -279.70045) (xy 71.709789 -279.652666) (xy 71.72908 -279.60739)
			(xy 71.755383 -279.565794) (xy 71.788018 -279.528957) (xy 71.826139 -279.497832) (xy 71.86876 -279.473225)
			(xy 71.914776 -279.455773) (xy 71.962995 -279.445929) (xy 72.01217 -279.443948) (xy 72.061025 -279.44988)
			(xy 72.108296 -279.463572) (xy 72.152758 -279.48467) (xy 72.193261 -279.512626) (xy 72.228754 -279.546718)
			(xy 72.258319 -279.586062) (xy 72.28119 -279.629639) (xy 72.296774 -279.67632) (xy 72.304669 -279.724897)
			(xy 72.305164 -279.749504) (xy 72.305159 -279.749758) (xy 72.644012 -279.749758) (xy 72.647972 -279.700704)
			(xy 72.659749 -279.65292) (xy 72.67904 -279.607644) (xy 72.705343 -279.566048) (xy 72.737978 -279.529211)
			(xy 72.776099 -279.498086) (xy 72.81872 -279.473479) (xy 72.864736 -279.456027) (xy 72.912955 -279.446183)
			(xy 72.96213 -279.444202) (xy 73.010985 -279.450134) (xy 73.058256 -279.463826) (xy 73.102718 -279.484924)
			(xy 73.143221 -279.51288) (xy 73.178714 -279.546972) (xy 73.208279 -279.586316) (xy 73.23115 -279.629893)
			(xy 73.246734 -279.676574) (xy 73.254629 -279.725151) (xy 73.255119 -279.749504) (xy 73.593972 -279.749504)
			(xy 73.597932 -279.70045) (xy 73.609709 -279.652666) (xy 73.629 -279.60739) (xy 73.655303 -279.565794)
			(xy 73.687938 -279.528957) (xy 73.726059 -279.497832) (xy 73.76868 -279.473225) (xy 73.814696 -279.455773)
			(xy 73.862915 -279.445929) (xy 73.91209 -279.443948) (xy 73.960945 -279.44988) (xy 74.008216 -279.463572)
			(xy 74.052678 -279.48467) (xy 74.093181 -279.512626) (xy 74.128674 -279.546718) (xy 74.158239 -279.586062)
			(xy 74.18111 -279.629639) (xy 74.196694 -279.67632) (xy 74.204589 -279.724897) (xy 74.205084 -279.749504)
			(xy 74.205079 -279.749758) (xy 74.543932 -279.749758) (xy 74.547892 -279.700704) (xy 74.559669 -279.65292)
			(xy 74.57896 -279.607644) (xy 74.605263 -279.566048) (xy 74.637898 -279.529211) (xy 74.676019 -279.498086)
			(xy 74.71864 -279.473479) (xy 74.764656 -279.456027) (xy 74.812875 -279.446183) (xy 74.86205 -279.444202)
			(xy 74.910905 -279.450134) (xy 74.958176 -279.463826) (xy 75.002638 -279.484924) (xy 75.043141 -279.51288)
			(xy 75.078634 -279.546972) (xy 75.108199 -279.586316) (xy 75.13107 -279.629893) (xy 75.146654 -279.676574)
			(xy 75.154549 -279.725151) (xy 75.155039 -279.749504) (xy 75.494146 -279.749504) (xy 75.498106 -279.70045)
			(xy 75.509883 -279.652666) (xy 75.529174 -279.60739) (xy 75.555477 -279.565794) (xy 75.588112 -279.528957)
			(xy 75.626233 -279.497832) (xy 75.668854 -279.473225) (xy 75.71487 -279.455773) (xy 75.763089 -279.445929)
			(xy 75.812264 -279.443948) (xy 75.861119 -279.44988) (xy 75.90839 -279.463572) (xy 75.952852 -279.48467)
			(xy 75.993355 -279.512626) (xy 76.028848 -279.546718) (xy 76.058413 -279.586062) (xy 76.081284 -279.629639)
			(xy 76.096868 -279.67632) (xy 76.104763 -279.724897) (xy 76.105258 -279.749504) (xy 76.105253 -279.749758)
			(xy 76.444106 -279.749758) (xy 76.448066 -279.700704) (xy 76.459843 -279.65292) (xy 76.479134 -279.607644)
			(xy 76.505437 -279.566048) (xy 76.538072 -279.529211) (xy 76.576193 -279.498086) (xy 76.618814 -279.473479)
			(xy 76.66483 -279.456027) (xy 76.713049 -279.446183) (xy 76.762224 -279.444202) (xy 76.811079 -279.450134)
			(xy 76.85835 -279.463826) (xy 76.902812 -279.484924) (xy 76.943315 -279.51288) (xy 76.978808 -279.546972)
			(xy 77.008373 -279.586316) (xy 77.031244 -279.629893) (xy 77.046828 -279.676574) (xy 77.054723 -279.725151)
			(xy 77.055213 -279.749504) (xy 77.394066 -279.749504) (xy 77.398026 -279.70045) (xy 77.409803 -279.652666)
			(xy 77.429094 -279.60739) (xy 77.455397 -279.565794) (xy 77.488032 -279.528957) (xy 77.526153 -279.497832)
			(xy 77.568774 -279.473225) (xy 77.61479 -279.455773) (xy 77.663009 -279.445929) (xy 77.712184 -279.443948)
			(xy 77.761039 -279.44988) (xy 77.80831 -279.463572) (xy 77.852772 -279.48467) (xy 77.893275 -279.512626)
			(xy 77.928768 -279.546718) (xy 77.958333 -279.586062) (xy 77.981204 -279.629639) (xy 77.996788 -279.67632)
			(xy 78.004683 -279.724897) (xy 78.005178 -279.749504) (xy 78.005173 -279.749758) (xy 78.344026 -279.749758)
			(xy 78.347986 -279.700704) (xy 78.359763 -279.65292) (xy 78.379054 -279.607644) (xy 78.405357 -279.566048)
			(xy 78.437992 -279.529211) (xy 78.476113 -279.498086) (xy 78.518734 -279.473479) (xy 78.56475 -279.456027)
			(xy 78.612969 -279.446183) (xy 78.662144 -279.444202) (xy 78.710999 -279.450134) (xy 78.75827 -279.463826)
			(xy 78.802732 -279.484924) (xy 78.843235 -279.51288) (xy 78.878728 -279.546972) (xy 78.908293 -279.586316)
			(xy 78.931164 -279.629893) (xy 78.946748 -279.676574) (xy 78.954643 -279.725151) (xy 78.955138 -279.749758)
			(xy 79.293986 -279.749758) (xy 79.297946 -279.700704) (xy 79.309723 -279.65292) (xy 79.329014 -279.607644)
			(xy 79.355317 -279.566048) (xy 79.387952 -279.529211) (xy 79.426073 -279.498086) (xy 79.468694 -279.473479)
			(xy 79.51471 -279.456027) (xy 79.562929 -279.446183) (xy 79.612104 -279.444202) (xy 79.660959 -279.450134)
			(xy 79.70823 -279.463826) (xy 79.752692 -279.484924) (xy 79.793195 -279.51288) (xy 79.828688 -279.546972)
			(xy 79.858253 -279.586316) (xy 79.881124 -279.629893) (xy 79.896708 -279.676574) (xy 79.904603 -279.725151)
			(xy 79.905098 -279.749758) (xy 80.243946 -279.749758) (xy 80.247906 -279.700704) (xy 80.259683 -279.65292)
			(xy 80.278974 -279.607644) (xy 80.305277 -279.566048) (xy 80.337912 -279.529211) (xy 80.376033 -279.498086)
			(xy 80.418654 -279.473479) (xy 80.46467 -279.456027) (xy 80.512889 -279.446183) (xy 80.562064 -279.444202)
			(xy 80.610919 -279.450134) (xy 80.65819 -279.463826) (xy 80.702652 -279.484924) (xy 80.743155 -279.51288)
			(xy 80.778648 -279.546972) (xy 80.808213 -279.586316) (xy 80.831084 -279.629893) (xy 80.846668 -279.676574)
			(xy 80.854563 -279.725151) (xy 80.855058 -279.749758) (xy 81.19416 -279.749758) (xy 81.19812 -279.700704)
			(xy 81.209897 -279.65292) (xy 81.229188 -279.607644) (xy 81.255491 -279.566048) (xy 81.288126 -279.529211)
			(xy 81.326247 -279.498086) (xy 81.368868 -279.473479) (xy 81.414884 -279.456027) (xy 81.463103 -279.446183)
			(xy 81.512278 -279.444202) (xy 81.561133 -279.450134) (xy 81.608404 -279.463826) (xy 81.652866 -279.484924)
			(xy 81.693369 -279.51288) (xy 81.728862 -279.546972) (xy 81.758427 -279.586316) (xy 81.781298 -279.629893)
			(xy 81.796882 -279.676574) (xy 81.804777 -279.725151) (xy 81.805272 -279.749758) (xy 82.14412 -279.749758)
			(xy 82.14808 -279.700704) (xy 82.159857 -279.65292) (xy 82.179148 -279.607644) (xy 82.205451 -279.566048)
			(xy 82.238086 -279.529211) (xy 82.276207 -279.498086) (xy 82.318828 -279.473479) (xy 82.364844 -279.456027)
			(xy 82.413063 -279.446183) (xy 82.462238 -279.444202) (xy 82.511093 -279.450134) (xy 82.558364 -279.463826)
			(xy 82.602826 -279.484924) (xy 82.643329 -279.51288) (xy 82.678822 -279.546972) (xy 82.708387 -279.586316)
			(xy 82.731258 -279.629893) (xy 82.746842 -279.676574) (xy 82.754737 -279.725151) (xy 82.755232 -279.749758)
			(xy 82.755227 -279.750012) (xy 83.094334 -279.750012) (xy 83.098294 -279.700958) (xy 83.110071 -279.653174)
			(xy 83.129362 -279.607898) (xy 83.155665 -279.566302) (xy 83.1883 -279.529465) (xy 83.226421 -279.49834)
			(xy 83.269042 -279.473733) (xy 83.315058 -279.456281) (xy 83.363277 -279.446437) (xy 83.412452 -279.444456)
			(xy 83.461307 -279.450388) (xy 83.508578 -279.46408) (xy 83.55304 -279.485178) (xy 83.593543 -279.513134)
			(xy 83.629036 -279.547226) (xy 83.658601 -279.58657) (xy 83.681472 -279.630147) (xy 83.697056 -279.676828)
			(xy 83.704951 -279.725405) (xy 83.705446 -279.750012) (xy 83.704951 -279.774619) (xy 83.697056 -279.823196)
			(xy 83.681472 -279.869877) (xy 83.658601 -279.913454) (xy 83.629036 -279.952798) (xy 83.593543 -279.98689)
			(xy 83.55304 -280.014846) (xy 83.508578 -280.035944) (xy 83.461307 -280.049636) (xy 83.412452 -280.055568)
			(xy 83.363277 -280.053587) (xy 83.315058 -280.043743) (xy 83.269042 -280.026291) (xy 83.226421 -280.001684)
			(xy 83.1883 -279.970559) (xy 83.155665 -279.933722) (xy 83.129362 -279.892126) (xy 83.110071 -279.84685)
			(xy 83.098294 -279.799066) (xy 83.094334 -279.750012) (xy 82.755227 -279.750012) (xy 82.754737 -279.774365)
			(xy 82.746842 -279.822942) (xy 82.731258 -279.869623) (xy 82.708387 -279.9132) (xy 82.678822 -279.952544)
			(xy 82.643329 -279.986636) (xy 82.602826 -280.014592) (xy 82.558364 -280.03569) (xy 82.511093 -280.049382)
			(xy 82.462238 -280.055314) (xy 82.413063 -280.053333) (xy 82.364844 -280.043489) (xy 82.318828 -280.026037)
			(xy 82.276207 -280.00143) (xy 82.238086 -279.970305) (xy 82.205451 -279.933468) (xy 82.179148 -279.891872)
			(xy 82.159857 -279.846596) (xy 82.14808 -279.798812) (xy 82.14412 -279.749758) (xy 81.805272 -279.749758)
			(xy 81.804777 -279.774365) (xy 81.796882 -279.822942) (xy 81.781298 -279.869623) (xy 81.758427 -279.9132)
			(xy 81.728862 -279.952544) (xy 81.693369 -279.986636) (xy 81.652866 -280.014592) (xy 81.608404 -280.03569)
			(xy 81.561133 -280.049382) (xy 81.512278 -280.055314) (xy 81.463103 -280.053333) (xy 81.414884 -280.043489)
			(xy 81.368868 -280.026037) (xy 81.326247 -280.00143) (xy 81.288126 -279.970305) (xy 81.255491 -279.933468)
			(xy 81.229188 -279.891872) (xy 81.209897 -279.846596) (xy 81.19812 -279.798812) (xy 81.19416 -279.749758)
			(xy 80.855058 -279.749758) (xy 80.854563 -279.774365) (xy 80.846668 -279.822942) (xy 80.831084 -279.869623)
			(xy 80.808213 -279.9132) (xy 80.778648 -279.952544) (xy 80.743155 -279.986636) (xy 80.702652 -280.014592)
			(xy 80.65819 -280.03569) (xy 80.610919 -280.049382) (xy 80.562064 -280.055314) (xy 80.512889 -280.053333)
			(xy 80.46467 -280.043489) (xy 80.418654 -280.026037) (xy 80.376033 -280.00143) (xy 80.337912 -279.970305)
			(xy 80.305277 -279.933468) (xy 80.278974 -279.891872) (xy 80.259683 -279.846596) (xy 80.247906 -279.798812)
			(xy 80.243946 -279.749758) (xy 79.905098 -279.749758) (xy 79.904603 -279.774365) (xy 79.896708 -279.822942)
			(xy 79.881124 -279.869623) (xy 79.858253 -279.9132) (xy 79.828688 -279.952544) (xy 79.793195 -279.986636)
			(xy 79.752692 -280.014592) (xy 79.70823 -280.03569) (xy 79.660959 -280.049382) (xy 79.612104 -280.055314)
			(xy 79.562929 -280.053333) (xy 79.51471 -280.043489) (xy 79.468694 -280.026037) (xy 79.426073 -280.00143)
			(xy 79.387952 -279.970305) (xy 79.355317 -279.933468) (xy 79.329014 -279.891872) (xy 79.309723 -279.846596)
			(xy 79.297946 -279.798812) (xy 79.293986 -279.749758) (xy 78.955138 -279.749758) (xy 78.954643 -279.774365)
			(xy 78.946748 -279.822942) (xy 78.931164 -279.869623) (xy 78.908293 -279.9132) (xy 78.878728 -279.952544)
			(xy 78.843235 -279.986636) (xy 78.802732 -280.014592) (xy 78.75827 -280.03569) (xy 78.710999 -280.049382)
			(xy 78.662144 -280.055314) (xy 78.612969 -280.053333) (xy 78.56475 -280.043489) (xy 78.518734 -280.026037)
			(xy 78.476113 -280.00143) (xy 78.437992 -279.970305) (xy 78.405357 -279.933468) (xy 78.379054 -279.891872)
			(xy 78.359763 -279.846596) (xy 78.347986 -279.798812) (xy 78.344026 -279.749758) (xy 78.005173 -279.749758)
			(xy 78.004683 -279.774111) (xy 77.996788 -279.822688) (xy 77.981204 -279.869369) (xy 77.958333 -279.912946)
			(xy 77.928768 -279.95229) (xy 77.893275 -279.986382) (xy 77.852772 -280.014338) (xy 77.80831 -280.035436)
			(xy 77.761039 -280.049128) (xy 77.712184 -280.05506) (xy 77.663009 -280.053079) (xy 77.61479 -280.043235)
			(xy 77.568774 -280.025783) (xy 77.526153 -280.001176) (xy 77.488032 -279.970051) (xy 77.455397 -279.933214)
			(xy 77.429094 -279.891618) (xy 77.409803 -279.846342) (xy 77.398026 -279.798558) (xy 77.394066 -279.749504)
			(xy 77.055213 -279.749504) (xy 77.055218 -279.749758) (xy 77.054723 -279.774365) (xy 77.046828 -279.822942)
			(xy 77.031244 -279.869623) (xy 77.008373 -279.9132) (xy 76.978808 -279.952544) (xy 76.943315 -279.986636)
			(xy 76.902812 -280.014592) (xy 76.85835 -280.03569) (xy 76.811079 -280.049382) (xy 76.762224 -280.055314)
			(xy 76.713049 -280.053333) (xy 76.66483 -280.043489) (xy 76.618814 -280.026037) (xy 76.576193 -280.00143)
			(xy 76.538072 -279.970305) (xy 76.505437 -279.933468) (xy 76.479134 -279.891872) (xy 76.459843 -279.846596)
			(xy 76.448066 -279.798812) (xy 76.444106 -279.749758) (xy 76.105253 -279.749758) (xy 76.104763 -279.774111)
			(xy 76.096868 -279.822688) (xy 76.081284 -279.869369) (xy 76.058413 -279.912946) (xy 76.028848 -279.95229)
			(xy 75.993355 -279.986382) (xy 75.952852 -280.014338) (xy 75.90839 -280.035436) (xy 75.861119 -280.049128)
			(xy 75.812264 -280.05506) (xy 75.763089 -280.053079) (xy 75.71487 -280.043235) (xy 75.668854 -280.025783)
			(xy 75.626233 -280.001176) (xy 75.588112 -279.970051) (xy 75.555477 -279.933214) (xy 75.529174 -279.891618)
			(xy 75.509883 -279.846342) (xy 75.498106 -279.798558) (xy 75.494146 -279.749504) (xy 75.155039 -279.749504)
			(xy 75.155044 -279.749758) (xy 75.154549 -279.774365) (xy 75.146654 -279.822942) (xy 75.13107 -279.869623)
			(xy 75.108199 -279.9132) (xy 75.078634 -279.952544) (xy 75.043141 -279.986636) (xy 75.002638 -280.014592)
			(xy 74.958176 -280.03569) (xy 74.910905 -280.049382) (xy 74.86205 -280.055314) (xy 74.812875 -280.053333)
			(xy 74.764656 -280.043489) (xy 74.71864 -280.026037) (xy 74.676019 -280.00143) (xy 74.637898 -279.970305)
			(xy 74.605263 -279.933468) (xy 74.57896 -279.891872) (xy 74.559669 -279.846596) (xy 74.547892 -279.798812)
			(xy 74.543932 -279.749758) (xy 74.205079 -279.749758) (xy 74.204589 -279.774111) (xy 74.196694 -279.822688)
			(xy 74.18111 -279.869369) (xy 74.158239 -279.912946) (xy 74.128674 -279.95229) (xy 74.093181 -279.986382)
			(xy 74.052678 -280.014338) (xy 74.008216 -280.035436) (xy 73.960945 -280.049128) (xy 73.91209 -280.05506)
			(xy 73.862915 -280.053079) (xy 73.814696 -280.043235) (xy 73.76868 -280.025783) (xy 73.726059 -280.001176)
			(xy 73.687938 -279.970051) (xy 73.655303 -279.933214) (xy 73.629 -279.891618) (xy 73.609709 -279.846342)
			(xy 73.597932 -279.798558) (xy 73.593972 -279.749504) (xy 73.255119 -279.749504) (xy 73.255124 -279.749758)
			(xy 73.254629 -279.774365) (xy 73.246734 -279.822942) (xy 73.23115 -279.869623) (xy 73.208279 -279.9132)
			(xy 73.178714 -279.952544) (xy 73.143221 -279.986636) (xy 73.102718 -280.014592) (xy 73.058256 -280.03569)
			(xy 73.010985 -280.049382) (xy 72.96213 -280.055314) (xy 72.912955 -280.053333) (xy 72.864736 -280.043489)
			(xy 72.81872 -280.026037) (xy 72.776099 -280.00143) (xy 72.737978 -279.970305) (xy 72.705343 -279.933468)
			(xy 72.67904 -279.891872) (xy 72.659749 -279.846596) (xy 72.647972 -279.798812) (xy 72.644012 -279.749758)
			(xy 72.305159 -279.749758) (xy 72.304669 -279.774111) (xy 72.296774 -279.822688) (xy 72.28119 -279.869369)
			(xy 72.258319 -279.912946) (xy 72.228754 -279.95229) (xy 72.193261 -279.986382) (xy 72.152758 -280.014338)
			(xy 72.108296 -280.035436) (xy 72.061025 -280.049128) (xy 72.01217 -280.05506) (xy 71.962995 -280.053079)
			(xy 71.914776 -280.043235) (xy 71.86876 -280.025783) (xy 71.826139 -280.001176) (xy 71.788018 -279.970051)
			(xy 71.755383 -279.933214) (xy 71.72908 -279.891618) (xy 71.709789 -279.846342) (xy 71.698012 -279.798558)
			(xy 71.694052 -279.749504) (xy 71.355199 -279.749504) (xy 71.355204 -279.749758) (xy 71.354709 -279.774365)
			(xy 71.346814 -279.822942) (xy 71.33123 -279.869623) (xy 71.308359 -279.9132) (xy 71.278794 -279.952544)
			(xy 71.243301 -279.986636) (xy 71.202798 -280.014592) (xy 71.158336 -280.03569) (xy 71.111065 -280.049382)
			(xy 71.06221 -280.055314) (xy 71.013035 -280.053333) (xy 70.964816 -280.043489) (xy 70.9188 -280.026037)
			(xy 70.876179 -280.00143) (xy 70.838058 -279.970305) (xy 70.805423 -279.933468) (xy 70.77912 -279.891872)
			(xy 70.759829 -279.846596) (xy 70.748052 -279.798812) (xy 70.744092 -279.749758) (xy 70.405239 -279.749758)
			(xy 70.404749 -279.774111) (xy 70.396854 -279.822688) (xy 70.38127 -279.869369) (xy 70.358399 -279.912946)
			(xy 70.328834 -279.95229) (xy 70.293341 -279.986382) (xy 70.252838 -280.014338) (xy 70.208376 -280.035436)
			(xy 70.161105 -280.049128) (xy 70.11225 -280.05506) (xy 70.063075 -280.053079) (xy 70.014856 -280.043235)
			(xy 69.96884 -280.025783) (xy 69.926219 -280.001176) (xy 69.888098 -279.970051) (xy 69.855463 -279.933214)
			(xy 69.82916 -279.891618) (xy 69.809869 -279.846342) (xy 69.798092 -279.798558) (xy 69.794132 -279.749504)
			(xy 69.455279 -279.749504) (xy 69.455284 -279.749758) (xy 69.454789 -279.774365) (xy 69.446894 -279.822942)
			(xy 69.43131 -279.869623) (xy 69.408439 -279.9132) (xy 69.378874 -279.952544) (xy 69.343381 -279.986636)
			(xy 69.302878 -280.014592) (xy 69.258416 -280.03569) (xy 69.211145 -280.049382) (xy 69.16229 -280.055314)
			(xy 69.113115 -280.053333) (xy 69.064896 -280.043489) (xy 69.01888 -280.026037) (xy 68.976259 -280.00143)
			(xy 68.938138 -279.970305) (xy 68.905503 -279.933468) (xy 68.8792 -279.891872) (xy 68.859909 -279.846596)
			(xy 68.848132 -279.798812) (xy 68.844172 -279.749758) (xy 68.505065 -279.749758) (xy 68.504575 -279.774111)
			(xy 68.49668 -279.822688) (xy 68.481096 -279.869369) (xy 68.458225 -279.912946) (xy 68.42866 -279.95229)
			(xy 68.393167 -279.986382) (xy 68.352664 -280.014338) (xy 68.308202 -280.035436) (xy 68.260931 -280.049128)
			(xy 68.212076 -280.05506) (xy 68.162901 -280.053079) (xy 68.114682 -280.043235) (xy 68.068666 -280.025783)
			(xy 68.026045 -280.001176) (xy 67.987924 -279.970051) (xy 67.955289 -279.933214) (xy 67.928986 -279.891618)
			(xy 67.909695 -279.846342) (xy 67.897918 -279.798558) (xy 67.893958 -279.749504) (xy 67.555105 -279.749504)
			(xy 67.55511 -279.749758) (xy 67.554615 -279.774365) (xy 67.54672 -279.822942) (xy 67.531136 -279.869623)
			(xy 67.508265 -279.9132) (xy 67.4787 -279.952544) (xy 67.443207 -279.986636) (xy 67.402704 -280.014592)
			(xy 67.358242 -280.03569) (xy 67.310971 -280.049382) (xy 67.262116 -280.055314) (xy 67.212941 -280.053333)
			(xy 67.164722 -280.043489) (xy 67.118706 -280.026037) (xy 67.076085 -280.00143) (xy 67.037964 -279.970305)
			(xy 67.005329 -279.933468) (xy 66.979026 -279.891872) (xy 66.959735 -279.846596) (xy 66.947958 -279.798812)
			(xy 66.943998 -279.749758) (xy 66.605145 -279.749758) (xy 66.604655 -279.774111) (xy 66.59676 -279.822688)
			(xy 66.581176 -279.869369) (xy 66.558305 -279.912946) (xy 66.52874 -279.95229) (xy 66.493247 -279.986382)
			(xy 66.452744 -280.014338) (xy 66.408282 -280.035436) (xy 66.361011 -280.049128) (xy 66.312156 -280.05506)
			(xy 66.262981 -280.053079) (xy 66.214762 -280.043235) (xy 66.168746 -280.025783) (xy 66.126125 -280.001176)
			(xy 66.088004 -279.970051) (xy 66.055369 -279.933214) (xy 66.029066 -279.891618) (xy 66.009775 -279.846342)
			(xy 65.997998 -279.798558) (xy 65.994038 -279.749504) (xy 65.655185 -279.749504) (xy 65.65519 -279.749758)
			(xy 65.654695 -279.774365) (xy 65.6468 -279.822942) (xy 65.631216 -279.869623) (xy 65.608345 -279.9132)
			(xy 65.57878 -279.952544) (xy 65.543287 -279.986636) (xy 65.502784 -280.014592) (xy 65.458322 -280.03569)
			(xy 65.411051 -280.049382) (xy 65.362196 -280.055314) (xy 65.313021 -280.053333) (xy 65.264802 -280.043489)
			(xy 65.218786 -280.026037) (xy 65.176165 -280.00143) (xy 65.138044 -279.970305) (xy 65.105409 -279.933468)
			(xy 65.079106 -279.891872) (xy 65.059815 -279.846596) (xy 65.048038 -279.798812) (xy 65.044078 -279.749758)
			(xy 64.705225 -279.749758) (xy 64.704735 -279.774111) (xy 64.69684 -279.822688) (xy 64.681256 -279.869369)
			(xy 64.658385 -279.912946) (xy 64.62882 -279.95229) (xy 64.593327 -279.986382) (xy 64.552824 -280.014338)
			(xy 64.508362 -280.035436) (xy 64.461091 -280.049128) (xy 64.412236 -280.05506) (xy 64.363061 -280.053079)
			(xy 64.314842 -280.043235) (xy 64.268826 -280.025783) (xy 64.226205 -280.001176) (xy 64.188084 -279.970051)
			(xy 64.155449 -279.933214) (xy 64.129146 -279.891618) (xy 64.109855 -279.846342) (xy 64.098078 -279.798558)
			(xy 64.094118 -279.749504) (xy 63.755265 -279.749504) (xy 63.75527 -279.749758) (xy 63.754775 -279.774365)
			(xy 63.74688 -279.822942) (xy 63.731296 -279.869623) (xy 63.708425 -279.9132) (xy 63.67886 -279.952544)
			(xy 63.643367 -279.986636) (xy 63.602864 -280.014592) (xy 63.558402 -280.03569) (xy 63.511131 -280.049382)
			(xy 63.462276 -280.055314) (xy 63.413101 -280.053333) (xy 63.364882 -280.043489) (xy 63.318866 -280.026037)
			(xy 63.276245 -280.00143) (xy 63.238124 -279.970305) (xy 63.205489 -279.933468) (xy 63.179186 -279.891872)
			(xy 63.159895 -279.846596) (xy 63.148118 -279.798812) (xy 63.144158 -279.749758) (xy 62.805051 -279.749758)
			(xy 62.804561 -279.774111) (xy 62.796666 -279.822688) (xy 62.781082 -279.869369) (xy 62.758211 -279.912946)
			(xy 62.728646 -279.95229) (xy 62.693153 -279.986382) (xy 62.65265 -280.014338) (xy 62.608188 -280.035436)
			(xy 62.560917 -280.049128) (xy 62.512062 -280.05506) (xy 62.462887 -280.053079) (xy 62.414668 -280.043235)
			(xy 62.368652 -280.025783) (xy 62.326031 -280.001176) (xy 62.28791 -279.970051) (xy 62.255275 -279.933214)
			(xy 62.228972 -279.891618) (xy 62.209681 -279.846342) (xy 62.197904 -279.798558) (xy 62.193944 -279.749504)
			(xy 61.855091 -279.749504) (xy 61.855096 -279.749758) (xy 61.854601 -279.774365) (xy 61.846706 -279.822942)
			(xy 61.831122 -279.869623) (xy 61.808251 -279.9132) (xy 61.778686 -279.952544) (xy 61.743193 -279.986636)
			(xy 61.70269 -280.014592) (xy 61.658228 -280.03569) (xy 61.610957 -280.049382) (xy 61.562102 -280.055314)
			(xy 61.512927 -280.053333) (xy 61.464708 -280.043489) (xy 61.418692 -280.026037) (xy 61.376071 -280.00143)
			(xy 61.33795 -279.970305) (xy 61.305315 -279.933468) (xy 61.279012 -279.891872) (xy 61.259721 -279.846596)
			(xy 61.247944 -279.798812) (xy 61.243984 -279.749758) (xy 60.905131 -279.749758) (xy 60.904641 -279.774111)
			(xy 60.896746 -279.822688) (xy 60.881162 -279.869369) (xy 60.858291 -279.912946) (xy 60.828726 -279.95229)
			(xy 60.793233 -279.986382) (xy 60.75273 -280.014338) (xy 60.708268 -280.035436) (xy 60.660997 -280.049128)
			(xy 60.612142 -280.05506) (xy 60.562967 -280.053079) (xy 60.514748 -280.043235) (xy 60.468732 -280.025783)
			(xy 60.426111 -280.001176) (xy 60.38799 -279.970051) (xy 60.355355 -279.933214) (xy 60.329052 -279.891618)
			(xy 60.309761 -279.846342) (xy 60.297984 -279.798558) (xy 60.294024 -279.749504) (xy 59.955171 -279.749504)
			(xy 59.955176 -279.749758) (xy 59.954681 -279.774365) (xy 59.946786 -279.822942) (xy 59.931202 -279.869623)
			(xy 59.908331 -279.9132) (xy 59.878766 -279.952544) (xy 59.843273 -279.986636) (xy 59.80277 -280.014592)
			(xy 59.758308 -280.03569) (xy 59.711037 -280.049382) (xy 59.662182 -280.055314) (xy 59.613007 -280.053333)
			(xy 59.564788 -280.043489) (xy 59.518772 -280.026037) (xy 59.476151 -280.00143) (xy 59.43803 -279.970305)
			(xy 59.405395 -279.933468) (xy 59.379092 -279.891872) (xy 59.359801 -279.846596) (xy 59.348024 -279.798812)
			(xy 59.344064 -279.749758) (xy 59.005211 -279.749758) (xy 59.004721 -279.774111) (xy 58.996826 -279.822688)
			(xy 58.981242 -279.869369) (xy 58.958371 -279.912946) (xy 58.928806 -279.95229) (xy 58.893313 -279.986382)
			(xy 58.85281 -280.014338) (xy 58.808348 -280.035436) (xy 58.761077 -280.049128) (xy 58.712222 -280.05506)
			(xy 58.663047 -280.053079) (xy 58.614828 -280.043235) (xy 58.568812 -280.025783) (xy 58.526191 -280.001176)
			(xy 58.48807 -279.970051) (xy 58.455435 -279.933214) (xy 58.429132 -279.891618) (xy 58.409841 -279.846342)
			(xy 58.398064 -279.798558) (xy 58.394104 -279.749504) (xy 58.055251 -279.749504) (xy 58.055256 -279.749758)
			(xy 58.054761 -279.774365) (xy 58.046866 -279.822942) (xy 58.031282 -279.869623) (xy 58.008411 -279.9132)
			(xy 57.978846 -279.952544) (xy 57.943353 -279.986636) (xy 57.90285 -280.014592) (xy 57.858388 -280.03569)
			(xy 57.811117 -280.049382) (xy 57.762262 -280.055314) (xy 57.713087 -280.053333) (xy 57.664868 -280.043489)
			(xy 57.618852 -280.026037) (xy 57.576231 -280.00143) (xy 57.53811 -279.970305) (xy 57.505475 -279.933468)
			(xy 57.479172 -279.891872) (xy 57.459881 -279.846596) (xy 57.448104 -279.798812) (xy 57.444144 -279.749758)
			(xy 57.105037 -279.749758) (xy 57.104547 -279.774111) (xy 57.096652 -279.822688) (xy 57.081068 -279.869369)
			(xy 57.058197 -279.912946) (xy 57.028632 -279.95229) (xy 56.993139 -279.986382) (xy 56.952636 -280.014338)
			(xy 56.908174 -280.035436) (xy 56.860903 -280.049128) (xy 56.812048 -280.05506) (xy 56.762873 -280.053079)
			(xy 56.714654 -280.043235) (xy 56.668638 -280.025783) (xy 56.626017 -280.001176) (xy 56.587896 -279.970051)
			(xy 56.555261 -279.933214) (xy 56.528958 -279.891618) (xy 56.509667 -279.846342) (xy 56.49789 -279.798558)
			(xy 56.49393 -279.749504) (xy 56.155077 -279.749504) (xy 56.155082 -279.749758) (xy 56.154587 -279.774365)
			(xy 56.146692 -279.822942) (xy 56.131108 -279.869623) (xy 56.108237 -279.9132) (xy 56.078672 -279.952544)
			(xy 56.043179 -279.986636) (xy 56.002676 -280.014592) (xy 55.958214 -280.03569) (xy 55.910943 -280.049382)
			(xy 55.862088 -280.055314) (xy 55.812913 -280.053333) (xy 55.764694 -280.043489) (xy 55.718678 -280.026037)
			(xy 55.676057 -280.00143) (xy 55.637936 -279.970305) (xy 55.605301 -279.933468) (xy 55.578998 -279.891872)
			(xy 55.559707 -279.846596) (xy 55.54793 -279.798812) (xy 55.54397 -279.749758) (xy 55.205117 -279.749758)
			(xy 55.204627 -279.774111) (xy 55.196732 -279.822688) (xy 55.181148 -279.869369) (xy 55.158277 -279.912946)
			(xy 55.128712 -279.95229) (xy 55.093219 -279.986382) (xy 55.052716 -280.014338) (xy 55.008254 -280.035436)
			(xy 54.960983 -280.049128) (xy 54.912128 -280.05506) (xy 54.862953 -280.053079) (xy 54.814734 -280.043235)
			(xy 54.768718 -280.025783) (xy 54.726097 -280.001176) (xy 54.687976 -279.970051) (xy 54.655341 -279.933214)
			(xy 54.629038 -279.891618) (xy 54.609747 -279.846342) (xy 54.59797 -279.798558) (xy 54.59401 -279.749504)
			(xy 54.255157 -279.749504) (xy 54.255162 -279.749758) (xy 54.254667 -279.774365) (xy 54.246772 -279.822942)
			(xy 54.231188 -279.869623) (xy 54.208317 -279.9132) (xy 54.178752 -279.952544) (xy 54.143259 -279.986636)
			(xy 54.102756 -280.014592) (xy 54.058294 -280.03569) (xy 54.011023 -280.049382) (xy 53.962168 -280.055314)
			(xy 53.912993 -280.053333) (xy 53.864774 -280.043489) (xy 53.818758 -280.026037) (xy 53.776137 -280.00143)
			(xy 53.738016 -279.970305) (xy 53.705381 -279.933468) (xy 53.679078 -279.891872) (xy 53.659787 -279.846596)
			(xy 53.64801 -279.798812) (xy 53.64405 -279.749758) (xy 53.305197 -279.749758) (xy 53.304707 -279.774111)
			(xy 53.296812 -279.822688) (xy 53.281228 -279.869369) (xy 53.258357 -279.912946) (xy 53.228792 -279.95229)
			(xy 53.193299 -279.986382) (xy 53.152796 -280.014338) (xy 53.108334 -280.035436) (xy 53.061063 -280.049128)
			(xy 53.012208 -280.05506) (xy 52.963033 -280.053079) (xy 52.914814 -280.043235) (xy 52.868798 -280.025783)
			(xy 52.826177 -280.001176) (xy 52.788056 -279.970051) (xy 52.755421 -279.933214) (xy 52.729118 -279.891618)
			(xy 52.709827 -279.846342) (xy 52.69805 -279.798558) (xy 52.69409 -279.749504) (xy 52.355237 -279.749504)
			(xy 52.355242 -279.749758) (xy 52.354747 -279.774365) (xy 52.346852 -279.822942) (xy 52.331268 -279.869623)
			(xy 52.308397 -279.9132) (xy 52.278832 -279.952544) (xy 52.243339 -279.986636) (xy 52.202836 -280.014592)
			(xy 52.158374 -280.03569) (xy 52.111103 -280.049382) (xy 52.062248 -280.055314) (xy 52.013073 -280.053333)
			(xy 51.964854 -280.043489) (xy 51.918838 -280.026037) (xy 51.876217 -280.00143) (xy 51.838096 -279.970305)
			(xy 51.805461 -279.933468) (xy 51.779158 -279.891872) (xy 51.759867 -279.846596) (xy 51.74809 -279.798812)
			(xy 51.74413 -279.749758) (xy 51.405277 -279.749758) (xy 51.404787 -279.774111) (xy 51.396892 -279.822688)
			(xy 51.381308 -279.869369) (xy 51.358437 -279.912946) (xy 51.328872 -279.95229) (xy 51.293379 -279.986382)
			(xy 51.252876 -280.014338) (xy 51.208414 -280.035436) (xy 51.161143 -280.049128) (xy 51.112288 -280.05506)
			(xy 51.063113 -280.053079) (xy 51.014894 -280.043235) (xy 50.968878 -280.025783) (xy 50.926257 -280.001176)
			(xy 50.888136 -279.970051) (xy 50.855501 -279.933214) (xy 50.829198 -279.891618) (xy 50.809907 -279.846342)
			(xy 50.79813 -279.798558) (xy 50.79417 -279.749504) (xy 50.455063 -279.749504) (xy 50.455068 -279.749758)
			(xy 50.454573 -279.774365) (xy 50.446678 -279.822942) (xy 50.431094 -279.869623) (xy 50.408223 -279.9132)
			(xy 50.378658 -279.952544) (xy 50.343165 -279.986636) (xy 50.302662 -280.014592) (xy 50.2582 -280.03569)
			(xy 50.210929 -280.049382) (xy 50.162074 -280.055314) (xy 50.112899 -280.053333) (xy 50.06468 -280.043489)
			(xy 50.018664 -280.026037) (xy 49.976043 -280.00143) (xy 49.937922 -279.970305) (xy 49.905287 -279.933468)
			(xy 49.878984 -279.891872) (xy 49.859693 -279.846596) (xy 49.847916 -279.798812) (xy 49.843956 -279.749758)
			(xy 49.505103 -279.749758) (xy 49.504613 -279.774111) (xy 49.496718 -279.822688) (xy 49.481134 -279.869369)
			(xy 49.458263 -279.912946) (xy 49.428698 -279.95229) (xy 49.393205 -279.986382) (xy 49.352702 -280.014338)
			(xy 49.30824 -280.035436) (xy 49.260969 -280.049128) (xy 49.212114 -280.05506) (xy 49.162939 -280.053079)
			(xy 49.11472 -280.043235) (xy 49.068704 -280.025783) (xy 49.026083 -280.001176) (xy 48.987962 -279.970051)
			(xy 48.955327 -279.933214) (xy 48.929024 -279.891618) (xy 48.909733 -279.846342) (xy 48.897956 -279.798558)
			(xy 48.893996 -279.749504) (xy 48.555648 -279.749504) (xy 48.555673 -279.7498) (xy 48.551502 -279.800141)
			(xy 48.539103 -279.849109) (xy 48.518813 -279.895368) (xy 48.491187 -279.937658) (xy 48.456978 -279.974824)
			(xy 48.417118 -280.005853) (xy 48.372695 -280.029898) (xy 48.32492 -280.046305) (xy 48.275097 -280.054625)
			(xy 48.24984 -280.055066) (xy 48.249586 -280.055066) (xy 48.220887 -280.054411) (xy 48.164505 -280.043665)
			(xy 48.137572 -280.03373) (xy 48.128682 -280.030174) (xy 48.11903 -280.030174) (xy 48.109003 -280.030588)
			(xy 48.090471 -280.038252) (xy 48.076283 -280.052424) (xy 48.068599 -280.070947) (xy 48.06823 -280.080974)
			(xy 48.06823 -280.133298) (xy 48.070008 -280.146506) (xy 48.07077 -280.149554) (xy 48.075158 -280.167975)
			(xy 48.079873 -280.20555) (xy 48.080168 -280.224484) (xy 48.080168 -280.224992) (xy 48.079914 -280.234136)
			(xy 48.079914 -280.241502) (xy 48.079914 -280.245058) (xy 48.07966 -280.246836) (xy 48.07966 -280.247852)
			(xy 48.078409 -280.262061) (xy 48.073573 -280.290174) (xy 48.070008 -280.303986) (xy 48.06823 -280.31059)
			(xy 48.06823 -280.368502) (xy 48.068651 -280.378521) (xy 48.076322 -280.397032) (xy 48.090495 -280.411196)
			(xy 48.109011 -280.418856) (xy 48.11903 -280.419302) (xy 48.128682 -280.419302) (xy 48.137572 -280.415746)
			(xy 48.164509 -280.40583) (xy 48.22089 -280.395095) (xy 48.249586 -280.39441) (xy 48.24984 -280.39441)
			(xy 48.275092 -280.394935) (xy 48.324905 -280.403253) (xy 48.372671 -280.419656) (xy 48.417085 -280.443697)
			(xy 48.456937 -280.47472) (xy 48.49114 -280.511879) (xy 48.518761 -280.55416) (xy 48.539046 -280.600411)
			(xy 48.551443 -280.649369) (xy 48.555613 -280.6997) (xy 48.555612 -280.699718) (xy 48.893996 -280.699718)
			(xy 48.897956 -280.650664) (xy 48.909733 -280.60288) (xy 48.929024 -280.557604) (xy 48.955327 -280.516008)
			(xy 48.987962 -280.479171) (xy 49.026083 -280.448046) (xy 49.068704 -280.423439) (xy 49.11472 -280.405987)
			(xy 49.162939 -280.396143) (xy 49.212114 -280.394162) (xy 49.260969 -280.400094) (xy 49.30824 -280.413786)
			(xy 49.352702 -280.434884) (xy 49.393205 -280.46284) (xy 49.428698 -280.496932) (xy 49.458263 -280.536276)
			(xy 49.481134 -280.579853) (xy 49.496718 -280.626534) (xy 49.504613 -280.675111) (xy 49.505108 -280.699718)
			(xy 49.843956 -280.699718) (xy 49.847916 -280.650664) (xy 49.859693 -280.60288) (xy 49.878984 -280.557604)
			(xy 49.905287 -280.516008) (xy 49.937922 -280.479171) (xy 49.976043 -280.448046) (xy 50.018664 -280.423439)
			(xy 50.06468 -280.405987) (xy 50.112899 -280.396143) (xy 50.162074 -280.394162) (xy 50.210929 -280.400094)
			(xy 50.2582 -280.413786) (xy 50.302662 -280.434884) (xy 50.343165 -280.46284) (xy 50.378658 -280.496932)
			(xy 50.408223 -280.536276) (xy 50.431094 -280.579853) (xy 50.446678 -280.626534) (xy 50.454573 -280.675111)
			(xy 50.455068 -280.699718) (xy 50.79417 -280.699718) (xy 50.79813 -280.650664) (xy 50.809907 -280.60288)
			(xy 50.829198 -280.557604) (xy 50.855501 -280.516008) (xy 50.888136 -280.479171) (xy 50.926257 -280.448046)
			(xy 50.968878 -280.423439) (xy 51.014894 -280.405987) (xy 51.063113 -280.396143) (xy 51.112288 -280.394162)
			(xy 51.161143 -280.400094) (xy 51.208414 -280.413786) (xy 51.252876 -280.434884) (xy 51.293379 -280.46284)
			(xy 51.328872 -280.496932) (xy 51.358437 -280.536276) (xy 51.381308 -280.579853) (xy 51.396892 -280.626534)
			(xy 51.404787 -280.675111) (xy 51.405282 -280.699718) (xy 51.74413 -280.699718) (xy 51.74809 -280.650664)
			(xy 51.759867 -280.60288) (xy 51.779158 -280.557604) (xy 51.805461 -280.516008) (xy 51.838096 -280.479171)
			(xy 51.876217 -280.448046) (xy 51.918838 -280.423439) (xy 51.964854 -280.405987) (xy 52.013073 -280.396143)
			(xy 52.062248 -280.394162) (xy 52.111103 -280.400094) (xy 52.158374 -280.413786) (xy 52.202836 -280.434884)
			(xy 52.243339 -280.46284) (xy 52.278832 -280.496932) (xy 52.308397 -280.536276) (xy 52.331268 -280.579853)
			(xy 52.346852 -280.626534) (xy 52.354747 -280.675111) (xy 52.355242 -280.699718) (xy 52.69409 -280.699718)
			(xy 52.69805 -280.650664) (xy 52.709827 -280.60288) (xy 52.729118 -280.557604) (xy 52.755421 -280.516008)
			(xy 52.788056 -280.479171) (xy 52.826177 -280.448046) (xy 52.868798 -280.423439) (xy 52.914814 -280.405987)
			(xy 52.963033 -280.396143) (xy 53.012208 -280.394162) (xy 53.061063 -280.400094) (xy 53.108334 -280.413786)
			(xy 53.152796 -280.434884) (xy 53.193299 -280.46284) (xy 53.228792 -280.496932) (xy 53.258357 -280.536276)
			(xy 53.281228 -280.579853) (xy 53.296812 -280.626534) (xy 53.304707 -280.675111) (xy 53.305202 -280.699718)
			(xy 53.64405 -280.699718) (xy 53.64801 -280.650664) (xy 53.659787 -280.60288) (xy 53.679078 -280.557604)
			(xy 53.705381 -280.516008) (xy 53.738016 -280.479171) (xy 53.776137 -280.448046) (xy 53.818758 -280.423439)
			(xy 53.864774 -280.405987) (xy 53.912993 -280.396143) (xy 53.962168 -280.394162) (xy 54.011023 -280.400094)
			(xy 54.058294 -280.413786) (xy 54.102756 -280.434884) (xy 54.143259 -280.46284) (xy 54.178752 -280.496932)
			(xy 54.208317 -280.536276) (xy 54.231188 -280.579853) (xy 54.246772 -280.626534) (xy 54.254667 -280.675111)
			(xy 54.255162 -280.699718) (xy 54.59401 -280.699718) (xy 54.59797 -280.650664) (xy 54.609747 -280.60288)
			(xy 54.629038 -280.557604) (xy 54.655341 -280.516008) (xy 54.687976 -280.479171) (xy 54.726097 -280.448046)
			(xy 54.768718 -280.423439) (xy 54.814734 -280.405987) (xy 54.862953 -280.396143) (xy 54.912128 -280.394162)
			(xy 54.960983 -280.400094) (xy 55.008254 -280.413786) (xy 55.052716 -280.434884) (xy 55.093219 -280.46284)
			(xy 55.128712 -280.496932) (xy 55.158277 -280.536276) (xy 55.181148 -280.579853) (xy 55.196732 -280.626534)
			(xy 55.204627 -280.675111) (xy 55.205122 -280.699718) (xy 55.54397 -280.699718) (xy 55.54793 -280.650664)
			(xy 55.559707 -280.60288) (xy 55.578998 -280.557604) (xy 55.605301 -280.516008) (xy 55.637936 -280.479171)
			(xy 55.676057 -280.448046) (xy 55.718678 -280.423439) (xy 55.764694 -280.405987) (xy 55.812913 -280.396143)
			(xy 55.862088 -280.394162) (xy 55.910943 -280.400094) (xy 55.958214 -280.413786) (xy 56.002676 -280.434884)
			(xy 56.043179 -280.46284) (xy 56.078672 -280.496932) (xy 56.108237 -280.536276) (xy 56.131108 -280.579853)
			(xy 56.146692 -280.626534) (xy 56.154587 -280.675111) (xy 56.155082 -280.699718) (xy 56.49393 -280.699718)
			(xy 56.49789 -280.650664) (xy 56.509667 -280.60288) (xy 56.528958 -280.557604) (xy 56.555261 -280.516008)
			(xy 56.587896 -280.479171) (xy 56.626017 -280.448046) (xy 56.668638 -280.423439) (xy 56.714654 -280.405987)
			(xy 56.762873 -280.396143) (xy 56.812048 -280.394162) (xy 56.860903 -280.400094) (xy 56.908174 -280.413786)
			(xy 56.952636 -280.434884) (xy 56.993139 -280.46284) (xy 57.028632 -280.496932) (xy 57.058197 -280.536276)
			(xy 57.081068 -280.579853) (xy 57.096652 -280.626534) (xy 57.104547 -280.675111) (xy 57.105042 -280.699718)
			(xy 57.444144 -280.699718) (xy 57.448104 -280.650664) (xy 57.459881 -280.60288) (xy 57.479172 -280.557604)
			(xy 57.505475 -280.516008) (xy 57.53811 -280.479171) (xy 57.576231 -280.448046) (xy 57.618852 -280.423439)
			(xy 57.664868 -280.405987) (xy 57.713087 -280.396143) (xy 57.762262 -280.394162) (xy 57.811117 -280.400094)
			(xy 57.858388 -280.413786) (xy 57.90285 -280.434884) (xy 57.943353 -280.46284) (xy 57.978846 -280.496932)
			(xy 58.008411 -280.536276) (xy 58.031282 -280.579853) (xy 58.046866 -280.626534) (xy 58.054761 -280.675111)
			(xy 58.055256 -280.699718) (xy 58.394104 -280.699718) (xy 58.398064 -280.650664) (xy 58.409841 -280.60288)
			(xy 58.429132 -280.557604) (xy 58.455435 -280.516008) (xy 58.48807 -280.479171) (xy 58.526191 -280.448046)
			(xy 58.568812 -280.423439) (xy 58.614828 -280.405987) (xy 58.663047 -280.396143) (xy 58.712222 -280.394162)
			(xy 58.761077 -280.400094) (xy 58.808348 -280.413786) (xy 58.85281 -280.434884) (xy 58.893313 -280.46284)
			(xy 58.928806 -280.496932) (xy 58.958371 -280.536276) (xy 58.981242 -280.579853) (xy 58.996826 -280.626534)
			(xy 59.004721 -280.675111) (xy 59.005216 -280.699718) (xy 59.344064 -280.699718) (xy 59.348024 -280.650664)
			(xy 59.359801 -280.60288) (xy 59.379092 -280.557604) (xy 59.405395 -280.516008) (xy 59.43803 -280.479171)
			(xy 59.476151 -280.448046) (xy 59.518772 -280.423439) (xy 59.564788 -280.405987) (xy 59.613007 -280.396143)
			(xy 59.662182 -280.394162) (xy 59.711037 -280.400094) (xy 59.758308 -280.413786) (xy 59.80277 -280.434884)
			(xy 59.843273 -280.46284) (xy 59.878766 -280.496932) (xy 59.908331 -280.536276) (xy 59.931202 -280.579853)
			(xy 59.946786 -280.626534) (xy 59.954681 -280.675111) (xy 59.955176 -280.699718) (xy 60.294024 -280.699718)
			(xy 60.297984 -280.650664) (xy 60.309761 -280.60288) (xy 60.329052 -280.557604) (xy 60.355355 -280.516008)
			(xy 60.38799 -280.479171) (xy 60.426111 -280.448046) (xy 60.468732 -280.423439) (xy 60.514748 -280.405987)
			(xy 60.562967 -280.396143) (xy 60.612142 -280.394162) (xy 60.660997 -280.400094) (xy 60.708268 -280.413786)
			(xy 60.75273 -280.434884) (xy 60.793233 -280.46284) (xy 60.828726 -280.496932) (xy 60.858291 -280.536276)
			(xy 60.881162 -280.579853) (xy 60.896746 -280.626534) (xy 60.904641 -280.675111) (xy 60.905136 -280.699718)
			(xy 61.243984 -280.699718) (xy 61.247944 -280.650664) (xy 61.259721 -280.60288) (xy 61.279012 -280.557604)
			(xy 61.305315 -280.516008) (xy 61.33795 -280.479171) (xy 61.376071 -280.448046) (xy 61.418692 -280.423439)
			(xy 61.464708 -280.405987) (xy 61.512927 -280.396143) (xy 61.562102 -280.394162) (xy 61.610957 -280.400094)
			(xy 61.658228 -280.413786) (xy 61.70269 -280.434884) (xy 61.743193 -280.46284) (xy 61.778686 -280.496932)
			(xy 61.808251 -280.536276) (xy 61.831122 -280.579853) (xy 61.846706 -280.626534) (xy 61.854601 -280.675111)
			(xy 61.855096 -280.699718) (xy 62.193944 -280.699718) (xy 62.197904 -280.650664) (xy 62.209681 -280.60288)
			(xy 62.228972 -280.557604) (xy 62.255275 -280.516008) (xy 62.28791 -280.479171) (xy 62.326031 -280.448046)
			(xy 62.368652 -280.423439) (xy 62.414668 -280.405987) (xy 62.462887 -280.396143) (xy 62.512062 -280.394162)
			(xy 62.560917 -280.400094) (xy 62.608188 -280.413786) (xy 62.65265 -280.434884) (xy 62.693153 -280.46284)
			(xy 62.728646 -280.496932) (xy 62.758211 -280.536276) (xy 62.781082 -280.579853) (xy 62.796666 -280.626534)
			(xy 62.804561 -280.675111) (xy 62.805056 -280.699718) (xy 63.144158 -280.699718) (xy 63.148118 -280.650664)
			(xy 63.159895 -280.60288) (xy 63.179186 -280.557604) (xy 63.205489 -280.516008) (xy 63.238124 -280.479171)
			(xy 63.276245 -280.448046) (xy 63.318866 -280.423439) (xy 63.364882 -280.405987) (xy 63.413101 -280.396143)
			(xy 63.462276 -280.394162) (xy 63.511131 -280.400094) (xy 63.558402 -280.413786) (xy 63.602864 -280.434884)
			(xy 63.643367 -280.46284) (xy 63.67886 -280.496932) (xy 63.708425 -280.536276) (xy 63.731296 -280.579853)
			(xy 63.74688 -280.626534) (xy 63.754775 -280.675111) (xy 63.75527 -280.699718) (xy 64.094118 -280.699718)
			(xy 64.098078 -280.650664) (xy 64.109855 -280.60288) (xy 64.129146 -280.557604) (xy 64.155449 -280.516008)
			(xy 64.188084 -280.479171) (xy 64.226205 -280.448046) (xy 64.268826 -280.423439) (xy 64.314842 -280.405987)
			(xy 64.363061 -280.396143) (xy 64.412236 -280.394162) (xy 64.461091 -280.400094) (xy 64.508362 -280.413786)
			(xy 64.552824 -280.434884) (xy 64.593327 -280.46284) (xy 64.62882 -280.496932) (xy 64.658385 -280.536276)
			(xy 64.681256 -280.579853) (xy 64.69684 -280.626534) (xy 64.704735 -280.675111) (xy 64.70523 -280.699718)
			(xy 65.044078 -280.699718) (xy 65.048038 -280.650664) (xy 65.059815 -280.60288) (xy 65.079106 -280.557604)
			(xy 65.105409 -280.516008) (xy 65.138044 -280.479171) (xy 65.176165 -280.448046) (xy 65.218786 -280.423439)
			(xy 65.264802 -280.405987) (xy 65.313021 -280.396143) (xy 65.362196 -280.394162) (xy 65.411051 -280.400094)
			(xy 65.458322 -280.413786) (xy 65.502784 -280.434884) (xy 65.543287 -280.46284) (xy 65.57878 -280.496932)
			(xy 65.608345 -280.536276) (xy 65.631216 -280.579853) (xy 65.6468 -280.626534) (xy 65.654695 -280.675111)
			(xy 65.65519 -280.699718) (xy 65.994038 -280.699718) (xy 65.997998 -280.650664) (xy 66.009775 -280.60288)
			(xy 66.029066 -280.557604) (xy 66.055369 -280.516008) (xy 66.088004 -280.479171) (xy 66.126125 -280.448046)
			(xy 66.168746 -280.423439) (xy 66.214762 -280.405987) (xy 66.262981 -280.396143) (xy 66.312156 -280.394162)
			(xy 66.361011 -280.400094) (xy 66.408282 -280.413786) (xy 66.452744 -280.434884) (xy 66.493247 -280.46284)
			(xy 66.52874 -280.496932) (xy 66.558305 -280.536276) (xy 66.581176 -280.579853) (xy 66.59676 -280.626534)
			(xy 66.604655 -280.675111) (xy 66.60515 -280.699718) (xy 66.943998 -280.699718) (xy 66.947958 -280.650664)
			(xy 66.959735 -280.60288) (xy 66.979026 -280.557604) (xy 67.005329 -280.516008) (xy 67.037964 -280.479171)
			(xy 67.076085 -280.448046) (xy 67.118706 -280.423439) (xy 67.164722 -280.405987) (xy 67.212941 -280.396143)
			(xy 67.262116 -280.394162) (xy 67.310971 -280.400094) (xy 67.358242 -280.413786) (xy 67.402704 -280.434884)
			(xy 67.443207 -280.46284) (xy 67.4787 -280.496932) (xy 67.508265 -280.536276) (xy 67.531136 -280.579853)
			(xy 67.54672 -280.626534) (xy 67.554615 -280.675111) (xy 67.55511 -280.699718) (xy 67.893958 -280.699718)
			(xy 67.897918 -280.650664) (xy 67.909695 -280.60288) (xy 67.928986 -280.557604) (xy 67.955289 -280.516008)
			(xy 67.987924 -280.479171) (xy 68.026045 -280.448046) (xy 68.068666 -280.423439) (xy 68.114682 -280.405987)
			(xy 68.162901 -280.396143) (xy 68.212076 -280.394162) (xy 68.260931 -280.400094) (xy 68.308202 -280.413786)
			(xy 68.352664 -280.434884) (xy 68.393167 -280.46284) (xy 68.42866 -280.496932) (xy 68.458225 -280.536276)
			(xy 68.481096 -280.579853) (xy 68.49668 -280.626534) (xy 68.504575 -280.675111) (xy 68.50507 -280.699718)
			(xy 68.844172 -280.699718) (xy 68.848132 -280.650664) (xy 68.859909 -280.60288) (xy 68.8792 -280.557604)
			(xy 68.905503 -280.516008) (xy 68.938138 -280.479171) (xy 68.976259 -280.448046) (xy 69.01888 -280.423439)
			(xy 69.064896 -280.405987) (xy 69.113115 -280.396143) (xy 69.16229 -280.394162) (xy 69.211145 -280.400094)
			(xy 69.258416 -280.413786) (xy 69.302878 -280.434884) (xy 69.343381 -280.46284) (xy 69.378874 -280.496932)
			(xy 69.408439 -280.536276) (xy 69.43131 -280.579853) (xy 69.446894 -280.626534) (xy 69.454789 -280.675111)
			(xy 69.455284 -280.699718) (xy 69.794132 -280.699718) (xy 69.798092 -280.650664) (xy 69.809869 -280.60288)
			(xy 69.82916 -280.557604) (xy 69.855463 -280.516008) (xy 69.888098 -280.479171) (xy 69.926219 -280.448046)
			(xy 69.96884 -280.423439) (xy 70.014856 -280.405987) (xy 70.063075 -280.396143) (xy 70.11225 -280.394162)
			(xy 70.161105 -280.400094) (xy 70.208376 -280.413786) (xy 70.252838 -280.434884) (xy 70.293341 -280.46284)
			(xy 70.328834 -280.496932) (xy 70.358399 -280.536276) (xy 70.38127 -280.579853) (xy 70.396854 -280.626534)
			(xy 70.404749 -280.675111) (xy 70.405244 -280.699718) (xy 70.744092 -280.699718) (xy 70.748052 -280.650664)
			(xy 70.759829 -280.60288) (xy 70.77912 -280.557604) (xy 70.805423 -280.516008) (xy 70.838058 -280.479171)
			(xy 70.876179 -280.448046) (xy 70.9188 -280.423439) (xy 70.964816 -280.405987) (xy 71.013035 -280.396143)
			(xy 71.06221 -280.394162) (xy 71.111065 -280.400094) (xy 71.158336 -280.413786) (xy 71.202798 -280.434884)
			(xy 71.243301 -280.46284) (xy 71.278794 -280.496932) (xy 71.308359 -280.536276) (xy 71.33123 -280.579853)
			(xy 71.346814 -280.626534) (xy 71.354709 -280.675111) (xy 71.355204 -280.699718) (xy 71.694052 -280.699718)
			(xy 71.698012 -280.650664) (xy 71.709789 -280.60288) (xy 71.72908 -280.557604) (xy 71.755383 -280.516008)
			(xy 71.788018 -280.479171) (xy 71.826139 -280.448046) (xy 71.86876 -280.423439) (xy 71.914776 -280.405987)
			(xy 71.962995 -280.396143) (xy 72.01217 -280.394162) (xy 72.061025 -280.400094) (xy 72.108296 -280.413786)
			(xy 72.152758 -280.434884) (xy 72.193261 -280.46284) (xy 72.228754 -280.496932) (xy 72.258319 -280.536276)
			(xy 72.28119 -280.579853) (xy 72.296774 -280.626534) (xy 72.304669 -280.675111) (xy 72.305164 -280.699718)
			(xy 72.644012 -280.699718) (xy 72.647972 -280.650664) (xy 72.659749 -280.60288) (xy 72.67904 -280.557604)
			(xy 72.705343 -280.516008) (xy 72.737978 -280.479171) (xy 72.776099 -280.448046) (xy 72.81872 -280.423439)
			(xy 72.864736 -280.405987) (xy 72.912955 -280.396143) (xy 72.96213 -280.394162) (xy 73.010985 -280.400094)
			(xy 73.058256 -280.413786) (xy 73.102718 -280.434884) (xy 73.143221 -280.46284) (xy 73.178714 -280.496932)
			(xy 73.208279 -280.536276) (xy 73.23115 -280.579853) (xy 73.246734 -280.626534) (xy 73.254629 -280.675111)
			(xy 73.255124 -280.699718) (xy 73.593972 -280.699718) (xy 73.597932 -280.650664) (xy 73.609709 -280.60288)
			(xy 73.629 -280.557604) (xy 73.655303 -280.516008) (xy 73.687938 -280.479171) (xy 73.726059 -280.448046)
			(xy 73.76868 -280.423439) (xy 73.814696 -280.405987) (xy 73.862915 -280.396143) (xy 73.91209 -280.394162)
			(xy 73.960945 -280.400094) (xy 74.008216 -280.413786) (xy 74.052678 -280.434884) (xy 74.093181 -280.46284)
			(xy 74.128674 -280.496932) (xy 74.158239 -280.536276) (xy 74.18111 -280.579853) (xy 74.196694 -280.626534)
			(xy 74.204589 -280.675111) (xy 74.205084 -280.699718) (xy 74.544186 -280.699718) (xy 74.548146 -280.650664)
			(xy 74.559923 -280.60288) (xy 74.579214 -280.557604) (xy 74.605517 -280.516008) (xy 74.638152 -280.479171)
			(xy 74.676273 -280.448046) (xy 74.718894 -280.423439) (xy 74.76491 -280.405987) (xy 74.813129 -280.396143)
			(xy 74.862304 -280.394162) (xy 74.911159 -280.400094) (xy 74.95843 -280.413786) (xy 75.002892 -280.434884)
			(xy 75.043395 -280.46284) (xy 75.078888 -280.496932) (xy 75.108453 -280.536276) (xy 75.131324 -280.579853)
			(xy 75.146908 -280.626534) (xy 75.154803 -280.675111) (xy 75.155298 -280.699718) (xy 75.494146 -280.699718)
			(xy 75.498106 -280.650664) (xy 75.509883 -280.60288) (xy 75.529174 -280.557604) (xy 75.555477 -280.516008)
			(xy 75.588112 -280.479171) (xy 75.626233 -280.448046) (xy 75.668854 -280.423439) (xy 75.71487 -280.405987)
			(xy 75.763089 -280.396143) (xy 75.812264 -280.394162) (xy 75.861119 -280.400094) (xy 75.90839 -280.413786)
			(xy 75.952852 -280.434884) (xy 75.993355 -280.46284) (xy 76.028848 -280.496932) (xy 76.058413 -280.536276)
			(xy 76.081284 -280.579853) (xy 76.096868 -280.626534) (xy 76.104763 -280.675111) (xy 76.105258 -280.699718)
			(xy 76.444106 -280.699718) (xy 76.448066 -280.650664) (xy 76.459843 -280.60288) (xy 76.479134 -280.557604)
			(xy 76.505437 -280.516008) (xy 76.538072 -280.479171) (xy 76.576193 -280.448046) (xy 76.618814 -280.423439)
			(xy 76.66483 -280.405987) (xy 76.713049 -280.396143) (xy 76.762224 -280.394162) (xy 76.811079 -280.400094)
			(xy 76.85835 -280.413786) (xy 76.902812 -280.434884) (xy 76.943315 -280.46284) (xy 76.978808 -280.496932)
			(xy 77.008373 -280.536276) (xy 77.031244 -280.579853) (xy 77.046828 -280.626534) (xy 77.054723 -280.675111)
			(xy 77.055218 -280.699718) (xy 77.394066 -280.699718) (xy 77.398026 -280.650664) (xy 77.409803 -280.60288)
			(xy 77.429094 -280.557604) (xy 77.455397 -280.516008) (xy 77.488032 -280.479171) (xy 77.526153 -280.448046)
			(xy 77.568774 -280.423439) (xy 77.61479 -280.405987) (xy 77.663009 -280.396143) (xy 77.712184 -280.394162)
			(xy 77.761039 -280.400094) (xy 77.80831 -280.413786) (xy 77.852772 -280.434884) (xy 77.893275 -280.46284)
			(xy 77.928768 -280.496932) (xy 77.958333 -280.536276) (xy 77.981204 -280.579853) (xy 77.996788 -280.626534)
			(xy 78.004683 -280.675111) (xy 78.005178 -280.699718) (xy 78.344026 -280.699718) (xy 78.347986 -280.650664)
			(xy 78.359763 -280.60288) (xy 78.379054 -280.557604) (xy 78.405357 -280.516008) (xy 78.437992 -280.479171)
			(xy 78.476113 -280.448046) (xy 78.518734 -280.423439) (xy 78.56475 -280.405987) (xy 78.612969 -280.396143)
			(xy 78.662144 -280.394162) (xy 78.710999 -280.400094) (xy 78.75827 -280.413786) (xy 78.802732 -280.434884)
			(xy 78.843235 -280.46284) (xy 78.878728 -280.496932) (xy 78.908293 -280.536276) (xy 78.931164 -280.579853)
			(xy 78.946748 -280.626534) (xy 78.954643 -280.675111) (xy 78.955138 -280.699718) (xy 79.293986 -280.699718)
			(xy 79.297946 -280.650664) (xy 79.309723 -280.60288) (xy 79.329014 -280.557604) (xy 79.355317 -280.516008)
			(xy 79.387952 -280.479171) (xy 79.426073 -280.448046) (xy 79.468694 -280.423439) (xy 79.51471 -280.405987)
			(xy 79.562929 -280.396143) (xy 79.612104 -280.394162) (xy 79.660959 -280.400094) (xy 79.70823 -280.413786)
			(xy 79.752692 -280.434884) (xy 79.793195 -280.46284) (xy 79.828688 -280.496932) (xy 79.858253 -280.536276)
			(xy 79.881124 -280.579853) (xy 79.896708 -280.626534) (xy 79.904603 -280.675111) (xy 79.905098 -280.699718)
			(xy 80.2442 -280.699718) (xy 80.24816 -280.650664) (xy 80.259937 -280.60288) (xy 80.279228 -280.557604)
			(xy 80.305531 -280.516008) (xy 80.338166 -280.479171) (xy 80.376287 -280.448046) (xy 80.418908 -280.423439)
			(xy 80.464924 -280.405987) (xy 80.513143 -280.396143) (xy 80.562318 -280.394162) (xy 80.611173 -280.400094)
			(xy 80.658444 -280.413786) (xy 80.702906 -280.434884) (xy 80.743409 -280.46284) (xy 80.778902 -280.496932)
			(xy 80.808467 -280.536276) (xy 80.831338 -280.579853) (xy 80.846922 -280.626534) (xy 80.854817 -280.675111)
			(xy 80.855312 -280.699718) (xy 81.19416 -280.699718) (xy 81.19812 -280.650664) (xy 81.209897 -280.60288)
			(xy 81.229188 -280.557604) (xy 81.255491 -280.516008) (xy 81.288126 -280.479171) (xy 81.326247 -280.448046)
			(xy 81.368868 -280.423439) (xy 81.414884 -280.405987) (xy 81.463103 -280.396143) (xy 81.512278 -280.394162)
			(xy 81.561133 -280.400094) (xy 81.608404 -280.413786) (xy 81.652866 -280.434884) (xy 81.693369 -280.46284)
			(xy 81.728862 -280.496932) (xy 81.758427 -280.536276) (xy 81.781298 -280.579853) (xy 81.796882 -280.626534)
			(xy 81.804777 -280.675111) (xy 81.805272 -280.699718) (xy 82.14412 -280.699718) (xy 82.14808 -280.650664)
			(xy 82.159857 -280.60288) (xy 82.179148 -280.557604) (xy 82.205451 -280.516008) (xy 82.238086 -280.479171)
			(xy 82.276207 -280.448046) (xy 82.318828 -280.423439) (xy 82.364844 -280.405987) (xy 82.413063 -280.396143)
			(xy 82.462238 -280.394162) (xy 82.511093 -280.400094) (xy 82.558364 -280.413786) (xy 82.602826 -280.434884)
			(xy 82.643329 -280.46284) (xy 82.678822 -280.496932) (xy 82.708387 -280.536276) (xy 82.731258 -280.579853)
			(xy 82.746842 -280.626534) (xy 82.754737 -280.675111) (xy 82.755232 -280.699718) (xy 82.754737 -280.724325)
			(xy 82.746842 -280.772902) (xy 82.731258 -280.819583) (xy 82.708387 -280.86316) (xy 82.678822 -280.902504)
			(xy 82.643329 -280.936596) (xy 82.602826 -280.964552) (xy 82.558364 -280.98565) (xy 82.511093 -280.999342)
			(xy 82.462238 -281.005274) (xy 82.413063 -281.003293) (xy 82.364844 -280.993449) (xy 82.318828 -280.975997)
			(xy 82.276207 -280.95139) (xy 82.238086 -280.920265) (xy 82.205451 -280.883428) (xy 82.179148 -280.841832)
			(xy 82.159857 -280.796556) (xy 82.14808 -280.748772) (xy 82.14412 -280.699718) (xy 81.805272 -280.699718)
			(xy 81.804777 -280.724325) (xy 81.796882 -280.772902) (xy 81.781298 -280.819583) (xy 81.758427 -280.86316)
			(xy 81.728862 -280.902504) (xy 81.693369 -280.936596) (xy 81.652866 -280.964552) (xy 81.608404 -280.98565)
			(xy 81.561133 -280.999342) (xy 81.512278 -281.005274) (xy 81.463103 -281.003293) (xy 81.414884 -280.993449)
			(xy 81.368868 -280.975997) (xy 81.326247 -280.95139) (xy 81.288126 -280.920265) (xy 81.255491 -280.883428)
			(xy 81.229188 -280.841832) (xy 81.209897 -280.796556) (xy 81.19812 -280.748772) (xy 81.19416 -280.699718)
			(xy 80.855312 -280.699718) (xy 80.854817 -280.724325) (xy 80.846922 -280.772902) (xy 80.831338 -280.819583)
			(xy 80.808467 -280.86316) (xy 80.778902 -280.902504) (xy 80.743409 -280.936596) (xy 80.702906 -280.964552)
			(xy 80.658444 -280.98565) (xy 80.611173 -280.999342) (xy 80.562318 -281.005274) (xy 80.513143 -281.003293)
			(xy 80.464924 -280.993449) (xy 80.418908 -280.975997) (xy 80.376287 -280.95139) (xy 80.338166 -280.920265)
			(xy 80.305531 -280.883428) (xy 80.279228 -280.841832) (xy 80.259937 -280.796556) (xy 80.24816 -280.748772)
			(xy 80.2442 -280.699718) (xy 79.905098 -280.699718) (xy 79.904603 -280.724325) (xy 79.896708 -280.772902)
			(xy 79.881124 -280.819583) (xy 79.858253 -280.86316) (xy 79.828688 -280.902504) (xy 79.793195 -280.936596)
			(xy 79.752692 -280.964552) (xy 79.70823 -280.98565) (xy 79.660959 -280.999342) (xy 79.612104 -281.005274)
			(xy 79.562929 -281.003293) (xy 79.51471 -280.993449) (xy 79.468694 -280.975997) (xy 79.426073 -280.95139)
			(xy 79.387952 -280.920265) (xy 79.355317 -280.883428) (xy 79.329014 -280.841832) (xy 79.309723 -280.796556)
			(xy 79.297946 -280.748772) (xy 79.293986 -280.699718) (xy 78.955138 -280.699718) (xy 78.954643 -280.724325)
			(xy 78.946748 -280.772902) (xy 78.931164 -280.819583) (xy 78.908293 -280.86316) (xy 78.878728 -280.902504)
			(xy 78.843235 -280.936596) (xy 78.802732 -280.964552) (xy 78.75827 -280.98565) (xy 78.710999 -280.999342)
			(xy 78.662144 -281.005274) (xy 78.612969 -281.003293) (xy 78.56475 -280.993449) (xy 78.518734 -280.975997)
			(xy 78.476113 -280.95139) (xy 78.437992 -280.920265) (xy 78.405357 -280.883428) (xy 78.379054 -280.841832)
			(xy 78.359763 -280.796556) (xy 78.347986 -280.748772) (xy 78.344026 -280.699718) (xy 78.005178 -280.699718)
			(xy 78.004683 -280.724325) (xy 77.996788 -280.772902) (xy 77.981204 -280.819583) (xy 77.958333 -280.86316)
			(xy 77.928768 -280.902504) (xy 77.893275 -280.936596) (xy 77.852772 -280.964552) (xy 77.80831 -280.98565)
			(xy 77.761039 -280.999342) (xy 77.712184 -281.005274) (xy 77.663009 -281.003293) (xy 77.61479 -280.993449)
			(xy 77.568774 -280.975997) (xy 77.526153 -280.95139) (xy 77.488032 -280.920265) (xy 77.455397 -280.883428)
			(xy 77.429094 -280.841832) (xy 77.409803 -280.796556) (xy 77.398026 -280.748772) (xy 77.394066 -280.699718)
			(xy 77.055218 -280.699718) (xy 77.054723 -280.724325) (xy 77.046828 -280.772902) (xy 77.031244 -280.819583)
			(xy 77.008373 -280.86316) (xy 76.978808 -280.902504) (xy 76.943315 -280.936596) (xy 76.902812 -280.964552)
			(xy 76.85835 -280.98565) (xy 76.811079 -280.999342) (xy 76.762224 -281.005274) (xy 76.713049 -281.003293)
			(xy 76.66483 -280.993449) (xy 76.618814 -280.975997) (xy 76.576193 -280.95139) (xy 76.538072 -280.920265)
			(xy 76.505437 -280.883428) (xy 76.479134 -280.841832) (xy 76.459843 -280.796556) (xy 76.448066 -280.748772)
			(xy 76.444106 -280.699718) (xy 76.105258 -280.699718) (xy 76.104763 -280.724325) (xy 76.096868 -280.772902)
			(xy 76.081284 -280.819583) (xy 76.058413 -280.86316) (xy 76.028848 -280.902504) (xy 75.993355 -280.936596)
			(xy 75.952852 -280.964552) (xy 75.90839 -280.98565) (xy 75.861119 -280.999342) (xy 75.812264 -281.005274)
			(xy 75.763089 -281.003293) (xy 75.71487 -280.993449) (xy 75.668854 -280.975997) (xy 75.626233 -280.95139)
			(xy 75.588112 -280.920265) (xy 75.555477 -280.883428) (xy 75.529174 -280.841832) (xy 75.509883 -280.796556)
			(xy 75.498106 -280.748772) (xy 75.494146 -280.699718) (xy 75.155298 -280.699718) (xy 75.154803 -280.724325)
			(xy 75.146908 -280.772902) (xy 75.131324 -280.819583) (xy 75.108453 -280.86316) (xy 75.078888 -280.902504)
			(xy 75.043395 -280.936596) (xy 75.002892 -280.964552) (xy 74.95843 -280.98565) (xy 74.911159 -280.999342)
			(xy 74.862304 -281.005274) (xy 74.813129 -281.003293) (xy 74.76491 -280.993449) (xy 74.718894 -280.975997)
			(xy 74.676273 -280.95139) (xy 74.638152 -280.920265) (xy 74.605517 -280.883428) (xy 74.579214 -280.841832)
			(xy 74.559923 -280.796556) (xy 74.548146 -280.748772) (xy 74.544186 -280.699718) (xy 74.205084 -280.699718)
			(xy 74.204589 -280.724325) (xy 74.196694 -280.772902) (xy 74.18111 -280.819583) (xy 74.158239 -280.86316)
			(xy 74.128674 -280.902504) (xy 74.093181 -280.936596) (xy 74.052678 -280.964552) (xy 74.008216 -280.98565)
			(xy 73.960945 -280.999342) (xy 73.91209 -281.005274) (xy 73.862915 -281.003293) (xy 73.814696 -280.993449)
			(xy 73.76868 -280.975997) (xy 73.726059 -280.95139) (xy 73.687938 -280.920265) (xy 73.655303 -280.883428)
			(xy 73.629 -280.841832) (xy 73.609709 -280.796556) (xy 73.597932 -280.748772) (xy 73.593972 -280.699718)
			(xy 73.255124 -280.699718) (xy 73.254629 -280.724325) (xy 73.246734 -280.772902) (xy 73.23115 -280.819583)
			(xy 73.208279 -280.86316) (xy 73.178714 -280.902504) (xy 73.143221 -280.936596) (xy 73.102718 -280.964552)
			(xy 73.058256 -280.98565) (xy 73.010985 -280.999342) (xy 72.96213 -281.005274) (xy 72.912955 -281.003293)
			(xy 72.864736 -280.993449) (xy 72.81872 -280.975997) (xy 72.776099 -280.95139) (xy 72.737978 -280.920265)
			(xy 72.705343 -280.883428) (xy 72.67904 -280.841832) (xy 72.659749 -280.796556) (xy 72.647972 -280.748772)
			(xy 72.644012 -280.699718) (xy 72.305164 -280.699718) (xy 72.304669 -280.724325) (xy 72.296774 -280.772902)
			(xy 72.28119 -280.819583) (xy 72.258319 -280.86316) (xy 72.228754 -280.902504) (xy 72.193261 -280.936596)
			(xy 72.152758 -280.964552) (xy 72.108296 -280.98565) (xy 72.061025 -280.999342) (xy 72.01217 -281.005274)
			(xy 71.962995 -281.003293) (xy 71.914776 -280.993449) (xy 71.86876 -280.975997) (xy 71.826139 -280.95139)
			(xy 71.788018 -280.920265) (xy 71.755383 -280.883428) (xy 71.72908 -280.841832) (xy 71.709789 -280.796556)
			(xy 71.698012 -280.748772) (xy 71.694052 -280.699718) (xy 71.355204 -280.699718) (xy 71.354709 -280.724325)
			(xy 71.346814 -280.772902) (xy 71.33123 -280.819583) (xy 71.308359 -280.86316) (xy 71.278794 -280.902504)
			(xy 71.243301 -280.936596) (xy 71.202798 -280.964552) (xy 71.158336 -280.98565) (xy 71.111065 -280.999342)
			(xy 71.06221 -281.005274) (xy 71.013035 -281.003293) (xy 70.964816 -280.993449) (xy 70.9188 -280.975997)
			(xy 70.876179 -280.95139) (xy 70.838058 -280.920265) (xy 70.805423 -280.883428) (xy 70.77912 -280.841832)
			(xy 70.759829 -280.796556) (xy 70.748052 -280.748772) (xy 70.744092 -280.699718) (xy 70.405244 -280.699718)
			(xy 70.404749 -280.724325) (xy 70.396854 -280.772902) (xy 70.38127 -280.819583) (xy 70.358399 -280.86316)
			(xy 70.328834 -280.902504) (xy 70.293341 -280.936596) (xy 70.252838 -280.964552) (xy 70.208376 -280.98565)
			(xy 70.161105 -280.999342) (xy 70.11225 -281.005274) (xy 70.063075 -281.003293) (xy 70.014856 -280.993449)
			(xy 69.96884 -280.975997) (xy 69.926219 -280.95139) (xy 69.888098 -280.920265) (xy 69.855463 -280.883428)
			(xy 69.82916 -280.841832) (xy 69.809869 -280.796556) (xy 69.798092 -280.748772) (xy 69.794132 -280.699718)
			(xy 69.455284 -280.699718) (xy 69.454789 -280.724325) (xy 69.446894 -280.772902) (xy 69.43131 -280.819583)
			(xy 69.408439 -280.86316) (xy 69.378874 -280.902504) (xy 69.343381 -280.936596) (xy 69.302878 -280.964552)
			(xy 69.258416 -280.98565) (xy 69.211145 -280.999342) (xy 69.16229 -281.005274) (xy 69.113115 -281.003293)
			(xy 69.064896 -280.993449) (xy 69.01888 -280.975997) (xy 68.976259 -280.95139) (xy 68.938138 -280.920265)
			(xy 68.905503 -280.883428) (xy 68.8792 -280.841832) (xy 68.859909 -280.796556) (xy 68.848132 -280.748772)
			(xy 68.844172 -280.699718) (xy 68.50507 -280.699718) (xy 68.504575 -280.724325) (xy 68.49668 -280.772902)
			(xy 68.481096 -280.819583) (xy 68.458225 -280.86316) (xy 68.42866 -280.902504) (xy 68.393167 -280.936596)
			(xy 68.352664 -280.964552) (xy 68.308202 -280.98565) (xy 68.260931 -280.999342) (xy 68.212076 -281.005274)
			(xy 68.162901 -281.003293) (xy 68.114682 -280.993449) (xy 68.068666 -280.975997) (xy 68.026045 -280.95139)
			(xy 67.987924 -280.920265) (xy 67.955289 -280.883428) (xy 67.928986 -280.841832) (xy 67.909695 -280.796556)
			(xy 67.897918 -280.748772) (xy 67.893958 -280.699718) (xy 67.55511 -280.699718) (xy 67.554615 -280.724325)
			(xy 67.54672 -280.772902) (xy 67.531136 -280.819583) (xy 67.508265 -280.86316) (xy 67.4787 -280.902504)
			(xy 67.443207 -280.936596) (xy 67.402704 -280.964552) (xy 67.358242 -280.98565) (xy 67.310971 -280.999342)
			(xy 67.262116 -281.005274) (xy 67.212941 -281.003293) (xy 67.164722 -280.993449) (xy 67.118706 -280.975997)
			(xy 67.076085 -280.95139) (xy 67.037964 -280.920265) (xy 67.005329 -280.883428) (xy 66.979026 -280.841832)
			(xy 66.959735 -280.796556) (xy 66.947958 -280.748772) (xy 66.943998 -280.699718) (xy 66.60515 -280.699718)
			(xy 66.604655 -280.724325) (xy 66.59676 -280.772902) (xy 66.581176 -280.819583) (xy 66.558305 -280.86316)
			(xy 66.52874 -280.902504) (xy 66.493247 -280.936596) (xy 66.452744 -280.964552) (xy 66.408282 -280.98565)
			(xy 66.361011 -280.999342) (xy 66.312156 -281.005274) (xy 66.262981 -281.003293) (xy 66.214762 -280.993449)
			(xy 66.168746 -280.975997) (xy 66.126125 -280.95139) (xy 66.088004 -280.920265) (xy 66.055369 -280.883428)
			(xy 66.029066 -280.841832) (xy 66.009775 -280.796556) (xy 65.997998 -280.748772) (xy 65.994038 -280.699718)
			(xy 65.65519 -280.699718) (xy 65.654695 -280.724325) (xy 65.6468 -280.772902) (xy 65.631216 -280.819583)
			(xy 65.608345 -280.86316) (xy 65.57878 -280.902504) (xy 65.543287 -280.936596) (xy 65.502784 -280.964552)
			(xy 65.458322 -280.98565) (xy 65.411051 -280.999342) (xy 65.362196 -281.005274) (xy 65.313021 -281.003293)
			(xy 65.264802 -280.993449) (xy 65.218786 -280.975997) (xy 65.176165 -280.95139) (xy 65.138044 -280.920265)
			(xy 65.105409 -280.883428) (xy 65.079106 -280.841832) (xy 65.059815 -280.796556) (xy 65.048038 -280.748772)
			(xy 65.044078 -280.699718) (xy 64.70523 -280.699718) (xy 64.704735 -280.724325) (xy 64.69684 -280.772902)
			(xy 64.681256 -280.819583) (xy 64.658385 -280.86316) (xy 64.62882 -280.902504) (xy 64.593327 -280.936596)
			(xy 64.552824 -280.964552) (xy 64.508362 -280.98565) (xy 64.461091 -280.999342) (xy 64.412236 -281.005274)
			(xy 64.363061 -281.003293) (xy 64.314842 -280.993449) (xy 64.268826 -280.975997) (xy 64.226205 -280.95139)
			(xy 64.188084 -280.920265) (xy 64.155449 -280.883428) (xy 64.129146 -280.841832) (xy 64.109855 -280.796556)
			(xy 64.098078 -280.748772) (xy 64.094118 -280.699718) (xy 63.75527 -280.699718) (xy 63.754775 -280.724325)
			(xy 63.74688 -280.772902) (xy 63.731296 -280.819583) (xy 63.708425 -280.86316) (xy 63.67886 -280.902504)
			(xy 63.643367 -280.936596) (xy 63.602864 -280.964552) (xy 63.558402 -280.98565) (xy 63.511131 -280.999342)
			(xy 63.462276 -281.005274) (xy 63.413101 -281.003293) (xy 63.364882 -280.993449) (xy 63.318866 -280.975997)
			(xy 63.276245 -280.95139) (xy 63.238124 -280.920265) (xy 63.205489 -280.883428) (xy 63.179186 -280.841832)
			(xy 63.159895 -280.796556) (xy 63.148118 -280.748772) (xy 63.144158 -280.699718) (xy 62.805056 -280.699718)
			(xy 62.804561 -280.724325) (xy 62.796666 -280.772902) (xy 62.781082 -280.819583) (xy 62.758211 -280.86316)
			(xy 62.728646 -280.902504) (xy 62.693153 -280.936596) (xy 62.65265 -280.964552) (xy 62.608188 -280.98565)
			(xy 62.560917 -280.999342) (xy 62.512062 -281.005274) (xy 62.462887 -281.003293) (xy 62.414668 -280.993449)
			(xy 62.368652 -280.975997) (xy 62.326031 -280.95139) (xy 62.28791 -280.920265) (xy 62.255275 -280.883428)
			(xy 62.228972 -280.841832) (xy 62.209681 -280.796556) (xy 62.197904 -280.748772) (xy 62.193944 -280.699718)
			(xy 61.855096 -280.699718) (xy 61.854601 -280.724325) (xy 61.846706 -280.772902) (xy 61.831122 -280.819583)
			(xy 61.808251 -280.86316) (xy 61.778686 -280.902504) (xy 61.743193 -280.936596) (xy 61.70269 -280.964552)
			(xy 61.658228 -280.98565) (xy 61.610957 -280.999342) (xy 61.562102 -281.005274) (xy 61.512927 -281.003293)
			(xy 61.464708 -280.993449) (xy 61.418692 -280.975997) (xy 61.376071 -280.95139) (xy 61.33795 -280.920265)
			(xy 61.305315 -280.883428) (xy 61.279012 -280.841832) (xy 61.259721 -280.796556) (xy 61.247944 -280.748772)
			(xy 61.243984 -280.699718) (xy 60.905136 -280.699718) (xy 60.904641 -280.724325) (xy 60.896746 -280.772902)
			(xy 60.881162 -280.819583) (xy 60.858291 -280.86316) (xy 60.828726 -280.902504) (xy 60.793233 -280.936596)
			(xy 60.75273 -280.964552) (xy 60.708268 -280.98565) (xy 60.660997 -280.999342) (xy 60.612142 -281.005274)
			(xy 60.562967 -281.003293) (xy 60.514748 -280.993449) (xy 60.468732 -280.975997) (xy 60.426111 -280.95139)
			(xy 60.38799 -280.920265) (xy 60.355355 -280.883428) (xy 60.329052 -280.841832) (xy 60.309761 -280.796556)
			(xy 60.297984 -280.748772) (xy 60.294024 -280.699718) (xy 59.955176 -280.699718) (xy 59.954681 -280.724325)
			(xy 59.946786 -280.772902) (xy 59.931202 -280.819583) (xy 59.908331 -280.86316) (xy 59.878766 -280.902504)
			(xy 59.843273 -280.936596) (xy 59.80277 -280.964552) (xy 59.758308 -280.98565) (xy 59.711037 -280.999342)
			(xy 59.662182 -281.005274) (xy 59.613007 -281.003293) (xy 59.564788 -280.993449) (xy 59.518772 -280.975997)
			(xy 59.476151 -280.95139) (xy 59.43803 -280.920265) (xy 59.405395 -280.883428) (xy 59.379092 -280.841832)
			(xy 59.359801 -280.796556) (xy 59.348024 -280.748772) (xy 59.344064 -280.699718) (xy 59.005216 -280.699718)
			(xy 59.004721 -280.724325) (xy 58.996826 -280.772902) (xy 58.981242 -280.819583) (xy 58.958371 -280.86316)
			(xy 58.928806 -280.902504) (xy 58.893313 -280.936596) (xy 58.85281 -280.964552) (xy 58.808348 -280.98565)
			(xy 58.761077 -280.999342) (xy 58.712222 -281.005274) (xy 58.663047 -281.003293) (xy 58.614828 -280.993449)
			(xy 58.568812 -280.975997) (xy 58.526191 -280.95139) (xy 58.48807 -280.920265) (xy 58.455435 -280.883428)
			(xy 58.429132 -280.841832) (xy 58.409841 -280.796556) (xy 58.398064 -280.748772) (xy 58.394104 -280.699718)
			(xy 58.055256 -280.699718) (xy 58.054761 -280.724325) (xy 58.046866 -280.772902) (xy 58.031282 -280.819583)
			(xy 58.008411 -280.86316) (xy 57.978846 -280.902504) (xy 57.943353 -280.936596) (xy 57.90285 -280.964552)
			(xy 57.858388 -280.98565) (xy 57.811117 -280.999342) (xy 57.762262 -281.005274) (xy 57.713087 -281.003293)
			(xy 57.664868 -280.993449) (xy 57.618852 -280.975997) (xy 57.576231 -280.95139) (xy 57.53811 -280.920265)
			(xy 57.505475 -280.883428) (xy 57.479172 -280.841832) (xy 57.459881 -280.796556) (xy 57.448104 -280.748772)
			(xy 57.444144 -280.699718) (xy 57.105042 -280.699718) (xy 57.104547 -280.724325) (xy 57.096652 -280.772902)
			(xy 57.081068 -280.819583) (xy 57.058197 -280.86316) (xy 57.028632 -280.902504) (xy 56.993139 -280.936596)
			(xy 56.952636 -280.964552) (xy 56.908174 -280.98565) (xy 56.860903 -280.999342) (xy 56.812048 -281.005274)
			(xy 56.762873 -281.003293) (xy 56.714654 -280.993449) (xy 56.668638 -280.975997) (xy 56.626017 -280.95139)
			(xy 56.587896 -280.920265) (xy 56.555261 -280.883428) (xy 56.528958 -280.841832) (xy 56.509667 -280.796556)
			(xy 56.49789 -280.748772) (xy 56.49393 -280.699718) (xy 56.155082 -280.699718) (xy 56.154587 -280.724325)
			(xy 56.146692 -280.772902) (xy 56.131108 -280.819583) (xy 56.108237 -280.86316) (xy 56.078672 -280.902504)
			(xy 56.043179 -280.936596) (xy 56.002676 -280.964552) (xy 55.958214 -280.98565) (xy 55.910943 -280.999342)
			(xy 55.862088 -281.005274) (xy 55.812913 -281.003293) (xy 55.764694 -280.993449) (xy 55.718678 -280.975997)
			(xy 55.676057 -280.95139) (xy 55.637936 -280.920265) (xy 55.605301 -280.883428) (xy 55.578998 -280.841832)
			(xy 55.559707 -280.796556) (xy 55.54793 -280.748772) (xy 55.54397 -280.699718) (xy 55.205122 -280.699718)
			(xy 55.204627 -280.724325) (xy 55.196732 -280.772902) (xy 55.181148 -280.819583) (xy 55.158277 -280.86316)
			(xy 55.128712 -280.902504) (xy 55.093219 -280.936596) (xy 55.052716 -280.964552) (xy 55.008254 -280.98565)
			(xy 54.960983 -280.999342) (xy 54.912128 -281.005274) (xy 54.862953 -281.003293) (xy 54.814734 -280.993449)
			(xy 54.768718 -280.975997) (xy 54.726097 -280.95139) (xy 54.687976 -280.920265) (xy 54.655341 -280.883428)
			(xy 54.629038 -280.841832) (xy 54.609747 -280.796556) (xy 54.59797 -280.748772) (xy 54.59401 -280.699718)
			(xy 54.255162 -280.699718) (xy 54.254667 -280.724325) (xy 54.246772 -280.772902) (xy 54.231188 -280.819583)
			(xy 54.208317 -280.86316) (xy 54.178752 -280.902504) (xy 54.143259 -280.936596) (xy 54.102756 -280.964552)
			(xy 54.058294 -280.98565) (xy 54.011023 -280.999342) (xy 53.962168 -281.005274) (xy 53.912993 -281.003293)
			(xy 53.864774 -280.993449) (xy 53.818758 -280.975997) (xy 53.776137 -280.95139) (xy 53.738016 -280.920265)
			(xy 53.705381 -280.883428) (xy 53.679078 -280.841832) (xy 53.659787 -280.796556) (xy 53.64801 -280.748772)
			(xy 53.64405 -280.699718) (xy 53.305202 -280.699718) (xy 53.304707 -280.724325) (xy 53.296812 -280.772902)
			(xy 53.281228 -280.819583) (xy 53.258357 -280.86316) (xy 53.228792 -280.902504) (xy 53.193299 -280.936596)
			(xy 53.152796 -280.964552) (xy 53.108334 -280.98565) (xy 53.061063 -280.999342) (xy 53.012208 -281.005274)
			(xy 52.963033 -281.003293) (xy 52.914814 -280.993449) (xy 52.868798 -280.975997) (xy 52.826177 -280.95139)
			(xy 52.788056 -280.920265) (xy 52.755421 -280.883428) (xy 52.729118 -280.841832) (xy 52.709827 -280.796556)
			(xy 52.69805 -280.748772) (xy 52.69409 -280.699718) (xy 52.355242 -280.699718) (xy 52.354747 -280.724325)
			(xy 52.346852 -280.772902) (xy 52.331268 -280.819583) (xy 52.308397 -280.86316) (xy 52.278832 -280.902504)
			(xy 52.243339 -280.936596) (xy 52.202836 -280.964552) (xy 52.158374 -280.98565) (xy 52.111103 -280.999342)
			(xy 52.062248 -281.005274) (xy 52.013073 -281.003293) (xy 51.964854 -280.993449) (xy 51.918838 -280.975997)
			(xy 51.876217 -280.95139) (xy 51.838096 -280.920265) (xy 51.805461 -280.883428) (xy 51.779158 -280.841832)
			(xy 51.759867 -280.796556) (xy 51.74809 -280.748772) (xy 51.74413 -280.699718) (xy 51.405282 -280.699718)
			(xy 51.404787 -280.724325) (xy 51.396892 -280.772902) (xy 51.381308 -280.819583) (xy 51.358437 -280.86316)
			(xy 51.328872 -280.902504) (xy 51.293379 -280.936596) (xy 51.252876 -280.964552) (xy 51.208414 -280.98565)
			(xy 51.161143 -280.999342) (xy 51.112288 -281.005274) (xy 51.063113 -281.003293) (xy 51.014894 -280.993449)
			(xy 50.968878 -280.975997) (xy 50.926257 -280.95139) (xy 50.888136 -280.920265) (xy 50.855501 -280.883428)
			(xy 50.829198 -280.841832) (xy 50.809907 -280.796556) (xy 50.79813 -280.748772) (xy 50.79417 -280.699718)
			(xy 50.455068 -280.699718) (xy 50.454573 -280.724325) (xy 50.446678 -280.772902) (xy 50.431094 -280.819583)
			(xy 50.408223 -280.86316) (xy 50.378658 -280.902504) (xy 50.343165 -280.936596) (xy 50.302662 -280.964552)
			(xy 50.2582 -280.98565) (xy 50.210929 -280.999342) (xy 50.162074 -281.005274) (xy 50.112899 -281.003293)
			(xy 50.06468 -280.993449) (xy 50.018664 -280.975997) (xy 49.976043 -280.95139) (xy 49.937922 -280.920265)
			(xy 49.905287 -280.883428) (xy 49.878984 -280.841832) (xy 49.859693 -280.796556) (xy 49.847916 -280.748772)
			(xy 49.843956 -280.699718) (xy 49.505108 -280.699718) (xy 49.504613 -280.724325) (xy 49.496718 -280.772902)
			(xy 49.481134 -280.819583) (xy 49.458263 -280.86316) (xy 49.428698 -280.902504) (xy 49.393205 -280.936596)
			(xy 49.352702 -280.964552) (xy 49.30824 -280.98565) (xy 49.260969 -280.999342) (xy 49.212114 -281.005274)
			(xy 49.162939 -281.003293) (xy 49.11472 -280.993449) (xy 49.068704 -280.975997) (xy 49.026083 -280.95139)
			(xy 48.987962 -280.920265) (xy 48.955327 -280.883428) (xy 48.929024 -280.841832) (xy 48.909733 -280.796556)
			(xy 48.897956 -280.748772) (xy 48.893996 -280.699718) (xy 48.555612 -280.699718) (xy 48.551443 -280.750031)
			(xy 48.539046 -280.798989) (xy 48.518761 -280.84524) (xy 48.49114 -280.887521) (xy 48.456937 -280.92468)
			(xy 48.417085 -280.955703) (xy 48.372671 -280.979744) (xy 48.324905 -280.996147) (xy 48.275092 -281.004465)
			(xy 48.24984 -281.005026) (xy 48.249586 -281.005026) (xy 48.220887 -281.004372) (xy 48.164504 -280.993627)
			(xy 48.137572 -280.98369) (xy 48.128682 -280.980134) (xy 48.11903 -280.980134) (xy 48.109007 -280.980549)
			(xy 48.090486 -280.988215) (xy 48.076313 -281.002389) (xy 48.068648 -281.020911) (xy 48.06823 -281.030934)
			(xy 48.06823 -281.083512) (xy 48.070008 -281.09672) (xy 48.07077 -281.099768) (xy 48.075157 -281.118189)
			(xy 48.079871 -281.155764) (xy 48.080168 -281.174698) (xy 48.080168 -281.175206) (xy 48.079914 -281.18435)
			(xy 48.079914 -281.191716) (xy 48.079914 -281.195272) (xy 48.07966 -281.19705) (xy 48.07966 -281.198066)
			(xy 48.078408 -281.212275) (xy 48.073571 -281.240388) (xy 48.070008 -281.2542) (xy 48.06823 -281.260804)
			(xy 48.06823 -281.318716) (xy 48.068653 -281.328733) (xy 48.076327 -281.347239) (xy 48.090499 -281.361399)
			(xy 48.109013 -281.369056) (xy 48.11903 -281.369516) (xy 48.128682 -281.369516) (xy 48.137572 -281.36596)
			(xy 48.164509 -281.356043) (xy 48.22089 -281.345308) (xy 48.249586 -281.344624) (xy 48.24984 -281.344624)
			(xy 48.275091 -281.345149) (xy 48.324902 -281.353467) (xy 48.372665 -281.369869) (xy 48.417077 -281.393909)
			(xy 48.456928 -281.424931) (xy 48.491129 -281.462088) (xy 48.518748 -281.504367) (xy 48.539033 -281.550615)
			(xy 48.551429 -281.599571) (xy 48.555599 -281.6499) (xy 48.555596 -281.649932) (xy 48.893996 -281.649932)
			(xy 48.897956 -281.600878) (xy 48.909733 -281.553094) (xy 48.929024 -281.507818) (xy 48.955327 -281.466222)
			(xy 48.987962 -281.429385) (xy 49.026083 -281.39826) (xy 49.068704 -281.373653) (xy 49.11472 -281.356201)
			(xy 49.162939 -281.346357) (xy 49.212114 -281.344376) (xy 49.260969 -281.350308) (xy 49.30824 -281.364)
			(xy 49.352702 -281.385098) (xy 49.393205 -281.413054) (xy 49.428698 -281.447146) (xy 49.458263 -281.48649)
			(xy 49.481134 -281.530067) (xy 49.496718 -281.576748) (xy 49.504613 -281.625325) (xy 49.505108 -281.649932)
			(xy 49.843956 -281.649932) (xy 49.847916 -281.600878) (xy 49.859693 -281.553094) (xy 49.878984 -281.507818)
			(xy 49.905287 -281.466222) (xy 49.937922 -281.429385) (xy 49.976043 -281.39826) (xy 50.018664 -281.373653)
			(xy 50.06468 -281.356201) (xy 50.112899 -281.346357) (xy 50.162074 -281.344376) (xy 50.210929 -281.350308)
			(xy 50.2582 -281.364) (xy 50.302662 -281.385098) (xy 50.343165 -281.413054) (xy 50.378658 -281.447146)
			(xy 50.408223 -281.48649) (xy 50.431094 -281.530067) (xy 50.446678 -281.576748) (xy 50.454573 -281.625325)
			(xy 50.455068 -281.649932) (xy 50.79417 -281.649932) (xy 50.79813 -281.600878) (xy 50.809907 -281.553094)
			(xy 50.829198 -281.507818) (xy 50.855501 -281.466222) (xy 50.888136 -281.429385) (xy 50.926257 -281.39826)
			(xy 50.968878 -281.373653) (xy 51.014894 -281.356201) (xy 51.063113 -281.346357) (xy 51.112288 -281.344376)
			(xy 51.161143 -281.350308) (xy 51.208414 -281.364) (xy 51.252876 -281.385098) (xy 51.293379 -281.413054)
			(xy 51.328872 -281.447146) (xy 51.358437 -281.48649) (xy 51.381308 -281.530067) (xy 51.396892 -281.576748)
			(xy 51.404787 -281.625325) (xy 51.405282 -281.649932) (xy 51.74413 -281.649932) (xy 51.74809 -281.600878)
			(xy 51.759867 -281.553094) (xy 51.779158 -281.507818) (xy 51.805461 -281.466222) (xy 51.838096 -281.429385)
			(xy 51.876217 -281.39826) (xy 51.918838 -281.373653) (xy 51.964854 -281.356201) (xy 52.013073 -281.346357)
			(xy 52.062248 -281.344376) (xy 52.111103 -281.350308) (xy 52.158374 -281.364) (xy 52.202836 -281.385098)
			(xy 52.243339 -281.413054) (xy 52.278832 -281.447146) (xy 52.308397 -281.48649) (xy 52.331268 -281.530067)
			(xy 52.346852 -281.576748) (xy 52.354747 -281.625325) (xy 52.355242 -281.649932) (xy 52.69409 -281.649932)
			(xy 52.69805 -281.600878) (xy 52.709827 -281.553094) (xy 52.729118 -281.507818) (xy 52.755421 -281.466222)
			(xy 52.788056 -281.429385) (xy 52.826177 -281.39826) (xy 52.868798 -281.373653) (xy 52.914814 -281.356201)
			(xy 52.963033 -281.346357) (xy 53.012208 -281.344376) (xy 53.061063 -281.350308) (xy 53.108334 -281.364)
			(xy 53.152796 -281.385098) (xy 53.193299 -281.413054) (xy 53.228792 -281.447146) (xy 53.258357 -281.48649)
			(xy 53.281228 -281.530067) (xy 53.296812 -281.576748) (xy 53.304707 -281.625325) (xy 53.305202 -281.649932)
			(xy 53.305037 -281.658139) (xy 53.644226 -281.658139) (xy 53.64692 -281.608578) (xy 53.657596 -281.560106)
			(xy 53.675973 -281.514) (xy 53.701568 -281.471475) (xy 53.733705 -281.43365) (xy 53.771538 -281.401522)
			(xy 53.81407 -281.375939) (xy 53.860181 -281.357573) (xy 53.908656 -281.346909) (xy 53.958217 -281.344228)
			(xy 54.007559 -281.3496) (xy 54.055382 -281.362884) (xy 54.100426 -281.38373) (xy 54.141504 -281.411589)
			(xy 54.177534 -281.445726) (xy 54.207567 -281.485242) (xy 54.230811 -281.529097) (xy 54.246654 -281.576134)
			(xy 54.254679 -281.625115) (xy 54.255162 -281.649932) (xy 54.254972 -281.664051) (xy 54.252303 -281.692164)
			(xy 54.249828 -281.706066) (xy 54.247542 -281.718512) (xy 54.254908 -281.742388) (xy 54.332378 -281.819858)
			(xy 54.356254 -281.827224) (xy 54.3687 -281.824938) (xy 54.382604 -281.822478) (xy 54.410715 -281.819805)
			(xy 54.424834 -281.819604) (xy 54.438953 -281.819792) (xy 54.467066 -281.822462) (xy 54.480968 -281.824938)
			(xy 54.493414 -281.827224) (xy 54.51729 -281.819858) (xy 54.59476 -281.742388) (xy 54.602126 -281.718512)
			(xy 54.59984 -281.706066) (xy 54.597375 -281.692163) (xy 54.594705 -281.664051) (xy 54.594506 -281.649932)
			(xy 54.594943 -281.625108) (xy 54.60297 -281.576114) (xy 54.618818 -281.529064) (xy 54.642069 -281.485197)
			(xy 54.672111 -281.44567) (xy 54.708151 -281.411524) (xy 54.749242 -281.383659) (xy 54.794299 -281.362808)
			(xy 54.842135 -281.349522) (xy 54.891491 -281.34415) (xy 54.941066 -281.346834) (xy 54.989554 -281.357502)
			(xy 55.035677 -281.375875) (xy 55.07822 -281.401468) (xy 55.116062 -281.433606) (xy 55.148205 -281.471443)
			(xy 55.173804 -281.513982) (xy 55.192184 -281.560102) (xy 55.20286 -281.608588) (xy 55.205104 -281.649932)
			(xy 55.54397 -281.649932) (xy 55.54793 -281.600878) (xy 55.559707 -281.553094) (xy 55.578998 -281.507818)
			(xy 55.605301 -281.466222) (xy 55.637936 -281.429385) (xy 55.676057 -281.39826) (xy 55.718678 -281.373653)
			(xy 55.764694 -281.356201) (xy 55.812913 -281.346357) (xy 55.862088 -281.344376) (xy 55.910943 -281.350308)
			(xy 55.958214 -281.364) (xy 56.002676 -281.385098) (xy 56.043179 -281.413054) (xy 56.078672 -281.447146)
			(xy 56.108237 -281.48649) (xy 56.131108 -281.530067) (xy 56.146692 -281.576748) (xy 56.154587 -281.625325)
			(xy 56.155082 -281.649932) (xy 56.494184 -281.649932) (xy 56.498144 -281.600878) (xy 56.509921 -281.553094)
			(xy 56.529212 -281.507818) (xy 56.555515 -281.466222) (xy 56.58815 -281.429385) (xy 56.626271 -281.39826)
			(xy 56.668892 -281.373653) (xy 56.714908 -281.356201) (xy 56.763127 -281.346357) (xy 56.812302 -281.344376)
			(xy 56.861157 -281.350308) (xy 56.908428 -281.364) (xy 56.95289 -281.385098) (xy 56.993393 -281.413054)
			(xy 57.028886 -281.447146) (xy 57.058451 -281.48649) (xy 57.081322 -281.530067) (xy 57.096906 -281.576748)
			(xy 57.104801 -281.625325) (xy 57.105296 -281.649932) (xy 57.444144 -281.649932) (xy 57.448104 -281.600878)
			(xy 57.459881 -281.553094) (xy 57.479172 -281.507818) (xy 57.505475 -281.466222) (xy 57.53811 -281.429385)
			(xy 57.576231 -281.39826) (xy 57.618852 -281.373653) (xy 57.664868 -281.356201) (xy 57.713087 -281.346357)
			(xy 57.762262 -281.344376) (xy 57.811117 -281.350308) (xy 57.858388 -281.364) (xy 57.90285 -281.385098)
			(xy 57.943353 -281.413054) (xy 57.978846 -281.447146) (xy 58.008411 -281.48649) (xy 58.031282 -281.530067)
			(xy 58.046866 -281.576748) (xy 58.054761 -281.625325) (xy 58.055256 -281.649932) (xy 58.394104 -281.649932)
			(xy 58.398064 -281.600878) (xy 58.409841 -281.553094) (xy 58.429132 -281.507818) (xy 58.455435 -281.466222)
			(xy 58.48807 -281.429385) (xy 58.526191 -281.39826) (xy 58.568812 -281.373653) (xy 58.614828 -281.356201)
			(xy 58.663047 -281.346357) (xy 58.712222 -281.344376) (xy 58.761077 -281.350308) (xy 58.808348 -281.364)
			(xy 58.85281 -281.385098) (xy 58.893313 -281.413054) (xy 58.928806 -281.447146) (xy 58.958371 -281.48649)
			(xy 58.981242 -281.530067) (xy 58.996826 -281.576748) (xy 59.004721 -281.625325) (xy 59.005216 -281.649932)
			(xy 59.344064 -281.649932) (xy 59.348024 -281.600878) (xy 59.359801 -281.553094) (xy 59.379092 -281.507818)
			(xy 59.405395 -281.466222) (xy 59.43803 -281.429385) (xy 59.476151 -281.39826) (xy 59.518772 -281.373653)
			(xy 59.564788 -281.356201) (xy 59.613007 -281.346357) (xy 59.662182 -281.344376) (xy 59.711037 -281.350308)
			(xy 59.758308 -281.364) (xy 59.80277 -281.385098) (xy 59.843273 -281.413054) (xy 59.878766 -281.447146)
			(xy 59.908331 -281.48649) (xy 59.931202 -281.530067) (xy 59.946786 -281.576748) (xy 59.954681 -281.625325)
			(xy 59.955176 -281.649932) (xy 60.294024 -281.649932) (xy 60.297984 -281.600878) (xy 60.309761 -281.553094)
			(xy 60.329052 -281.507818) (xy 60.355355 -281.466222) (xy 60.38799 -281.429385) (xy 60.426111 -281.39826)
			(xy 60.468732 -281.373653) (xy 60.514748 -281.356201) (xy 60.562967 -281.346357) (xy 60.612142 -281.344376)
			(xy 60.660997 -281.350308) (xy 60.708268 -281.364) (xy 60.75273 -281.385098) (xy 60.793233 -281.413054)
			(xy 60.828726 -281.447146) (xy 60.858291 -281.48649) (xy 60.881162 -281.530067) (xy 60.896746 -281.576748)
			(xy 60.904641 -281.625325) (xy 60.905136 -281.649932) (xy 61.243984 -281.649932) (xy 61.247944 -281.600878)
			(xy 61.259721 -281.553094) (xy 61.279012 -281.507818) (xy 61.305315 -281.466222) (xy 61.33795 -281.429385)
			(xy 61.376071 -281.39826) (xy 61.418692 -281.373653) (xy 61.464708 -281.356201) (xy 61.512927 -281.346357)
			(xy 61.562102 -281.344376) (xy 61.610957 -281.350308) (xy 61.658228 -281.364) (xy 61.70269 -281.385098)
			(xy 61.743193 -281.413054) (xy 61.778686 -281.447146) (xy 61.808251 -281.48649) (xy 61.831122 -281.530067)
			(xy 61.846706 -281.576748) (xy 61.854601 -281.625325) (xy 61.855096 -281.649932) (xy 62.193944 -281.649932)
			(xy 62.197904 -281.600878) (xy 62.209681 -281.553094) (xy 62.228972 -281.507818) (xy 62.255275 -281.466222)
			(xy 62.28791 -281.429385) (xy 62.326031 -281.39826) (xy 62.368652 -281.373653) (xy 62.414668 -281.356201)
			(xy 62.462887 -281.346357) (xy 62.512062 -281.344376) (xy 62.560917 -281.350308) (xy 62.608188 -281.364)
			(xy 62.65265 -281.385098) (xy 62.693153 -281.413054) (xy 62.728646 -281.447146) (xy 62.758211 -281.48649)
			(xy 62.781082 -281.530067) (xy 62.796666 -281.576748) (xy 62.804561 -281.625325) (xy 62.805056 -281.649932)
			(xy 63.144158 -281.649932) (xy 63.148118 -281.600878) (xy 63.159895 -281.553094) (xy 63.179186 -281.507818)
			(xy 63.205489 -281.466222) (xy 63.238124 -281.429385) (xy 63.276245 -281.39826) (xy 63.318866 -281.373653)
			(xy 63.364882 -281.356201) (xy 63.413101 -281.346357) (xy 63.462276 -281.344376) (xy 63.511131 -281.350308)
			(xy 63.558402 -281.364) (xy 63.602864 -281.385098) (xy 63.643367 -281.413054) (xy 63.67886 -281.447146)
			(xy 63.708425 -281.48649) (xy 63.731296 -281.530067) (xy 63.74688 -281.576748) (xy 63.754775 -281.625325)
			(xy 63.75527 -281.649932) (xy 64.094118 -281.649932) (xy 64.098078 -281.600878) (xy 64.109855 -281.553094)
			(xy 64.129146 -281.507818) (xy 64.155449 -281.466222) (xy 64.188084 -281.429385) (xy 64.226205 -281.39826)
			(xy 64.268826 -281.373653) (xy 64.314842 -281.356201) (xy 64.363061 -281.346357) (xy 64.412236 -281.344376)
			(xy 64.461091 -281.350308) (xy 64.508362 -281.364) (xy 64.552824 -281.385098) (xy 64.593327 -281.413054)
			(xy 64.62882 -281.447146) (xy 64.658385 -281.48649) (xy 64.681256 -281.530067) (xy 64.69684 -281.576748)
			(xy 64.704735 -281.625325) (xy 64.70523 -281.649932) (xy 65.044078 -281.649932) (xy 65.048038 -281.600878)
			(xy 65.059815 -281.553094) (xy 65.079106 -281.507818) (xy 65.105409 -281.466222) (xy 65.138044 -281.429385)
			(xy 65.176165 -281.39826) (xy 65.218786 -281.373653) (xy 65.264802 -281.356201) (xy 65.313021 -281.346357)
			(xy 65.362196 -281.344376) (xy 65.411051 -281.350308) (xy 65.458322 -281.364) (xy 65.502784 -281.385098)
			(xy 65.543287 -281.413054) (xy 65.57878 -281.447146) (xy 65.608345 -281.48649) (xy 65.631216 -281.530067)
			(xy 65.6468 -281.576748) (xy 65.654695 -281.625325) (xy 65.65519 -281.649932) (xy 65.994038 -281.649932)
			(xy 65.997998 -281.600878) (xy 66.009775 -281.553094) (xy 66.029066 -281.507818) (xy 66.055369 -281.466222)
			(xy 66.088004 -281.429385) (xy 66.126125 -281.39826) (xy 66.168746 -281.373653) (xy 66.214762 -281.356201)
			(xy 66.262981 -281.346357) (xy 66.312156 -281.344376) (xy 66.361011 -281.350308) (xy 66.408282 -281.364)
			(xy 66.452744 -281.385098) (xy 66.493247 -281.413054) (xy 66.52874 -281.447146) (xy 66.558305 -281.48649)
			(xy 66.581176 -281.530067) (xy 66.59676 -281.576748) (xy 66.604655 -281.625325) (xy 66.60515 -281.649932)
			(xy 66.943998 -281.649932) (xy 66.947958 -281.600878) (xy 66.959735 -281.553094) (xy 66.979026 -281.507818)
			(xy 67.005329 -281.466222) (xy 67.037964 -281.429385) (xy 67.076085 -281.39826) (xy 67.118706 -281.373653)
			(xy 67.164722 -281.356201) (xy 67.212941 -281.346357) (xy 67.262116 -281.344376) (xy 67.310971 -281.350308)
			(xy 67.358242 -281.364) (xy 67.402704 -281.385098) (xy 67.443207 -281.413054) (xy 67.4787 -281.447146)
			(xy 67.508265 -281.48649) (xy 67.531136 -281.530067) (xy 67.54672 -281.576748) (xy 67.554615 -281.625325)
			(xy 67.55511 -281.649932) (xy 67.893958 -281.649932) (xy 67.897918 -281.600878) (xy 67.909695 -281.553094)
			(xy 67.928986 -281.507818) (xy 67.955289 -281.466222) (xy 67.987924 -281.429385) (xy 68.026045 -281.39826)
			(xy 68.068666 -281.373653) (xy 68.114682 -281.356201) (xy 68.162901 -281.346357) (xy 68.212076 -281.344376)
			(xy 68.260931 -281.350308) (xy 68.308202 -281.364) (xy 68.352664 -281.385098) (xy 68.393167 -281.413054)
			(xy 68.42866 -281.447146) (xy 68.458225 -281.48649) (xy 68.481096 -281.530067) (xy 68.49668 -281.576748)
			(xy 68.504575 -281.625325) (xy 68.50507 -281.649932) (xy 68.844172 -281.649932) (xy 68.848132 -281.600878)
			(xy 68.859909 -281.553094) (xy 68.8792 -281.507818) (xy 68.905503 -281.466222) (xy 68.938138 -281.429385)
			(xy 68.976259 -281.39826) (xy 69.01888 -281.373653) (xy 69.064896 -281.356201) (xy 69.113115 -281.346357)
			(xy 69.16229 -281.344376) (xy 69.211145 -281.350308) (xy 69.258416 -281.364) (xy 69.302878 -281.385098)
			(xy 69.343381 -281.413054) (xy 69.378874 -281.447146) (xy 69.408439 -281.48649) (xy 69.43131 -281.530067)
			(xy 69.446894 -281.576748) (xy 69.454789 -281.625325) (xy 69.455284 -281.649932) (xy 69.794132 -281.649932)
			(xy 69.798092 -281.600878) (xy 69.809869 -281.553094) (xy 69.82916 -281.507818) (xy 69.855463 -281.466222)
			(xy 69.888098 -281.429385) (xy 69.926219 -281.39826) (xy 69.96884 -281.373653) (xy 70.014856 -281.356201)
			(xy 70.063075 -281.346357) (xy 70.11225 -281.344376) (xy 70.161105 -281.350308) (xy 70.208376 -281.364)
			(xy 70.252838 -281.385098) (xy 70.293341 -281.413054) (xy 70.328834 -281.447146) (xy 70.358399 -281.48649)
			(xy 70.38127 -281.530067) (xy 70.396854 -281.576748) (xy 70.404749 -281.625325) (xy 70.405244 -281.649932)
			(xy 70.744092 -281.649932) (xy 70.748052 -281.600878) (xy 70.759829 -281.553094) (xy 70.77912 -281.507818)
			(xy 70.805423 -281.466222) (xy 70.838058 -281.429385) (xy 70.876179 -281.39826) (xy 70.9188 -281.373653)
			(xy 70.964816 -281.356201) (xy 71.013035 -281.346357) (xy 71.06221 -281.344376) (xy 71.111065 -281.350308)
			(xy 71.158336 -281.364) (xy 71.202798 -281.385098) (xy 71.243301 -281.413054) (xy 71.278794 -281.447146)
			(xy 71.308359 -281.48649) (xy 71.33123 -281.530067) (xy 71.346814 -281.576748) (xy 71.354709 -281.625325)
			(xy 71.355204 -281.649932) (xy 71.694052 -281.649932) (xy 71.698012 -281.600878) (xy 71.709789 -281.553094)
			(xy 71.72908 -281.507818) (xy 71.755383 -281.466222) (xy 71.788018 -281.429385) (xy 71.826139 -281.39826)
			(xy 71.86876 -281.373653) (xy 71.914776 -281.356201) (xy 71.962995 -281.346357) (xy 72.01217 -281.344376)
			(xy 72.061025 -281.350308) (xy 72.108296 -281.364) (xy 72.152758 -281.385098) (xy 72.193261 -281.413054)
			(xy 72.228754 -281.447146) (xy 72.258319 -281.48649) (xy 72.28119 -281.530067) (xy 72.296774 -281.576748)
			(xy 72.304669 -281.625325) (xy 72.305164 -281.649932) (xy 72.644012 -281.649932) (xy 72.647972 -281.600878)
			(xy 72.659749 -281.553094) (xy 72.67904 -281.507818) (xy 72.705343 -281.466222) (xy 72.737978 -281.429385)
			(xy 72.776099 -281.39826) (xy 72.81872 -281.373653) (xy 72.864736 -281.356201) (xy 72.912955 -281.346357)
			(xy 72.96213 -281.344376) (xy 73.010985 -281.350308) (xy 73.058256 -281.364) (xy 73.102718 -281.385098)
			(xy 73.143221 -281.413054) (xy 73.178714 -281.447146) (xy 73.208279 -281.48649) (xy 73.23115 -281.530067)
			(xy 73.246734 -281.576748) (xy 73.254629 -281.625325) (xy 73.255124 -281.649932) (xy 73.593972 -281.649932)
			(xy 73.597932 -281.600878) (xy 73.609709 -281.553094) (xy 73.629 -281.507818) (xy 73.655303 -281.466222)
			(xy 73.687938 -281.429385) (xy 73.726059 -281.39826) (xy 73.76868 -281.373653) (xy 73.814696 -281.356201)
			(xy 73.862915 -281.346357) (xy 73.91209 -281.344376) (xy 73.960945 -281.350308) (xy 74.008216 -281.364)
			(xy 74.052678 -281.385098) (xy 74.093181 -281.413054) (xy 74.128674 -281.447146) (xy 74.158239 -281.48649)
			(xy 74.18111 -281.530067) (xy 74.196694 -281.576748) (xy 74.204589 -281.625325) (xy 74.205084 -281.649932)
			(xy 74.544186 -281.649932) (xy 74.548146 -281.600878) (xy 74.559923 -281.553094) (xy 74.579214 -281.507818)
			(xy 74.605517 -281.466222) (xy 74.638152 -281.429385) (xy 74.676273 -281.39826) (xy 74.718894 -281.373653)
			(xy 74.76491 -281.356201) (xy 74.813129 -281.346357) (xy 74.862304 -281.344376) (xy 74.911159 -281.350308)
			(xy 74.95843 -281.364) (xy 75.002892 -281.385098) (xy 75.043395 -281.413054) (xy 75.078888 -281.447146)
			(xy 75.108453 -281.48649) (xy 75.131324 -281.530067) (xy 75.146908 -281.576748) (xy 75.154803 -281.625325)
			(xy 75.155298 -281.649932) (xy 75.494146 -281.649932) (xy 75.498106 -281.600878) (xy 75.509883 -281.553094)
			(xy 75.529174 -281.507818) (xy 75.555477 -281.466222) (xy 75.588112 -281.429385) (xy 75.626233 -281.39826)
			(xy 75.668854 -281.373653) (xy 75.71487 -281.356201) (xy 75.763089 -281.346357) (xy 75.812264 -281.344376)
			(xy 75.861119 -281.350308) (xy 75.90839 -281.364) (xy 75.952852 -281.385098) (xy 75.993355 -281.413054)
			(xy 76.028848 -281.447146) (xy 76.058413 -281.48649) (xy 76.081284 -281.530067) (xy 76.096868 -281.576748)
			(xy 76.104763 -281.625325) (xy 76.105258 -281.649932) (xy 76.444106 -281.649932) (xy 76.448066 -281.600878)
			(xy 76.459843 -281.553094) (xy 76.479134 -281.507818) (xy 76.505437 -281.466222) (xy 76.538072 -281.429385)
			(xy 76.576193 -281.39826) (xy 76.618814 -281.373653) (xy 76.66483 -281.356201) (xy 76.713049 -281.346357)
			(xy 76.762224 -281.344376) (xy 76.811079 -281.350308) (xy 76.85835 -281.364) (xy 76.902812 -281.385098)
			(xy 76.943315 -281.413054) (xy 76.978808 -281.447146) (xy 77.008373 -281.48649) (xy 77.031244 -281.530067)
			(xy 77.046828 -281.576748) (xy 77.054723 -281.625325) (xy 77.055213 -281.649678) (xy 77.393812 -281.649678)
			(xy 77.397772 -281.600624) (xy 77.409549 -281.55284) (xy 77.42884 -281.507564) (xy 77.455143 -281.465968)
			(xy 77.487778 -281.429131) (xy 77.525899 -281.398006) (xy 77.56852 -281.373399) (xy 77.614536 -281.355947)
			(xy 77.662755 -281.346103) (xy 77.71193 -281.344122) (xy 77.760785 -281.350054) (xy 77.808056 -281.363746)
			(xy 77.852518 -281.384844) (xy 77.893021 -281.4128) (xy 77.928514 -281.446892) (xy 77.958079 -281.486236)
			(xy 77.98095 -281.529813) (xy 77.996534 -281.576494) (xy 78.004429 -281.625071) (xy 78.004924 -281.649678)
			(xy 78.004919 -281.649932) (xy 78.343772 -281.649932) (xy 78.347732 -281.600878) (xy 78.359509 -281.553094)
			(xy 78.3788 -281.507818) (xy 78.405103 -281.466222) (xy 78.437738 -281.429385) (xy 78.475859 -281.39826)
			(xy 78.51848 -281.373653) (xy 78.564496 -281.356201) (xy 78.612715 -281.346357) (xy 78.66189 -281.344376)
			(xy 78.710745 -281.350308) (xy 78.758016 -281.364) (xy 78.802478 -281.385098) (xy 78.842981 -281.413054)
			(xy 78.878474 -281.447146) (xy 78.908039 -281.48649) (xy 78.93091 -281.530067) (xy 78.946494 -281.576748)
			(xy 78.954389 -281.625325) (xy 78.954884 -281.649932) (xy 79.293986 -281.649932) (xy 79.297946 -281.600878)
			(xy 79.309723 -281.553094) (xy 79.329014 -281.507818) (xy 79.355317 -281.466222) (xy 79.387952 -281.429385)
			(xy 79.426073 -281.39826) (xy 79.468694 -281.373653) (xy 79.51471 -281.356201) (xy 79.562929 -281.346357)
			(xy 79.612104 -281.344376) (xy 79.660959 -281.350308) (xy 79.70823 -281.364) (xy 79.752692 -281.385098)
			(xy 79.793195 -281.413054) (xy 79.828688 -281.447146) (xy 79.858253 -281.48649) (xy 79.881124 -281.530067)
			(xy 79.896708 -281.576748) (xy 79.904603 -281.625325) (xy 79.905098 -281.649932) (xy 80.243946 -281.649932)
			(xy 80.247906 -281.600878) (xy 80.259683 -281.553094) (xy 80.278974 -281.507818) (xy 80.305277 -281.466222)
			(xy 80.337912 -281.429385) (xy 80.376033 -281.39826) (xy 80.418654 -281.373653) (xy 80.46467 -281.356201)
			(xy 80.512889 -281.346357) (xy 80.562064 -281.344376) (xy 80.610919 -281.350308) (xy 80.65819 -281.364)
			(xy 80.702652 -281.385098) (xy 80.743155 -281.413054) (xy 80.778648 -281.447146) (xy 80.808213 -281.48649)
			(xy 80.831084 -281.530067) (xy 80.846668 -281.576748) (xy 80.854563 -281.625325) (xy 80.855058 -281.649932)
			(xy 80.854563 -281.674539) (xy 80.854384 -281.67564) (xy 81.173316 -281.67564) (xy 81.173316 -281.624224)
			(xy 81.181359 -281.573442) (xy 81.197247 -281.524543) (xy 81.22059 -281.478731) (xy 81.250811 -281.437135)
			(xy 81.287167 -281.400779) (xy 81.328763 -281.370558) (xy 81.374575 -281.347215) (xy 81.423474 -281.331327)
			(xy 81.474256 -281.323284) (xy 81.525672 -281.323284) (xy 81.576454 -281.331327) (xy 81.625353 -281.347215)
			(xy 81.671165 -281.370558) (xy 81.712761 -281.400779) (xy 81.749117 -281.437135) (xy 81.779338 -281.478731)
			(xy 81.802681 -281.524543) (xy 81.818569 -281.573442) (xy 81.826612 -281.624224) (xy 81.827116 -281.649932)
			(xy 81.826612 -281.67564) (xy 82.123276 -281.67564) (xy 82.123276 -281.624224) (xy 82.131319 -281.573442)
			(xy 82.147207 -281.524543) (xy 82.17055 -281.478731) (xy 82.200771 -281.437135) (xy 82.237127 -281.400779)
			(xy 82.278723 -281.370558) (xy 82.324535 -281.347215) (xy 82.373434 -281.331327) (xy 82.424216 -281.323284)
			(xy 82.475632 -281.323284) (xy 82.526414 -281.331327) (xy 82.575313 -281.347215) (xy 82.621125 -281.370558)
			(xy 82.662721 -281.400779) (xy 82.699077 -281.437135) (xy 82.729298 -281.478731) (xy 82.752641 -281.524543)
			(xy 82.768529 -281.573442) (xy 82.776572 -281.624224) (xy 82.777076 -281.649932) (xy 82.777071 -281.650186)
			(xy 83.094334 -281.650186) (xy 83.098294 -281.601132) (xy 83.110071 -281.553348) (xy 83.129362 -281.508072)
			(xy 83.155665 -281.466476) (xy 83.1883 -281.429639) (xy 83.226421 -281.398514) (xy 83.269042 -281.373907)
			(xy 83.315058 -281.356455) (xy 83.363277 -281.346611) (xy 83.412452 -281.34463) (xy 83.461307 -281.350562)
			(xy 83.508578 -281.364254) (xy 83.55304 -281.385352) (xy 83.593543 -281.413308) (xy 83.629036 -281.4474)
			(xy 83.658601 -281.486744) (xy 83.681472 -281.530321) (xy 83.697056 -281.577002) (xy 83.704951 -281.625579)
			(xy 83.705446 -281.650186) (xy 83.704951 -281.674793) (xy 83.697056 -281.72337) (xy 83.681472 -281.770051)
			(xy 83.658601 -281.813628) (xy 83.629036 -281.852972) (xy 83.593543 -281.887064) (xy 83.55304 -281.91502)
			(xy 83.508578 -281.936118) (xy 83.461307 -281.94981) (xy 83.412452 -281.955742) (xy 83.363277 -281.953761)
			(xy 83.315058 -281.943917) (xy 83.269042 -281.926465) (xy 83.226421 -281.901858) (xy 83.1883 -281.870733)
			(xy 83.155665 -281.833896) (xy 83.129362 -281.7923) (xy 83.110071 -281.747024) (xy 83.098294 -281.69924)
			(xy 83.094334 -281.650186) (xy 82.777071 -281.650186) (xy 82.776572 -281.67564) (xy 82.768529 -281.726422)
			(xy 82.752641 -281.775321) (xy 82.729298 -281.821133) (xy 82.699077 -281.862729) (xy 82.662721 -281.899085)
			(xy 82.621125 -281.929306) (xy 82.575313 -281.952649) (xy 82.526414 -281.968537) (xy 82.475632 -281.97658)
			(xy 82.424216 -281.97658) (xy 82.373434 -281.968537) (xy 82.324535 -281.952649) (xy 82.278723 -281.929306)
			(xy 82.237127 -281.899085) (xy 82.200771 -281.862729) (xy 82.17055 -281.821133) (xy 82.147207 -281.775321)
			(xy 82.131319 -281.726422) (xy 82.123276 -281.67564) (xy 81.826612 -281.67564) (xy 81.818569 -281.726422)
			(xy 81.802681 -281.775321) (xy 81.779338 -281.821133) (xy 81.749117 -281.862729) (xy 81.712761 -281.899085)
			(xy 81.671165 -281.929306) (xy 81.625353 -281.952649) (xy 81.576454 -281.968537) (xy 81.525672 -281.97658)
			(xy 81.474256 -281.97658) (xy 81.423474 -281.968537) (xy 81.374575 -281.952649) (xy 81.328763 -281.929306)
			(xy 81.287167 -281.899085) (xy 81.250811 -281.862729) (xy 81.22059 -281.821133) (xy 81.197247 -281.775321)
			(xy 81.181359 -281.726422) (xy 81.173316 -281.67564) (xy 80.854384 -281.67564) (xy 80.846668 -281.723116)
			(xy 80.831084 -281.769797) (xy 80.808213 -281.813374) (xy 80.778648 -281.852718) (xy 80.743155 -281.88681)
			(xy 80.702652 -281.914766) (xy 80.65819 -281.935864) (xy 80.610919 -281.949556) (xy 80.562064 -281.955488)
			(xy 80.512889 -281.953507) (xy 80.46467 -281.943663) (xy 80.418654 -281.926211) (xy 80.376033 -281.901604)
			(xy 80.337912 -281.870479) (xy 80.305277 -281.833642) (xy 80.278974 -281.792046) (xy 80.259683 -281.74677)
			(xy 80.247906 -281.698986) (xy 80.243946 -281.649932) (xy 79.905098 -281.649932) (xy 79.904603 -281.674539)
			(xy 79.896708 -281.723116) (xy 79.881124 -281.769797) (xy 79.858253 -281.813374) (xy 79.828688 -281.852718)
			(xy 79.793195 -281.88681) (xy 79.752692 -281.914766) (xy 79.70823 -281.935864) (xy 79.660959 -281.949556)
			(xy 79.612104 -281.955488) (xy 79.562929 -281.953507) (xy 79.51471 -281.943663) (xy 79.468694 -281.926211)
			(xy 79.426073 -281.901604) (xy 79.387952 -281.870479) (xy 79.355317 -281.833642) (xy 79.329014 -281.792046)
			(xy 79.309723 -281.74677) (xy 79.297946 -281.698986) (xy 79.293986 -281.649932) (xy 78.954884 -281.649932)
			(xy 78.954389 -281.674539) (xy 78.946494 -281.723116) (xy 78.93091 -281.769797) (xy 78.908039 -281.813374)
			(xy 78.878474 -281.852718) (xy 78.842981 -281.88681) (xy 78.802478 -281.914766) (xy 78.758016 -281.935864)
			(xy 78.710745 -281.949556) (xy 78.66189 -281.955488) (xy 78.612715 -281.953507) (xy 78.564496 -281.943663)
			(xy 78.51848 -281.926211) (xy 78.475859 -281.901604) (xy 78.437738 -281.870479) (xy 78.405103 -281.833642)
			(xy 78.3788 -281.792046) (xy 78.359509 -281.74677) (xy 78.347732 -281.698986) (xy 78.343772 -281.649932)
			(xy 78.004919 -281.649932) (xy 78.004429 -281.674285) (xy 77.996534 -281.722862) (xy 77.98095 -281.769543)
			(xy 77.958079 -281.81312) (xy 77.928514 -281.852464) (xy 77.893021 -281.886556) (xy 77.852518 -281.914512)
			(xy 77.808056 -281.93561) (xy 77.760785 -281.949302) (xy 77.71193 -281.955234) (xy 77.662755 -281.953253)
			(xy 77.614536 -281.943409) (xy 77.56852 -281.925957) (xy 77.525899 -281.90135) (xy 77.487778 -281.870225)
			(xy 77.455143 -281.833388) (xy 77.42884 -281.791792) (xy 77.409549 -281.746516) (xy 77.397772 -281.698732)
			(xy 77.393812 -281.649678) (xy 77.055213 -281.649678) (xy 77.055218 -281.649932) (xy 77.054723 -281.674539)
			(xy 77.046828 -281.723116) (xy 77.031244 -281.769797) (xy 77.008373 -281.813374) (xy 76.978808 -281.852718)
			(xy 76.943315 -281.88681) (xy 76.902812 -281.914766) (xy 76.85835 -281.935864) (xy 76.811079 -281.949556)
			(xy 76.762224 -281.955488) (xy 76.713049 -281.953507) (xy 76.66483 -281.943663) (xy 76.618814 -281.926211)
			(xy 76.576193 -281.901604) (xy 76.538072 -281.870479) (xy 76.505437 -281.833642) (xy 76.479134 -281.792046)
			(xy 76.459843 -281.74677) (xy 76.448066 -281.698986) (xy 76.444106 -281.649932) (xy 76.105258 -281.649932)
			(xy 76.104763 -281.674539) (xy 76.096868 -281.723116) (xy 76.081284 -281.769797) (xy 76.058413 -281.813374)
			(xy 76.028848 -281.852718) (xy 75.993355 -281.88681) (xy 75.952852 -281.914766) (xy 75.90839 -281.935864)
			(xy 75.861119 -281.949556) (xy 75.812264 -281.955488) (xy 75.763089 -281.953507) (xy 75.71487 -281.943663)
			(xy 75.668854 -281.926211) (xy 75.626233 -281.901604) (xy 75.588112 -281.870479) (xy 75.555477 -281.833642)
			(xy 75.529174 -281.792046) (xy 75.509883 -281.74677) (xy 75.498106 -281.698986) (xy 75.494146 -281.649932)
			(xy 75.155298 -281.649932) (xy 75.154803 -281.674539) (xy 75.146908 -281.723116) (xy 75.131324 -281.769797)
			(xy 75.108453 -281.813374) (xy 75.078888 -281.852718) (xy 75.043395 -281.88681) (xy 75.002892 -281.914766)
			(xy 74.95843 -281.935864) (xy 74.911159 -281.949556) (xy 74.862304 -281.955488) (xy 74.813129 -281.953507)
			(xy 74.76491 -281.943663) (xy 74.718894 -281.926211) (xy 74.676273 -281.901604) (xy 74.638152 -281.870479)
			(xy 74.605517 -281.833642) (xy 74.579214 -281.792046) (xy 74.559923 -281.74677) (xy 74.548146 -281.698986)
			(xy 74.544186 -281.649932) (xy 74.205084 -281.649932) (xy 74.204589 -281.674539) (xy 74.196694 -281.723116)
			(xy 74.18111 -281.769797) (xy 74.158239 -281.813374) (xy 74.128674 -281.852718) (xy 74.093181 -281.88681)
			(xy 74.052678 -281.914766) (xy 74.008216 -281.935864) (xy 73.960945 -281.949556) (xy 73.91209 -281.955488)
			(xy 73.862915 -281.953507) (xy 73.814696 -281.943663) (xy 73.76868 -281.926211) (xy 73.726059 -281.901604)
			(xy 73.687938 -281.870479) (xy 73.655303 -281.833642) (xy 73.629 -281.792046) (xy 73.609709 -281.74677)
			(xy 73.597932 -281.698986) (xy 73.593972 -281.649932) (xy 73.255124 -281.649932) (xy 73.254629 -281.674539)
			(xy 73.246734 -281.723116) (xy 73.23115 -281.769797) (xy 73.208279 -281.813374) (xy 73.178714 -281.852718)
			(xy 73.143221 -281.88681) (xy 73.102718 -281.914766) (xy 73.058256 -281.935864) (xy 73.010985 -281.949556)
			(xy 72.96213 -281.955488) (xy 72.912955 -281.953507) (xy 72.864736 -281.943663) (xy 72.81872 -281.926211)
			(xy 72.776099 -281.901604) (xy 72.737978 -281.870479) (xy 72.705343 -281.833642) (xy 72.67904 -281.792046)
			(xy 72.659749 -281.74677) (xy 72.647972 -281.698986) (xy 72.644012 -281.649932) (xy 72.305164 -281.649932)
			(xy 72.304669 -281.674539) (xy 72.296774 -281.723116) (xy 72.28119 -281.769797) (xy 72.258319 -281.813374)
			(xy 72.228754 -281.852718) (xy 72.193261 -281.88681) (xy 72.152758 -281.914766) (xy 72.108296 -281.935864)
			(xy 72.061025 -281.949556) (xy 72.01217 -281.955488) (xy 71.962995 -281.953507) (xy 71.914776 -281.943663)
			(xy 71.86876 -281.926211) (xy 71.826139 -281.901604) (xy 71.788018 -281.870479) (xy 71.755383 -281.833642)
			(xy 71.72908 -281.792046) (xy 71.709789 -281.74677) (xy 71.698012 -281.698986) (xy 71.694052 -281.649932)
			(xy 71.355204 -281.649932) (xy 71.354709 -281.674539) (xy 71.346814 -281.723116) (xy 71.33123 -281.769797)
			(xy 71.308359 -281.813374) (xy 71.278794 -281.852718) (xy 71.243301 -281.88681) (xy 71.202798 -281.914766)
			(xy 71.158336 -281.935864) (xy 71.111065 -281.949556) (xy 71.06221 -281.955488) (xy 71.013035 -281.953507)
			(xy 70.964816 -281.943663) (xy 70.9188 -281.926211) (xy 70.876179 -281.901604) (xy 70.838058 -281.870479)
			(xy 70.805423 -281.833642) (xy 70.77912 -281.792046) (xy 70.759829 -281.74677) (xy 70.748052 -281.698986)
			(xy 70.744092 -281.649932) (xy 70.405244 -281.649932) (xy 70.404749 -281.674539) (xy 70.396854 -281.723116)
			(xy 70.38127 -281.769797) (xy 70.358399 -281.813374) (xy 70.328834 -281.852718) (xy 70.293341 -281.88681)
			(xy 70.252838 -281.914766) (xy 70.208376 -281.935864) (xy 70.161105 -281.949556) (xy 70.11225 -281.955488)
			(xy 70.063075 -281.953507) (xy 70.014856 -281.943663) (xy 69.96884 -281.926211) (xy 69.926219 -281.901604)
			(xy 69.888098 -281.870479) (xy 69.855463 -281.833642) (xy 69.82916 -281.792046) (xy 69.809869 -281.74677)
			(xy 69.798092 -281.698986) (xy 69.794132 -281.649932) (xy 69.455284 -281.649932) (xy 69.454789 -281.674539)
			(xy 69.446894 -281.723116) (xy 69.43131 -281.769797) (xy 69.408439 -281.813374) (xy 69.378874 -281.852718)
			(xy 69.343381 -281.88681) (xy 69.302878 -281.914766) (xy 69.258416 -281.935864) (xy 69.211145 -281.949556)
			(xy 69.16229 -281.955488) (xy 69.113115 -281.953507) (xy 69.064896 -281.943663) (xy 69.01888 -281.926211)
			(xy 68.976259 -281.901604) (xy 68.938138 -281.870479) (xy 68.905503 -281.833642) (xy 68.8792 -281.792046)
			(xy 68.859909 -281.74677) (xy 68.848132 -281.698986) (xy 68.844172 -281.649932) (xy 68.50507 -281.649932)
			(xy 68.504575 -281.674539) (xy 68.49668 -281.723116) (xy 68.481096 -281.769797) (xy 68.458225 -281.813374)
			(xy 68.42866 -281.852718) (xy 68.393167 -281.88681) (xy 68.352664 -281.914766) (xy 68.308202 -281.935864)
			(xy 68.260931 -281.949556) (xy 68.212076 -281.955488) (xy 68.162901 -281.953507) (xy 68.114682 -281.943663)
			(xy 68.068666 -281.926211) (xy 68.026045 -281.901604) (xy 67.987924 -281.870479) (xy 67.955289 -281.833642)
			(xy 67.928986 -281.792046) (xy 67.909695 -281.74677) (xy 67.897918 -281.698986) (xy 67.893958 -281.649932)
			(xy 67.55511 -281.649932) (xy 67.554615 -281.674539) (xy 67.54672 -281.723116) (xy 67.531136 -281.769797)
			(xy 67.508265 -281.813374) (xy 67.4787 -281.852718) (xy 67.443207 -281.88681) (xy 67.402704 -281.914766)
			(xy 67.358242 -281.935864) (xy 67.310971 -281.949556) (xy 67.262116 -281.955488) (xy 67.212941 -281.953507)
			(xy 67.164722 -281.943663) (xy 67.118706 -281.926211) (xy 67.076085 -281.901604) (xy 67.037964 -281.870479)
			(xy 67.005329 -281.833642) (xy 66.979026 -281.792046) (xy 66.959735 -281.74677) (xy 66.947958 -281.698986)
			(xy 66.943998 -281.649932) (xy 66.60515 -281.649932) (xy 66.604655 -281.674539) (xy 66.59676 -281.723116)
			(xy 66.581176 -281.769797) (xy 66.558305 -281.813374) (xy 66.52874 -281.852718) (xy 66.493247 -281.88681)
			(xy 66.452744 -281.914766) (xy 66.408282 -281.935864) (xy 66.361011 -281.949556) (xy 66.312156 -281.955488)
			(xy 66.262981 -281.953507) (xy 66.214762 -281.943663) (xy 66.168746 -281.926211) (xy 66.126125 -281.901604)
			(xy 66.088004 -281.870479) (xy 66.055369 -281.833642) (xy 66.029066 -281.792046) (xy 66.009775 -281.74677)
			(xy 65.997998 -281.698986) (xy 65.994038 -281.649932) (xy 65.65519 -281.649932) (xy 65.654695 -281.674539)
			(xy 65.6468 -281.723116) (xy 65.631216 -281.769797) (xy 65.608345 -281.813374) (xy 65.57878 -281.852718)
			(xy 65.543287 -281.88681) (xy 65.502784 -281.914766) (xy 65.458322 -281.935864) (xy 65.411051 -281.949556)
			(xy 65.362196 -281.955488) (xy 65.313021 -281.953507) (xy 65.264802 -281.943663) (xy 65.218786 -281.926211)
			(xy 65.176165 -281.901604) (xy 65.138044 -281.870479) (xy 65.105409 -281.833642) (xy 65.079106 -281.792046)
			(xy 65.059815 -281.74677) (xy 65.048038 -281.698986) (xy 65.044078 -281.649932) (xy 64.70523 -281.649932)
			(xy 64.704735 -281.674539) (xy 64.69684 -281.723116) (xy 64.681256 -281.769797) (xy 64.658385 -281.813374)
			(xy 64.62882 -281.852718) (xy 64.593327 -281.88681) (xy 64.552824 -281.914766) (xy 64.508362 -281.935864)
			(xy 64.461091 -281.949556) (xy 64.412236 -281.955488) (xy 64.363061 -281.953507) (xy 64.314842 -281.943663)
			(xy 64.268826 -281.926211) (xy 64.226205 -281.901604) (xy 64.188084 -281.870479) (xy 64.155449 -281.833642)
			(xy 64.129146 -281.792046) (xy 64.109855 -281.74677) (xy 64.098078 -281.698986) (xy 64.094118 -281.649932)
			(xy 63.75527 -281.649932) (xy 63.754775 -281.674539) (xy 63.74688 -281.723116) (xy 63.731296 -281.769797)
			(xy 63.708425 -281.813374) (xy 63.67886 -281.852718) (xy 63.643367 -281.88681) (xy 63.602864 -281.914766)
			(xy 63.558402 -281.935864) (xy 63.511131 -281.949556) (xy 63.462276 -281.955488) (xy 63.413101 -281.953507)
			(xy 63.364882 -281.943663) (xy 63.318866 -281.926211) (xy 63.276245 -281.901604) (xy 63.238124 -281.870479)
			(xy 63.205489 -281.833642) (xy 63.179186 -281.792046) (xy 63.159895 -281.74677) (xy 63.148118 -281.698986)
			(xy 63.144158 -281.649932) (xy 62.805056 -281.649932) (xy 62.804561 -281.674539) (xy 62.796666 -281.723116)
			(xy 62.781082 -281.769797) (xy 62.758211 -281.813374) (xy 62.728646 -281.852718) (xy 62.693153 -281.88681)
			(xy 62.65265 -281.914766) (xy 62.608188 -281.935864) (xy 62.560917 -281.949556) (xy 62.512062 -281.955488)
			(xy 62.462887 -281.953507) (xy 62.414668 -281.943663) (xy 62.368652 -281.926211) (xy 62.326031 -281.901604)
			(xy 62.28791 -281.870479) (xy 62.255275 -281.833642) (xy 62.228972 -281.792046) (xy 62.209681 -281.74677)
			(xy 62.197904 -281.698986) (xy 62.193944 -281.649932) (xy 61.855096 -281.649932) (xy 61.854601 -281.674539)
			(xy 61.846706 -281.723116) (xy 61.831122 -281.769797) (xy 61.808251 -281.813374) (xy 61.778686 -281.852718)
			(xy 61.743193 -281.88681) (xy 61.70269 -281.914766) (xy 61.658228 -281.935864) (xy 61.610957 -281.949556)
			(xy 61.562102 -281.955488) (xy 61.512927 -281.953507) (xy 61.464708 -281.943663) (xy 61.418692 -281.926211)
			(xy 61.376071 -281.901604) (xy 61.33795 -281.870479) (xy 61.305315 -281.833642) (xy 61.279012 -281.792046)
			(xy 61.259721 -281.74677) (xy 61.247944 -281.698986) (xy 61.243984 -281.649932) (xy 60.905136 -281.649932)
			(xy 60.904641 -281.674539) (xy 60.896746 -281.723116) (xy 60.881162 -281.769797) (xy 60.858291 -281.813374)
			(xy 60.828726 -281.852718) (xy 60.793233 -281.88681) (xy 60.75273 -281.914766) (xy 60.708268 -281.935864)
			(xy 60.660997 -281.949556) (xy 60.612142 -281.955488) (xy 60.562967 -281.953507) (xy 60.514748 -281.943663)
			(xy 60.468732 -281.926211) (xy 60.426111 -281.901604) (xy 60.38799 -281.870479) (xy 60.355355 -281.833642)
			(xy 60.329052 -281.792046) (xy 60.309761 -281.74677) (xy 60.297984 -281.698986) (xy 60.294024 -281.649932)
			(xy 59.955176 -281.649932) (xy 59.954681 -281.674539) (xy 59.946786 -281.723116) (xy 59.931202 -281.769797)
			(xy 59.908331 -281.813374) (xy 59.878766 -281.852718) (xy 59.843273 -281.88681) (xy 59.80277 -281.914766)
			(xy 59.758308 -281.935864) (xy 59.711037 -281.949556) (xy 59.662182 -281.955488) (xy 59.613007 -281.953507)
			(xy 59.564788 -281.943663) (xy 59.518772 -281.926211) (xy 59.476151 -281.901604) (xy 59.43803 -281.870479)
			(xy 59.405395 -281.833642) (xy 59.379092 -281.792046) (xy 59.359801 -281.74677) (xy 59.348024 -281.698986)
			(xy 59.344064 -281.649932) (xy 59.005216 -281.649932) (xy 59.004721 -281.674539) (xy 58.996826 -281.723116)
			(xy 58.981242 -281.769797) (xy 58.958371 -281.813374) (xy 58.928806 -281.852718) (xy 58.893313 -281.88681)
			(xy 58.85281 -281.914766) (xy 58.808348 -281.935864) (xy 58.761077 -281.949556) (xy 58.712222 -281.955488)
			(xy 58.663047 -281.953507) (xy 58.614828 -281.943663) (xy 58.568812 -281.926211) (xy 58.526191 -281.901604)
			(xy 58.48807 -281.870479) (xy 58.455435 -281.833642) (xy 58.429132 -281.792046) (xy 58.409841 -281.74677)
			(xy 58.398064 -281.698986) (xy 58.394104 -281.649932) (xy 58.055256 -281.649932) (xy 58.054761 -281.674539)
			(xy 58.046866 -281.723116) (xy 58.031282 -281.769797) (xy 58.008411 -281.813374) (xy 57.978846 -281.852718)
			(xy 57.943353 -281.88681) (xy 57.90285 -281.914766) (xy 57.858388 -281.935864) (xy 57.811117 -281.949556)
			(xy 57.762262 -281.955488) (xy 57.713087 -281.953507) (xy 57.664868 -281.943663) (xy 57.618852 -281.926211)
			(xy 57.576231 -281.901604) (xy 57.53811 -281.870479) (xy 57.505475 -281.833642) (xy 57.479172 -281.792046)
			(xy 57.459881 -281.74677) (xy 57.448104 -281.698986) (xy 57.444144 -281.649932) (xy 57.105296 -281.649932)
			(xy 57.104801 -281.674539) (xy 57.096906 -281.723116) (xy 57.081322 -281.769797) (xy 57.058451 -281.813374)
			(xy 57.028886 -281.852718) (xy 56.993393 -281.88681) (xy 56.95289 -281.914766) (xy 56.908428 -281.935864)
			(xy 56.861157 -281.949556) (xy 56.812302 -281.955488) (xy 56.763127 -281.953507) (xy 56.714908 -281.943663)
			(xy 56.668892 -281.926211) (xy 56.626271 -281.901604) (xy 56.58815 -281.870479) (xy 56.555515 -281.833642)
			(xy 56.529212 -281.792046) (xy 56.509921 -281.74677) (xy 56.498144 -281.698986) (xy 56.494184 -281.649932)
			(xy 56.155082 -281.649932) (xy 56.154587 -281.674539) (xy 56.146692 -281.723116) (xy 56.131108 -281.769797)
			(xy 56.108237 -281.813374) (xy 56.078672 -281.852718) (xy 56.043179 -281.88681) (xy 56.002676 -281.914766)
			(xy 55.958214 -281.935864) (xy 55.910943 -281.949556) (xy 55.862088 -281.955488) (xy 55.812913 -281.953507)
			(xy 55.764694 -281.943663) (xy 55.718678 -281.926211) (xy 55.676057 -281.901604) (xy 55.637936 -281.870479)
			(xy 55.605301 -281.833642) (xy 55.578998 -281.792046) (xy 55.559707 -281.74677) (xy 55.54793 -281.698986)
			(xy 55.54397 -281.649932) (xy 55.205104 -281.649932) (xy 55.205551 -281.658163) (xy 55.200187 -281.707519)
			(xy 55.186908 -281.755358) (xy 55.166064 -281.800418) (xy 55.138205 -281.841513) (xy 55.104064 -281.877558)
			(xy 55.064542 -281.907606) (xy 55.020679 -281.930864) (xy 54.973631 -281.946718) (xy 54.924638 -281.954753)
			(xy 54.899814 -281.95524) (xy 54.885694 -281.955058) (xy 54.857582 -281.952384) (xy 54.84368 -281.949906)
			(xy 54.831234 -281.94762) (xy 54.807358 -281.954986) (xy 54.729888 -282.032456) (xy 54.722522 -282.056332)
			(xy 54.724808 -282.068778) (xy 54.727265 -282.082683) (xy 54.72994 -282.110794) (xy 54.730142 -282.124912)
			(xy 54.72962 -282.150167) (xy 54.721307 -282.199989) (xy 54.704906 -282.247763) (xy 54.680865 -282.292186)
			(xy 54.649841 -282.332046) (xy 54.612679 -282.366256) (xy 54.570393 -282.393882) (xy 54.524137 -282.414172)
			(xy 54.475172 -282.426572) (xy 54.424834 -282.430743) (xy 54.374496 -282.426572) (xy 54.325531 -282.414172)
			(xy 54.279275 -282.393882) (xy 54.236989 -282.366256) (xy 54.199827 -282.332046) (xy 54.168803 -282.292186)
			(xy 54.144762 -282.247763) (xy 54.128361 -282.199989) (xy 54.120048 -282.150167) (xy 54.119526 -282.124912)
			(xy 54.119708 -282.110792) (xy 54.122383 -282.08268) (xy 54.12486 -282.068778) (xy 54.127146 -282.056332)
			(xy 54.11978 -282.032456) (xy 54.04231 -281.954986) (xy 54.018434 -281.94762) (xy 54.005988 -281.949906)
			(xy 53.992084 -281.952368) (xy 53.963973 -281.95504) (xy 53.949854 -281.95524) (xy 53.925037 -281.954673)
			(xy 53.876058 -281.946635) (xy 53.829025 -281.93078) (xy 53.785177 -281.907525) (xy 53.745668 -281.877482)
			(xy 53.71154 -281.841444) (xy 53.683692 -281.800358) (xy 53.662857 -281.755309) (xy 53.649586 -281.707483)
			(xy 53.644226 -281.658139) (xy 53.305037 -281.658139) (xy 53.304707 -281.674539) (xy 53.296812 -281.723116)
			(xy 53.281228 -281.769797) (xy 53.258357 -281.813374) (xy 53.228792 -281.852718) (xy 53.193299 -281.88681)
			(xy 53.152796 -281.914766) (xy 53.108334 -281.935864) (xy 53.061063 -281.949556) (xy 53.012208 -281.955488)
			(xy 52.963033 -281.953507) (xy 52.914814 -281.943663) (xy 52.868798 -281.926211) (xy 52.826177 -281.901604)
			(xy 52.788056 -281.870479) (xy 52.755421 -281.833642) (xy 52.729118 -281.792046) (xy 52.709827 -281.74677)
			(xy 52.69805 -281.698986) (xy 52.69409 -281.649932) (xy 52.355242 -281.649932) (xy 52.354747 -281.674539)
			(xy 52.346852 -281.723116) (xy 52.331268 -281.769797) (xy 52.308397 -281.813374) (xy 52.278832 -281.852718)
			(xy 52.243339 -281.88681) (xy 52.202836 -281.914766) (xy 52.158374 -281.935864) (xy 52.111103 -281.949556)
			(xy 52.062248 -281.955488) (xy 52.013073 -281.953507) (xy 51.964854 -281.943663) (xy 51.918838 -281.926211)
			(xy 51.876217 -281.901604) (xy 51.838096 -281.870479) (xy 51.805461 -281.833642) (xy 51.779158 -281.792046)
			(xy 51.759867 -281.74677) (xy 51.74809 -281.698986) (xy 51.74413 -281.649932) (xy 51.405282 -281.649932)
			(xy 51.404787 -281.674539) (xy 51.396892 -281.723116) (xy 51.381308 -281.769797) (xy 51.358437 -281.813374)
			(xy 51.328872 -281.852718) (xy 51.293379 -281.88681) (xy 51.252876 -281.914766) (xy 51.208414 -281.935864)
			(xy 51.161143 -281.949556) (xy 51.112288 -281.955488) (xy 51.063113 -281.953507) (xy 51.014894 -281.943663)
			(xy 50.968878 -281.926211) (xy 50.926257 -281.901604) (xy 50.888136 -281.870479) (xy 50.855501 -281.833642)
			(xy 50.829198 -281.792046) (xy 50.809907 -281.74677) (xy 50.79813 -281.698986) (xy 50.79417 -281.649932)
			(xy 50.455068 -281.649932) (xy 50.454573 -281.674539) (xy 50.446678 -281.723116) (xy 50.431094 -281.769797)
			(xy 50.408223 -281.813374) (xy 50.378658 -281.852718) (xy 50.343165 -281.88681) (xy 50.302662 -281.914766)
			(xy 50.2582 -281.935864) (xy 50.210929 -281.949556) (xy 50.162074 -281.955488) (xy 50.112899 -281.953507)
			(xy 50.06468 -281.943663) (xy 50.018664 -281.926211) (xy 49.976043 -281.901604) (xy 49.937922 -281.870479)
			(xy 49.905287 -281.833642) (xy 49.878984 -281.792046) (xy 49.859693 -281.74677) (xy 49.847916 -281.698986)
			(xy 49.843956 -281.649932) (xy 49.505108 -281.649932) (xy 49.504613 -281.674539) (xy 49.496718 -281.723116)
			(xy 49.481134 -281.769797) (xy 49.458263 -281.813374) (xy 49.428698 -281.852718) (xy 49.393205 -281.88681)
			(xy 49.352702 -281.914766) (xy 49.30824 -281.935864) (xy 49.260969 -281.949556) (xy 49.212114 -281.955488)
			(xy 49.162939 -281.953507) (xy 49.11472 -281.943663) (xy 49.068704 -281.926211) (xy 49.026083 -281.901604)
			(xy 48.987962 -281.870479) (xy 48.955327 -281.833642) (xy 48.929024 -281.792046) (xy 48.909733 -281.74677)
			(xy 48.897956 -281.698986) (xy 48.893996 -281.649932) (xy 48.555596 -281.649932) (xy 48.551429 -281.700229)
			(xy 48.539033 -281.749185) (xy 48.518748 -281.795433) (xy 48.491129 -281.837712) (xy 48.456928 -281.874869)
			(xy 48.417077 -281.905891) (xy 48.372665 -281.929931) (xy 48.324902 -281.946333) (xy 48.275091 -281.954651)
			(xy 48.24984 -281.95524) (xy 48.249586 -281.95524) (xy 48.220887 -281.954585) (xy 48.164505 -281.943838)
			(xy 48.137572 -281.933904) (xy 48.128682 -281.930348) (xy 48.11903 -281.930348) (xy 48.109008 -281.930763)
			(xy 48.090489 -281.938429) (xy 48.076319 -281.952604) (xy 48.06866 -281.971126) (xy 48.06823 -281.981148)
			(xy 48.06823 -282.033472) (xy 48.070008 -282.04668) (xy 48.07077 -282.049728) (xy 48.07516 -282.068149)
			(xy 48.079878 -282.105723) (xy 48.080168 -282.124658) (xy 48.080168 -282.125166) (xy 48.079914 -282.13431)
			(xy 48.079914 -282.141676) (xy 48.079914 -282.145232) (xy 48.07966 -282.14701) (xy 48.07966 -282.148026)
			(xy 48.07841 -282.162235) (xy 48.073576 -282.190349) (xy 48.070008 -282.20416) (xy 48.06823 -282.210764)
			(xy 48.06823 -282.599892) (xy 73.593972 -282.599892) (xy 73.597932 -282.550838) (xy 73.609709 -282.503054)
			(xy 73.629 -282.457778) (xy 73.655303 -282.416182) (xy 73.687938 -282.379345) (xy 73.726059 -282.34822)
			(xy 73.76868 -282.323613) (xy 73.814696 -282.306161) (xy 73.862915 -282.296317) (xy 73.91209 -282.294336)
			(xy 73.960945 -282.300268) (xy 74.008216 -282.31396) (xy 74.052678 -282.335058) (xy 74.093181 -282.363014)
			(xy 74.128674 -282.397106) (xy 74.158239 -282.43645) (xy 74.18111 -282.480027) (xy 74.196694 -282.526708)
			(xy 74.204589 -282.575285) (xy 74.205084 -282.599892) (xy 74.543932 -282.599892) (xy 74.547892 -282.550838)
			(xy 74.559669 -282.503054) (xy 74.57896 -282.457778) (xy 74.605263 -282.416182) (xy 74.637898 -282.379345)
			(xy 74.676019 -282.34822) (xy 74.71864 -282.323613) (xy 74.764656 -282.306161) (xy 74.812875 -282.296317)
			(xy 74.86205 -282.294336) (xy 74.910905 -282.300268) (xy 74.958176 -282.31396) (xy 75.002638 -282.335058)
			(xy 75.043141 -282.363014) (xy 75.078634 -282.397106) (xy 75.108199 -282.43645) (xy 75.13107 -282.480027)
			(xy 75.146654 -282.526708) (xy 75.154549 -282.575285) (xy 75.155044 -282.599892) (xy 75.494146 -282.599892)
			(xy 75.498106 -282.550838) (xy 75.509883 -282.503054) (xy 75.529174 -282.457778) (xy 75.555477 -282.416182)
			(xy 75.588112 -282.379345) (xy 75.626233 -282.34822) (xy 75.668854 -282.323613) (xy 75.71487 -282.306161)
			(xy 75.763089 -282.296317) (xy 75.812264 -282.294336) (xy 75.861119 -282.300268) (xy 75.90839 -282.31396)
			(xy 75.952852 -282.335058) (xy 75.993355 -282.363014) (xy 76.028848 -282.397106) (xy 76.058413 -282.43645)
			(xy 76.081284 -282.480027) (xy 76.096868 -282.526708) (xy 76.104763 -282.575285) (xy 76.105258 -282.599892)
			(xy 76.444106 -282.599892) (xy 76.448066 -282.550838) (xy 76.459843 -282.503054) (xy 76.479134 -282.457778)
			(xy 76.505437 -282.416182) (xy 76.538072 -282.379345) (xy 76.576193 -282.34822) (xy 76.618814 -282.323613)
			(xy 76.66483 -282.306161) (xy 76.713049 -282.296317) (xy 76.762224 -282.294336) (xy 76.811079 -282.300268)
			(xy 76.85835 -282.31396) (xy 76.902812 -282.335058) (xy 76.943315 -282.363014) (xy 76.978808 -282.397106)
			(xy 77.008373 -282.43645) (xy 77.031244 -282.480027) (xy 77.046828 -282.526708) (xy 77.054723 -282.575285)
			(xy 77.055218 -282.599892) (xy 77.394066 -282.599892) (xy 77.398026 -282.550838) (xy 77.409803 -282.503054)
			(xy 77.429094 -282.457778) (xy 77.455397 -282.416182) (xy 77.488032 -282.379345) (xy 77.526153 -282.34822)
			(xy 77.568774 -282.323613) (xy 77.61479 -282.306161) (xy 77.663009 -282.296317) (xy 77.712184 -282.294336)
			(xy 77.761039 -282.300268) (xy 77.80831 -282.31396) (xy 77.852772 -282.335058) (xy 77.893275 -282.363014)
			(xy 77.928768 -282.397106) (xy 77.958333 -282.43645) (xy 77.981204 -282.480027) (xy 77.996788 -282.526708)
			(xy 78.004683 -282.575285) (xy 78.005178 -282.599892) (xy 78.344026 -282.599892) (xy 78.347986 -282.550838)
			(xy 78.359763 -282.503054) (xy 78.379054 -282.457778) (xy 78.405357 -282.416182) (xy 78.437992 -282.379345)
			(xy 78.476113 -282.34822) (xy 78.518734 -282.323613) (xy 78.56475 -282.306161) (xy 78.612969 -282.296317)
			(xy 78.662144 -282.294336) (xy 78.710999 -282.300268) (xy 78.75827 -282.31396) (xy 78.802732 -282.335058)
			(xy 78.843235 -282.363014) (xy 78.878728 -282.397106) (xy 78.908293 -282.43645) (xy 78.931164 -282.480027)
			(xy 78.946748 -282.526708) (xy 78.954643 -282.575285) (xy 78.955138 -282.599892) (xy 78.954643 -282.624499)
			(xy 78.954464 -282.6256) (xy 79.273142 -282.6256) (xy 79.273142 -282.574184) (xy 79.281185 -282.523402)
			(xy 79.297073 -282.474503) (xy 79.320416 -282.428691) (xy 79.350637 -282.387095) (xy 79.386993 -282.350739)
			(xy 79.428589 -282.320518) (xy 79.474401 -282.297175) (xy 79.5233 -282.281287) (xy 79.574082 -282.273244)
			(xy 79.625498 -282.273244) (xy 79.67628 -282.281287) (xy 79.725179 -282.297175) (xy 79.770991 -282.320518)
			(xy 79.812587 -282.350739) (xy 79.848943 -282.387095) (xy 79.879164 -282.428691) (xy 79.902507 -282.474503)
			(xy 79.918395 -282.523402) (xy 79.926438 -282.574184) (xy 79.926942 -282.599892) (xy 79.926438 -282.6256)
			(xy 80.223102 -282.6256) (xy 80.223102 -282.574184) (xy 80.231145 -282.523402) (xy 80.247033 -282.474503)
			(xy 80.270376 -282.428691) (xy 80.300597 -282.387095) (xy 80.336953 -282.350739) (xy 80.378549 -282.320518)
			(xy 80.424361 -282.297175) (xy 80.47326 -282.281287) (xy 80.524042 -282.273244) (xy 80.575458 -282.273244)
			(xy 80.62624 -282.281287) (xy 80.675139 -282.297175) (xy 80.720951 -282.320518) (xy 80.762547 -282.350739)
			(xy 80.798903 -282.387095) (xy 80.829124 -282.428691) (xy 80.852467 -282.474503) (xy 80.868355 -282.523402)
			(xy 80.876398 -282.574184) (xy 80.876902 -282.599892) (xy 81.19416 -282.599892) (xy 81.19812 -282.550838)
			(xy 81.209897 -282.503054) (xy 81.229188 -282.457778) (xy 81.255491 -282.416182) (xy 81.288126 -282.379345)
			(xy 81.326247 -282.34822) (xy 81.368868 -282.323613) (xy 81.414884 -282.306161) (xy 81.463103 -282.296317)
			(xy 81.512278 -282.294336) (xy 81.561133 -282.300268) (xy 81.608404 -282.31396) (xy 81.652866 -282.335058)
			(xy 81.693369 -282.363014) (xy 81.728862 -282.397106) (xy 81.758427 -282.43645) (xy 81.781298 -282.480027)
			(xy 81.796882 -282.526708) (xy 81.804777 -282.575285) (xy 81.805272 -282.599892) (xy 82.14412 -282.599892)
			(xy 82.14808 -282.550838) (xy 82.159857 -282.503054) (xy 82.179148 -282.457778) (xy 82.205451 -282.416182)
			(xy 82.238086 -282.379345) (xy 82.276207 -282.34822) (xy 82.318828 -282.323613) (xy 82.364844 -282.306161)
			(xy 82.413063 -282.296317) (xy 82.462238 -282.294336) (xy 82.511093 -282.300268) (xy 82.558364 -282.31396)
			(xy 82.602826 -282.335058) (xy 82.643329 -282.363014) (xy 82.678822 -282.397106) (xy 82.708387 -282.43645)
			(xy 82.731258 -282.480027) (xy 82.746842 -282.526708) (xy 82.754737 -282.575285) (xy 82.755232 -282.599892)
			(xy 82.754737 -282.624499) (xy 82.746842 -282.673076) (xy 82.731258 -282.719757) (xy 82.708387 -282.763334)
			(xy 82.678822 -282.802678) (xy 82.643329 -282.83677) (xy 82.602826 -282.864726) (xy 82.558364 -282.885824)
			(xy 82.511093 -282.899516) (xy 82.462238 -282.905448) (xy 82.413063 -282.903467) (xy 82.364844 -282.893623)
			(xy 82.318828 -282.876171) (xy 82.276207 -282.851564) (xy 82.238086 -282.820439) (xy 82.205451 -282.783602)
			(xy 82.179148 -282.742006) (xy 82.159857 -282.69673) (xy 82.14808 -282.648946) (xy 82.14412 -282.599892)
			(xy 81.805272 -282.599892) (xy 81.804777 -282.624499) (xy 81.796882 -282.673076) (xy 81.781298 -282.719757)
			(xy 81.758427 -282.763334) (xy 81.728862 -282.802678) (xy 81.693369 -282.83677) (xy 81.652866 -282.864726)
			(xy 81.608404 -282.885824) (xy 81.561133 -282.899516) (xy 81.512278 -282.905448) (xy 81.463103 -282.903467)
			(xy 81.414884 -282.893623) (xy 81.368868 -282.876171) (xy 81.326247 -282.851564) (xy 81.288126 -282.820439)
			(xy 81.255491 -282.783602) (xy 81.229188 -282.742006) (xy 81.209897 -282.69673) (xy 81.19812 -282.648946)
			(xy 81.19416 -282.599892) (xy 80.876902 -282.599892) (xy 80.876398 -282.6256) (xy 80.868355 -282.676382)
			(xy 80.852467 -282.725281) (xy 80.829124 -282.771093) (xy 80.798903 -282.812689) (xy 80.762547 -282.849045)
			(xy 80.720951 -282.879266) (xy 80.675139 -282.902609) (xy 80.62624 -282.918497) (xy 80.575458 -282.92654)
			(xy 80.524042 -282.92654) (xy 80.47326 -282.918497) (xy 80.424361 -282.902609) (xy 80.378549 -282.879266)
			(xy 80.336953 -282.849045) (xy 80.300597 -282.812689) (xy 80.270376 -282.771093) (xy 80.247033 -282.725281)
			(xy 80.231145 -282.676382) (xy 80.223102 -282.6256) (xy 79.926438 -282.6256) (xy 79.918395 -282.676382)
			(xy 79.902507 -282.725281) (xy 79.879164 -282.771093) (xy 79.848943 -282.812689) (xy 79.812587 -282.849045)
			(xy 79.770991 -282.879266) (xy 79.725179 -282.902609) (xy 79.67628 -282.918497) (xy 79.625498 -282.92654)
			(xy 79.574082 -282.92654) (xy 79.5233 -282.918497) (xy 79.474401 -282.902609) (xy 79.428589 -282.879266)
			(xy 79.386993 -282.849045) (xy 79.350637 -282.812689) (xy 79.320416 -282.771093) (xy 79.297073 -282.725281)
			(xy 79.281185 -282.676382) (xy 79.273142 -282.6256) (xy 78.954464 -282.6256) (xy 78.946748 -282.673076)
			(xy 78.931164 -282.719757) (xy 78.908293 -282.763334) (xy 78.878728 -282.802678) (xy 78.843235 -282.83677)
			(xy 78.802732 -282.864726) (xy 78.75827 -282.885824) (xy 78.710999 -282.899516) (xy 78.662144 -282.905448)
			(xy 78.612969 -282.903467) (xy 78.56475 -282.893623) (xy 78.518734 -282.876171) (xy 78.476113 -282.851564)
			(xy 78.437992 -282.820439) (xy 78.405357 -282.783602) (xy 78.379054 -282.742006) (xy 78.359763 -282.69673)
			(xy 78.347986 -282.648946) (xy 78.344026 -282.599892) (xy 78.005178 -282.599892) (xy 78.004683 -282.624499)
			(xy 77.996788 -282.673076) (xy 77.981204 -282.719757) (xy 77.958333 -282.763334) (xy 77.928768 -282.802678)
			(xy 77.893275 -282.83677) (xy 77.852772 -282.864726) (xy 77.80831 -282.885824) (xy 77.761039 -282.899516)
			(xy 77.712184 -282.905448) (xy 77.663009 -282.903467) (xy 77.61479 -282.893623) (xy 77.568774 -282.876171)
			(xy 77.526153 -282.851564) (xy 77.488032 -282.820439) (xy 77.455397 -282.783602) (xy 77.429094 -282.742006)
			(xy 77.409803 -282.69673) (xy 77.398026 -282.648946) (xy 77.394066 -282.599892) (xy 77.055218 -282.599892)
			(xy 77.054723 -282.624499) (xy 77.046828 -282.673076) (xy 77.031244 -282.719757) (xy 77.008373 -282.763334)
			(xy 76.978808 -282.802678) (xy 76.943315 -282.83677) (xy 76.902812 -282.864726) (xy 76.85835 -282.885824)
			(xy 76.811079 -282.899516) (xy 76.762224 -282.905448) (xy 76.713049 -282.903467) (xy 76.66483 -282.893623)
			(xy 76.618814 -282.876171) (xy 76.576193 -282.851564) (xy 76.538072 -282.820439) (xy 76.505437 -282.783602)
			(xy 76.479134 -282.742006) (xy 76.459843 -282.69673) (xy 76.448066 -282.648946) (xy 76.444106 -282.599892)
			(xy 76.105258 -282.599892) (xy 76.104763 -282.624499) (xy 76.096868 -282.673076) (xy 76.081284 -282.719757)
			(xy 76.058413 -282.763334) (xy 76.028848 -282.802678) (xy 75.993355 -282.83677) (xy 75.952852 -282.864726)
			(xy 75.90839 -282.885824) (xy 75.861119 -282.899516) (xy 75.812264 -282.905448) (xy 75.763089 -282.903467)
			(xy 75.71487 -282.893623) (xy 75.668854 -282.876171) (xy 75.626233 -282.851564) (xy 75.588112 -282.820439)
			(xy 75.555477 -282.783602) (xy 75.529174 -282.742006) (xy 75.509883 -282.69673) (xy 75.498106 -282.648946)
			(xy 75.494146 -282.599892) (xy 75.155044 -282.599892) (xy 75.154549 -282.624499) (xy 75.146654 -282.673076)
			(xy 75.13107 -282.719757) (xy 75.108199 -282.763334) (xy 75.078634 -282.802678) (xy 75.043141 -282.83677)
			(xy 75.002638 -282.864726) (xy 74.958176 -282.885824) (xy 74.910905 -282.899516) (xy 74.86205 -282.905448)
			(xy 74.812875 -282.903467) (xy 74.764656 -282.893623) (xy 74.71864 -282.876171) (xy 74.676019 -282.851564)
			(xy 74.637898 -282.820439) (xy 74.605263 -282.783602) (xy 74.57896 -282.742006) (xy 74.559669 -282.69673)
			(xy 74.547892 -282.648946) (xy 74.543932 -282.599892) (xy 74.205084 -282.599892) (xy 74.204589 -282.624499)
			(xy 74.196694 -282.673076) (xy 74.18111 -282.719757) (xy 74.158239 -282.763334) (xy 74.128674 -282.802678)
			(xy 74.093181 -282.83677) (xy 74.052678 -282.864726) (xy 74.008216 -282.885824) (xy 73.960945 -282.899516)
			(xy 73.91209 -282.905448) (xy 73.862915 -282.903467) (xy 73.814696 -282.893623) (xy 73.76868 -282.876171)
			(xy 73.726059 -282.851564) (xy 73.687938 -282.820439) (xy 73.655303 -282.783602) (xy 73.629 -282.742006)
			(xy 73.609709 -282.69673) (xy 73.597932 -282.648946) (xy 73.593972 -282.599892) (xy 48.06823 -282.599892)
			(xy 48.06823 -282.983432) (xy 48.070008 -282.99664) (xy 48.07077 -282.999688) (xy 48.075166 -283.018172)
			(xy 48.079876 -283.055874) (xy 48.080168 -283.074872) (xy 48.419016 -283.074872) (xy 48.422976 -283.025818)
			(xy 48.434753 -282.978034) (xy 48.454044 -282.932758) (xy 48.480347 -282.891162) (xy 48.512982 -282.854325)
			(xy 48.551103 -282.8232) (xy 48.593724 -282.798593) (xy 48.63974 -282.781141) (xy 48.687959 -282.771297)
			(xy 48.737134 -282.769316) (xy 48.785989 -282.775248) (xy 48.83326 -282.78894) (xy 48.877722 -282.810038)
			(xy 48.918225 -282.837994) (xy 48.953718 -282.872086) (xy 48.983283 -282.91143) (xy 49.006154 -282.955007)
			(xy 49.021738 -283.001688) (xy 49.029633 -283.050265) (xy 49.030128 -283.074872) (xy 49.368976 -283.074872)
			(xy 49.372936 -283.025818) (xy 49.384713 -282.978034) (xy 49.404004 -282.932758) (xy 49.430307 -282.891162)
			(xy 49.462942 -282.854325) (xy 49.501063 -282.8232) (xy 49.543684 -282.798593) (xy 49.5897 -282.781141)
			(xy 49.637919 -282.771297) (xy 49.687094 -282.769316) (xy 49.735949 -282.775248) (xy 49.78322 -282.78894)
			(xy 49.827682 -282.810038) (xy 49.868185 -282.837994) (xy 49.903678 -282.872086) (xy 49.933243 -282.91143)
			(xy 49.956114 -282.955007) (xy 49.971698 -283.001688) (xy 49.979593 -283.050265) (xy 49.980088 -283.074872)
			(xy 50.31919 -283.074872) (xy 50.32315 -283.025818) (xy 50.334927 -282.978034) (xy 50.354218 -282.932758)
			(xy 50.380521 -282.891162) (xy 50.413156 -282.854325) (xy 50.451277 -282.8232) (xy 50.493898 -282.798593)
			(xy 50.539914 -282.781141) (xy 50.588133 -282.771297) (xy 50.637308 -282.769316) (xy 50.686163 -282.775248)
			(xy 50.733434 -282.78894) (xy 50.777896 -282.810038) (xy 50.818399 -282.837994) (xy 50.853892 -282.872086)
			(xy 50.883457 -282.91143) (xy 50.906328 -282.955007) (xy 50.921912 -283.001688) (xy 50.929807 -283.050265)
			(xy 50.930302 -283.074872) (xy 51.26915 -283.074872) (xy 51.27311 -283.025818) (xy 51.284887 -282.978034)
			(xy 51.304178 -282.932758) (xy 51.330481 -282.891162) (xy 51.363116 -282.854325) (xy 51.401237 -282.8232)
			(xy 51.443858 -282.798593) (xy 51.489874 -282.781141) (xy 51.538093 -282.771297) (xy 51.587268 -282.769316)
			(xy 51.636123 -282.775248) (xy 51.683394 -282.78894) (xy 51.727856 -282.810038) (xy 51.768359 -282.837994)
			(xy 51.803852 -282.872086) (xy 51.833417 -282.91143) (xy 51.856288 -282.955007) (xy 51.871872 -283.001688)
			(xy 51.879767 -283.050265) (xy 51.880262 -283.074872) (xy 52.21911 -283.074872) (xy 52.22307 -283.025818)
			(xy 52.234847 -282.978034) (xy 52.254138 -282.932758) (xy 52.280441 -282.891162) (xy 52.313076 -282.854325)
			(xy 52.351197 -282.8232) (xy 52.393818 -282.798593) (xy 52.439834 -282.781141) (xy 52.488053 -282.771297)
			(xy 52.537228 -282.769316) (xy 52.586083 -282.775248) (xy 52.633354 -282.78894) (xy 52.677816 -282.810038)
			(xy 52.718319 -282.837994) (xy 52.753812 -282.872086) (xy 52.783377 -282.91143) (xy 52.806248 -282.955007)
			(xy 52.821832 -283.001688) (xy 52.829727 -283.050265) (xy 52.830222 -283.074872) (xy 53.16907 -283.074872)
			(xy 53.17303 -283.025818) (xy 53.184807 -282.978034) (xy 53.204098 -282.932758) (xy 53.230401 -282.891162)
			(xy 53.263036 -282.854325) (xy 53.301157 -282.8232) (xy 53.343778 -282.798593) (xy 53.389794 -282.781141)
			(xy 53.438013 -282.771297) (xy 53.487188 -282.769316) (xy 53.536043 -282.775248) (xy 53.583314 -282.78894)
			(xy 53.627776 -282.810038) (xy 53.668279 -282.837994) (xy 53.703772 -282.872086) (xy 53.733337 -282.91143)
			(xy 53.756208 -282.955007) (xy 53.771792 -283.001688) (xy 53.779687 -283.050265) (xy 53.780182 -283.074872)
			(xy 54.11903 -283.074872) (xy 54.12299 -283.025818) (xy 54.134767 -282.978034) (xy 54.154058 -282.932758)
			(xy 54.180361 -282.891162) (xy 54.212996 -282.854325) (xy 54.251117 -282.8232) (xy 54.293738 -282.798593)
			(xy 54.339754 -282.781141) (xy 54.387973 -282.771297) (xy 54.437148 -282.769316) (xy 54.486003 -282.775248)
			(xy 54.533274 -282.78894) (xy 54.577736 -282.810038) (xy 54.618239 -282.837994) (xy 54.653732 -282.872086)
			(xy 54.683297 -282.91143) (xy 54.706168 -282.955007) (xy 54.721752 -283.001688) (xy 54.729647 -283.050265)
			(xy 54.730142 -283.074872) (xy 55.06899 -283.074872) (xy 55.07295 -283.025818) (xy 55.084727 -282.978034)
			(xy 55.104018 -282.932758) (xy 55.130321 -282.891162) (xy 55.162956 -282.854325) (xy 55.201077 -282.8232)
			(xy 55.243698 -282.798593) (xy 55.289714 -282.781141) (xy 55.337933 -282.771297) (xy 55.387108 -282.769316)
			(xy 55.435963 -282.775248) (xy 55.483234 -282.78894) (xy 55.527696 -282.810038) (xy 55.568199 -282.837994)
			(xy 55.603692 -282.872086) (xy 55.633257 -282.91143) (xy 55.656128 -282.955007) (xy 55.671712 -283.001688)
			(xy 55.679607 -283.050265) (xy 55.680102 -283.074872) (xy 56.019204 -283.074872) (xy 56.023164 -283.025818)
			(xy 56.034941 -282.978034) (xy 56.054232 -282.932758) (xy 56.080535 -282.891162) (xy 56.11317 -282.854325)
			(xy 56.151291 -282.8232) (xy 56.193912 -282.798593) (xy 56.239928 -282.781141) (xy 56.288147 -282.771297)
			(xy 56.337322 -282.769316) (xy 56.386177 -282.775248) (xy 56.433448 -282.78894) (xy 56.47791 -282.810038)
			(xy 56.518413 -282.837994) (xy 56.553906 -282.872086) (xy 56.583471 -282.91143) (xy 56.606342 -282.955007)
			(xy 56.621926 -283.001688) (xy 56.629821 -283.050265) (xy 56.630316 -283.074872) (xy 56.969164 -283.074872)
			(xy 56.973124 -283.025818) (xy 56.984901 -282.978034) (xy 57.004192 -282.932758) (xy 57.030495 -282.891162)
			(xy 57.06313 -282.854325) (xy 57.101251 -282.8232) (xy 57.143872 -282.798593) (xy 57.189888 -282.781141)
			(xy 57.238107 -282.771297) (xy 57.287282 -282.769316) (xy 57.336137 -282.775248) (xy 57.383408 -282.78894)
			(xy 57.42787 -282.810038) (xy 57.468373 -282.837994) (xy 57.503866 -282.872086) (xy 57.533431 -282.91143)
			(xy 57.556302 -282.955007) (xy 57.571886 -283.001688) (xy 57.579781 -283.050265) (xy 57.580276 -283.074872)
			(xy 57.919124 -283.074872) (xy 57.923084 -283.025818) (xy 57.934861 -282.978034) (xy 57.954152 -282.932758)
			(xy 57.980455 -282.891162) (xy 58.01309 -282.854325) (xy 58.051211 -282.8232) (xy 58.093832 -282.798593)
			(xy 58.139848 -282.781141) (xy 58.188067 -282.771297) (xy 58.237242 -282.769316) (xy 58.286097 -282.775248)
			(xy 58.333368 -282.78894) (xy 58.37783 -282.810038) (xy 58.418333 -282.837994) (xy 58.453826 -282.872086)
			(xy 58.483391 -282.91143) (xy 58.506262 -282.955007) (xy 58.521846 -283.001688) (xy 58.529741 -283.050265)
			(xy 58.530236 -283.074872) (xy 59.819044 -283.074872) (xy 59.823004 -283.025818) (xy 59.834781 -282.978034)
			(xy 59.854072 -282.932758) (xy 59.880375 -282.891162) (xy 59.91301 -282.854325) (xy 59.951131 -282.8232)
			(xy 59.993752 -282.798593) (xy 60.039768 -282.781141) (xy 60.087987 -282.771297) (xy 60.137162 -282.769316)
			(xy 60.186017 -282.775248) (xy 60.233288 -282.78894) (xy 60.27775 -282.810038) (xy 60.318253 -282.837994)
			(xy 60.353746 -282.872086) (xy 60.383311 -282.91143) (xy 60.406182 -282.955007) (xy 60.421766 -283.001688)
			(xy 60.429661 -283.050265) (xy 60.430156 -283.074872) (xy 60.769004 -283.074872) (xy 60.772964 -283.025818)
			(xy 60.784741 -282.978034) (xy 60.804032 -282.932758) (xy 60.830335 -282.891162) (xy 60.86297 -282.854325)
			(xy 60.901091 -282.8232) (xy 60.943712 -282.798593) (xy 60.989728 -282.781141) (xy 61.037947 -282.771297)
			(xy 61.087122 -282.769316) (xy 61.135977 -282.775248) (xy 61.183248 -282.78894) (xy 61.22771 -282.810038)
			(xy 61.268213 -282.837994) (xy 61.303706 -282.872086) (xy 61.333271 -282.91143) (xy 61.356142 -282.955007)
			(xy 61.371726 -283.001688) (xy 61.379621 -283.050265) (xy 61.380116 -283.074872) (xy 61.718964 -283.074872)
			(xy 61.722924 -283.025818) (xy 61.734701 -282.978034) (xy 61.753992 -282.932758) (xy 61.780295 -282.891162)
			(xy 61.81293 -282.854325) (xy 61.851051 -282.8232) (xy 61.893672 -282.798593) (xy 61.939688 -282.781141)
			(xy 61.987907 -282.771297) (xy 62.037082 -282.769316) (xy 62.085937 -282.775248) (xy 62.133208 -282.78894)
			(xy 62.17767 -282.810038) (xy 62.218173 -282.837994) (xy 62.253666 -282.872086) (xy 62.283231 -282.91143)
			(xy 62.306102 -282.955007) (xy 62.321686 -283.001688) (xy 62.329581 -283.050265) (xy 62.330076 -283.074872)
			(xy 62.669178 -283.074872) (xy 62.673138 -283.025818) (xy 62.684915 -282.978034) (xy 62.704206 -282.932758)
			(xy 62.730509 -282.891162) (xy 62.763144 -282.854325) (xy 62.801265 -282.8232) (xy 62.843886 -282.798593)
			(xy 62.889902 -282.781141) (xy 62.938121 -282.771297) (xy 62.987296 -282.769316) (xy 63.036151 -282.775248)
			(xy 63.083422 -282.78894) (xy 63.127884 -282.810038) (xy 63.168387 -282.837994) (xy 63.20388 -282.872086)
			(xy 63.233445 -282.91143) (xy 63.256316 -282.955007) (xy 63.2719 -283.001688) (xy 63.279795 -283.050265)
			(xy 63.28029 -283.074872) (xy 63.619138 -283.074872) (xy 63.623098 -283.025818) (xy 63.634875 -282.978034)
			(xy 63.654166 -282.932758) (xy 63.680469 -282.891162) (xy 63.713104 -282.854325) (xy 63.751225 -282.8232)
			(xy 63.793846 -282.798593) (xy 63.839862 -282.781141) (xy 63.888081 -282.771297) (xy 63.937256 -282.769316)
			(xy 63.986111 -282.775248) (xy 64.033382 -282.78894) (xy 64.077844 -282.810038) (xy 64.118347 -282.837994)
			(xy 64.15384 -282.872086) (xy 64.183405 -282.91143) (xy 64.206276 -282.955007) (xy 64.22186 -283.001688)
			(xy 64.229755 -283.050265) (xy 64.23025 -283.074872) (xy 64.569098 -283.074872) (xy 64.573058 -283.025818)
			(xy 64.584835 -282.978034) (xy 64.604126 -282.932758) (xy 64.630429 -282.891162) (xy 64.663064 -282.854325)
			(xy 64.701185 -282.8232) (xy 64.743806 -282.798593) (xy 64.789822 -282.781141) (xy 64.838041 -282.771297)
			(xy 64.887216 -282.769316) (xy 64.936071 -282.775248) (xy 64.983342 -282.78894) (xy 65.027804 -282.810038)
			(xy 65.068307 -282.837994) (xy 65.1038 -282.872086) (xy 65.133365 -282.91143) (xy 65.156236 -282.955007)
			(xy 65.17182 -283.001688) (xy 65.179715 -283.050265) (xy 65.18021 -283.074872) (xy 65.519058 -283.074872)
			(xy 65.523018 -283.025818) (xy 65.534795 -282.978034) (xy 65.554086 -282.932758) (xy 65.580389 -282.891162)
			(xy 65.613024 -282.854325) (xy 65.651145 -282.8232) (xy 65.693766 -282.798593) (xy 65.739782 -282.781141)
			(xy 65.788001 -282.771297) (xy 65.837176 -282.769316) (xy 65.886031 -282.775248) (xy 65.933302 -282.78894)
			(xy 65.977764 -282.810038) (xy 66.018267 -282.837994) (xy 66.05376 -282.872086) (xy 66.083325 -282.91143)
			(xy 66.106196 -282.955007) (xy 66.12178 -283.001688) (xy 66.129675 -283.050265) (xy 66.13017 -283.074872)
			(xy 66.469018 -283.074872) (xy 66.472978 -283.025818) (xy 66.484755 -282.978034) (xy 66.504046 -282.932758)
			(xy 66.530349 -282.891162) (xy 66.562984 -282.854325) (xy 66.601105 -282.8232) (xy 66.643726 -282.798593)
			(xy 66.689742 -282.781141) (xy 66.737961 -282.771297) (xy 66.787136 -282.769316) (xy 66.835991 -282.775248)
			(xy 66.883262 -282.78894) (xy 66.927724 -282.810038) (xy 66.968227 -282.837994) (xy 67.00372 -282.872086)
			(xy 67.033285 -282.91143) (xy 67.056156 -282.955007) (xy 67.07174 -283.001688) (xy 67.079635 -283.050265)
			(xy 67.08013 -283.074872) (xy 68.368938 -283.074872) (xy 68.372898 -283.025818) (xy 68.384675 -282.978034)
			(xy 68.403966 -282.932758) (xy 68.430269 -282.891162) (xy 68.462904 -282.854325) (xy 68.501025 -282.8232)
			(xy 68.543646 -282.798593) (xy 68.589662 -282.781141) (xy 68.637881 -282.771297) (xy 68.687056 -282.769316)
			(xy 68.735911 -282.775248) (xy 68.783182 -282.78894) (xy 68.827644 -282.810038) (xy 68.868147 -282.837994)
			(xy 68.90364 -282.872086) (xy 68.933205 -282.91143) (xy 68.956076 -282.955007) (xy 68.97166 -283.001688)
			(xy 68.979555 -283.050265) (xy 68.98005 -283.074872) (xy 69.319152 -283.074872) (xy 69.323112 -283.025818)
			(xy 69.334889 -282.978034) (xy 69.35418 -282.932758) (xy 69.380483 -282.891162) (xy 69.413118 -282.854325)
			(xy 69.451239 -282.8232) (xy 69.49386 -282.798593) (xy 69.539876 -282.781141) (xy 69.588095 -282.771297)
			(xy 69.63727 -282.769316) (xy 69.686125 -282.775248) (xy 69.733396 -282.78894) (xy 69.777858 -282.810038)
			(xy 69.818361 -282.837994) (xy 69.853854 -282.872086) (xy 69.883419 -282.91143) (xy 69.90629 -282.955007)
			(xy 69.921874 -283.001688) (xy 69.929769 -283.050265) (xy 69.930264 -283.074872) (xy 70.269112 -283.074872)
			(xy 70.273072 -283.025818) (xy 70.284849 -282.978034) (xy 70.30414 -282.932758) (xy 70.330443 -282.891162)
			(xy 70.363078 -282.854325) (xy 70.401199 -282.8232) (xy 70.44382 -282.798593) (xy 70.489836 -282.781141)
			(xy 70.538055 -282.771297) (xy 70.58723 -282.769316) (xy 70.636085 -282.775248) (xy 70.683356 -282.78894)
			(xy 70.727818 -282.810038) (xy 70.768321 -282.837994) (xy 70.803814 -282.872086) (xy 70.833379 -282.91143)
			(xy 70.85625 -282.955007) (xy 70.871834 -283.001688) (xy 70.879729 -283.050265) (xy 70.880224 -283.074872)
			(xy 71.219072 -283.074872) (xy 71.223032 -283.025818) (xy 71.234809 -282.978034) (xy 71.2541 -282.932758)
			(xy 71.280403 -282.891162) (xy 71.313038 -282.854325) (xy 71.351159 -282.8232) (xy 71.39378 -282.798593)
			(xy 71.439796 -282.781141) (xy 71.488015 -282.771297) (xy 71.53719 -282.769316) (xy 71.586045 -282.775248)
			(xy 71.633316 -282.78894) (xy 71.677778 -282.810038) (xy 71.718281 -282.837994) (xy 71.753774 -282.872086)
			(xy 71.783339 -282.91143) (xy 71.80621 -282.955007) (xy 71.821794 -283.001688) (xy 71.829689 -283.050265)
			(xy 71.830184 -283.074872) (xy 72.169032 -283.074872) (xy 72.172992 -283.025818) (xy 72.184769 -282.978034)
			(xy 72.20406 -282.932758) (xy 72.230363 -282.891162) (xy 72.262998 -282.854325) (xy 72.301119 -282.8232)
			(xy 72.34374 -282.798593) (xy 72.389756 -282.781141) (xy 72.437975 -282.771297) (xy 72.48715 -282.769316)
			(xy 72.536005 -282.775248) (xy 72.583276 -282.78894) (xy 72.627738 -282.810038) (xy 72.668241 -282.837994)
			(xy 72.703734 -282.872086) (xy 72.733299 -282.91143) (xy 72.75617 -282.955007) (xy 72.771754 -283.001688)
			(xy 72.779649 -283.050265) (xy 72.780144 -283.074872) (xy 72.779649 -283.099479) (xy 72.771754 -283.148056)
			(xy 72.75617 -283.194737) (xy 72.733299 -283.238314) (xy 72.703734 -283.277658) (xy 72.668241 -283.31175)
			(xy 72.627738 -283.339706) (xy 72.583276 -283.360804) (xy 72.536005 -283.374496) (xy 72.48715 -283.380428)
			(xy 72.437975 -283.378447) (xy 72.389756 -283.368603) (xy 72.34374 -283.351151) (xy 72.301119 -283.326544)
			(xy 72.262998 -283.295419) (xy 72.230363 -283.258582) (xy 72.20406 -283.216986) (xy 72.184769 -283.17171)
			(xy 72.172992 -283.123926) (xy 72.169032 -283.074872) (xy 71.830184 -283.074872) (xy 71.829689 -283.099479)
			(xy 71.821794 -283.148056) (xy 71.80621 -283.194737) (xy 71.783339 -283.238314) (xy 71.753774 -283.277658)
			(xy 71.718281 -283.31175) (xy 71.677778 -283.339706) (xy 71.633316 -283.360804) (xy 71.586045 -283.374496)
			(xy 71.53719 -283.380428) (xy 71.488015 -283.378447) (xy 71.439796 -283.368603) (xy 71.39378 -283.351151)
			(xy 71.351159 -283.326544) (xy 71.313038 -283.295419) (xy 71.280403 -283.258582) (xy 71.2541 -283.216986)
			(xy 71.234809 -283.17171) (xy 71.223032 -283.123926) (xy 71.219072 -283.074872) (xy 70.880224 -283.074872)
			(xy 70.879729 -283.099479) (xy 70.871834 -283.148056) (xy 70.85625 -283.194737) (xy 70.833379 -283.238314)
			(xy 70.803814 -283.277658) (xy 70.768321 -283.31175) (xy 70.727818 -283.339706) (xy 70.683356 -283.360804)
			(xy 70.636085 -283.374496) (xy 70.58723 -283.380428) (xy 70.538055 -283.378447) (xy 70.489836 -283.368603)
			(xy 70.44382 -283.351151) (xy 70.401199 -283.326544) (xy 70.363078 -283.295419) (xy 70.330443 -283.258582)
			(xy 70.30414 -283.216986) (xy 70.284849 -283.17171) (xy 70.273072 -283.123926) (xy 70.269112 -283.074872)
			(xy 69.930264 -283.074872) (xy 69.929769 -283.099479) (xy 69.921874 -283.148056) (xy 69.90629 -283.194737)
			(xy 69.883419 -283.238314) (xy 69.853854 -283.277658) (xy 69.818361 -283.31175) (xy 69.777858 -283.339706)
			(xy 69.733396 -283.360804) (xy 69.686125 -283.374496) (xy 69.63727 -283.380428) (xy 69.588095 -283.378447)
			(xy 69.539876 -283.368603) (xy 69.49386 -283.351151) (xy 69.451239 -283.326544) (xy 69.413118 -283.295419)
			(xy 69.380483 -283.258582) (xy 69.35418 -283.216986) (xy 69.334889 -283.17171) (xy 69.323112 -283.123926)
			(xy 69.319152 -283.074872) (xy 68.98005 -283.074872) (xy 68.979555 -283.099479) (xy 68.97166 -283.148056)
			(xy 68.956076 -283.194737) (xy 68.933205 -283.238314) (xy 68.90364 -283.277658) (xy 68.868147 -283.31175)
			(xy 68.827644 -283.339706) (xy 68.783182 -283.360804) (xy 68.735911 -283.374496) (xy 68.687056 -283.380428)
			(xy 68.637881 -283.378447) (xy 68.589662 -283.368603) (xy 68.543646 -283.351151) (xy 68.501025 -283.326544)
			(xy 68.462904 -283.295419) (xy 68.430269 -283.258582) (xy 68.403966 -283.216986) (xy 68.384675 -283.17171)
			(xy 68.372898 -283.123926) (xy 68.368938 -283.074872) (xy 67.08013 -283.074872) (xy 67.079635 -283.099479)
			(xy 67.07174 -283.148056) (xy 67.056156 -283.194737) (xy 67.033285 -283.238314) (xy 67.00372 -283.277658)
			(xy 66.968227 -283.31175) (xy 66.927724 -283.339706) (xy 66.883262 -283.360804) (xy 66.835991 -283.374496)
			(xy 66.787136 -283.380428) (xy 66.737961 -283.378447) (xy 66.689742 -283.368603) (xy 66.643726 -283.351151)
			(xy 66.601105 -283.326544) (xy 66.562984 -283.295419) (xy 66.530349 -283.258582) (xy 66.504046 -283.216986)
			(xy 66.484755 -283.17171) (xy 66.472978 -283.123926) (xy 66.469018 -283.074872) (xy 66.13017 -283.074872)
			(xy 66.129675 -283.099479) (xy 66.12178 -283.148056) (xy 66.106196 -283.194737) (xy 66.083325 -283.238314)
			(xy 66.05376 -283.277658) (xy 66.018267 -283.31175) (xy 65.977764 -283.339706) (xy 65.933302 -283.360804)
			(xy 65.886031 -283.374496) (xy 65.837176 -283.380428) (xy 65.788001 -283.378447) (xy 65.739782 -283.368603)
			(xy 65.693766 -283.351151) (xy 65.651145 -283.326544) (xy 65.613024 -283.295419) (xy 65.580389 -283.258582)
			(xy 65.554086 -283.216986) (xy 65.534795 -283.17171) (xy 65.523018 -283.123926) (xy 65.519058 -283.074872)
			(xy 65.18021 -283.074872) (xy 65.179715 -283.099479) (xy 65.17182 -283.148056) (xy 65.156236 -283.194737)
			(xy 65.133365 -283.238314) (xy 65.1038 -283.277658) (xy 65.068307 -283.31175) (xy 65.027804 -283.339706)
			(xy 64.983342 -283.360804) (xy 64.936071 -283.374496) (xy 64.887216 -283.380428) (xy 64.838041 -283.378447)
			(xy 64.789822 -283.368603) (xy 64.743806 -283.351151) (xy 64.701185 -283.326544) (xy 64.663064 -283.295419)
			(xy 64.630429 -283.258582) (xy 64.604126 -283.216986) (xy 64.584835 -283.17171) (xy 64.573058 -283.123926)
			(xy 64.569098 -283.074872) (xy 64.23025 -283.074872) (xy 64.229755 -283.099479) (xy 64.22186 -283.148056)
			(xy 64.206276 -283.194737) (xy 64.183405 -283.238314) (xy 64.15384 -283.277658) (xy 64.118347 -283.31175)
			(xy 64.077844 -283.339706) (xy 64.033382 -283.360804) (xy 63.986111 -283.374496) (xy 63.937256 -283.380428)
			(xy 63.888081 -283.378447) (xy 63.839862 -283.368603) (xy 63.793846 -283.351151) (xy 63.751225 -283.326544)
			(xy 63.713104 -283.295419) (xy 63.680469 -283.258582) (xy 63.654166 -283.216986) (xy 63.634875 -283.17171)
			(xy 63.623098 -283.123926) (xy 63.619138 -283.074872) (xy 63.28029 -283.074872) (xy 63.279795 -283.099479)
			(xy 63.2719 -283.148056) (xy 63.256316 -283.194737) (xy 63.233445 -283.238314) (xy 63.20388 -283.277658)
			(xy 63.168387 -283.31175) (xy 63.127884 -283.339706) (xy 63.083422 -283.360804) (xy 63.036151 -283.374496)
			(xy 62.987296 -283.380428) (xy 62.938121 -283.378447) (xy 62.889902 -283.368603) (xy 62.843886 -283.351151)
			(xy 62.801265 -283.326544) (xy 62.763144 -283.295419) (xy 62.730509 -283.258582) (xy 62.704206 -283.216986)
			(xy 62.684915 -283.17171) (xy 62.673138 -283.123926) (xy 62.669178 -283.074872) (xy 62.330076 -283.074872)
			(xy 62.329581 -283.099479) (xy 62.321686 -283.148056) (xy 62.306102 -283.194737) (xy 62.283231 -283.238314)
			(xy 62.253666 -283.277658) (xy 62.218173 -283.31175) (xy 62.17767 -283.339706) (xy 62.133208 -283.360804)
			(xy 62.085937 -283.374496) (xy 62.037082 -283.380428) (xy 61.987907 -283.378447) (xy 61.939688 -283.368603)
			(xy 61.893672 -283.351151) (xy 61.851051 -283.326544) (xy 61.81293 -283.295419) (xy 61.780295 -283.258582)
			(xy 61.753992 -283.216986) (xy 61.734701 -283.17171) (xy 61.722924 -283.123926) (xy 61.718964 -283.074872)
			(xy 61.380116 -283.074872) (xy 61.379621 -283.099479) (xy 61.371726 -283.148056) (xy 61.356142 -283.194737)
			(xy 61.333271 -283.238314) (xy 61.303706 -283.277658) (xy 61.268213 -283.31175) (xy 61.22771 -283.339706)
			(xy 61.183248 -283.360804) (xy 61.135977 -283.374496) (xy 61.087122 -283.380428) (xy 61.037947 -283.378447)
			(xy 60.989728 -283.368603) (xy 60.943712 -283.351151) (xy 60.901091 -283.326544) (xy 60.86297 -283.295419)
			(xy 60.830335 -283.258582) (xy 60.804032 -283.216986) (xy 60.784741 -283.17171) (xy 60.772964 -283.123926)
			(xy 60.769004 -283.074872) (xy 60.430156 -283.074872) (xy 60.429661 -283.099479) (xy 60.421766 -283.148056)
			(xy 60.406182 -283.194737) (xy 60.383311 -283.238314) (xy 60.353746 -283.277658) (xy 60.318253 -283.31175)
			(xy 60.27775 -283.339706) (xy 60.233288 -283.360804) (xy 60.186017 -283.374496) (xy 60.137162 -283.380428)
			(xy 60.087987 -283.378447) (xy 60.039768 -283.368603) (xy 59.993752 -283.351151) (xy 59.951131 -283.326544)
			(xy 59.91301 -283.295419) (xy 59.880375 -283.258582) (xy 59.854072 -283.216986) (xy 59.834781 -283.17171)
			(xy 59.823004 -283.123926) (xy 59.819044 -283.074872) (xy 58.530236 -283.074872) (xy 58.529741 -283.099479)
			(xy 58.521846 -283.148056) (xy 58.506262 -283.194737) (xy 58.483391 -283.238314) (xy 58.453826 -283.277658)
			(xy 58.418333 -283.31175) (xy 58.37783 -283.339706) (xy 58.333368 -283.360804) (xy 58.286097 -283.374496)
			(xy 58.237242 -283.380428) (xy 58.188067 -283.378447) (xy 58.139848 -283.368603) (xy 58.093832 -283.351151)
			(xy 58.051211 -283.326544) (xy 58.01309 -283.295419) (xy 57.980455 -283.258582) (xy 57.954152 -283.216986)
			(xy 57.934861 -283.17171) (xy 57.923084 -283.123926) (xy 57.919124 -283.074872) (xy 57.580276 -283.074872)
			(xy 57.579781 -283.099479) (xy 57.571886 -283.148056) (xy 57.556302 -283.194737) (xy 57.533431 -283.238314)
			(xy 57.503866 -283.277658) (xy 57.468373 -283.31175) (xy 57.42787 -283.339706) (xy 57.383408 -283.360804)
			(xy 57.336137 -283.374496) (xy 57.287282 -283.380428) (xy 57.238107 -283.378447) (xy 57.189888 -283.368603)
			(xy 57.143872 -283.351151) (xy 57.101251 -283.326544) (xy 57.06313 -283.295419) (xy 57.030495 -283.258582)
			(xy 57.004192 -283.216986) (xy 56.984901 -283.17171) (xy 56.973124 -283.123926) (xy 56.969164 -283.074872)
			(xy 56.630316 -283.074872) (xy 56.629821 -283.099479) (xy 56.621926 -283.148056) (xy 56.606342 -283.194737)
			(xy 56.583471 -283.238314) (xy 56.553906 -283.277658) (xy 56.518413 -283.31175) (xy 56.47791 -283.339706)
			(xy 56.433448 -283.360804) (xy 56.386177 -283.374496) (xy 56.337322 -283.380428) (xy 56.288147 -283.378447)
			(xy 56.239928 -283.368603) (xy 56.193912 -283.351151) (xy 56.151291 -283.326544) (xy 56.11317 -283.295419)
			(xy 56.080535 -283.258582) (xy 56.054232 -283.216986) (xy 56.034941 -283.17171) (xy 56.023164 -283.123926)
			(xy 56.019204 -283.074872) (xy 55.680102 -283.074872) (xy 55.679607 -283.099479) (xy 55.671712 -283.148056)
			(xy 55.656128 -283.194737) (xy 55.633257 -283.238314) (xy 55.603692 -283.277658) (xy 55.568199 -283.31175)
			(xy 55.527696 -283.339706) (xy 55.483234 -283.360804) (xy 55.435963 -283.374496) (xy 55.387108 -283.380428)
			(xy 55.337933 -283.378447) (xy 55.289714 -283.368603) (xy 55.243698 -283.351151) (xy 55.201077 -283.326544)
			(xy 55.162956 -283.295419) (xy 55.130321 -283.258582) (xy 55.104018 -283.216986) (xy 55.084727 -283.17171)
			(xy 55.07295 -283.123926) (xy 55.06899 -283.074872) (xy 54.730142 -283.074872) (xy 54.729647 -283.099479)
			(xy 54.721752 -283.148056) (xy 54.706168 -283.194737) (xy 54.683297 -283.238314) (xy 54.653732 -283.277658)
			(xy 54.618239 -283.31175) (xy 54.577736 -283.339706) (xy 54.533274 -283.360804) (xy 54.486003 -283.374496)
			(xy 54.437148 -283.380428) (xy 54.387973 -283.378447) (xy 54.339754 -283.368603) (xy 54.293738 -283.351151)
			(xy 54.251117 -283.326544) (xy 54.212996 -283.295419) (xy 54.180361 -283.258582) (xy 54.154058 -283.216986)
			(xy 54.134767 -283.17171) (xy 54.12299 -283.123926) (xy 54.11903 -283.074872) (xy 53.780182 -283.074872)
			(xy 53.779687 -283.099479) (xy 53.771792 -283.148056) (xy 53.756208 -283.194737) (xy 53.733337 -283.238314)
			(xy 53.703772 -283.277658) (xy 53.668279 -283.31175) (xy 53.627776 -283.339706) (xy 53.583314 -283.360804)
			(xy 53.536043 -283.374496) (xy 53.487188 -283.380428) (xy 53.438013 -283.378447) (xy 53.389794 -283.368603)
			(xy 53.343778 -283.351151) (xy 53.301157 -283.326544) (xy 53.263036 -283.295419) (xy 53.230401 -283.258582)
			(xy 53.204098 -283.216986) (xy 53.184807 -283.17171) (xy 53.17303 -283.123926) (xy 53.16907 -283.074872)
			(xy 52.830222 -283.074872) (xy 52.829727 -283.099479) (xy 52.821832 -283.148056) (xy 52.806248 -283.194737)
			(xy 52.783377 -283.238314) (xy 52.753812 -283.277658) (xy 52.718319 -283.31175) (xy 52.677816 -283.339706)
			(xy 52.633354 -283.360804) (xy 52.586083 -283.374496) (xy 52.537228 -283.380428) (xy 52.488053 -283.378447)
			(xy 52.439834 -283.368603) (xy 52.393818 -283.351151) (xy 52.351197 -283.326544) (xy 52.313076 -283.295419)
			(xy 52.280441 -283.258582) (xy 52.254138 -283.216986) (xy 52.234847 -283.17171) (xy 52.22307 -283.123926)
			(xy 52.21911 -283.074872) (xy 51.880262 -283.074872) (xy 51.879767 -283.099479) (xy 51.871872 -283.148056)
			(xy 51.856288 -283.194737) (xy 51.833417 -283.238314) (xy 51.803852 -283.277658) (xy 51.768359 -283.31175)
			(xy 51.727856 -283.339706) (xy 51.683394 -283.360804) (xy 51.636123 -283.374496) (xy 51.587268 -283.380428)
			(xy 51.538093 -283.378447) (xy 51.489874 -283.368603) (xy 51.443858 -283.351151) (xy 51.401237 -283.326544)
			(xy 51.363116 -283.295419) (xy 51.330481 -283.258582) (xy 51.304178 -283.216986) (xy 51.284887 -283.17171)
			(xy 51.27311 -283.123926) (xy 51.26915 -283.074872) (xy 50.930302 -283.074872) (xy 50.929807 -283.099479)
			(xy 50.921912 -283.148056) (xy 50.906328 -283.194737) (xy 50.883457 -283.238314) (xy 50.853892 -283.277658)
			(xy 50.818399 -283.31175) (xy 50.777896 -283.339706) (xy 50.733434 -283.360804) (xy 50.686163 -283.374496)
			(xy 50.637308 -283.380428) (xy 50.588133 -283.378447) (xy 50.539914 -283.368603) (xy 50.493898 -283.351151)
			(xy 50.451277 -283.326544) (xy 50.413156 -283.295419) (xy 50.380521 -283.258582) (xy 50.354218 -283.216986)
			(xy 50.334927 -283.17171) (xy 50.32315 -283.123926) (xy 50.31919 -283.074872) (xy 49.980088 -283.074872)
			(xy 49.979593 -283.099479) (xy 49.971698 -283.148056) (xy 49.956114 -283.194737) (xy 49.933243 -283.238314)
			(xy 49.903678 -283.277658) (xy 49.868185 -283.31175) (xy 49.827682 -283.339706) (xy 49.78322 -283.360804)
			(xy 49.735949 -283.374496) (xy 49.687094 -283.380428) (xy 49.637919 -283.378447) (xy 49.5897 -283.368603)
			(xy 49.543684 -283.351151) (xy 49.501063 -283.326544) (xy 49.462942 -283.295419) (xy 49.430307 -283.258582)
			(xy 49.404004 -283.216986) (xy 49.384713 -283.17171) (xy 49.372936 -283.123926) (xy 49.368976 -283.074872)
			(xy 49.030128 -283.074872) (xy 49.029633 -283.099479) (xy 49.021738 -283.148056) (xy 49.006154 -283.194737)
			(xy 48.983283 -283.238314) (xy 48.953718 -283.277658) (xy 48.918225 -283.31175) (xy 48.877722 -283.339706)
			(xy 48.83326 -283.360804) (xy 48.785989 -283.374496) (xy 48.737134 -283.380428) (xy 48.687959 -283.378447)
			(xy 48.63974 -283.368603) (xy 48.593724 -283.351151) (xy 48.551103 -283.326544) (xy 48.512982 -283.295419)
			(xy 48.480347 -283.258582) (xy 48.454044 -283.216986) (xy 48.434753 -283.17171) (xy 48.422976 -283.123926)
			(xy 48.419016 -283.074872) (xy 48.080168 -283.074872) (xy 48.079914 -283.085286) (xy 48.079914 -283.091636)
			(xy 48.07966 -283.096208) (xy 48.07966 -283.09697) (xy 48.078434 -283.11137) (xy 48.073596 -283.139866)
			(xy 48.070008 -283.153866) (xy 48.06823 -283.16047) (xy 48.06823 -283.549852) (xy 73.593972 -283.549852)
			(xy 73.597932 -283.500798) (xy 73.609709 -283.453014) (xy 73.629 -283.407738) (xy 73.655303 -283.366142)
			(xy 73.687938 -283.329305) (xy 73.726059 -283.29818) (xy 73.76868 -283.273573) (xy 73.814696 -283.256121)
			(xy 73.862915 -283.246277) (xy 73.91209 -283.244296) (xy 73.960945 -283.250228) (xy 74.008216 -283.26392)
			(xy 74.052678 -283.285018) (xy 74.093181 -283.312974) (xy 74.128674 -283.347066) (xy 74.158239 -283.38641)
			(xy 74.18111 -283.429987) (xy 74.196694 -283.476668) (xy 74.204589 -283.525245) (xy 74.205084 -283.549852)
			(xy 74.543932 -283.549852) (xy 74.547892 -283.500798) (xy 74.559669 -283.453014) (xy 74.57896 -283.407738)
			(xy 74.605263 -283.366142) (xy 74.637898 -283.329305) (xy 74.676019 -283.29818) (xy 74.71864 -283.273573)
			(xy 74.764656 -283.256121) (xy 74.812875 -283.246277) (xy 74.86205 -283.244296) (xy 74.910905 -283.250228)
			(xy 74.958176 -283.26392) (xy 75.002638 -283.285018) (xy 75.043141 -283.312974) (xy 75.078634 -283.347066)
			(xy 75.108199 -283.38641) (xy 75.13107 -283.429987) (xy 75.146654 -283.476668) (xy 75.154549 -283.525245)
			(xy 75.155044 -283.549852) (xy 75.494146 -283.549852) (xy 75.498106 -283.500798) (xy 75.509883 -283.453014)
			(xy 75.529174 -283.407738) (xy 75.555477 -283.366142) (xy 75.588112 -283.329305) (xy 75.626233 -283.29818)
			(xy 75.668854 -283.273573) (xy 75.71487 -283.256121) (xy 75.763089 -283.246277) (xy 75.812264 -283.244296)
			(xy 75.861119 -283.250228) (xy 75.90839 -283.26392) (xy 75.952852 -283.285018) (xy 75.993355 -283.312974)
			(xy 76.028848 -283.347066) (xy 76.058413 -283.38641) (xy 76.081284 -283.429987) (xy 76.096868 -283.476668)
			(xy 76.104763 -283.525245) (xy 76.105258 -283.549852) (xy 76.444106 -283.549852) (xy 76.448066 -283.500798)
			(xy 76.459843 -283.453014) (xy 76.479134 -283.407738) (xy 76.505437 -283.366142) (xy 76.538072 -283.329305)
			(xy 76.576193 -283.29818) (xy 76.618814 -283.273573) (xy 76.66483 -283.256121) (xy 76.713049 -283.246277)
			(xy 76.762224 -283.244296) (xy 76.811079 -283.250228) (xy 76.85835 -283.26392) (xy 76.902812 -283.285018)
			(xy 76.943315 -283.312974) (xy 76.978808 -283.347066) (xy 77.008373 -283.38641) (xy 77.031244 -283.429987)
			(xy 77.046828 -283.476668) (xy 77.054723 -283.525245) (xy 77.055218 -283.549852) (xy 77.394066 -283.549852)
			(xy 77.398026 -283.500798) (xy 77.409803 -283.453014) (xy 77.429094 -283.407738) (xy 77.455397 -283.366142)
			(xy 77.488032 -283.329305) (xy 77.526153 -283.29818) (xy 77.568774 -283.273573) (xy 77.61479 -283.256121)
			(xy 77.663009 -283.246277) (xy 77.712184 -283.244296) (xy 77.761039 -283.250228) (xy 77.80831 -283.26392)
			(xy 77.852772 -283.285018) (xy 77.893275 -283.312974) (xy 77.928768 -283.347066) (xy 77.958333 -283.38641)
			(xy 77.981204 -283.429987) (xy 77.996788 -283.476668) (xy 78.004683 -283.525245) (xy 78.005178 -283.549852)
			(xy 78.344026 -283.549852) (xy 78.347986 -283.500798) (xy 78.359763 -283.453014) (xy 78.379054 -283.407738)
			(xy 78.405357 -283.366142) (xy 78.437992 -283.329305) (xy 78.476113 -283.29818) (xy 78.518734 -283.273573)
			(xy 78.56475 -283.256121) (xy 78.612969 -283.246277) (xy 78.662144 -283.244296) (xy 78.710999 -283.250228)
			(xy 78.75827 -283.26392) (xy 78.802732 -283.285018) (xy 78.843235 -283.312974) (xy 78.878728 -283.347066)
			(xy 78.908293 -283.38641) (xy 78.931164 -283.429987) (xy 78.946748 -283.476668) (xy 78.954643 -283.525245)
			(xy 78.955138 -283.549852) (xy 79.293986 -283.549852) (xy 79.297946 -283.500798) (xy 79.309723 -283.453014)
			(xy 79.329014 -283.407738) (xy 79.355317 -283.366142) (xy 79.387952 -283.329305) (xy 79.426073 -283.29818)
			(xy 79.468694 -283.273573) (xy 79.51471 -283.256121) (xy 79.562929 -283.246277) (xy 79.612104 -283.244296)
			(xy 79.660959 -283.250228) (xy 79.70823 -283.26392) (xy 79.752692 -283.285018) (xy 79.793195 -283.312974)
			(xy 79.828688 -283.347066) (xy 79.858253 -283.38641) (xy 79.881124 -283.429987) (xy 79.896708 -283.476668)
			(xy 79.904603 -283.525245) (xy 79.905098 -283.549852) (xy 80.243946 -283.549852) (xy 80.247906 -283.500798)
			(xy 80.259683 -283.453014) (xy 80.278974 -283.407738) (xy 80.305277 -283.366142) (xy 80.337912 -283.329305)
			(xy 80.376033 -283.29818) (xy 80.418654 -283.273573) (xy 80.46467 -283.256121) (xy 80.512889 -283.246277)
			(xy 80.562064 -283.244296) (xy 80.610919 -283.250228) (xy 80.65819 -283.26392) (xy 80.702652 -283.285018)
			(xy 80.743155 -283.312974) (xy 80.778648 -283.347066) (xy 80.808213 -283.38641) (xy 80.831084 -283.429987)
			(xy 80.846668 -283.476668) (xy 80.854563 -283.525245) (xy 80.855058 -283.549852) (xy 80.854563 -283.574459)
			(xy 80.854384 -283.57556) (xy 81.173316 -283.57556) (xy 81.173316 -283.524144) (xy 81.181359 -283.473362)
			(xy 81.197247 -283.424463) (xy 81.22059 -283.378651) (xy 81.250811 -283.337055) (xy 81.287167 -283.300699)
			(xy 81.328763 -283.270478) (xy 81.374575 -283.247135) (xy 81.423474 -283.231247) (xy 81.474256 -283.223204)
			(xy 81.525672 -283.223204) (xy 81.576454 -283.231247) (xy 81.625353 -283.247135) (xy 81.671165 -283.270478)
			(xy 81.712761 -283.300699) (xy 81.749117 -283.337055) (xy 81.779338 -283.378651) (xy 81.802681 -283.424463)
			(xy 81.818569 -283.473362) (xy 81.826612 -283.524144) (xy 81.827116 -283.549852) (xy 81.826612 -283.57556)
			(xy 82.123276 -283.57556) (xy 82.123276 -283.524144) (xy 82.131319 -283.473362) (xy 82.147207 -283.424463)
			(xy 82.17055 -283.378651) (xy 82.200771 -283.337055) (xy 82.237127 -283.300699) (xy 82.278723 -283.270478)
			(xy 82.324535 -283.247135) (xy 82.373434 -283.231247) (xy 82.424216 -283.223204) (xy 82.475632 -283.223204)
			(xy 82.526414 -283.231247) (xy 82.575313 -283.247135) (xy 82.621125 -283.270478) (xy 82.662721 -283.300699)
			(xy 82.699077 -283.337055) (xy 82.729298 -283.378651) (xy 82.752641 -283.424463) (xy 82.768529 -283.473362)
			(xy 82.776572 -283.524144) (xy 82.777076 -283.549852) (xy 82.777071 -283.550106) (xy 83.094334 -283.550106)
			(xy 83.098294 -283.501052) (xy 83.110071 -283.453268) (xy 83.129362 -283.407992) (xy 83.155665 -283.366396)
			(xy 83.1883 -283.329559) (xy 83.226421 -283.298434) (xy 83.269042 -283.273827) (xy 83.315058 -283.256375)
			(xy 83.363277 -283.246531) (xy 83.412452 -283.24455) (xy 83.461307 -283.250482) (xy 83.508578 -283.264174)
			(xy 83.55304 -283.285272) (xy 83.593543 -283.313228) (xy 83.629036 -283.34732) (xy 83.658601 -283.386664)
			(xy 83.681472 -283.430241) (xy 83.697056 -283.476922) (xy 83.704951 -283.525499) (xy 83.705446 -283.550106)
			(xy 83.704951 -283.574713) (xy 83.697056 -283.62329) (xy 83.681472 -283.669971) (xy 83.658601 -283.713548)
			(xy 83.629036 -283.752892) (xy 83.593543 -283.786984) (xy 83.55304 -283.81494) (xy 83.508578 -283.836038)
			(xy 83.461307 -283.84973) (xy 83.412452 -283.855662) (xy 83.363277 -283.853681) (xy 83.315058 -283.843837)
			(xy 83.269042 -283.826385) (xy 83.226421 -283.801778) (xy 83.1883 -283.770653) (xy 83.155665 -283.733816)
			(xy 83.129362 -283.69222) (xy 83.110071 -283.646944) (xy 83.098294 -283.59916) (xy 83.094334 -283.550106)
			(xy 82.777071 -283.550106) (xy 82.776572 -283.57556) (xy 82.768529 -283.626342) (xy 82.752641 -283.675241)
			(xy 82.729298 -283.721053) (xy 82.699077 -283.762649) (xy 82.662721 -283.799005) (xy 82.621125 -283.829226)
			(xy 82.575313 -283.852569) (xy 82.526414 -283.868457) (xy 82.475632 -283.8765) (xy 82.424216 -283.8765)
			(xy 82.373434 -283.868457) (xy 82.324535 -283.852569) (xy 82.278723 -283.829226) (xy 82.237127 -283.799005)
			(xy 82.200771 -283.762649) (xy 82.17055 -283.721053) (xy 82.147207 -283.675241) (xy 82.131319 -283.626342)
			(xy 82.123276 -283.57556) (xy 81.826612 -283.57556) (xy 81.818569 -283.626342) (xy 81.802681 -283.675241)
			(xy 81.779338 -283.721053) (xy 81.749117 -283.762649) (xy 81.712761 -283.799005) (xy 81.671165 -283.829226)
			(xy 81.625353 -283.852569) (xy 81.576454 -283.868457) (xy 81.525672 -283.8765) (xy 81.474256 -283.8765)
			(xy 81.423474 -283.868457) (xy 81.374575 -283.852569) (xy 81.328763 -283.829226) (xy 81.287167 -283.799005)
			(xy 81.250811 -283.762649) (xy 81.22059 -283.721053) (xy 81.197247 -283.675241) (xy 81.181359 -283.626342)
			(xy 81.173316 -283.57556) (xy 80.854384 -283.57556) (xy 80.846668 -283.623036) (xy 80.831084 -283.669717)
			(xy 80.808213 -283.713294) (xy 80.778648 -283.752638) (xy 80.743155 -283.78673) (xy 80.702652 -283.814686)
			(xy 80.65819 -283.835784) (xy 80.610919 -283.849476) (xy 80.562064 -283.855408) (xy 80.512889 -283.853427)
			(xy 80.46467 -283.843583) (xy 80.418654 -283.826131) (xy 80.376033 -283.801524) (xy 80.337912 -283.770399)
			(xy 80.305277 -283.733562) (xy 80.278974 -283.691966) (xy 80.259683 -283.64669) (xy 80.247906 -283.598906)
			(xy 80.243946 -283.549852) (xy 79.905098 -283.549852) (xy 79.904603 -283.574459) (xy 79.896708 -283.623036)
			(xy 79.881124 -283.669717) (xy 79.858253 -283.713294) (xy 79.828688 -283.752638) (xy 79.793195 -283.78673)
			(xy 79.752692 -283.814686) (xy 79.70823 -283.835784) (xy 79.660959 -283.849476) (xy 79.612104 -283.855408)
			(xy 79.562929 -283.853427) (xy 79.51471 -283.843583) (xy 79.468694 -283.826131) (xy 79.426073 -283.801524)
			(xy 79.387952 -283.770399) (xy 79.355317 -283.733562) (xy 79.329014 -283.691966) (xy 79.309723 -283.64669)
			(xy 79.297946 -283.598906) (xy 79.293986 -283.549852) (xy 78.955138 -283.549852) (xy 78.954643 -283.574459)
			(xy 78.946748 -283.623036) (xy 78.931164 -283.669717) (xy 78.908293 -283.713294) (xy 78.878728 -283.752638)
			(xy 78.843235 -283.78673) (xy 78.802732 -283.814686) (xy 78.75827 -283.835784) (xy 78.710999 -283.849476)
			(xy 78.662144 -283.855408) (xy 78.612969 -283.853427) (xy 78.56475 -283.843583) (xy 78.518734 -283.826131)
			(xy 78.476113 -283.801524) (xy 78.437992 -283.770399) (xy 78.405357 -283.733562) (xy 78.379054 -283.691966)
			(xy 78.359763 -283.64669) (xy 78.347986 -283.598906) (xy 78.344026 -283.549852) (xy 78.005178 -283.549852)
			(xy 78.004683 -283.574459) (xy 77.996788 -283.623036) (xy 77.981204 -283.669717) (xy 77.958333 -283.713294)
			(xy 77.928768 -283.752638) (xy 77.893275 -283.78673) (xy 77.852772 -283.814686) (xy 77.80831 -283.835784)
			(xy 77.761039 -283.849476) (xy 77.712184 -283.855408) (xy 77.663009 -283.853427) (xy 77.61479 -283.843583)
			(xy 77.568774 -283.826131) (xy 77.526153 -283.801524) (xy 77.488032 -283.770399) (xy 77.455397 -283.733562)
			(xy 77.429094 -283.691966) (xy 77.409803 -283.64669) (xy 77.398026 -283.598906) (xy 77.394066 -283.549852)
			(xy 77.055218 -283.549852) (xy 77.054723 -283.574459) (xy 77.046828 -283.623036) (xy 77.031244 -283.669717)
			(xy 77.008373 -283.713294) (xy 76.978808 -283.752638) (xy 76.943315 -283.78673) (xy 76.902812 -283.814686)
			(xy 76.85835 -283.835784) (xy 76.811079 -283.849476) (xy 76.762224 -283.855408) (xy 76.713049 -283.853427)
			(xy 76.66483 -283.843583) (xy 76.618814 -283.826131) (xy 76.576193 -283.801524) (xy 76.538072 -283.770399)
			(xy 76.505437 -283.733562) (xy 76.479134 -283.691966) (xy 76.459843 -283.64669) (xy 76.448066 -283.598906)
			(xy 76.444106 -283.549852) (xy 76.105258 -283.549852) (xy 76.104763 -283.574459) (xy 76.096868 -283.623036)
			(xy 76.081284 -283.669717) (xy 76.058413 -283.713294) (xy 76.028848 -283.752638) (xy 75.993355 -283.78673)
			(xy 75.952852 -283.814686) (xy 75.90839 -283.835784) (xy 75.861119 -283.849476) (xy 75.812264 -283.855408)
			(xy 75.763089 -283.853427) (xy 75.71487 -283.843583) (xy 75.668854 -283.826131) (xy 75.626233 -283.801524)
			(xy 75.588112 -283.770399) (xy 75.555477 -283.733562) (xy 75.529174 -283.691966) (xy 75.509883 -283.64669)
			(xy 75.498106 -283.598906) (xy 75.494146 -283.549852) (xy 75.155044 -283.549852) (xy 75.154549 -283.574459)
			(xy 75.146654 -283.623036) (xy 75.13107 -283.669717) (xy 75.108199 -283.713294) (xy 75.078634 -283.752638)
			(xy 75.043141 -283.78673) (xy 75.002638 -283.814686) (xy 74.958176 -283.835784) (xy 74.910905 -283.849476)
			(xy 74.86205 -283.855408) (xy 74.812875 -283.853427) (xy 74.764656 -283.843583) (xy 74.71864 -283.826131)
			(xy 74.676019 -283.801524) (xy 74.637898 -283.770399) (xy 74.605263 -283.733562) (xy 74.57896 -283.691966)
			(xy 74.559669 -283.64669) (xy 74.547892 -283.598906) (xy 74.543932 -283.549852) (xy 74.205084 -283.549852)
			(xy 74.204589 -283.574459) (xy 74.196694 -283.623036) (xy 74.18111 -283.669717) (xy 74.158239 -283.713294)
			(xy 74.128674 -283.752638) (xy 74.093181 -283.78673) (xy 74.052678 -283.814686) (xy 74.008216 -283.835784)
			(xy 73.960945 -283.849476) (xy 73.91209 -283.855408) (xy 73.862915 -283.853427) (xy 73.814696 -283.843583)
			(xy 73.76868 -283.826131) (xy 73.726059 -283.801524) (xy 73.687938 -283.770399) (xy 73.655303 -283.733562)
			(xy 73.629 -283.691966) (xy 73.609709 -283.64669) (xy 73.597932 -283.598906) (xy 73.593972 -283.549852)
			(xy 48.06823 -283.549852) (xy 48.06823 -283.933392) (xy 48.070008 -283.9466) (xy 48.07077 -283.949648)
			(xy 48.075169 -283.968132) (xy 48.079883 -284.005834) (xy 48.080168 -284.024832) (xy 48.419016 -284.024832)
			(xy 48.422976 -283.975778) (xy 48.434753 -283.927994) (xy 48.454044 -283.882718) (xy 48.480347 -283.841122)
			(xy 48.512982 -283.804285) (xy 48.551103 -283.77316) (xy 48.593724 -283.748553) (xy 48.63974 -283.731101)
			(xy 48.687959 -283.721257) (xy 48.737134 -283.719276) (xy 48.785989 -283.725208) (xy 48.83326 -283.7389)
			(xy 48.877722 -283.759998) (xy 48.918225 -283.787954) (xy 48.953718 -283.822046) (xy 48.983283 -283.86139)
			(xy 49.006154 -283.904967) (xy 49.021738 -283.951648) (xy 49.029633 -284.000225) (xy 49.030128 -284.024832)
			(xy 49.368976 -284.024832) (xy 49.372936 -283.975778) (xy 49.384713 -283.927994) (xy 49.404004 -283.882718)
			(xy 49.430307 -283.841122) (xy 49.462942 -283.804285) (xy 49.501063 -283.77316) (xy 49.543684 -283.748553)
			(xy 49.5897 -283.731101) (xy 49.637919 -283.721257) (xy 49.687094 -283.719276) (xy 49.735949 -283.725208)
			(xy 49.78322 -283.7389) (xy 49.827682 -283.759998) (xy 49.868185 -283.787954) (xy 49.903678 -283.822046)
			(xy 49.933243 -283.86139) (xy 49.956114 -283.904967) (xy 49.971698 -283.951648) (xy 49.979593 -284.000225)
			(xy 49.980088 -284.024832) (xy 50.31919 -284.024832) (xy 50.32315 -283.975778) (xy 50.334927 -283.927994)
			(xy 50.354218 -283.882718) (xy 50.380521 -283.841122) (xy 50.413156 -283.804285) (xy 50.451277 -283.77316)
			(xy 50.493898 -283.748553) (xy 50.539914 -283.731101) (xy 50.588133 -283.721257) (xy 50.637308 -283.719276)
			(xy 50.686163 -283.725208) (xy 50.733434 -283.7389) (xy 50.777896 -283.759998) (xy 50.818399 -283.787954)
			(xy 50.853892 -283.822046) (xy 50.883457 -283.86139) (xy 50.906328 -283.904967) (xy 50.921912 -283.951648)
			(xy 50.929807 -284.000225) (xy 50.930302 -284.024832) (xy 51.26915 -284.024832) (xy 51.27311 -283.975778)
			(xy 51.284887 -283.927994) (xy 51.304178 -283.882718) (xy 51.330481 -283.841122) (xy 51.363116 -283.804285)
			(xy 51.401237 -283.77316) (xy 51.443858 -283.748553) (xy 51.489874 -283.731101) (xy 51.538093 -283.721257)
			(xy 51.587268 -283.719276) (xy 51.636123 -283.725208) (xy 51.683394 -283.7389) (xy 51.727856 -283.759998)
			(xy 51.768359 -283.787954) (xy 51.803852 -283.822046) (xy 51.833417 -283.86139) (xy 51.856288 -283.904967)
			(xy 51.871872 -283.951648) (xy 51.879767 -284.000225) (xy 51.880262 -284.024832) (xy 52.21911 -284.024832)
			(xy 52.22307 -283.975778) (xy 52.234847 -283.927994) (xy 52.254138 -283.882718) (xy 52.280441 -283.841122)
			(xy 52.313076 -283.804285) (xy 52.351197 -283.77316) (xy 52.393818 -283.748553) (xy 52.439834 -283.731101)
			(xy 52.488053 -283.721257) (xy 52.537228 -283.719276) (xy 52.586083 -283.725208) (xy 52.633354 -283.7389)
			(xy 52.677816 -283.759998) (xy 52.718319 -283.787954) (xy 52.753812 -283.822046) (xy 52.783377 -283.86139)
			(xy 52.806248 -283.904967) (xy 52.821832 -283.951648) (xy 52.829727 -284.000225) (xy 52.830222 -284.024832)
			(xy 53.16907 -284.024832) (xy 53.17303 -283.975778) (xy 53.184807 -283.927994) (xy 53.204098 -283.882718)
			(xy 53.230401 -283.841122) (xy 53.263036 -283.804285) (xy 53.301157 -283.77316) (xy 53.343778 -283.748553)
			(xy 53.389794 -283.731101) (xy 53.438013 -283.721257) (xy 53.487188 -283.719276) (xy 53.536043 -283.725208)
			(xy 53.583314 -283.7389) (xy 53.627776 -283.759998) (xy 53.668279 -283.787954) (xy 53.703772 -283.822046)
			(xy 53.733337 -283.86139) (xy 53.756208 -283.904967) (xy 53.771792 -283.951648) (xy 53.779687 -284.000225)
			(xy 53.780182 -284.024832) (xy 54.11903 -284.024832) (xy 54.12299 -283.975778) (xy 54.134767 -283.927994)
			(xy 54.154058 -283.882718) (xy 54.180361 -283.841122) (xy 54.212996 -283.804285) (xy 54.251117 -283.77316)
			(xy 54.293738 -283.748553) (xy 54.339754 -283.731101) (xy 54.387973 -283.721257) (xy 54.437148 -283.719276)
			(xy 54.486003 -283.725208) (xy 54.533274 -283.7389) (xy 54.577736 -283.759998) (xy 54.618239 -283.787954)
			(xy 54.653732 -283.822046) (xy 54.683297 -283.86139) (xy 54.706168 -283.904967) (xy 54.721752 -283.951648)
			(xy 54.729647 -284.000225) (xy 54.730142 -284.024832) (xy 55.06899 -284.024832) (xy 55.07295 -283.975778)
			(xy 55.084727 -283.927994) (xy 55.104018 -283.882718) (xy 55.130321 -283.841122) (xy 55.162956 -283.804285)
			(xy 55.201077 -283.77316) (xy 55.243698 -283.748553) (xy 55.289714 -283.731101) (xy 55.337933 -283.721257)
			(xy 55.387108 -283.719276) (xy 55.435963 -283.725208) (xy 55.483234 -283.7389) (xy 55.527696 -283.759998)
			(xy 55.568199 -283.787954) (xy 55.603692 -283.822046) (xy 55.633257 -283.86139) (xy 55.656128 -283.904967)
			(xy 55.671712 -283.951648) (xy 55.679607 -284.000225) (xy 55.680102 -284.024832) (xy 56.01895 -284.024832)
			(xy 56.02291 -283.975778) (xy 56.034687 -283.927994) (xy 56.053978 -283.882718) (xy 56.080281 -283.841122)
			(xy 56.112916 -283.804285) (xy 56.151037 -283.77316) (xy 56.193658 -283.748553) (xy 56.239674 -283.731101)
			(xy 56.287893 -283.721257) (xy 56.337068 -283.719276) (xy 56.385923 -283.725208) (xy 56.433194 -283.7389)
			(xy 56.477656 -283.759998) (xy 56.518159 -283.787954) (xy 56.553652 -283.822046) (xy 56.583217 -283.86139)
			(xy 56.606088 -283.904967) (xy 56.621672 -283.951648) (xy 56.629567 -284.000225) (xy 56.630062 -284.024832)
			(xy 56.969164 -284.024832) (xy 56.973124 -283.975778) (xy 56.984901 -283.927994) (xy 57.004192 -283.882718)
			(xy 57.030495 -283.841122) (xy 57.06313 -283.804285) (xy 57.101251 -283.77316) (xy 57.143872 -283.748553)
			(xy 57.189888 -283.731101) (xy 57.238107 -283.721257) (xy 57.287282 -283.719276) (xy 57.336137 -283.725208)
			(xy 57.383408 -283.7389) (xy 57.42787 -283.759998) (xy 57.468373 -283.787954) (xy 57.503866 -283.822046)
			(xy 57.533431 -283.86139) (xy 57.556302 -283.904967) (xy 57.571886 -283.951648) (xy 57.579781 -284.000225)
			(xy 57.580276 -284.024832) (xy 57.919124 -284.024832) (xy 57.923084 -283.975778) (xy 57.934861 -283.927994)
			(xy 57.954152 -283.882718) (xy 57.980455 -283.841122) (xy 58.01309 -283.804285) (xy 58.051211 -283.77316)
			(xy 58.093832 -283.748553) (xy 58.139848 -283.731101) (xy 58.188067 -283.721257) (xy 58.237242 -283.719276)
			(xy 58.286097 -283.725208) (xy 58.333368 -283.7389) (xy 58.37783 -283.759998) (xy 58.418333 -283.787954)
			(xy 58.453826 -283.822046) (xy 58.483391 -283.86139) (xy 58.506262 -283.904967) (xy 58.521846 -283.951648)
			(xy 58.529741 -284.000225) (xy 58.530236 -284.024832) (xy 59.819044 -284.024832) (xy 59.823004 -283.975778)
			(xy 59.834781 -283.927994) (xy 59.854072 -283.882718) (xy 59.880375 -283.841122) (xy 59.91301 -283.804285)
			(xy 59.951131 -283.77316) (xy 59.993752 -283.748553) (xy 60.039768 -283.731101) (xy 60.087987 -283.721257)
			(xy 60.137162 -283.719276) (xy 60.186017 -283.725208) (xy 60.233288 -283.7389) (xy 60.27775 -283.759998)
			(xy 60.318253 -283.787954) (xy 60.353746 -283.822046) (xy 60.383311 -283.86139) (xy 60.406182 -283.904967)
			(xy 60.421766 -283.951648) (xy 60.429661 -284.000225) (xy 60.430156 -284.024832) (xy 60.769004 -284.024832)
			(xy 60.772964 -283.975778) (xy 60.784741 -283.927994) (xy 60.804032 -283.882718) (xy 60.830335 -283.841122)
			(xy 60.86297 -283.804285) (xy 60.901091 -283.77316) (xy 60.943712 -283.748553) (xy 60.989728 -283.731101)
			(xy 61.037947 -283.721257) (xy 61.087122 -283.719276) (xy 61.135977 -283.725208) (xy 61.183248 -283.7389)
			(xy 61.22771 -283.759998) (xy 61.268213 -283.787954) (xy 61.303706 -283.822046) (xy 61.333271 -283.86139)
			(xy 61.356142 -283.904967) (xy 61.371726 -283.951648) (xy 61.379621 -284.000225) (xy 61.380116 -284.024832)
			(xy 61.718964 -284.024832) (xy 61.722924 -283.975778) (xy 61.734701 -283.927994) (xy 61.753992 -283.882718)
			(xy 61.780295 -283.841122) (xy 61.81293 -283.804285) (xy 61.851051 -283.77316) (xy 61.893672 -283.748553)
			(xy 61.939688 -283.731101) (xy 61.987907 -283.721257) (xy 62.037082 -283.719276) (xy 62.085937 -283.725208)
			(xy 62.133208 -283.7389) (xy 62.17767 -283.759998) (xy 62.218173 -283.787954) (xy 62.253666 -283.822046)
			(xy 62.283231 -283.86139) (xy 62.306102 -283.904967) (xy 62.321686 -283.951648) (xy 62.329581 -284.000225)
			(xy 62.330076 -284.024832) (xy 62.669178 -284.024832) (xy 62.673138 -283.975778) (xy 62.684915 -283.927994)
			(xy 62.704206 -283.882718) (xy 62.730509 -283.841122) (xy 62.763144 -283.804285) (xy 62.801265 -283.77316)
			(xy 62.843886 -283.748553) (xy 62.889902 -283.731101) (xy 62.938121 -283.721257) (xy 62.987296 -283.719276)
			(xy 63.036151 -283.725208) (xy 63.083422 -283.7389) (xy 63.127884 -283.759998) (xy 63.168387 -283.787954)
			(xy 63.20388 -283.822046) (xy 63.233445 -283.86139) (xy 63.256316 -283.904967) (xy 63.2719 -283.951648)
			(xy 63.279795 -284.000225) (xy 63.28029 -284.024832) (xy 63.619138 -284.024832) (xy 63.623098 -283.975778)
			(xy 63.634875 -283.927994) (xy 63.654166 -283.882718) (xy 63.680469 -283.841122) (xy 63.713104 -283.804285)
			(xy 63.751225 -283.77316) (xy 63.793846 -283.748553) (xy 63.839862 -283.731101) (xy 63.888081 -283.721257)
			(xy 63.937256 -283.719276) (xy 63.986111 -283.725208) (xy 64.033382 -283.7389) (xy 64.077844 -283.759998)
			(xy 64.118347 -283.787954) (xy 64.15384 -283.822046) (xy 64.183405 -283.86139) (xy 64.206276 -283.904967)
			(xy 64.22186 -283.951648) (xy 64.229755 -284.000225) (xy 64.23025 -284.024832) (xy 64.569098 -284.024832)
			(xy 64.573058 -283.975778) (xy 64.584835 -283.927994) (xy 64.604126 -283.882718) (xy 64.630429 -283.841122)
			(xy 64.663064 -283.804285) (xy 64.701185 -283.77316) (xy 64.743806 -283.748553) (xy 64.789822 -283.731101)
			(xy 64.838041 -283.721257) (xy 64.887216 -283.719276) (xy 64.936071 -283.725208) (xy 64.983342 -283.7389)
			(xy 65.027804 -283.759998) (xy 65.068307 -283.787954) (xy 65.1038 -283.822046) (xy 65.133365 -283.86139)
			(xy 65.156236 -283.904967) (xy 65.17182 -283.951648) (xy 65.179715 -284.000225) (xy 65.18021 -284.024832)
			(xy 65.519058 -284.024832) (xy 65.523018 -283.975778) (xy 65.534795 -283.927994) (xy 65.554086 -283.882718)
			(xy 65.580389 -283.841122) (xy 65.613024 -283.804285) (xy 65.651145 -283.77316) (xy 65.693766 -283.748553)
			(xy 65.739782 -283.731101) (xy 65.788001 -283.721257) (xy 65.837176 -283.719276) (xy 65.886031 -283.725208)
			(xy 65.933302 -283.7389) (xy 65.977764 -283.759998) (xy 66.018267 -283.787954) (xy 66.05376 -283.822046)
			(xy 66.083325 -283.86139) (xy 66.106196 -283.904967) (xy 66.12178 -283.951648) (xy 66.129675 -284.000225)
			(xy 66.13017 -284.024832) (xy 66.469018 -284.024832) (xy 66.472978 -283.975778) (xy 66.484755 -283.927994)
			(xy 66.504046 -283.882718) (xy 66.530349 -283.841122) (xy 66.562984 -283.804285) (xy 66.601105 -283.77316)
			(xy 66.643726 -283.748553) (xy 66.689742 -283.731101) (xy 66.737961 -283.721257) (xy 66.787136 -283.719276)
			(xy 66.835991 -283.725208) (xy 66.883262 -283.7389) (xy 66.927724 -283.759998) (xy 66.968227 -283.787954)
			(xy 67.00372 -283.822046) (xy 67.033285 -283.86139) (xy 67.056156 -283.904967) (xy 67.07174 -283.951648)
			(xy 67.079635 -284.000225) (xy 67.08013 -284.024832) (xy 68.368938 -284.024832) (xy 68.372898 -283.975778)
			(xy 68.384675 -283.927994) (xy 68.403966 -283.882718) (xy 68.430269 -283.841122) (xy 68.462904 -283.804285)
			(xy 68.501025 -283.77316) (xy 68.543646 -283.748553) (xy 68.589662 -283.731101) (xy 68.637881 -283.721257)
			(xy 68.687056 -283.719276) (xy 68.735911 -283.725208) (xy 68.783182 -283.7389) (xy 68.827644 -283.759998)
			(xy 68.868147 -283.787954) (xy 68.90364 -283.822046) (xy 68.933205 -283.86139) (xy 68.956076 -283.904967)
			(xy 68.97166 -283.951648) (xy 68.979555 -284.000225) (xy 68.98005 -284.024832) (xy 69.319152 -284.024832)
			(xy 69.323112 -283.975778) (xy 69.334889 -283.927994) (xy 69.35418 -283.882718) (xy 69.380483 -283.841122)
			(xy 69.413118 -283.804285) (xy 69.451239 -283.77316) (xy 69.49386 -283.748553) (xy 69.539876 -283.731101)
			(xy 69.588095 -283.721257) (xy 69.63727 -283.719276) (xy 69.686125 -283.725208) (xy 69.733396 -283.7389)
			(xy 69.777858 -283.759998) (xy 69.818361 -283.787954) (xy 69.853854 -283.822046) (xy 69.883419 -283.86139)
			(xy 69.90629 -283.904967) (xy 69.921874 -283.951648) (xy 69.929769 -284.000225) (xy 69.930264 -284.024832)
			(xy 70.269112 -284.024832) (xy 70.273072 -283.975778) (xy 70.284849 -283.927994) (xy 70.30414 -283.882718)
			(xy 70.330443 -283.841122) (xy 70.363078 -283.804285) (xy 70.401199 -283.77316) (xy 70.44382 -283.748553)
			(xy 70.489836 -283.731101) (xy 70.538055 -283.721257) (xy 70.58723 -283.719276) (xy 70.636085 -283.725208)
			(xy 70.683356 -283.7389) (xy 70.727818 -283.759998) (xy 70.768321 -283.787954) (xy 70.803814 -283.822046)
			(xy 70.833379 -283.86139) (xy 70.85625 -283.904967) (xy 70.871834 -283.951648) (xy 70.879729 -284.000225)
			(xy 70.880224 -284.024832) (xy 71.219072 -284.024832) (xy 71.223032 -283.975778) (xy 71.234809 -283.927994)
			(xy 71.2541 -283.882718) (xy 71.280403 -283.841122) (xy 71.313038 -283.804285) (xy 71.351159 -283.77316)
			(xy 71.39378 -283.748553) (xy 71.439796 -283.731101) (xy 71.488015 -283.721257) (xy 71.53719 -283.719276)
			(xy 71.586045 -283.725208) (xy 71.633316 -283.7389) (xy 71.677778 -283.759998) (xy 71.718281 -283.787954)
			(xy 71.753774 -283.822046) (xy 71.783339 -283.86139) (xy 71.80621 -283.904967) (xy 71.821794 -283.951648)
			(xy 71.829689 -284.000225) (xy 71.830184 -284.024832) (xy 72.169032 -284.024832) (xy 72.172992 -283.975778)
			(xy 72.184769 -283.927994) (xy 72.20406 -283.882718) (xy 72.230363 -283.841122) (xy 72.262998 -283.804285)
			(xy 72.301119 -283.77316) (xy 72.34374 -283.748553) (xy 72.389756 -283.731101) (xy 72.437975 -283.721257)
			(xy 72.48715 -283.719276) (xy 72.536005 -283.725208) (xy 72.583276 -283.7389) (xy 72.627738 -283.759998)
			(xy 72.668241 -283.787954) (xy 72.703734 -283.822046) (xy 72.733299 -283.86139) (xy 72.75617 -283.904967)
			(xy 72.771754 -283.951648) (xy 72.779649 -284.000225) (xy 72.780144 -284.024832) (xy 72.779649 -284.049439)
			(xy 72.771754 -284.098016) (xy 72.75617 -284.144697) (xy 72.733299 -284.188274) (xy 72.703734 -284.227618)
			(xy 72.668241 -284.26171) (xy 72.627738 -284.289666) (xy 72.583276 -284.310764) (xy 72.536005 -284.324456)
			(xy 72.48715 -284.330388) (xy 72.437975 -284.328407) (xy 72.389756 -284.318563) (xy 72.34374 -284.301111)
			(xy 72.301119 -284.276504) (xy 72.262998 -284.245379) (xy 72.230363 -284.208542) (xy 72.20406 -284.166946)
			(xy 72.184769 -284.12167) (xy 72.172992 -284.073886) (xy 72.169032 -284.024832) (xy 71.830184 -284.024832)
			(xy 71.829689 -284.049439) (xy 71.821794 -284.098016) (xy 71.80621 -284.144697) (xy 71.783339 -284.188274)
			(xy 71.753774 -284.227618) (xy 71.718281 -284.26171) (xy 71.677778 -284.289666) (xy 71.633316 -284.310764)
			(xy 71.586045 -284.324456) (xy 71.53719 -284.330388) (xy 71.488015 -284.328407) (xy 71.439796 -284.318563)
			(xy 71.39378 -284.301111) (xy 71.351159 -284.276504) (xy 71.313038 -284.245379) (xy 71.280403 -284.208542)
			(xy 71.2541 -284.166946) (xy 71.234809 -284.12167) (xy 71.223032 -284.073886) (xy 71.219072 -284.024832)
			(xy 70.880224 -284.024832) (xy 70.879729 -284.049439) (xy 70.871834 -284.098016) (xy 70.85625 -284.144697)
			(xy 70.833379 -284.188274) (xy 70.803814 -284.227618) (xy 70.768321 -284.26171) (xy 70.727818 -284.289666)
			(xy 70.683356 -284.310764) (xy 70.636085 -284.324456) (xy 70.58723 -284.330388) (xy 70.538055 -284.328407)
			(xy 70.489836 -284.318563) (xy 70.44382 -284.301111) (xy 70.401199 -284.276504) (xy 70.363078 -284.245379)
			(xy 70.330443 -284.208542) (xy 70.30414 -284.166946) (xy 70.284849 -284.12167) (xy 70.273072 -284.073886)
			(xy 70.269112 -284.024832) (xy 69.930264 -284.024832) (xy 69.929769 -284.049439) (xy 69.921874 -284.098016)
			(xy 69.90629 -284.144697) (xy 69.883419 -284.188274) (xy 69.853854 -284.227618) (xy 69.818361 -284.26171)
			(xy 69.777858 -284.289666) (xy 69.733396 -284.310764) (xy 69.686125 -284.324456) (xy 69.63727 -284.330388)
			(xy 69.588095 -284.328407) (xy 69.539876 -284.318563) (xy 69.49386 -284.301111) (xy 69.451239 -284.276504)
			(xy 69.413118 -284.245379) (xy 69.380483 -284.208542) (xy 69.35418 -284.166946) (xy 69.334889 -284.12167)
			(xy 69.323112 -284.073886) (xy 69.319152 -284.024832) (xy 68.98005 -284.024832) (xy 68.979555 -284.049439)
			(xy 68.97166 -284.098016) (xy 68.956076 -284.144697) (xy 68.933205 -284.188274) (xy 68.90364 -284.227618)
			(xy 68.868147 -284.26171) (xy 68.827644 -284.289666) (xy 68.783182 -284.310764) (xy 68.735911 -284.324456)
			(xy 68.687056 -284.330388) (xy 68.637881 -284.328407) (xy 68.589662 -284.318563) (xy 68.543646 -284.301111)
			(xy 68.501025 -284.276504) (xy 68.462904 -284.245379) (xy 68.430269 -284.208542) (xy 68.403966 -284.166946)
			(xy 68.384675 -284.12167) (xy 68.372898 -284.073886) (xy 68.368938 -284.024832) (xy 67.08013 -284.024832)
			(xy 67.079635 -284.049439) (xy 67.07174 -284.098016) (xy 67.056156 -284.144697) (xy 67.033285 -284.188274)
			(xy 67.00372 -284.227618) (xy 66.968227 -284.26171) (xy 66.927724 -284.289666) (xy 66.883262 -284.310764)
			(xy 66.835991 -284.324456) (xy 66.787136 -284.330388) (xy 66.737961 -284.328407) (xy 66.689742 -284.318563)
			(xy 66.643726 -284.301111) (xy 66.601105 -284.276504) (xy 66.562984 -284.245379) (xy 66.530349 -284.208542)
			(xy 66.504046 -284.166946) (xy 66.484755 -284.12167) (xy 66.472978 -284.073886) (xy 66.469018 -284.024832)
			(xy 66.13017 -284.024832) (xy 66.129675 -284.049439) (xy 66.12178 -284.098016) (xy 66.106196 -284.144697)
			(xy 66.083325 -284.188274) (xy 66.05376 -284.227618) (xy 66.018267 -284.26171) (xy 65.977764 -284.289666)
			(xy 65.933302 -284.310764) (xy 65.886031 -284.324456) (xy 65.837176 -284.330388) (xy 65.788001 -284.328407)
			(xy 65.739782 -284.318563) (xy 65.693766 -284.301111) (xy 65.651145 -284.276504) (xy 65.613024 -284.245379)
			(xy 65.580389 -284.208542) (xy 65.554086 -284.166946) (xy 65.534795 -284.12167) (xy 65.523018 -284.073886)
			(xy 65.519058 -284.024832) (xy 65.18021 -284.024832) (xy 65.179715 -284.049439) (xy 65.17182 -284.098016)
			(xy 65.156236 -284.144697) (xy 65.133365 -284.188274) (xy 65.1038 -284.227618) (xy 65.068307 -284.26171)
			(xy 65.027804 -284.289666) (xy 64.983342 -284.310764) (xy 64.936071 -284.324456) (xy 64.887216 -284.330388)
			(xy 64.838041 -284.328407) (xy 64.789822 -284.318563) (xy 64.743806 -284.301111) (xy 64.701185 -284.276504)
			(xy 64.663064 -284.245379) (xy 64.630429 -284.208542) (xy 64.604126 -284.166946) (xy 64.584835 -284.12167)
			(xy 64.573058 -284.073886) (xy 64.569098 -284.024832) (xy 64.23025 -284.024832) (xy 64.229755 -284.049439)
			(xy 64.22186 -284.098016) (xy 64.206276 -284.144697) (xy 64.183405 -284.188274) (xy 64.15384 -284.227618)
			(xy 64.118347 -284.26171) (xy 64.077844 -284.289666) (xy 64.033382 -284.310764) (xy 63.986111 -284.324456)
			(xy 63.937256 -284.330388) (xy 63.888081 -284.328407) (xy 63.839862 -284.318563) (xy 63.793846 -284.301111)
			(xy 63.751225 -284.276504) (xy 63.713104 -284.245379) (xy 63.680469 -284.208542) (xy 63.654166 -284.166946)
			(xy 63.634875 -284.12167) (xy 63.623098 -284.073886) (xy 63.619138 -284.024832) (xy 63.28029 -284.024832)
			(xy 63.279795 -284.049439) (xy 63.2719 -284.098016) (xy 63.256316 -284.144697) (xy 63.233445 -284.188274)
			(xy 63.20388 -284.227618) (xy 63.168387 -284.26171) (xy 63.127884 -284.289666) (xy 63.083422 -284.310764)
			(xy 63.036151 -284.324456) (xy 62.987296 -284.330388) (xy 62.938121 -284.328407) (xy 62.889902 -284.318563)
			(xy 62.843886 -284.301111) (xy 62.801265 -284.276504) (xy 62.763144 -284.245379) (xy 62.730509 -284.208542)
			(xy 62.704206 -284.166946) (xy 62.684915 -284.12167) (xy 62.673138 -284.073886) (xy 62.669178 -284.024832)
			(xy 62.330076 -284.024832) (xy 62.329581 -284.049439) (xy 62.321686 -284.098016) (xy 62.306102 -284.144697)
			(xy 62.283231 -284.188274) (xy 62.253666 -284.227618) (xy 62.218173 -284.26171) (xy 62.17767 -284.289666)
			(xy 62.133208 -284.310764) (xy 62.085937 -284.324456) (xy 62.037082 -284.330388) (xy 61.987907 -284.328407)
			(xy 61.939688 -284.318563) (xy 61.893672 -284.301111) (xy 61.851051 -284.276504) (xy 61.81293 -284.245379)
			(xy 61.780295 -284.208542) (xy 61.753992 -284.166946) (xy 61.734701 -284.12167) (xy 61.722924 -284.073886)
			(xy 61.718964 -284.024832) (xy 61.380116 -284.024832) (xy 61.379621 -284.049439) (xy 61.371726 -284.098016)
			(xy 61.356142 -284.144697) (xy 61.333271 -284.188274) (xy 61.303706 -284.227618) (xy 61.268213 -284.26171)
			(xy 61.22771 -284.289666) (xy 61.183248 -284.310764) (xy 61.135977 -284.324456) (xy 61.087122 -284.330388)
			(xy 61.037947 -284.328407) (xy 60.989728 -284.318563) (xy 60.943712 -284.301111) (xy 60.901091 -284.276504)
			(xy 60.86297 -284.245379) (xy 60.830335 -284.208542) (xy 60.804032 -284.166946) (xy 60.784741 -284.12167)
			(xy 60.772964 -284.073886) (xy 60.769004 -284.024832) (xy 60.430156 -284.024832) (xy 60.429661 -284.049439)
			(xy 60.421766 -284.098016) (xy 60.406182 -284.144697) (xy 60.383311 -284.188274) (xy 60.353746 -284.227618)
			(xy 60.318253 -284.26171) (xy 60.27775 -284.289666) (xy 60.233288 -284.310764) (xy 60.186017 -284.324456)
			(xy 60.137162 -284.330388) (xy 60.087987 -284.328407) (xy 60.039768 -284.318563) (xy 59.993752 -284.301111)
			(xy 59.951131 -284.276504) (xy 59.91301 -284.245379) (xy 59.880375 -284.208542) (xy 59.854072 -284.166946)
			(xy 59.834781 -284.12167) (xy 59.823004 -284.073886) (xy 59.819044 -284.024832) (xy 58.530236 -284.024832)
			(xy 58.529741 -284.049439) (xy 58.521846 -284.098016) (xy 58.506262 -284.144697) (xy 58.483391 -284.188274)
			(xy 58.453826 -284.227618) (xy 58.418333 -284.26171) (xy 58.37783 -284.289666) (xy 58.333368 -284.310764)
			(xy 58.286097 -284.324456) (xy 58.237242 -284.330388) (xy 58.188067 -284.328407) (xy 58.139848 -284.318563)
			(xy 58.093832 -284.301111) (xy 58.051211 -284.276504) (xy 58.01309 -284.245379) (xy 57.980455 -284.208542)
			(xy 57.954152 -284.166946) (xy 57.934861 -284.12167) (xy 57.923084 -284.073886) (xy 57.919124 -284.024832)
			(xy 57.580276 -284.024832) (xy 57.579781 -284.049439) (xy 57.571886 -284.098016) (xy 57.556302 -284.144697)
			(xy 57.533431 -284.188274) (xy 57.503866 -284.227618) (xy 57.468373 -284.26171) (xy 57.42787 -284.289666)
			(xy 57.383408 -284.310764) (xy 57.336137 -284.324456) (xy 57.287282 -284.330388) (xy 57.238107 -284.328407)
			(xy 57.189888 -284.318563) (xy 57.143872 -284.301111) (xy 57.101251 -284.276504) (xy 57.06313 -284.245379)
			(xy 57.030495 -284.208542) (xy 57.004192 -284.166946) (xy 56.984901 -284.12167) (xy 56.973124 -284.073886)
			(xy 56.969164 -284.024832) (xy 56.630062 -284.024832) (xy 56.629567 -284.049439) (xy 56.621672 -284.098016)
			(xy 56.606088 -284.144697) (xy 56.583217 -284.188274) (xy 56.553652 -284.227618) (xy 56.518159 -284.26171)
			(xy 56.477656 -284.289666) (xy 56.433194 -284.310764) (xy 56.385923 -284.324456) (xy 56.337068 -284.330388)
			(xy 56.287893 -284.328407) (xy 56.239674 -284.318563) (xy 56.193658 -284.301111) (xy 56.151037 -284.276504)
			(xy 56.112916 -284.245379) (xy 56.080281 -284.208542) (xy 56.053978 -284.166946) (xy 56.034687 -284.12167)
			(xy 56.02291 -284.073886) (xy 56.01895 -284.024832) (xy 55.680102 -284.024832) (xy 55.679607 -284.049439)
			(xy 55.671712 -284.098016) (xy 55.656128 -284.144697) (xy 55.633257 -284.188274) (xy 55.603692 -284.227618)
			(xy 55.568199 -284.26171) (xy 55.527696 -284.289666) (xy 55.483234 -284.310764) (xy 55.435963 -284.324456)
			(xy 55.387108 -284.330388) (xy 55.337933 -284.328407) (xy 55.289714 -284.318563) (xy 55.243698 -284.301111)
			(xy 55.201077 -284.276504) (xy 55.162956 -284.245379) (xy 55.130321 -284.208542) (xy 55.104018 -284.166946)
			(xy 55.084727 -284.12167) (xy 55.07295 -284.073886) (xy 55.06899 -284.024832) (xy 54.730142 -284.024832)
			(xy 54.729647 -284.049439) (xy 54.721752 -284.098016) (xy 54.706168 -284.144697) (xy 54.683297 -284.188274)
			(xy 54.653732 -284.227618) (xy 54.618239 -284.26171) (xy 54.577736 -284.289666) (xy 54.533274 -284.310764)
			(xy 54.486003 -284.324456) (xy 54.437148 -284.330388) (xy 54.387973 -284.328407) (xy 54.339754 -284.318563)
			(xy 54.293738 -284.301111) (xy 54.251117 -284.276504) (xy 54.212996 -284.245379) (xy 54.180361 -284.208542)
			(xy 54.154058 -284.166946) (xy 54.134767 -284.12167) (xy 54.12299 -284.073886) (xy 54.11903 -284.024832)
			(xy 53.780182 -284.024832) (xy 53.779687 -284.049439) (xy 53.771792 -284.098016) (xy 53.756208 -284.144697)
			(xy 53.733337 -284.188274) (xy 53.703772 -284.227618) (xy 53.668279 -284.26171) (xy 53.627776 -284.289666)
			(xy 53.583314 -284.310764) (xy 53.536043 -284.324456) (xy 53.487188 -284.330388) (xy 53.438013 -284.328407)
			(xy 53.389794 -284.318563) (xy 53.343778 -284.301111) (xy 53.301157 -284.276504) (xy 53.263036 -284.245379)
			(xy 53.230401 -284.208542) (xy 53.204098 -284.166946) (xy 53.184807 -284.12167) (xy 53.17303 -284.073886)
			(xy 53.16907 -284.024832) (xy 52.830222 -284.024832) (xy 52.829727 -284.049439) (xy 52.821832 -284.098016)
			(xy 52.806248 -284.144697) (xy 52.783377 -284.188274) (xy 52.753812 -284.227618) (xy 52.718319 -284.26171)
			(xy 52.677816 -284.289666) (xy 52.633354 -284.310764) (xy 52.586083 -284.324456) (xy 52.537228 -284.330388)
			(xy 52.488053 -284.328407) (xy 52.439834 -284.318563) (xy 52.393818 -284.301111) (xy 52.351197 -284.276504)
			(xy 52.313076 -284.245379) (xy 52.280441 -284.208542) (xy 52.254138 -284.166946) (xy 52.234847 -284.12167)
			(xy 52.22307 -284.073886) (xy 52.21911 -284.024832) (xy 51.880262 -284.024832) (xy 51.879767 -284.049439)
			(xy 51.871872 -284.098016) (xy 51.856288 -284.144697) (xy 51.833417 -284.188274) (xy 51.803852 -284.227618)
			(xy 51.768359 -284.26171) (xy 51.727856 -284.289666) (xy 51.683394 -284.310764) (xy 51.636123 -284.324456)
			(xy 51.587268 -284.330388) (xy 51.538093 -284.328407) (xy 51.489874 -284.318563) (xy 51.443858 -284.301111)
			(xy 51.401237 -284.276504) (xy 51.363116 -284.245379) (xy 51.330481 -284.208542) (xy 51.304178 -284.166946)
			(xy 51.284887 -284.12167) (xy 51.27311 -284.073886) (xy 51.26915 -284.024832) (xy 50.930302 -284.024832)
			(xy 50.929807 -284.049439) (xy 50.921912 -284.098016) (xy 50.906328 -284.144697) (xy 50.883457 -284.188274)
			(xy 50.853892 -284.227618) (xy 50.818399 -284.26171) (xy 50.777896 -284.289666) (xy 50.733434 -284.310764)
			(xy 50.686163 -284.324456) (xy 50.637308 -284.330388) (xy 50.588133 -284.328407) (xy 50.539914 -284.318563)
			(xy 50.493898 -284.301111) (xy 50.451277 -284.276504) (xy 50.413156 -284.245379) (xy 50.380521 -284.208542)
			(xy 50.354218 -284.166946) (xy 50.334927 -284.12167) (xy 50.32315 -284.073886) (xy 50.31919 -284.024832)
			(xy 49.980088 -284.024832) (xy 49.979593 -284.049439) (xy 49.971698 -284.098016) (xy 49.956114 -284.144697)
			(xy 49.933243 -284.188274) (xy 49.903678 -284.227618) (xy 49.868185 -284.26171) (xy 49.827682 -284.289666)
			(xy 49.78322 -284.310764) (xy 49.735949 -284.324456) (xy 49.687094 -284.330388) (xy 49.637919 -284.328407)
			(xy 49.5897 -284.318563) (xy 49.543684 -284.301111) (xy 49.501063 -284.276504) (xy 49.462942 -284.245379)
			(xy 49.430307 -284.208542) (xy 49.404004 -284.166946) (xy 49.384713 -284.12167) (xy 49.372936 -284.073886)
			(xy 49.368976 -284.024832) (xy 49.030128 -284.024832) (xy 49.029633 -284.049439) (xy 49.021738 -284.098016)
			(xy 49.006154 -284.144697) (xy 48.983283 -284.188274) (xy 48.953718 -284.227618) (xy 48.918225 -284.26171)
			(xy 48.877722 -284.289666) (xy 48.83326 -284.310764) (xy 48.785989 -284.324456) (xy 48.737134 -284.330388)
			(xy 48.687959 -284.328407) (xy 48.63974 -284.318563) (xy 48.593724 -284.301111) (xy 48.551103 -284.276504)
			(xy 48.512982 -284.245379) (xy 48.480347 -284.208542) (xy 48.454044 -284.166946) (xy 48.434753 -284.12167)
			(xy 48.422976 -284.073886) (xy 48.419016 -284.024832) (xy 48.080168 -284.024832) (xy 48.079914 -284.035246)
			(xy 48.079914 -284.041596) (xy 48.07966 -284.046168) (xy 48.07966 -284.04693) (xy 48.078436 -284.061331)
			(xy 48.073601 -284.089827) (xy 48.070008 -284.103826) (xy 48.06823 -284.11043) (xy 48.06823 -284.499812)
			(xy 73.593972 -284.499812) (xy 73.597932 -284.450758) (xy 73.609709 -284.402974) (xy 73.629 -284.357698)
			(xy 73.655303 -284.316102) (xy 73.687938 -284.279265) (xy 73.726059 -284.24814) (xy 73.76868 -284.223533)
			(xy 73.814696 -284.206081) (xy 73.862915 -284.196237) (xy 73.91209 -284.194256) (xy 73.960945 -284.200188)
			(xy 74.008216 -284.21388) (xy 74.052678 -284.234978) (xy 74.093181 -284.262934) (xy 74.128674 -284.297026)
			(xy 74.158239 -284.33637) (xy 74.18111 -284.379947) (xy 74.196694 -284.426628) (xy 74.204589 -284.475205)
			(xy 74.205084 -284.499812) (xy 74.543932 -284.499812) (xy 74.547892 -284.450758) (xy 74.559669 -284.402974)
			(xy 74.57896 -284.357698) (xy 74.605263 -284.316102) (xy 74.637898 -284.279265) (xy 74.676019 -284.24814)
			(xy 74.71864 -284.223533) (xy 74.764656 -284.206081) (xy 74.812875 -284.196237) (xy 74.86205 -284.194256)
			(xy 74.910905 -284.200188) (xy 74.958176 -284.21388) (xy 75.002638 -284.234978) (xy 75.043141 -284.262934)
			(xy 75.078634 -284.297026) (xy 75.108199 -284.33637) (xy 75.13107 -284.379947) (xy 75.146654 -284.426628)
			(xy 75.154549 -284.475205) (xy 75.155044 -284.499812) (xy 75.494146 -284.499812) (xy 75.498106 -284.450758)
			(xy 75.509883 -284.402974) (xy 75.529174 -284.357698) (xy 75.555477 -284.316102) (xy 75.588112 -284.279265)
			(xy 75.626233 -284.24814) (xy 75.668854 -284.223533) (xy 75.71487 -284.206081) (xy 75.763089 -284.196237)
			(xy 75.812264 -284.194256) (xy 75.861119 -284.200188) (xy 75.90839 -284.21388) (xy 75.952852 -284.234978)
			(xy 75.993355 -284.262934) (xy 76.028848 -284.297026) (xy 76.058413 -284.33637) (xy 76.081284 -284.379947)
			(xy 76.096868 -284.426628) (xy 76.104763 -284.475205) (xy 76.105258 -284.499812) (xy 76.444106 -284.499812)
			(xy 76.448066 -284.450758) (xy 76.459843 -284.402974) (xy 76.479134 -284.357698) (xy 76.505437 -284.316102)
			(xy 76.538072 -284.279265) (xy 76.576193 -284.24814) (xy 76.618814 -284.223533) (xy 76.66483 -284.206081)
			(xy 76.713049 -284.196237) (xy 76.762224 -284.194256) (xy 76.811079 -284.200188) (xy 76.85835 -284.21388)
			(xy 76.902812 -284.234978) (xy 76.943315 -284.262934) (xy 76.978808 -284.297026) (xy 77.008373 -284.33637)
			(xy 77.031244 -284.379947) (xy 77.046828 -284.426628) (xy 77.054723 -284.475205) (xy 77.055218 -284.499812)
			(xy 77.394066 -284.499812) (xy 77.398026 -284.450758) (xy 77.409803 -284.402974) (xy 77.429094 -284.357698)
			(xy 77.455397 -284.316102) (xy 77.488032 -284.279265) (xy 77.526153 -284.24814) (xy 77.568774 -284.223533)
			(xy 77.61479 -284.206081) (xy 77.663009 -284.196237) (xy 77.712184 -284.194256) (xy 77.761039 -284.200188)
			(xy 77.80831 -284.21388) (xy 77.852772 -284.234978) (xy 77.893275 -284.262934) (xy 77.928768 -284.297026)
			(xy 77.958333 -284.33637) (xy 77.981204 -284.379947) (xy 77.996788 -284.426628) (xy 78.004683 -284.475205)
			(xy 78.005178 -284.499812) (xy 78.344026 -284.499812) (xy 78.347986 -284.450758) (xy 78.359763 -284.402974)
			(xy 78.379054 -284.357698) (xy 78.405357 -284.316102) (xy 78.437992 -284.279265) (xy 78.476113 -284.24814)
			(xy 78.518734 -284.223533) (xy 78.56475 -284.206081) (xy 78.612969 -284.196237) (xy 78.662144 -284.194256)
			(xy 78.710999 -284.200188) (xy 78.75827 -284.21388) (xy 78.802732 -284.234978) (xy 78.843235 -284.262934)
			(xy 78.878728 -284.297026) (xy 78.908293 -284.33637) (xy 78.931164 -284.379947) (xy 78.946748 -284.426628)
			(xy 78.954643 -284.475205) (xy 78.955138 -284.499812) (xy 78.954643 -284.524419) (xy 78.954464 -284.52552)
			(xy 79.273142 -284.52552) (xy 79.273142 -284.474104) (xy 79.281185 -284.423322) (xy 79.297073 -284.374423)
			(xy 79.320416 -284.328611) (xy 79.350637 -284.287015) (xy 79.386993 -284.250659) (xy 79.428589 -284.220438)
			(xy 79.474401 -284.197095) (xy 79.5233 -284.181207) (xy 79.574082 -284.173164) (xy 79.625498 -284.173164)
			(xy 79.67628 -284.181207) (xy 79.725179 -284.197095) (xy 79.770991 -284.220438) (xy 79.812587 -284.250659)
			(xy 79.848943 -284.287015) (xy 79.879164 -284.328611) (xy 79.902507 -284.374423) (xy 79.918395 -284.423322)
			(xy 79.926438 -284.474104) (xy 79.926942 -284.499812) (xy 79.926438 -284.52552) (xy 80.223102 -284.52552)
			(xy 80.223102 -284.474104) (xy 80.231145 -284.423322) (xy 80.247033 -284.374423) (xy 80.270376 -284.328611)
			(xy 80.300597 -284.287015) (xy 80.336953 -284.250659) (xy 80.378549 -284.220438) (xy 80.424361 -284.197095)
			(xy 80.47326 -284.181207) (xy 80.524042 -284.173164) (xy 80.575458 -284.173164) (xy 80.62624 -284.181207)
			(xy 80.675139 -284.197095) (xy 80.720951 -284.220438) (xy 80.762547 -284.250659) (xy 80.798903 -284.287015)
			(xy 80.829124 -284.328611) (xy 80.852467 -284.374423) (xy 80.868355 -284.423322) (xy 80.876398 -284.474104)
			(xy 80.876902 -284.499812) (xy 81.19416 -284.499812) (xy 81.19812 -284.450758) (xy 81.209897 -284.402974)
			(xy 81.229188 -284.357698) (xy 81.255491 -284.316102) (xy 81.288126 -284.279265) (xy 81.326247 -284.24814)
			(xy 81.368868 -284.223533) (xy 81.414884 -284.206081) (xy 81.463103 -284.196237) (xy 81.512278 -284.194256)
			(xy 81.561133 -284.200188) (xy 81.608404 -284.21388) (xy 81.652866 -284.234978) (xy 81.693369 -284.262934)
			(xy 81.728862 -284.297026) (xy 81.758427 -284.33637) (xy 81.781298 -284.379947) (xy 81.796882 -284.426628)
			(xy 81.804777 -284.475205) (xy 81.805272 -284.499812) (xy 82.14412 -284.499812) (xy 82.14808 -284.450758)
			(xy 82.159857 -284.402974) (xy 82.179148 -284.357698) (xy 82.205451 -284.316102) (xy 82.238086 -284.279265)
			(xy 82.276207 -284.24814) (xy 82.318828 -284.223533) (xy 82.364844 -284.206081) (xy 82.413063 -284.196237)
			(xy 82.462238 -284.194256) (xy 82.511093 -284.200188) (xy 82.558364 -284.21388) (xy 82.602826 -284.234978)
			(xy 82.643329 -284.262934) (xy 82.678822 -284.297026) (xy 82.708387 -284.33637) (xy 82.731258 -284.379947)
			(xy 82.746842 -284.426628) (xy 82.754737 -284.475205) (xy 82.755232 -284.499812) (xy 82.754737 -284.524419)
			(xy 82.746842 -284.572996) (xy 82.731258 -284.619677) (xy 82.708387 -284.663254) (xy 82.678822 -284.702598)
			(xy 82.643329 -284.73669) (xy 82.602826 -284.764646) (xy 82.558364 -284.785744) (xy 82.511093 -284.799436)
			(xy 82.462238 -284.805368) (xy 82.413063 -284.803387) (xy 82.364844 -284.793543) (xy 82.318828 -284.776091)
			(xy 82.276207 -284.751484) (xy 82.238086 -284.720359) (xy 82.205451 -284.683522) (xy 82.179148 -284.641926)
			(xy 82.159857 -284.59665) (xy 82.14808 -284.548866) (xy 82.14412 -284.499812) (xy 81.805272 -284.499812)
			(xy 81.804777 -284.524419) (xy 81.796882 -284.572996) (xy 81.781298 -284.619677) (xy 81.758427 -284.663254)
			(xy 81.728862 -284.702598) (xy 81.693369 -284.73669) (xy 81.652866 -284.764646) (xy 81.608404 -284.785744)
			(xy 81.561133 -284.799436) (xy 81.512278 -284.805368) (xy 81.463103 -284.803387) (xy 81.414884 -284.793543)
			(xy 81.368868 -284.776091) (xy 81.326247 -284.751484) (xy 81.288126 -284.720359) (xy 81.255491 -284.683522)
			(xy 81.229188 -284.641926) (xy 81.209897 -284.59665) (xy 81.19812 -284.548866) (xy 81.19416 -284.499812)
			(xy 80.876902 -284.499812) (xy 80.876398 -284.52552) (xy 80.868355 -284.576302) (xy 80.852467 -284.625201)
			(xy 80.829124 -284.671013) (xy 80.798903 -284.712609) (xy 80.762547 -284.748965) (xy 80.720951 -284.779186)
			(xy 80.675139 -284.802529) (xy 80.62624 -284.818417) (xy 80.575458 -284.82646) (xy 80.524042 -284.82646)
			(xy 80.47326 -284.818417) (xy 80.424361 -284.802529) (xy 80.378549 -284.779186) (xy 80.336953 -284.748965)
			(xy 80.300597 -284.712609) (xy 80.270376 -284.671013) (xy 80.247033 -284.625201) (xy 80.231145 -284.576302)
			(xy 80.223102 -284.52552) (xy 79.926438 -284.52552) (xy 79.918395 -284.576302) (xy 79.902507 -284.625201)
			(xy 79.879164 -284.671013) (xy 79.848943 -284.712609) (xy 79.812587 -284.748965) (xy 79.770991 -284.779186)
			(xy 79.725179 -284.802529) (xy 79.67628 -284.818417) (xy 79.625498 -284.82646) (xy 79.574082 -284.82646)
			(xy 79.5233 -284.818417) (xy 79.474401 -284.802529) (xy 79.428589 -284.779186) (xy 79.386993 -284.748965)
			(xy 79.350637 -284.712609) (xy 79.320416 -284.671013) (xy 79.297073 -284.625201) (xy 79.281185 -284.576302)
			(xy 79.273142 -284.52552) (xy 78.954464 -284.52552) (xy 78.946748 -284.572996) (xy 78.931164 -284.619677)
			(xy 78.908293 -284.663254) (xy 78.878728 -284.702598) (xy 78.843235 -284.73669) (xy 78.802732 -284.764646)
			(xy 78.75827 -284.785744) (xy 78.710999 -284.799436) (xy 78.662144 -284.805368) (xy 78.612969 -284.803387)
			(xy 78.56475 -284.793543) (xy 78.518734 -284.776091) (xy 78.476113 -284.751484) (xy 78.437992 -284.720359)
			(xy 78.405357 -284.683522) (xy 78.379054 -284.641926) (xy 78.359763 -284.59665) (xy 78.347986 -284.548866)
			(xy 78.344026 -284.499812) (xy 78.005178 -284.499812) (xy 78.004683 -284.524419) (xy 77.996788 -284.572996)
			(xy 77.981204 -284.619677) (xy 77.958333 -284.663254) (xy 77.928768 -284.702598) (xy 77.893275 -284.73669)
			(xy 77.852772 -284.764646) (xy 77.80831 -284.785744) (xy 77.761039 -284.799436) (xy 77.712184 -284.805368)
			(xy 77.663009 -284.803387) (xy 77.61479 -284.793543) (xy 77.568774 -284.776091) (xy 77.526153 -284.751484)
			(xy 77.488032 -284.720359) (xy 77.455397 -284.683522) (xy 77.429094 -284.641926) (xy 77.409803 -284.59665)
			(xy 77.398026 -284.548866) (xy 77.394066 -284.499812) (xy 77.055218 -284.499812) (xy 77.054723 -284.524419)
			(xy 77.046828 -284.572996) (xy 77.031244 -284.619677) (xy 77.008373 -284.663254) (xy 76.978808 -284.702598)
			(xy 76.943315 -284.73669) (xy 76.902812 -284.764646) (xy 76.85835 -284.785744) (xy 76.811079 -284.799436)
			(xy 76.762224 -284.805368) (xy 76.713049 -284.803387) (xy 76.66483 -284.793543) (xy 76.618814 -284.776091)
			(xy 76.576193 -284.751484) (xy 76.538072 -284.720359) (xy 76.505437 -284.683522) (xy 76.479134 -284.641926)
			(xy 76.459843 -284.59665) (xy 76.448066 -284.548866) (xy 76.444106 -284.499812) (xy 76.105258 -284.499812)
			(xy 76.104763 -284.524419) (xy 76.096868 -284.572996) (xy 76.081284 -284.619677) (xy 76.058413 -284.663254)
			(xy 76.028848 -284.702598) (xy 75.993355 -284.73669) (xy 75.952852 -284.764646) (xy 75.90839 -284.785744)
			(xy 75.861119 -284.799436) (xy 75.812264 -284.805368) (xy 75.763089 -284.803387) (xy 75.71487 -284.793543)
			(xy 75.668854 -284.776091) (xy 75.626233 -284.751484) (xy 75.588112 -284.720359) (xy 75.555477 -284.683522)
			(xy 75.529174 -284.641926) (xy 75.509883 -284.59665) (xy 75.498106 -284.548866) (xy 75.494146 -284.499812)
			(xy 75.155044 -284.499812) (xy 75.154549 -284.524419) (xy 75.146654 -284.572996) (xy 75.13107 -284.619677)
			(xy 75.108199 -284.663254) (xy 75.078634 -284.702598) (xy 75.043141 -284.73669) (xy 75.002638 -284.764646)
			(xy 74.958176 -284.785744) (xy 74.910905 -284.799436) (xy 74.86205 -284.805368) (xy 74.812875 -284.803387)
			(xy 74.764656 -284.793543) (xy 74.71864 -284.776091) (xy 74.676019 -284.751484) (xy 74.637898 -284.720359)
			(xy 74.605263 -284.683522) (xy 74.57896 -284.641926) (xy 74.559669 -284.59665) (xy 74.547892 -284.548866)
			(xy 74.543932 -284.499812) (xy 74.205084 -284.499812) (xy 74.204589 -284.524419) (xy 74.196694 -284.572996)
			(xy 74.18111 -284.619677) (xy 74.158239 -284.663254) (xy 74.128674 -284.702598) (xy 74.093181 -284.73669)
			(xy 74.052678 -284.764646) (xy 74.008216 -284.785744) (xy 73.960945 -284.799436) (xy 73.91209 -284.805368)
			(xy 73.862915 -284.803387) (xy 73.814696 -284.793543) (xy 73.76868 -284.776091) (xy 73.726059 -284.751484)
			(xy 73.687938 -284.720359) (xy 73.655303 -284.683522) (xy 73.629 -284.641926) (xy 73.609709 -284.59665)
			(xy 73.597932 -284.548866) (xy 73.593972 -284.499812) (xy 48.06823 -284.499812) (xy 48.06823 -284.883352)
			(xy 48.070008 -284.89656) (xy 48.07077 -284.899608) (xy 48.075165 -284.918092) (xy 48.079872 -284.955794)
			(xy 48.080168 -284.974792) (xy 48.419016 -284.974792) (xy 48.422976 -284.925738) (xy 48.434753 -284.877954)
			(xy 48.454044 -284.832678) (xy 48.480347 -284.791082) (xy 48.512982 -284.754245) (xy 48.551103 -284.72312)
			(xy 48.593724 -284.698513) (xy 48.63974 -284.681061) (xy 48.687959 -284.671217) (xy 48.737134 -284.669236)
			(xy 48.785989 -284.675168) (xy 48.83326 -284.68886) (xy 48.877722 -284.709958) (xy 48.918225 -284.737914)
			(xy 48.953718 -284.772006) (xy 48.983283 -284.81135) (xy 49.006154 -284.854927) (xy 49.021738 -284.901608)
			(xy 49.029633 -284.950185) (xy 49.030128 -284.974792) (xy 49.368976 -284.974792) (xy 49.372936 -284.925738)
			(xy 49.384713 -284.877954) (xy 49.404004 -284.832678) (xy 49.430307 -284.791082) (xy 49.462942 -284.754245)
			(xy 49.501063 -284.72312) (xy 49.543684 -284.698513) (xy 49.5897 -284.681061) (xy 49.637919 -284.671217)
			(xy 49.687094 -284.669236) (xy 49.735949 -284.675168) (xy 49.78322 -284.68886) (xy 49.827682 -284.709958)
			(xy 49.868185 -284.737914) (xy 49.903678 -284.772006) (xy 49.933243 -284.81135) (xy 49.956114 -284.854927)
			(xy 49.971698 -284.901608) (xy 49.979593 -284.950185) (xy 49.980088 -284.974792) (xy 50.31919 -284.974792)
			(xy 50.32315 -284.925738) (xy 50.334927 -284.877954) (xy 50.354218 -284.832678) (xy 50.380521 -284.791082)
			(xy 50.413156 -284.754245) (xy 50.451277 -284.72312) (xy 50.493898 -284.698513) (xy 50.539914 -284.681061)
			(xy 50.588133 -284.671217) (xy 50.637308 -284.669236) (xy 50.686163 -284.675168) (xy 50.733434 -284.68886)
			(xy 50.777896 -284.709958) (xy 50.818399 -284.737914) (xy 50.853892 -284.772006) (xy 50.883457 -284.81135)
			(xy 50.906328 -284.854927) (xy 50.921912 -284.901608) (xy 50.929807 -284.950185) (xy 50.930302 -284.974792)
			(xy 51.26915 -284.974792) (xy 51.27311 -284.925738) (xy 51.284887 -284.877954) (xy 51.304178 -284.832678)
			(xy 51.330481 -284.791082) (xy 51.363116 -284.754245) (xy 51.401237 -284.72312) (xy 51.443858 -284.698513)
			(xy 51.489874 -284.681061) (xy 51.538093 -284.671217) (xy 51.587268 -284.669236) (xy 51.636123 -284.675168)
			(xy 51.683394 -284.68886) (xy 51.727856 -284.709958) (xy 51.768359 -284.737914) (xy 51.803852 -284.772006)
			(xy 51.833417 -284.81135) (xy 51.856288 -284.854927) (xy 51.871872 -284.901608) (xy 51.879767 -284.950185)
			(xy 51.880262 -284.974792) (xy 52.21911 -284.974792) (xy 52.22307 -284.925738) (xy 52.234847 -284.877954)
			(xy 52.254138 -284.832678) (xy 52.280441 -284.791082) (xy 52.313076 -284.754245) (xy 52.351197 -284.72312)
			(xy 52.393818 -284.698513) (xy 52.439834 -284.681061) (xy 52.488053 -284.671217) (xy 52.537228 -284.669236)
			(xy 52.586083 -284.675168) (xy 52.633354 -284.68886) (xy 52.677816 -284.709958) (xy 52.718319 -284.737914)
			(xy 52.753812 -284.772006) (xy 52.783377 -284.81135) (xy 52.806248 -284.854927) (xy 52.821832 -284.901608)
			(xy 52.829727 -284.950185) (xy 52.830222 -284.974792) (xy 53.16907 -284.974792) (xy 53.17303 -284.925738)
			(xy 53.184807 -284.877954) (xy 53.204098 -284.832678) (xy 53.230401 -284.791082) (xy 53.263036 -284.754245)
			(xy 53.301157 -284.72312) (xy 53.343778 -284.698513) (xy 53.389794 -284.681061) (xy 53.438013 -284.671217)
			(xy 53.487188 -284.669236) (xy 53.536043 -284.675168) (xy 53.583314 -284.68886) (xy 53.627776 -284.709958)
			(xy 53.668279 -284.737914) (xy 53.703772 -284.772006) (xy 53.733337 -284.81135) (xy 53.756208 -284.854927)
			(xy 53.771792 -284.901608) (xy 53.779687 -284.950185) (xy 53.780182 -284.974792) (xy 54.11903 -284.974792)
			(xy 54.12299 -284.925738) (xy 54.134767 -284.877954) (xy 54.154058 -284.832678) (xy 54.180361 -284.791082)
			(xy 54.212996 -284.754245) (xy 54.251117 -284.72312) (xy 54.293738 -284.698513) (xy 54.339754 -284.681061)
			(xy 54.387973 -284.671217) (xy 54.437148 -284.669236) (xy 54.486003 -284.675168) (xy 54.533274 -284.68886)
			(xy 54.577736 -284.709958) (xy 54.618239 -284.737914) (xy 54.653732 -284.772006) (xy 54.683297 -284.81135)
			(xy 54.706168 -284.854927) (xy 54.721752 -284.901608) (xy 54.729647 -284.950185) (xy 54.730142 -284.974792)
			(xy 55.06899 -284.974792) (xy 55.07295 -284.925738) (xy 55.084727 -284.877954) (xy 55.104018 -284.832678)
			(xy 55.130321 -284.791082) (xy 55.162956 -284.754245) (xy 55.201077 -284.72312) (xy 55.243698 -284.698513)
			(xy 55.289714 -284.681061) (xy 55.337933 -284.671217) (xy 55.387108 -284.669236) (xy 55.435963 -284.675168)
			(xy 55.483234 -284.68886) (xy 55.527696 -284.709958) (xy 55.568199 -284.737914) (xy 55.603692 -284.772006)
			(xy 55.633257 -284.81135) (xy 55.656128 -284.854927) (xy 55.671712 -284.901608) (xy 55.679607 -284.950185)
			(xy 55.680102 -284.974792) (xy 56.01895 -284.974792) (xy 56.02291 -284.925738) (xy 56.034687 -284.877954)
			(xy 56.053978 -284.832678) (xy 56.080281 -284.791082) (xy 56.112916 -284.754245) (xy 56.151037 -284.72312)
			(xy 56.193658 -284.698513) (xy 56.239674 -284.681061) (xy 56.287893 -284.671217) (xy 56.337068 -284.669236)
			(xy 56.385923 -284.675168) (xy 56.433194 -284.68886) (xy 56.477656 -284.709958) (xy 56.518159 -284.737914)
			(xy 56.553652 -284.772006) (xy 56.583217 -284.81135) (xy 56.606088 -284.854927) (xy 56.621672 -284.901608)
			(xy 56.629567 -284.950185) (xy 56.630062 -284.974792) (xy 56.969164 -284.974792) (xy 56.973124 -284.925738)
			(xy 56.984901 -284.877954) (xy 57.004192 -284.832678) (xy 57.030495 -284.791082) (xy 57.06313 -284.754245)
			(xy 57.101251 -284.72312) (xy 57.143872 -284.698513) (xy 57.189888 -284.681061) (xy 57.238107 -284.671217)
			(xy 57.287282 -284.669236) (xy 57.336137 -284.675168) (xy 57.383408 -284.68886) (xy 57.42787 -284.709958)
			(xy 57.468373 -284.737914) (xy 57.503866 -284.772006) (xy 57.533431 -284.81135) (xy 57.556302 -284.854927)
			(xy 57.571886 -284.901608) (xy 57.579781 -284.950185) (xy 57.580276 -284.974792) (xy 57.919124 -284.974792)
			(xy 57.923084 -284.925738) (xy 57.934861 -284.877954) (xy 57.954152 -284.832678) (xy 57.980455 -284.791082)
			(xy 58.01309 -284.754245) (xy 58.051211 -284.72312) (xy 58.093832 -284.698513) (xy 58.139848 -284.681061)
			(xy 58.188067 -284.671217) (xy 58.237242 -284.669236) (xy 58.286097 -284.675168) (xy 58.333368 -284.68886)
			(xy 58.37783 -284.709958) (xy 58.418333 -284.737914) (xy 58.453826 -284.772006) (xy 58.483391 -284.81135)
			(xy 58.506262 -284.854927) (xy 58.521846 -284.901608) (xy 58.529741 -284.950185) (xy 58.530236 -284.974792)
			(xy 59.819044 -284.974792) (xy 59.823004 -284.925738) (xy 59.834781 -284.877954) (xy 59.854072 -284.832678)
			(xy 59.880375 -284.791082) (xy 59.91301 -284.754245) (xy 59.951131 -284.72312) (xy 59.993752 -284.698513)
			(xy 60.039768 -284.681061) (xy 60.087987 -284.671217) (xy 60.137162 -284.669236) (xy 60.186017 -284.675168)
			(xy 60.233288 -284.68886) (xy 60.27775 -284.709958) (xy 60.318253 -284.737914) (xy 60.353746 -284.772006)
			(xy 60.383311 -284.81135) (xy 60.406182 -284.854927) (xy 60.421766 -284.901608) (xy 60.429661 -284.950185)
			(xy 60.430156 -284.974792) (xy 60.769004 -284.974792) (xy 60.772964 -284.925738) (xy 60.784741 -284.877954)
			(xy 60.804032 -284.832678) (xy 60.830335 -284.791082) (xy 60.86297 -284.754245) (xy 60.901091 -284.72312)
			(xy 60.943712 -284.698513) (xy 60.989728 -284.681061) (xy 61.037947 -284.671217) (xy 61.087122 -284.669236)
			(xy 61.135977 -284.675168) (xy 61.183248 -284.68886) (xy 61.22771 -284.709958) (xy 61.268213 -284.737914)
			(xy 61.303706 -284.772006) (xy 61.333271 -284.81135) (xy 61.356142 -284.854927) (xy 61.371726 -284.901608)
			(xy 61.379621 -284.950185) (xy 61.380116 -284.974792) (xy 61.718964 -284.974792) (xy 61.722924 -284.925738)
			(xy 61.734701 -284.877954) (xy 61.753992 -284.832678) (xy 61.780295 -284.791082) (xy 61.81293 -284.754245)
			(xy 61.851051 -284.72312) (xy 61.893672 -284.698513) (xy 61.939688 -284.681061) (xy 61.987907 -284.671217)
			(xy 62.037082 -284.669236) (xy 62.085937 -284.675168) (xy 62.133208 -284.68886) (xy 62.17767 -284.709958)
			(xy 62.218173 -284.737914) (xy 62.253666 -284.772006) (xy 62.283231 -284.81135) (xy 62.306102 -284.854927)
			(xy 62.321686 -284.901608) (xy 62.329581 -284.950185) (xy 62.330076 -284.974792) (xy 62.669178 -284.974792)
			(xy 62.673138 -284.925738) (xy 62.684915 -284.877954) (xy 62.704206 -284.832678) (xy 62.730509 -284.791082)
			(xy 62.763144 -284.754245) (xy 62.801265 -284.72312) (xy 62.843886 -284.698513) (xy 62.889902 -284.681061)
			(xy 62.938121 -284.671217) (xy 62.987296 -284.669236) (xy 63.036151 -284.675168) (xy 63.083422 -284.68886)
			(xy 63.127884 -284.709958) (xy 63.168387 -284.737914) (xy 63.20388 -284.772006) (xy 63.233445 -284.81135)
			(xy 63.256316 -284.854927) (xy 63.2719 -284.901608) (xy 63.279795 -284.950185) (xy 63.28029 -284.974792)
			(xy 63.619138 -284.974792) (xy 63.623098 -284.925738) (xy 63.634875 -284.877954) (xy 63.654166 -284.832678)
			(xy 63.680469 -284.791082) (xy 63.713104 -284.754245) (xy 63.751225 -284.72312) (xy 63.793846 -284.698513)
			(xy 63.839862 -284.681061) (xy 63.888081 -284.671217) (xy 63.937256 -284.669236) (xy 63.986111 -284.675168)
			(xy 64.033382 -284.68886) (xy 64.077844 -284.709958) (xy 64.118347 -284.737914) (xy 64.15384 -284.772006)
			(xy 64.183405 -284.81135) (xy 64.206276 -284.854927) (xy 64.22186 -284.901608) (xy 64.229755 -284.950185)
			(xy 64.23025 -284.974792) (xy 64.569098 -284.974792) (xy 64.573058 -284.925738) (xy 64.584835 -284.877954)
			(xy 64.604126 -284.832678) (xy 64.630429 -284.791082) (xy 64.663064 -284.754245) (xy 64.701185 -284.72312)
			(xy 64.743806 -284.698513) (xy 64.789822 -284.681061) (xy 64.838041 -284.671217) (xy 64.887216 -284.669236)
			(xy 64.936071 -284.675168) (xy 64.983342 -284.68886) (xy 65.027804 -284.709958) (xy 65.068307 -284.737914)
			(xy 65.1038 -284.772006) (xy 65.133365 -284.81135) (xy 65.156236 -284.854927) (xy 65.17182 -284.901608)
			(xy 65.179715 -284.950185) (xy 65.18021 -284.974792) (xy 65.519058 -284.974792) (xy 65.523018 -284.925738)
			(xy 65.534795 -284.877954) (xy 65.554086 -284.832678) (xy 65.580389 -284.791082) (xy 65.613024 -284.754245)
			(xy 65.651145 -284.72312) (xy 65.693766 -284.698513) (xy 65.739782 -284.681061) (xy 65.788001 -284.671217)
			(xy 65.837176 -284.669236) (xy 65.886031 -284.675168) (xy 65.933302 -284.68886) (xy 65.977764 -284.709958)
			(xy 66.018267 -284.737914) (xy 66.05376 -284.772006) (xy 66.083325 -284.81135) (xy 66.106196 -284.854927)
			(xy 66.12178 -284.901608) (xy 66.129675 -284.950185) (xy 66.13017 -284.974792) (xy 66.469018 -284.974792)
			(xy 66.472978 -284.925738) (xy 66.484755 -284.877954) (xy 66.504046 -284.832678) (xy 66.530349 -284.791082)
			(xy 66.562984 -284.754245) (xy 66.601105 -284.72312) (xy 66.643726 -284.698513) (xy 66.689742 -284.681061)
			(xy 66.737961 -284.671217) (xy 66.787136 -284.669236) (xy 66.835991 -284.675168) (xy 66.883262 -284.68886)
			(xy 66.927724 -284.709958) (xy 66.968227 -284.737914) (xy 67.00372 -284.772006) (xy 67.033285 -284.81135)
			(xy 67.056156 -284.854927) (xy 67.07174 -284.901608) (xy 67.079635 -284.950185) (xy 67.08013 -284.974792)
			(xy 67.418978 -284.974792) (xy 67.422938 -284.925738) (xy 67.434715 -284.877954) (xy 67.454006 -284.832678)
			(xy 67.480309 -284.791082) (xy 67.512944 -284.754245) (xy 67.551065 -284.72312) (xy 67.593686 -284.698513)
			(xy 67.639702 -284.681061) (xy 67.687921 -284.671217) (xy 67.737096 -284.669236) (xy 67.785951 -284.675168)
			(xy 67.833222 -284.68886) (xy 67.877684 -284.709958) (xy 67.918187 -284.737914) (xy 67.95368 -284.772006)
			(xy 67.983245 -284.81135) (xy 68.006116 -284.854927) (xy 68.0217 -284.901608) (xy 68.029595 -284.950185)
			(xy 68.03009 -284.974792) (xy 68.368938 -284.974792) (xy 68.372898 -284.925738) (xy 68.384675 -284.877954)
			(xy 68.403966 -284.832678) (xy 68.430269 -284.791082) (xy 68.462904 -284.754245) (xy 68.501025 -284.72312)
			(xy 68.543646 -284.698513) (xy 68.589662 -284.681061) (xy 68.637881 -284.671217) (xy 68.687056 -284.669236)
			(xy 68.735911 -284.675168) (xy 68.783182 -284.68886) (xy 68.827644 -284.709958) (xy 68.868147 -284.737914)
			(xy 68.90364 -284.772006) (xy 68.933205 -284.81135) (xy 68.956076 -284.854927) (xy 68.97166 -284.901608)
			(xy 68.979555 -284.950185) (xy 68.98005 -284.974792) (xy 69.319152 -284.974792) (xy 69.323112 -284.925738)
			(xy 69.334889 -284.877954) (xy 69.35418 -284.832678) (xy 69.380483 -284.791082) (xy 69.413118 -284.754245)
			(xy 69.451239 -284.72312) (xy 69.49386 -284.698513) (xy 69.539876 -284.681061) (xy 69.588095 -284.671217)
			(xy 69.63727 -284.669236) (xy 69.686125 -284.675168) (xy 69.733396 -284.68886) (xy 69.777858 -284.709958)
			(xy 69.818361 -284.737914) (xy 69.853854 -284.772006) (xy 69.883419 -284.81135) (xy 69.90629 -284.854927)
			(xy 69.921874 -284.901608) (xy 69.929769 -284.950185) (xy 69.930264 -284.974792) (xy 70.269112 -284.974792)
			(xy 70.273072 -284.925738) (xy 70.284849 -284.877954) (xy 70.30414 -284.832678) (xy 70.330443 -284.791082)
			(xy 70.363078 -284.754245) (xy 70.401199 -284.72312) (xy 70.44382 -284.698513) (xy 70.489836 -284.681061)
			(xy 70.538055 -284.671217) (xy 70.58723 -284.669236) (xy 70.636085 -284.675168) (xy 70.683356 -284.68886)
			(xy 70.727818 -284.709958) (xy 70.768321 -284.737914) (xy 70.803814 -284.772006) (xy 70.833379 -284.81135)
			(xy 70.85625 -284.854927) (xy 70.871834 -284.901608) (xy 70.879729 -284.950185) (xy 70.880224 -284.974792)
			(xy 70.879729 -284.999399) (xy 70.871834 -285.047976) (xy 70.85625 -285.094657) (xy 70.833379 -285.138234)
			(xy 70.803814 -285.177578) (xy 70.768321 -285.21167) (xy 70.727818 -285.239626) (xy 70.683356 -285.260724)
			(xy 70.636085 -285.274416) (xy 70.58723 -285.280348) (xy 70.538055 -285.278367) (xy 70.489836 -285.268523)
			(xy 70.44382 -285.251071) (xy 70.401199 -285.226464) (xy 70.363078 -285.195339) (xy 70.330443 -285.158502)
			(xy 70.30414 -285.116906) (xy 70.284849 -285.07163) (xy 70.273072 -285.023846) (xy 70.269112 -284.974792)
			(xy 69.930264 -284.974792) (xy 69.929769 -284.999399) (xy 69.921874 -285.047976) (xy 69.90629 -285.094657)
			(xy 69.883419 -285.138234) (xy 69.853854 -285.177578) (xy 69.818361 -285.21167) (xy 69.777858 -285.239626)
			(xy 69.733396 -285.260724) (xy 69.686125 -285.274416) (xy 69.63727 -285.280348) (xy 69.588095 -285.278367)
			(xy 69.539876 -285.268523) (xy 69.49386 -285.251071) (xy 69.451239 -285.226464) (xy 69.413118 -285.195339)
			(xy 69.380483 -285.158502) (xy 69.35418 -285.116906) (xy 69.334889 -285.07163) (xy 69.323112 -285.023846)
			(xy 69.319152 -284.974792) (xy 68.98005 -284.974792) (xy 68.979555 -284.999399) (xy 68.97166 -285.047976)
			(xy 68.956076 -285.094657) (xy 68.933205 -285.138234) (xy 68.90364 -285.177578) (xy 68.868147 -285.21167)
			(xy 68.827644 -285.239626) (xy 68.783182 -285.260724) (xy 68.735911 -285.274416) (xy 68.687056 -285.280348)
			(xy 68.637881 -285.278367) (xy 68.589662 -285.268523) (xy 68.543646 -285.251071) (xy 68.501025 -285.226464)
			(xy 68.462904 -285.195339) (xy 68.430269 -285.158502) (xy 68.403966 -285.116906) (xy 68.384675 -285.07163)
			(xy 68.372898 -285.023846) (xy 68.368938 -284.974792) (xy 68.03009 -284.974792) (xy 68.029595 -284.999399)
			(xy 68.0217 -285.047976) (xy 68.006116 -285.094657) (xy 67.983245 -285.138234) (xy 67.95368 -285.177578)
			(xy 67.918187 -285.21167) (xy 67.877684 -285.239626) (xy 67.833222 -285.260724) (xy 67.785951 -285.274416)
			(xy 67.737096 -285.280348) (xy 67.687921 -285.278367) (xy 67.639702 -285.268523) (xy 67.593686 -285.251071)
			(xy 67.551065 -285.226464) (xy 67.512944 -285.195339) (xy 67.480309 -285.158502) (xy 67.454006 -285.116906)
			(xy 67.434715 -285.07163) (xy 67.422938 -285.023846) (xy 67.418978 -284.974792) (xy 67.08013 -284.974792)
			(xy 67.079635 -284.999399) (xy 67.07174 -285.047976) (xy 67.056156 -285.094657) (xy 67.033285 -285.138234)
			(xy 67.00372 -285.177578) (xy 66.968227 -285.21167) (xy 66.927724 -285.239626) (xy 66.883262 -285.260724)
			(xy 66.835991 -285.274416) (xy 66.787136 -285.280348) (xy 66.737961 -285.278367) (xy 66.689742 -285.268523)
			(xy 66.643726 -285.251071) (xy 66.601105 -285.226464) (xy 66.562984 -285.195339) (xy 66.530349 -285.158502)
			(xy 66.504046 -285.116906) (xy 66.484755 -285.07163) (xy 66.472978 -285.023846) (xy 66.469018 -284.974792)
			(xy 66.13017 -284.974792) (xy 66.129675 -284.999399) (xy 66.12178 -285.047976) (xy 66.106196 -285.094657)
			(xy 66.083325 -285.138234) (xy 66.05376 -285.177578) (xy 66.018267 -285.21167) (xy 65.977764 -285.239626)
			(xy 65.933302 -285.260724) (xy 65.886031 -285.274416) (xy 65.837176 -285.280348) (xy 65.788001 -285.278367)
			(xy 65.739782 -285.268523) (xy 65.693766 -285.251071) (xy 65.651145 -285.226464) (xy 65.613024 -285.195339)
			(xy 65.580389 -285.158502) (xy 65.554086 -285.116906) (xy 65.534795 -285.07163) (xy 65.523018 -285.023846)
			(xy 65.519058 -284.974792) (xy 65.18021 -284.974792) (xy 65.179715 -284.999399) (xy 65.17182 -285.047976)
			(xy 65.156236 -285.094657) (xy 65.133365 -285.138234) (xy 65.1038 -285.177578) (xy 65.068307 -285.21167)
			(xy 65.027804 -285.239626) (xy 64.983342 -285.260724) (xy 64.936071 -285.274416) (xy 64.887216 -285.280348)
			(xy 64.838041 -285.278367) (xy 64.789822 -285.268523) (xy 64.743806 -285.251071) (xy 64.701185 -285.226464)
			(xy 64.663064 -285.195339) (xy 64.630429 -285.158502) (xy 64.604126 -285.116906) (xy 64.584835 -285.07163)
			(xy 64.573058 -285.023846) (xy 64.569098 -284.974792) (xy 64.23025 -284.974792) (xy 64.229755 -284.999399)
			(xy 64.22186 -285.047976) (xy 64.206276 -285.094657) (xy 64.183405 -285.138234) (xy 64.15384 -285.177578)
			(xy 64.118347 -285.21167) (xy 64.077844 -285.239626) (xy 64.033382 -285.260724) (xy 63.986111 -285.274416)
			(xy 63.937256 -285.280348) (xy 63.888081 -285.278367) (xy 63.839862 -285.268523) (xy 63.793846 -285.251071)
			(xy 63.751225 -285.226464) (xy 63.713104 -285.195339) (xy 63.680469 -285.158502) (xy 63.654166 -285.116906)
			(xy 63.634875 -285.07163) (xy 63.623098 -285.023846) (xy 63.619138 -284.974792) (xy 63.28029 -284.974792)
			(xy 63.279795 -284.999399) (xy 63.2719 -285.047976) (xy 63.256316 -285.094657) (xy 63.233445 -285.138234)
			(xy 63.20388 -285.177578) (xy 63.168387 -285.21167) (xy 63.127884 -285.239626) (xy 63.083422 -285.260724)
			(xy 63.036151 -285.274416) (xy 62.987296 -285.280348) (xy 62.938121 -285.278367) (xy 62.889902 -285.268523)
			(xy 62.843886 -285.251071) (xy 62.801265 -285.226464) (xy 62.763144 -285.195339) (xy 62.730509 -285.158502)
			(xy 62.704206 -285.116906) (xy 62.684915 -285.07163) (xy 62.673138 -285.023846) (xy 62.669178 -284.974792)
			(xy 62.330076 -284.974792) (xy 62.329581 -284.999399) (xy 62.321686 -285.047976) (xy 62.306102 -285.094657)
			(xy 62.283231 -285.138234) (xy 62.253666 -285.177578) (xy 62.218173 -285.21167) (xy 62.17767 -285.239626)
			(xy 62.133208 -285.260724) (xy 62.085937 -285.274416) (xy 62.037082 -285.280348) (xy 61.987907 -285.278367)
			(xy 61.939688 -285.268523) (xy 61.893672 -285.251071) (xy 61.851051 -285.226464) (xy 61.81293 -285.195339)
			(xy 61.780295 -285.158502) (xy 61.753992 -285.116906) (xy 61.734701 -285.07163) (xy 61.722924 -285.023846)
			(xy 61.718964 -284.974792) (xy 61.380116 -284.974792) (xy 61.379621 -284.999399) (xy 61.371726 -285.047976)
			(xy 61.356142 -285.094657) (xy 61.333271 -285.138234) (xy 61.303706 -285.177578) (xy 61.268213 -285.21167)
			(xy 61.22771 -285.239626) (xy 61.183248 -285.260724) (xy 61.135977 -285.274416) (xy 61.087122 -285.280348)
			(xy 61.037947 -285.278367) (xy 60.989728 -285.268523) (xy 60.943712 -285.251071) (xy 60.901091 -285.226464)
			(xy 60.86297 -285.195339) (xy 60.830335 -285.158502) (xy 60.804032 -285.116906) (xy 60.784741 -285.07163)
			(xy 60.772964 -285.023846) (xy 60.769004 -284.974792) (xy 60.430156 -284.974792) (xy 60.429661 -284.999399)
			(xy 60.421766 -285.047976) (xy 60.406182 -285.094657) (xy 60.383311 -285.138234) (xy 60.353746 -285.177578)
			(xy 60.318253 -285.21167) (xy 60.27775 -285.239626) (xy 60.233288 -285.260724) (xy 60.186017 -285.274416)
			(xy 60.137162 -285.280348) (xy 60.087987 -285.278367) (xy 60.039768 -285.268523) (xy 59.993752 -285.251071)
			(xy 59.951131 -285.226464) (xy 59.91301 -285.195339) (xy 59.880375 -285.158502) (xy 59.854072 -285.116906)
			(xy 59.834781 -285.07163) (xy 59.823004 -285.023846) (xy 59.819044 -284.974792) (xy 58.530236 -284.974792)
			(xy 58.529741 -284.999399) (xy 58.521846 -285.047976) (xy 58.506262 -285.094657) (xy 58.483391 -285.138234)
			(xy 58.453826 -285.177578) (xy 58.418333 -285.21167) (xy 58.37783 -285.239626) (xy 58.333368 -285.260724)
			(xy 58.286097 -285.274416) (xy 58.237242 -285.280348) (xy 58.188067 -285.278367) (xy 58.139848 -285.268523)
			(xy 58.093832 -285.251071) (xy 58.051211 -285.226464) (xy 58.01309 -285.195339) (xy 57.980455 -285.158502)
			(xy 57.954152 -285.116906) (xy 57.934861 -285.07163) (xy 57.923084 -285.023846) (xy 57.919124 -284.974792)
			(xy 57.580276 -284.974792) (xy 57.579781 -284.999399) (xy 57.571886 -285.047976) (xy 57.556302 -285.094657)
			(xy 57.533431 -285.138234) (xy 57.503866 -285.177578) (xy 57.468373 -285.21167) (xy 57.42787 -285.239626)
			(xy 57.383408 -285.260724) (xy 57.336137 -285.274416) (xy 57.287282 -285.280348) (xy 57.238107 -285.278367)
			(xy 57.189888 -285.268523) (xy 57.143872 -285.251071) (xy 57.101251 -285.226464) (xy 57.06313 -285.195339)
			(xy 57.030495 -285.158502) (xy 57.004192 -285.116906) (xy 56.984901 -285.07163) (xy 56.973124 -285.023846)
			(xy 56.969164 -284.974792) (xy 56.630062 -284.974792) (xy 56.629567 -284.999399) (xy 56.621672 -285.047976)
			(xy 56.606088 -285.094657) (xy 56.583217 -285.138234) (xy 56.553652 -285.177578) (xy 56.518159 -285.21167)
			(xy 56.477656 -285.239626) (xy 56.433194 -285.260724) (xy 56.385923 -285.274416) (xy 56.337068 -285.280348)
			(xy 56.287893 -285.278367) (xy 56.239674 -285.268523) (xy 56.193658 -285.251071) (xy 56.151037 -285.226464)
			(xy 56.112916 -285.195339) (xy 56.080281 -285.158502) (xy 56.053978 -285.116906) (xy 56.034687 -285.07163)
			(xy 56.02291 -285.023846) (xy 56.01895 -284.974792) (xy 55.680102 -284.974792) (xy 55.679607 -284.999399)
			(xy 55.671712 -285.047976) (xy 55.656128 -285.094657) (xy 55.633257 -285.138234) (xy 55.603692 -285.177578)
			(xy 55.568199 -285.21167) (xy 55.527696 -285.239626) (xy 55.483234 -285.260724) (xy 55.435963 -285.274416)
			(xy 55.387108 -285.280348) (xy 55.337933 -285.278367) (xy 55.289714 -285.268523) (xy 55.243698 -285.251071)
			(xy 55.201077 -285.226464) (xy 55.162956 -285.195339) (xy 55.130321 -285.158502) (xy 55.104018 -285.116906)
			(xy 55.084727 -285.07163) (xy 55.07295 -285.023846) (xy 55.06899 -284.974792) (xy 54.730142 -284.974792)
			(xy 54.729647 -284.999399) (xy 54.721752 -285.047976) (xy 54.706168 -285.094657) (xy 54.683297 -285.138234)
			(xy 54.653732 -285.177578) (xy 54.618239 -285.21167) (xy 54.577736 -285.239626) (xy 54.533274 -285.260724)
			(xy 54.486003 -285.274416) (xy 54.437148 -285.280348) (xy 54.387973 -285.278367) (xy 54.339754 -285.268523)
			(xy 54.293738 -285.251071) (xy 54.251117 -285.226464) (xy 54.212996 -285.195339) (xy 54.180361 -285.158502)
			(xy 54.154058 -285.116906) (xy 54.134767 -285.07163) (xy 54.12299 -285.023846) (xy 54.11903 -284.974792)
			(xy 53.780182 -284.974792) (xy 53.779687 -284.999399) (xy 53.771792 -285.047976) (xy 53.756208 -285.094657)
			(xy 53.733337 -285.138234) (xy 53.703772 -285.177578) (xy 53.668279 -285.21167) (xy 53.627776 -285.239626)
			(xy 53.583314 -285.260724) (xy 53.536043 -285.274416) (xy 53.487188 -285.280348) (xy 53.438013 -285.278367)
			(xy 53.389794 -285.268523) (xy 53.343778 -285.251071) (xy 53.301157 -285.226464) (xy 53.263036 -285.195339)
			(xy 53.230401 -285.158502) (xy 53.204098 -285.116906) (xy 53.184807 -285.07163) (xy 53.17303 -285.023846)
			(xy 53.16907 -284.974792) (xy 52.830222 -284.974792) (xy 52.829727 -284.999399) (xy 52.821832 -285.047976)
			(xy 52.806248 -285.094657) (xy 52.783377 -285.138234) (xy 52.753812 -285.177578) (xy 52.718319 -285.21167)
			(xy 52.677816 -285.239626) (xy 52.633354 -285.260724) (xy 52.586083 -285.274416) (xy 52.537228 -285.280348)
			(xy 52.488053 -285.278367) (xy 52.439834 -285.268523) (xy 52.393818 -285.251071) (xy 52.351197 -285.226464)
			(xy 52.313076 -285.195339) (xy 52.280441 -285.158502) (xy 52.254138 -285.116906) (xy 52.234847 -285.07163)
			(xy 52.22307 -285.023846) (xy 52.21911 -284.974792) (xy 51.880262 -284.974792) (xy 51.879767 -284.999399)
			(xy 51.871872 -285.047976) (xy 51.856288 -285.094657) (xy 51.833417 -285.138234) (xy 51.803852 -285.177578)
			(xy 51.768359 -285.21167) (xy 51.727856 -285.239626) (xy 51.683394 -285.260724) (xy 51.636123 -285.274416)
			(xy 51.587268 -285.280348) (xy 51.538093 -285.278367) (xy 51.489874 -285.268523) (xy 51.443858 -285.251071)
			(xy 51.401237 -285.226464) (xy 51.363116 -285.195339) (xy 51.330481 -285.158502) (xy 51.304178 -285.116906)
			(xy 51.284887 -285.07163) (xy 51.27311 -285.023846) (xy 51.26915 -284.974792) (xy 50.930302 -284.974792)
			(xy 50.929807 -284.999399) (xy 50.921912 -285.047976) (xy 50.906328 -285.094657) (xy 50.883457 -285.138234)
			(xy 50.853892 -285.177578) (xy 50.818399 -285.21167) (xy 50.777896 -285.239626) (xy 50.733434 -285.260724)
			(xy 50.686163 -285.274416) (xy 50.637308 -285.280348) (xy 50.588133 -285.278367) (xy 50.539914 -285.268523)
			(xy 50.493898 -285.251071) (xy 50.451277 -285.226464) (xy 50.413156 -285.195339) (xy 50.380521 -285.158502)
			(xy 50.354218 -285.116906) (xy 50.334927 -285.07163) (xy 50.32315 -285.023846) (xy 50.31919 -284.974792)
			(xy 49.980088 -284.974792) (xy 49.979593 -284.999399) (xy 49.971698 -285.047976) (xy 49.956114 -285.094657)
			(xy 49.933243 -285.138234) (xy 49.903678 -285.177578) (xy 49.868185 -285.21167) (xy 49.827682 -285.239626)
			(xy 49.78322 -285.260724) (xy 49.735949 -285.274416) (xy 49.687094 -285.280348) (xy 49.637919 -285.278367)
			(xy 49.5897 -285.268523) (xy 49.543684 -285.251071) (xy 49.501063 -285.226464) (xy 49.462942 -285.195339)
			(xy 49.430307 -285.158502) (xy 49.404004 -285.116906) (xy 49.384713 -285.07163) (xy 49.372936 -285.023846)
			(xy 49.368976 -284.974792) (xy 49.030128 -284.974792) (xy 49.029633 -284.999399) (xy 49.021738 -285.047976)
			(xy 49.006154 -285.094657) (xy 48.983283 -285.138234) (xy 48.953718 -285.177578) (xy 48.918225 -285.21167)
			(xy 48.877722 -285.239626) (xy 48.83326 -285.260724) (xy 48.785989 -285.274416) (xy 48.737134 -285.280348)
			(xy 48.687959 -285.278367) (xy 48.63974 -285.268523) (xy 48.593724 -285.251071) (xy 48.551103 -285.226464)
			(xy 48.512982 -285.195339) (xy 48.480347 -285.158502) (xy 48.454044 -285.116906) (xy 48.434753 -285.07163)
			(xy 48.422976 -285.023846) (xy 48.419016 -284.974792) (xy 48.080168 -284.974792) (xy 48.079914 -284.985206)
			(xy 48.079914 -284.991556) (xy 48.07966 -284.996128) (xy 48.07966 -284.99689) (xy 48.078438 -285.011291)
			(xy 48.073607 -285.039788) (xy 48.070008 -285.053786) (xy 48.06823 -285.06039) (xy 48.06823 -285.449772)
			(xy 73.593972 -285.449772) (xy 73.597932 -285.400718) (xy 73.609709 -285.352934) (xy 73.629 -285.307658)
			(xy 73.655303 -285.266062) (xy 73.687938 -285.229225) (xy 73.726059 -285.1981) (xy 73.76868 -285.173493)
			(xy 73.814696 -285.156041) (xy 73.862915 -285.146197) (xy 73.91209 -285.144216) (xy 73.960945 -285.150148)
			(xy 74.008216 -285.16384) (xy 74.052678 -285.184938) (xy 74.093181 -285.212894) (xy 74.128674 -285.246986)
			(xy 74.158239 -285.28633) (xy 74.18111 -285.329907) (xy 74.196694 -285.376588) (xy 74.204589 -285.425165)
			(xy 74.205084 -285.449772) (xy 74.543932 -285.449772) (xy 74.547892 -285.400718) (xy 74.559669 -285.352934)
			(xy 74.57896 -285.307658) (xy 74.605263 -285.266062) (xy 74.637898 -285.229225) (xy 74.676019 -285.1981)
			(xy 74.71864 -285.173493) (xy 74.764656 -285.156041) (xy 74.812875 -285.146197) (xy 74.86205 -285.144216)
			(xy 74.910905 -285.150148) (xy 74.958176 -285.16384) (xy 75.002638 -285.184938) (xy 75.043141 -285.212894)
			(xy 75.078634 -285.246986) (xy 75.108199 -285.28633) (xy 75.13107 -285.329907) (xy 75.146654 -285.376588)
			(xy 75.154549 -285.425165) (xy 75.155044 -285.449772) (xy 75.494146 -285.449772) (xy 75.498106 -285.400718)
			(xy 75.509883 -285.352934) (xy 75.529174 -285.307658) (xy 75.555477 -285.266062) (xy 75.588112 -285.229225)
			(xy 75.626233 -285.1981) (xy 75.668854 -285.173493) (xy 75.71487 -285.156041) (xy 75.763089 -285.146197)
			(xy 75.812264 -285.144216) (xy 75.861119 -285.150148) (xy 75.90839 -285.16384) (xy 75.952852 -285.184938)
			(xy 75.993355 -285.212894) (xy 76.028848 -285.246986) (xy 76.058413 -285.28633) (xy 76.081284 -285.329907)
			(xy 76.096868 -285.376588) (xy 76.104763 -285.425165) (xy 76.105258 -285.449772) (xy 76.444106 -285.449772)
			(xy 76.448066 -285.400718) (xy 76.459843 -285.352934) (xy 76.479134 -285.307658) (xy 76.505437 -285.266062)
			(xy 76.538072 -285.229225) (xy 76.576193 -285.1981) (xy 76.618814 -285.173493) (xy 76.66483 -285.156041)
			(xy 76.713049 -285.146197) (xy 76.762224 -285.144216) (xy 76.811079 -285.150148) (xy 76.85835 -285.16384)
			(xy 76.902812 -285.184938) (xy 76.943315 -285.212894) (xy 76.978808 -285.246986) (xy 77.008373 -285.28633)
			(xy 77.031244 -285.329907) (xy 77.046828 -285.376588) (xy 77.054723 -285.425165) (xy 77.055218 -285.449772)
			(xy 77.394066 -285.449772) (xy 77.398026 -285.400718) (xy 77.409803 -285.352934) (xy 77.429094 -285.307658)
			(xy 77.455397 -285.266062) (xy 77.488032 -285.229225) (xy 77.526153 -285.1981) (xy 77.568774 -285.173493)
			(xy 77.61479 -285.156041) (xy 77.663009 -285.146197) (xy 77.712184 -285.144216) (xy 77.761039 -285.150148)
			(xy 77.80831 -285.16384) (xy 77.852772 -285.184938) (xy 77.893275 -285.212894) (xy 77.928768 -285.246986)
			(xy 77.958333 -285.28633) (xy 77.981204 -285.329907) (xy 77.996788 -285.376588) (xy 78.004683 -285.425165)
			(xy 78.005178 -285.449772) (xy 78.344026 -285.449772) (xy 78.347986 -285.400718) (xy 78.359763 -285.352934)
			(xy 78.379054 -285.307658) (xy 78.405357 -285.266062) (xy 78.437992 -285.229225) (xy 78.476113 -285.1981)
			(xy 78.518734 -285.173493) (xy 78.56475 -285.156041) (xy 78.612969 -285.146197) (xy 78.662144 -285.144216)
			(xy 78.710999 -285.150148) (xy 78.75827 -285.16384) (xy 78.802732 -285.184938) (xy 78.843235 -285.212894)
			(xy 78.878728 -285.246986) (xy 78.908293 -285.28633) (xy 78.931164 -285.329907) (xy 78.946748 -285.376588)
			(xy 78.954643 -285.425165) (xy 78.955138 -285.449772) (xy 79.293986 -285.449772) (xy 79.297946 -285.400718)
			(xy 79.309723 -285.352934) (xy 79.329014 -285.307658) (xy 79.355317 -285.266062) (xy 79.387952 -285.229225)
			(xy 79.426073 -285.1981) (xy 79.468694 -285.173493) (xy 79.51471 -285.156041) (xy 79.562929 -285.146197)
			(xy 79.612104 -285.144216) (xy 79.660959 -285.150148) (xy 79.70823 -285.16384) (xy 79.752692 -285.184938)
			(xy 79.793195 -285.212894) (xy 79.828688 -285.246986) (xy 79.858253 -285.28633) (xy 79.881124 -285.329907)
			(xy 79.896708 -285.376588) (xy 79.904603 -285.425165) (xy 79.905098 -285.449772) (xy 80.243946 -285.449772)
			(xy 80.247906 -285.400718) (xy 80.259683 -285.352934) (xy 80.278974 -285.307658) (xy 80.305277 -285.266062)
			(xy 80.337912 -285.229225) (xy 80.376033 -285.1981) (xy 80.418654 -285.173493) (xy 80.46467 -285.156041)
			(xy 80.512889 -285.146197) (xy 80.562064 -285.144216) (xy 80.610919 -285.150148) (xy 80.65819 -285.16384)
			(xy 80.702652 -285.184938) (xy 80.743155 -285.212894) (xy 80.778648 -285.246986) (xy 80.808213 -285.28633)
			(xy 80.831084 -285.329907) (xy 80.846668 -285.376588) (xy 80.854563 -285.425165) (xy 80.855058 -285.449772)
			(xy 80.854563 -285.474379) (xy 80.854384 -285.47548) (xy 81.173316 -285.47548) (xy 81.173316 -285.424064)
			(xy 81.181359 -285.373282) (xy 81.197247 -285.324383) (xy 81.22059 -285.278571) (xy 81.250811 -285.236975)
			(xy 81.287167 -285.200619) (xy 81.328763 -285.170398) (xy 81.374575 -285.147055) (xy 81.423474 -285.131167)
			(xy 81.474256 -285.123124) (xy 81.525672 -285.123124) (xy 81.576454 -285.131167) (xy 81.625353 -285.147055)
			(xy 81.671165 -285.170398) (xy 81.712761 -285.200619) (xy 81.749117 -285.236975) (xy 81.779338 -285.278571)
			(xy 81.802681 -285.324383) (xy 81.818569 -285.373282) (xy 81.826612 -285.424064) (xy 81.827116 -285.449772)
			(xy 81.826612 -285.47548) (xy 82.123276 -285.47548) (xy 82.123276 -285.424064) (xy 82.131319 -285.373282)
			(xy 82.147207 -285.324383) (xy 82.17055 -285.278571) (xy 82.200771 -285.236975) (xy 82.237127 -285.200619)
			(xy 82.278723 -285.170398) (xy 82.324535 -285.147055) (xy 82.373434 -285.131167) (xy 82.424216 -285.123124)
			(xy 82.475632 -285.123124) (xy 82.526414 -285.131167) (xy 82.575313 -285.147055) (xy 82.621125 -285.170398)
			(xy 82.662721 -285.200619) (xy 82.699077 -285.236975) (xy 82.729298 -285.278571) (xy 82.752641 -285.324383)
			(xy 82.768529 -285.373282) (xy 82.776572 -285.424064) (xy 82.777076 -285.449772) (xy 82.777071 -285.450026)
			(xy 83.094334 -285.450026) (xy 83.098294 -285.400972) (xy 83.110071 -285.353188) (xy 83.129362 -285.307912)
			(xy 83.155665 -285.266316) (xy 83.1883 -285.229479) (xy 83.226421 -285.198354) (xy 83.269042 -285.173747)
			(xy 83.315058 -285.156295) (xy 83.363277 -285.146451) (xy 83.412452 -285.14447) (xy 83.461307 -285.150402)
			(xy 83.508578 -285.164094) (xy 83.55304 -285.185192) (xy 83.593543 -285.213148) (xy 83.629036 -285.24724)
			(xy 83.658601 -285.286584) (xy 83.681472 -285.330161) (xy 83.697056 -285.376842) (xy 83.703831 -285.41853)
			(xy 94.233236 -285.41853) (xy 94.237307 -285.362908) (xy 94.249433 -285.308471) (xy 94.269356 -285.25638)
			(xy 94.296652 -285.207745) (xy 94.330738 -285.163602) (xy 94.370887 -285.124893) (xy 94.416245 -285.092442)
			(xy 94.465845 -285.066941) (xy 94.518629 -285.048934) (xy 94.573472 -285.038804) (xy 94.629206 -285.036767)
			(xy 94.684643 -285.042867) (xy 94.7386 -285.056973) (xy 94.789929 -285.078785) (xy 94.837535 -285.107839)
			(xy 94.880403 -285.143514) (xy 94.91762 -285.185051) (xy 94.948393 -285.231564) (xy 94.972065 -285.282061)
			(xy 94.988133 -285.335468) (xy 94.996253 -285.390644) (xy 94.996762 -285.41853) (xy 94.996253 -285.446416)
			(xy 94.988133 -285.501592) (xy 94.972065 -285.554999) (xy 94.948393 -285.605496) (xy 94.91762 -285.652009)
			(xy 94.880403 -285.693546) (xy 94.837535 -285.729221) (xy 94.789929 -285.758275) (xy 94.7386 -285.780087)
			(xy 94.684643 -285.794193) (xy 94.629206 -285.800293) (xy 94.573472 -285.798256) (xy 94.518629 -285.788126)
			(xy 94.465845 -285.770119) (xy 94.416245 -285.744618) (xy 94.370887 -285.712167) (xy 94.330738 -285.673458)
			(xy 94.296652 -285.629315) (xy 94.269356 -285.58068) (xy 94.249433 -285.528589) (xy 94.237307 -285.474152)
			(xy 94.233236 -285.41853) (xy 83.703831 -285.41853) (xy 83.704951 -285.425419) (xy 83.705446 -285.450026)
			(xy 83.704951 -285.474633) (xy 83.697056 -285.52321) (xy 83.681472 -285.569891) (xy 83.658601 -285.613468)
			(xy 83.629036 -285.652812) (xy 83.593543 -285.686904) (xy 83.55304 -285.71486) (xy 83.508578 -285.735958)
			(xy 83.461307 -285.74965) (xy 83.412452 -285.755582) (xy 83.363277 -285.753601) (xy 83.315058 -285.743757)
			(xy 83.269042 -285.726305) (xy 83.226421 -285.701698) (xy 83.1883 -285.670573) (xy 83.155665 -285.633736)
			(xy 83.129362 -285.59214) (xy 83.110071 -285.546864) (xy 83.098294 -285.49908) (xy 83.094334 -285.450026)
			(xy 82.777071 -285.450026) (xy 82.776572 -285.47548) (xy 82.768529 -285.526262) (xy 82.752641 -285.575161)
			(xy 82.729298 -285.620973) (xy 82.699077 -285.662569) (xy 82.662721 -285.698925) (xy 82.621125 -285.729146)
			(xy 82.575313 -285.752489) (xy 82.526414 -285.768377) (xy 82.475632 -285.77642) (xy 82.424216 -285.77642)
			(xy 82.373434 -285.768377) (xy 82.324535 -285.752489) (xy 82.278723 -285.729146) (xy 82.237127 -285.698925)
			(xy 82.200771 -285.662569) (xy 82.17055 -285.620973) (xy 82.147207 -285.575161) (xy 82.131319 -285.526262)
			(xy 82.123276 -285.47548) (xy 81.826612 -285.47548) (xy 81.818569 -285.526262) (xy 81.802681 -285.575161)
			(xy 81.779338 -285.620973) (xy 81.749117 -285.662569) (xy 81.712761 -285.698925) (xy 81.671165 -285.729146)
			(xy 81.625353 -285.752489) (xy 81.576454 -285.768377) (xy 81.525672 -285.77642) (xy 81.474256 -285.77642)
			(xy 81.423474 -285.768377) (xy 81.374575 -285.752489) (xy 81.328763 -285.729146) (xy 81.287167 -285.698925)
			(xy 81.250811 -285.662569) (xy 81.22059 -285.620973) (xy 81.197247 -285.575161) (xy 81.181359 -285.526262)
			(xy 81.173316 -285.47548) (xy 80.854384 -285.47548) (xy 80.846668 -285.522956) (xy 80.831084 -285.569637)
			(xy 80.808213 -285.613214) (xy 80.778648 -285.652558) (xy 80.743155 -285.68665) (xy 80.702652 -285.714606)
			(xy 80.65819 -285.735704) (xy 80.610919 -285.749396) (xy 80.562064 -285.755328) (xy 80.512889 -285.753347)
			(xy 80.46467 -285.743503) (xy 80.418654 -285.726051) (xy 80.376033 -285.701444) (xy 80.337912 -285.670319)
			(xy 80.305277 -285.633482) (xy 80.278974 -285.591886) (xy 80.259683 -285.54661) (xy 80.247906 -285.498826)
			(xy 80.243946 -285.449772) (xy 79.905098 -285.449772) (xy 79.904603 -285.474379) (xy 79.896708 -285.522956)
			(xy 79.881124 -285.569637) (xy 79.858253 -285.613214) (xy 79.828688 -285.652558) (xy 79.793195 -285.68665)
			(xy 79.752692 -285.714606) (xy 79.70823 -285.735704) (xy 79.660959 -285.749396) (xy 79.612104 -285.755328)
			(xy 79.562929 -285.753347) (xy 79.51471 -285.743503) (xy 79.468694 -285.726051) (xy 79.426073 -285.701444)
			(xy 79.387952 -285.670319) (xy 79.355317 -285.633482) (xy 79.329014 -285.591886) (xy 79.309723 -285.54661)
			(xy 79.297946 -285.498826) (xy 79.293986 -285.449772) (xy 78.955138 -285.449772) (xy 78.954643 -285.474379)
			(xy 78.946748 -285.522956) (xy 78.931164 -285.569637) (xy 78.908293 -285.613214) (xy 78.878728 -285.652558)
			(xy 78.843235 -285.68665) (xy 78.802732 -285.714606) (xy 78.75827 -285.735704) (xy 78.710999 -285.749396)
			(xy 78.662144 -285.755328) (xy 78.612969 -285.753347) (xy 78.56475 -285.743503) (xy 78.518734 -285.726051)
			(xy 78.476113 -285.701444) (xy 78.437992 -285.670319) (xy 78.405357 -285.633482) (xy 78.379054 -285.591886)
			(xy 78.359763 -285.54661) (xy 78.347986 -285.498826) (xy 78.344026 -285.449772) (xy 78.005178 -285.449772)
			(xy 78.004683 -285.474379) (xy 77.996788 -285.522956) (xy 77.981204 -285.569637) (xy 77.958333 -285.613214)
			(xy 77.928768 -285.652558) (xy 77.893275 -285.68665) (xy 77.852772 -285.714606) (xy 77.80831 -285.735704)
			(xy 77.761039 -285.749396) (xy 77.712184 -285.755328) (xy 77.663009 -285.753347) (xy 77.61479 -285.743503)
			(xy 77.568774 -285.726051) (xy 77.526153 -285.701444) (xy 77.488032 -285.670319) (xy 77.455397 -285.633482)
			(xy 77.429094 -285.591886) (xy 77.409803 -285.54661) (xy 77.398026 -285.498826) (xy 77.394066 -285.449772)
			(xy 77.055218 -285.449772) (xy 77.054723 -285.474379) (xy 77.046828 -285.522956) (xy 77.031244 -285.569637)
			(xy 77.008373 -285.613214) (xy 76.978808 -285.652558) (xy 76.943315 -285.68665) (xy 76.902812 -285.714606)
			(xy 76.85835 -285.735704) (xy 76.811079 -285.749396) (xy 76.762224 -285.755328) (xy 76.713049 -285.753347)
			(xy 76.66483 -285.743503) (xy 76.618814 -285.726051) (xy 76.576193 -285.701444) (xy 76.538072 -285.670319)
			(xy 76.505437 -285.633482) (xy 76.479134 -285.591886) (xy 76.459843 -285.54661) (xy 76.448066 -285.498826)
			(xy 76.444106 -285.449772) (xy 76.105258 -285.449772) (xy 76.104763 -285.474379) (xy 76.096868 -285.522956)
			(xy 76.081284 -285.569637) (xy 76.058413 -285.613214) (xy 76.028848 -285.652558) (xy 75.993355 -285.68665)
			(xy 75.952852 -285.714606) (xy 75.90839 -285.735704) (xy 75.861119 -285.749396) (xy 75.812264 -285.755328)
			(xy 75.763089 -285.753347) (xy 75.71487 -285.743503) (xy 75.668854 -285.726051) (xy 75.626233 -285.701444)
			(xy 75.588112 -285.670319) (xy 75.555477 -285.633482) (xy 75.529174 -285.591886) (xy 75.509883 -285.54661)
			(xy 75.498106 -285.498826) (xy 75.494146 -285.449772) (xy 75.155044 -285.449772) (xy 75.154549 -285.474379)
			(xy 75.146654 -285.522956) (xy 75.13107 -285.569637) (xy 75.108199 -285.613214) (xy 75.078634 -285.652558)
			(xy 75.043141 -285.68665) (xy 75.002638 -285.714606) (xy 74.958176 -285.735704) (xy 74.910905 -285.749396)
			(xy 74.86205 -285.755328) (xy 74.812875 -285.753347) (xy 74.764656 -285.743503) (xy 74.71864 -285.726051)
			(xy 74.676019 -285.701444) (xy 74.637898 -285.670319) (xy 74.605263 -285.633482) (xy 74.57896 -285.591886)
			(xy 74.559669 -285.54661) (xy 74.547892 -285.498826) (xy 74.543932 -285.449772) (xy 74.205084 -285.449772)
			(xy 74.204589 -285.474379) (xy 74.196694 -285.522956) (xy 74.18111 -285.569637) (xy 74.158239 -285.613214)
			(xy 74.128674 -285.652558) (xy 74.093181 -285.68665) (xy 74.052678 -285.714606) (xy 74.008216 -285.735704)
			(xy 73.960945 -285.749396) (xy 73.91209 -285.755328) (xy 73.862915 -285.753347) (xy 73.814696 -285.743503)
			(xy 73.76868 -285.726051) (xy 73.726059 -285.701444) (xy 73.687938 -285.670319) (xy 73.655303 -285.633482)
			(xy 73.629 -285.591886) (xy 73.609709 -285.54661) (xy 73.597932 -285.498826) (xy 73.593972 -285.449772)
			(xy 48.06823 -285.449772) (xy 48.06823 -285.833312) (xy 48.070008 -285.84652) (xy 48.07077 -285.849568)
			(xy 48.075168 -285.868052) (xy 48.07988 -285.905754) (xy 48.080168 -285.924752) (xy 48.419016 -285.924752)
			(xy 48.422976 -285.875698) (xy 48.434753 -285.827914) (xy 48.454044 -285.782638) (xy 48.480347 -285.741042)
			(xy 48.512982 -285.704205) (xy 48.551103 -285.67308) (xy 48.593724 -285.648473) (xy 48.63974 -285.631021)
			(xy 48.687959 -285.621177) (xy 48.737134 -285.619196) (xy 48.785989 -285.625128) (xy 48.83326 -285.63882)
			(xy 48.877722 -285.659918) (xy 48.918225 -285.687874) (xy 48.953718 -285.721966) (xy 48.983283 -285.76131)
			(xy 49.006154 -285.804887) (xy 49.021738 -285.851568) (xy 49.029633 -285.900145) (xy 49.030128 -285.924752)
			(xy 49.368976 -285.924752) (xy 49.372936 -285.875698) (xy 49.384713 -285.827914) (xy 49.404004 -285.782638)
			(xy 49.430307 -285.741042) (xy 49.462942 -285.704205) (xy 49.501063 -285.67308) (xy 49.543684 -285.648473)
			(xy 49.5897 -285.631021) (xy 49.637919 -285.621177) (xy 49.687094 -285.619196) (xy 49.735949 -285.625128)
			(xy 49.78322 -285.63882) (xy 49.827682 -285.659918) (xy 49.868185 -285.687874) (xy 49.903678 -285.721966)
			(xy 49.933243 -285.76131) (xy 49.956114 -285.804887) (xy 49.971698 -285.851568) (xy 49.979593 -285.900145)
			(xy 49.980088 -285.924752) (xy 50.31919 -285.924752) (xy 50.32315 -285.875698) (xy 50.334927 -285.827914)
			(xy 50.354218 -285.782638) (xy 50.380521 -285.741042) (xy 50.413156 -285.704205) (xy 50.451277 -285.67308)
			(xy 50.493898 -285.648473) (xy 50.539914 -285.631021) (xy 50.588133 -285.621177) (xy 50.637308 -285.619196)
			(xy 50.686163 -285.625128) (xy 50.733434 -285.63882) (xy 50.777896 -285.659918) (xy 50.818399 -285.687874)
			(xy 50.853892 -285.721966) (xy 50.883457 -285.76131) (xy 50.906328 -285.804887) (xy 50.921912 -285.851568)
			(xy 50.929807 -285.900145) (xy 50.930302 -285.924752) (xy 51.26915 -285.924752) (xy 51.27311 -285.875698)
			(xy 51.284887 -285.827914) (xy 51.304178 -285.782638) (xy 51.330481 -285.741042) (xy 51.363116 -285.704205)
			(xy 51.401237 -285.67308) (xy 51.443858 -285.648473) (xy 51.489874 -285.631021) (xy 51.538093 -285.621177)
			(xy 51.587268 -285.619196) (xy 51.636123 -285.625128) (xy 51.683394 -285.63882) (xy 51.727856 -285.659918)
			(xy 51.768359 -285.687874) (xy 51.803852 -285.721966) (xy 51.833417 -285.76131) (xy 51.856288 -285.804887)
			(xy 51.871872 -285.851568) (xy 51.879767 -285.900145) (xy 51.880262 -285.924752) (xy 52.21911 -285.924752)
			(xy 52.22307 -285.875698) (xy 52.234847 -285.827914) (xy 52.254138 -285.782638) (xy 52.280441 -285.741042)
			(xy 52.313076 -285.704205) (xy 52.351197 -285.67308) (xy 52.393818 -285.648473) (xy 52.439834 -285.631021)
			(xy 52.488053 -285.621177) (xy 52.537228 -285.619196) (xy 52.586083 -285.625128) (xy 52.633354 -285.63882)
			(xy 52.677816 -285.659918) (xy 52.718319 -285.687874) (xy 52.753812 -285.721966) (xy 52.783377 -285.76131)
			(xy 52.806248 -285.804887) (xy 52.821832 -285.851568) (xy 52.829727 -285.900145) (xy 52.830222 -285.924752)
			(xy 53.16907 -285.924752) (xy 53.17303 -285.875698) (xy 53.184807 -285.827914) (xy 53.204098 -285.782638)
			(xy 53.230401 -285.741042) (xy 53.263036 -285.704205) (xy 53.301157 -285.67308) (xy 53.343778 -285.648473)
			(xy 53.389794 -285.631021) (xy 53.438013 -285.621177) (xy 53.487188 -285.619196) (xy 53.536043 -285.625128)
			(xy 53.583314 -285.63882) (xy 53.627776 -285.659918) (xy 53.668279 -285.687874) (xy 53.703772 -285.721966)
			(xy 53.733337 -285.76131) (xy 53.756208 -285.804887) (xy 53.771792 -285.851568) (xy 53.779687 -285.900145)
			(xy 53.780182 -285.924752) (xy 54.11903 -285.924752) (xy 54.12299 -285.875698) (xy 54.134767 -285.827914)
			(xy 54.154058 -285.782638) (xy 54.180361 -285.741042) (xy 54.212996 -285.704205) (xy 54.251117 -285.67308)
			(xy 54.293738 -285.648473) (xy 54.339754 -285.631021) (xy 54.387973 -285.621177) (xy 54.437148 -285.619196)
			(xy 54.486003 -285.625128) (xy 54.533274 -285.63882) (xy 54.577736 -285.659918) (xy 54.618239 -285.687874)
			(xy 54.653732 -285.721966) (xy 54.683297 -285.76131) (xy 54.706168 -285.804887) (xy 54.721752 -285.851568)
			(xy 54.729647 -285.900145) (xy 54.730142 -285.924752) (xy 55.06899 -285.924752) (xy 55.07295 -285.875698)
			(xy 55.084727 -285.827914) (xy 55.104018 -285.782638) (xy 55.130321 -285.741042) (xy 55.162956 -285.704205)
			(xy 55.201077 -285.67308) (xy 55.243698 -285.648473) (xy 55.289714 -285.631021) (xy 55.337933 -285.621177)
			(xy 55.387108 -285.619196) (xy 55.435963 -285.625128) (xy 55.483234 -285.63882) (xy 55.527696 -285.659918)
			(xy 55.568199 -285.687874) (xy 55.603692 -285.721966) (xy 55.633257 -285.76131) (xy 55.656128 -285.804887)
			(xy 55.671712 -285.851568) (xy 55.679607 -285.900145) (xy 55.680102 -285.924752) (xy 56.01895 -285.924752)
			(xy 56.02291 -285.875698) (xy 56.034687 -285.827914) (xy 56.053978 -285.782638) (xy 56.080281 -285.741042)
			(xy 56.112916 -285.704205) (xy 56.151037 -285.67308) (xy 56.193658 -285.648473) (xy 56.239674 -285.631021)
			(xy 56.287893 -285.621177) (xy 56.337068 -285.619196) (xy 56.385923 -285.625128) (xy 56.433194 -285.63882)
			(xy 56.477656 -285.659918) (xy 56.518159 -285.687874) (xy 56.553652 -285.721966) (xy 56.583217 -285.76131)
			(xy 56.606088 -285.804887) (xy 56.621672 -285.851568) (xy 56.629567 -285.900145) (xy 56.630062 -285.924752)
			(xy 56.969164 -285.924752) (xy 56.973124 -285.875698) (xy 56.984901 -285.827914) (xy 57.004192 -285.782638)
			(xy 57.030495 -285.741042) (xy 57.06313 -285.704205) (xy 57.101251 -285.67308) (xy 57.143872 -285.648473)
			(xy 57.189888 -285.631021) (xy 57.238107 -285.621177) (xy 57.287282 -285.619196) (xy 57.336137 -285.625128)
			(xy 57.383408 -285.63882) (xy 57.42787 -285.659918) (xy 57.468373 -285.687874) (xy 57.503866 -285.721966)
			(xy 57.533431 -285.76131) (xy 57.556302 -285.804887) (xy 57.571886 -285.851568) (xy 57.579781 -285.900145)
			(xy 57.580276 -285.924752) (xy 57.919124 -285.924752) (xy 57.923084 -285.875698) (xy 57.934861 -285.827914)
			(xy 57.954152 -285.782638) (xy 57.980455 -285.741042) (xy 58.01309 -285.704205) (xy 58.051211 -285.67308)
			(xy 58.093832 -285.648473) (xy 58.139848 -285.631021) (xy 58.188067 -285.621177) (xy 58.237242 -285.619196)
			(xy 58.286097 -285.625128) (xy 58.333368 -285.63882) (xy 58.37783 -285.659918) (xy 58.418333 -285.687874)
			(xy 58.453826 -285.721966) (xy 58.483391 -285.76131) (xy 58.506262 -285.804887) (xy 58.521846 -285.851568)
			(xy 58.529741 -285.900145) (xy 58.530236 -285.924752) (xy 59.819044 -285.924752) (xy 59.823004 -285.875698)
			(xy 59.834781 -285.827914) (xy 59.854072 -285.782638) (xy 59.880375 -285.741042) (xy 59.91301 -285.704205)
			(xy 59.951131 -285.67308) (xy 59.993752 -285.648473) (xy 60.039768 -285.631021) (xy 60.087987 -285.621177)
			(xy 60.137162 -285.619196) (xy 60.186017 -285.625128) (xy 60.233288 -285.63882) (xy 60.27775 -285.659918)
			(xy 60.318253 -285.687874) (xy 60.353746 -285.721966) (xy 60.383311 -285.76131) (xy 60.406182 -285.804887)
			(xy 60.421766 -285.851568) (xy 60.429661 -285.900145) (xy 60.430156 -285.924752) (xy 60.769004 -285.924752)
			(xy 60.772964 -285.875698) (xy 60.784741 -285.827914) (xy 60.804032 -285.782638) (xy 60.830335 -285.741042)
			(xy 60.86297 -285.704205) (xy 60.901091 -285.67308) (xy 60.943712 -285.648473) (xy 60.989728 -285.631021)
			(xy 61.037947 -285.621177) (xy 61.087122 -285.619196) (xy 61.135977 -285.625128) (xy 61.183248 -285.63882)
			(xy 61.22771 -285.659918) (xy 61.268213 -285.687874) (xy 61.303706 -285.721966) (xy 61.333271 -285.76131)
			(xy 61.356142 -285.804887) (xy 61.371726 -285.851568) (xy 61.379621 -285.900145) (xy 61.380116 -285.924752)
			(xy 61.718964 -285.924752) (xy 61.722924 -285.875698) (xy 61.734701 -285.827914) (xy 61.753992 -285.782638)
			(xy 61.780295 -285.741042) (xy 61.81293 -285.704205) (xy 61.851051 -285.67308) (xy 61.893672 -285.648473)
			(xy 61.939688 -285.631021) (xy 61.987907 -285.621177) (xy 62.037082 -285.619196) (xy 62.085937 -285.625128)
			(xy 62.133208 -285.63882) (xy 62.17767 -285.659918) (xy 62.218173 -285.687874) (xy 62.253666 -285.721966)
			(xy 62.283231 -285.76131) (xy 62.306102 -285.804887) (xy 62.321686 -285.851568) (xy 62.329581 -285.900145)
			(xy 62.330076 -285.924752) (xy 62.669178 -285.924752) (xy 62.673138 -285.875698) (xy 62.684915 -285.827914)
			(xy 62.704206 -285.782638) (xy 62.730509 -285.741042) (xy 62.763144 -285.704205) (xy 62.801265 -285.67308)
			(xy 62.843886 -285.648473) (xy 62.889902 -285.631021) (xy 62.938121 -285.621177) (xy 62.987296 -285.619196)
			(xy 63.036151 -285.625128) (xy 63.083422 -285.63882) (xy 63.127884 -285.659918) (xy 63.168387 -285.687874)
			(xy 63.20388 -285.721966) (xy 63.233445 -285.76131) (xy 63.256316 -285.804887) (xy 63.2719 -285.851568)
			(xy 63.279795 -285.900145) (xy 63.28029 -285.924752) (xy 63.619138 -285.924752) (xy 63.623098 -285.875698)
			(xy 63.634875 -285.827914) (xy 63.654166 -285.782638) (xy 63.680469 -285.741042) (xy 63.713104 -285.704205)
			(xy 63.751225 -285.67308) (xy 63.793846 -285.648473) (xy 63.839862 -285.631021) (xy 63.888081 -285.621177)
			(xy 63.937256 -285.619196) (xy 63.986111 -285.625128) (xy 64.033382 -285.63882) (xy 64.077844 -285.659918)
			(xy 64.118347 -285.687874) (xy 64.15384 -285.721966) (xy 64.183405 -285.76131) (xy 64.206276 -285.804887)
			(xy 64.22186 -285.851568) (xy 64.229755 -285.900145) (xy 64.23025 -285.924752) (xy 64.569098 -285.924752)
			(xy 64.573058 -285.875698) (xy 64.584835 -285.827914) (xy 64.604126 -285.782638) (xy 64.630429 -285.741042)
			(xy 64.663064 -285.704205) (xy 64.701185 -285.67308) (xy 64.743806 -285.648473) (xy 64.789822 -285.631021)
			(xy 64.838041 -285.621177) (xy 64.887216 -285.619196) (xy 64.936071 -285.625128) (xy 64.983342 -285.63882)
			(xy 65.027804 -285.659918) (xy 65.068307 -285.687874) (xy 65.1038 -285.721966) (xy 65.133365 -285.76131)
			(xy 65.156236 -285.804887) (xy 65.17182 -285.851568) (xy 65.179715 -285.900145) (xy 65.18021 -285.924752)
			(xy 65.519058 -285.924752) (xy 65.523018 -285.875698) (xy 65.534795 -285.827914) (xy 65.554086 -285.782638)
			(xy 65.580389 -285.741042) (xy 65.613024 -285.704205) (xy 65.651145 -285.67308) (xy 65.693766 -285.648473)
			(xy 65.739782 -285.631021) (xy 65.788001 -285.621177) (xy 65.837176 -285.619196) (xy 65.886031 -285.625128)
			(xy 65.933302 -285.63882) (xy 65.977764 -285.659918) (xy 66.018267 -285.687874) (xy 66.05376 -285.721966)
			(xy 66.083325 -285.76131) (xy 66.106196 -285.804887) (xy 66.12178 -285.851568) (xy 66.129675 -285.900145)
			(xy 66.13017 -285.924752) (xy 66.469018 -285.924752) (xy 66.472978 -285.875698) (xy 66.484755 -285.827914)
			(xy 66.504046 -285.782638) (xy 66.530349 -285.741042) (xy 66.562984 -285.704205) (xy 66.601105 -285.67308)
			(xy 66.643726 -285.648473) (xy 66.689742 -285.631021) (xy 66.737961 -285.621177) (xy 66.787136 -285.619196)
			(xy 66.835991 -285.625128) (xy 66.883262 -285.63882) (xy 66.927724 -285.659918) (xy 66.968227 -285.687874)
			(xy 67.00372 -285.721966) (xy 67.033285 -285.76131) (xy 67.056156 -285.804887) (xy 67.07174 -285.851568)
			(xy 67.079635 -285.900145) (xy 67.08013 -285.924752) (xy 67.418978 -285.924752) (xy 67.422938 -285.875698)
			(xy 67.434715 -285.827914) (xy 67.454006 -285.782638) (xy 67.480309 -285.741042) (xy 67.512944 -285.704205)
			(xy 67.551065 -285.67308) (xy 67.593686 -285.648473) (xy 67.639702 -285.631021) (xy 67.687921 -285.621177)
			(xy 67.737096 -285.619196) (xy 67.785951 -285.625128) (xy 67.833222 -285.63882) (xy 67.877684 -285.659918)
			(xy 67.918187 -285.687874) (xy 67.95368 -285.721966) (xy 67.983245 -285.76131) (xy 68.006116 -285.804887)
			(xy 68.0217 -285.851568) (xy 68.029595 -285.900145) (xy 68.03009 -285.924752) (xy 68.368938 -285.924752)
			(xy 68.372898 -285.875698) (xy 68.384675 -285.827914) (xy 68.403966 -285.782638) (xy 68.430269 -285.741042)
			(xy 68.462904 -285.704205) (xy 68.501025 -285.67308) (xy 68.543646 -285.648473) (xy 68.589662 -285.631021)
			(xy 68.637881 -285.621177) (xy 68.687056 -285.619196) (xy 68.735911 -285.625128) (xy 68.783182 -285.63882)
			(xy 68.827644 -285.659918) (xy 68.868147 -285.687874) (xy 68.90364 -285.721966) (xy 68.933205 -285.76131)
			(xy 68.956076 -285.804887) (xy 68.97166 -285.851568) (xy 68.979555 -285.900145) (xy 68.98005 -285.924752)
			(xy 69.319152 -285.924752) (xy 69.323112 -285.875698) (xy 69.334889 -285.827914) (xy 69.35418 -285.782638)
			(xy 69.380483 -285.741042) (xy 69.413118 -285.704205) (xy 69.451239 -285.67308) (xy 69.49386 -285.648473)
			(xy 69.539876 -285.631021) (xy 69.588095 -285.621177) (xy 69.63727 -285.619196) (xy 69.686125 -285.625128)
			(xy 69.733396 -285.63882) (xy 69.777858 -285.659918) (xy 69.818361 -285.687874) (xy 69.853854 -285.721966)
			(xy 69.883419 -285.76131) (xy 69.90629 -285.804887) (xy 69.921874 -285.851568) (xy 69.929769 -285.900145)
			(xy 69.930264 -285.924752) (xy 70.269112 -285.924752) (xy 70.273072 -285.875698) (xy 70.284849 -285.827914)
			(xy 70.30414 -285.782638) (xy 70.330443 -285.741042) (xy 70.363078 -285.704205) (xy 70.401199 -285.67308)
			(xy 70.44382 -285.648473) (xy 70.489836 -285.631021) (xy 70.538055 -285.621177) (xy 70.58723 -285.619196)
			(xy 70.636085 -285.625128) (xy 70.683356 -285.63882) (xy 70.727818 -285.659918) (xy 70.768321 -285.687874)
			(xy 70.803814 -285.721966) (xy 70.833379 -285.76131) (xy 70.85625 -285.804887) (xy 70.871834 -285.851568)
			(xy 70.879729 -285.900145) (xy 70.880224 -285.924752) (xy 70.879729 -285.949359) (xy 70.871834 -285.997936)
			(xy 70.85625 -286.044617) (xy 70.833379 -286.088194) (xy 70.803814 -286.127538) (xy 70.768321 -286.16163)
			(xy 70.727818 -286.189586) (xy 70.683356 -286.210684) (xy 70.636085 -286.224376) (xy 70.58723 -286.230308)
			(xy 70.538055 -286.228327) (xy 70.489836 -286.218483) (xy 70.44382 -286.201031) (xy 70.401199 -286.176424)
			(xy 70.363078 -286.145299) (xy 70.330443 -286.108462) (xy 70.30414 -286.066866) (xy 70.284849 -286.02159)
			(xy 70.273072 -285.973806) (xy 70.269112 -285.924752) (xy 69.930264 -285.924752) (xy 69.929769 -285.949359)
			(xy 69.921874 -285.997936) (xy 69.90629 -286.044617) (xy 69.883419 -286.088194) (xy 69.853854 -286.127538)
			(xy 69.818361 -286.16163) (xy 69.777858 -286.189586) (xy 69.733396 -286.210684) (xy 69.686125 -286.224376)
			(xy 69.63727 -286.230308) (xy 69.588095 -286.228327) (xy 69.539876 -286.218483) (xy 69.49386 -286.201031)
			(xy 69.451239 -286.176424) (xy 69.413118 -286.145299) (xy 69.380483 -286.108462) (xy 69.35418 -286.066866)
			(xy 69.334889 -286.02159) (xy 69.323112 -285.973806) (xy 69.319152 -285.924752) (xy 68.98005 -285.924752)
			(xy 68.979555 -285.949359) (xy 68.97166 -285.997936) (xy 68.956076 -286.044617) (xy 68.933205 -286.088194)
			(xy 68.90364 -286.127538) (xy 68.868147 -286.16163) (xy 68.827644 -286.189586) (xy 68.783182 -286.210684)
			(xy 68.735911 -286.224376) (xy 68.687056 -286.230308) (xy 68.637881 -286.228327) (xy 68.589662 -286.218483)
			(xy 68.543646 -286.201031) (xy 68.501025 -286.176424) (xy 68.462904 -286.145299) (xy 68.430269 -286.108462)
			(xy 68.403966 -286.066866) (xy 68.384675 -286.02159) (xy 68.372898 -285.973806) (xy 68.368938 -285.924752)
			(xy 68.03009 -285.924752) (xy 68.029595 -285.949359) (xy 68.0217 -285.997936) (xy 68.006116 -286.044617)
			(xy 67.983245 -286.088194) (xy 67.95368 -286.127538) (xy 67.918187 -286.16163) (xy 67.877684 -286.189586)
			(xy 67.833222 -286.210684) (xy 67.785951 -286.224376) (xy 67.737096 -286.230308) (xy 67.687921 -286.228327)
			(xy 67.639702 -286.218483) (xy 67.593686 -286.201031) (xy 67.551065 -286.176424) (xy 67.512944 -286.145299)
			(xy 67.480309 -286.108462) (xy 67.454006 -286.066866) (xy 67.434715 -286.02159) (xy 67.422938 -285.973806)
			(xy 67.418978 -285.924752) (xy 67.08013 -285.924752) (xy 67.079635 -285.949359) (xy 67.07174 -285.997936)
			(xy 67.056156 -286.044617) (xy 67.033285 -286.088194) (xy 67.00372 -286.127538) (xy 66.968227 -286.16163)
			(xy 66.927724 -286.189586) (xy 66.883262 -286.210684) (xy 66.835991 -286.224376) (xy 66.787136 -286.230308)
			(xy 66.737961 -286.228327) (xy 66.689742 -286.218483) (xy 66.643726 -286.201031) (xy 66.601105 -286.176424)
			(xy 66.562984 -286.145299) (xy 66.530349 -286.108462) (xy 66.504046 -286.066866) (xy 66.484755 -286.02159)
			(xy 66.472978 -285.973806) (xy 66.469018 -285.924752) (xy 66.13017 -285.924752) (xy 66.129675 -285.949359)
			(xy 66.12178 -285.997936) (xy 66.106196 -286.044617) (xy 66.083325 -286.088194) (xy 66.05376 -286.127538)
			(xy 66.018267 -286.16163) (xy 65.977764 -286.189586) (xy 65.933302 -286.210684) (xy 65.886031 -286.224376)
			(xy 65.837176 -286.230308) (xy 65.788001 -286.228327) (xy 65.739782 -286.218483) (xy 65.693766 -286.201031)
			(xy 65.651145 -286.176424) (xy 65.613024 -286.145299) (xy 65.580389 -286.108462) (xy 65.554086 -286.066866)
			(xy 65.534795 -286.02159) (xy 65.523018 -285.973806) (xy 65.519058 -285.924752) (xy 65.18021 -285.924752)
			(xy 65.179715 -285.949359) (xy 65.17182 -285.997936) (xy 65.156236 -286.044617) (xy 65.133365 -286.088194)
			(xy 65.1038 -286.127538) (xy 65.068307 -286.16163) (xy 65.027804 -286.189586) (xy 64.983342 -286.210684)
			(xy 64.936071 -286.224376) (xy 64.887216 -286.230308) (xy 64.838041 -286.228327) (xy 64.789822 -286.218483)
			(xy 64.743806 -286.201031) (xy 64.701185 -286.176424) (xy 64.663064 -286.145299) (xy 64.630429 -286.108462)
			(xy 64.604126 -286.066866) (xy 64.584835 -286.02159) (xy 64.573058 -285.973806) (xy 64.569098 -285.924752)
			(xy 64.23025 -285.924752) (xy 64.229755 -285.949359) (xy 64.22186 -285.997936) (xy 64.206276 -286.044617)
			(xy 64.183405 -286.088194) (xy 64.15384 -286.127538) (xy 64.118347 -286.16163) (xy 64.077844 -286.189586)
			(xy 64.033382 -286.210684) (xy 63.986111 -286.224376) (xy 63.937256 -286.230308) (xy 63.888081 -286.228327)
			(xy 63.839862 -286.218483) (xy 63.793846 -286.201031) (xy 63.751225 -286.176424) (xy 63.713104 -286.145299)
			(xy 63.680469 -286.108462) (xy 63.654166 -286.066866) (xy 63.634875 -286.02159) (xy 63.623098 -285.973806)
			(xy 63.619138 -285.924752) (xy 63.28029 -285.924752) (xy 63.279795 -285.949359) (xy 63.2719 -285.997936)
			(xy 63.256316 -286.044617) (xy 63.233445 -286.088194) (xy 63.20388 -286.127538) (xy 63.168387 -286.16163)
			(xy 63.127884 -286.189586) (xy 63.083422 -286.210684) (xy 63.036151 -286.224376) (xy 62.987296 -286.230308)
			(xy 62.938121 -286.228327) (xy 62.889902 -286.218483) (xy 62.843886 -286.201031) (xy 62.801265 -286.176424)
			(xy 62.763144 -286.145299) (xy 62.730509 -286.108462) (xy 62.704206 -286.066866) (xy 62.684915 -286.02159)
			(xy 62.673138 -285.973806) (xy 62.669178 -285.924752) (xy 62.330076 -285.924752) (xy 62.329581 -285.949359)
			(xy 62.321686 -285.997936) (xy 62.306102 -286.044617) (xy 62.283231 -286.088194) (xy 62.253666 -286.127538)
			(xy 62.218173 -286.16163) (xy 62.17767 -286.189586) (xy 62.133208 -286.210684) (xy 62.085937 -286.224376)
			(xy 62.037082 -286.230308) (xy 61.987907 -286.228327) (xy 61.939688 -286.218483) (xy 61.893672 -286.201031)
			(xy 61.851051 -286.176424) (xy 61.81293 -286.145299) (xy 61.780295 -286.108462) (xy 61.753992 -286.066866)
			(xy 61.734701 -286.02159) (xy 61.722924 -285.973806) (xy 61.718964 -285.924752) (xy 61.380116 -285.924752)
			(xy 61.379621 -285.949359) (xy 61.371726 -285.997936) (xy 61.356142 -286.044617) (xy 61.333271 -286.088194)
			(xy 61.303706 -286.127538) (xy 61.268213 -286.16163) (xy 61.22771 -286.189586) (xy 61.183248 -286.210684)
			(xy 61.135977 -286.224376) (xy 61.087122 -286.230308) (xy 61.037947 -286.228327) (xy 60.989728 -286.218483)
			(xy 60.943712 -286.201031) (xy 60.901091 -286.176424) (xy 60.86297 -286.145299) (xy 60.830335 -286.108462)
			(xy 60.804032 -286.066866) (xy 60.784741 -286.02159) (xy 60.772964 -285.973806) (xy 60.769004 -285.924752)
			(xy 60.430156 -285.924752) (xy 60.429661 -285.949359) (xy 60.421766 -285.997936) (xy 60.406182 -286.044617)
			(xy 60.383311 -286.088194) (xy 60.353746 -286.127538) (xy 60.318253 -286.16163) (xy 60.27775 -286.189586)
			(xy 60.233288 -286.210684) (xy 60.186017 -286.224376) (xy 60.137162 -286.230308) (xy 60.087987 -286.228327)
			(xy 60.039768 -286.218483) (xy 59.993752 -286.201031) (xy 59.951131 -286.176424) (xy 59.91301 -286.145299)
			(xy 59.880375 -286.108462) (xy 59.854072 -286.066866) (xy 59.834781 -286.02159) (xy 59.823004 -285.973806)
			(xy 59.819044 -285.924752) (xy 58.530236 -285.924752) (xy 58.529741 -285.949359) (xy 58.521846 -285.997936)
			(xy 58.506262 -286.044617) (xy 58.483391 -286.088194) (xy 58.453826 -286.127538) (xy 58.418333 -286.16163)
			(xy 58.37783 -286.189586) (xy 58.333368 -286.210684) (xy 58.286097 -286.224376) (xy 58.237242 -286.230308)
			(xy 58.188067 -286.228327) (xy 58.139848 -286.218483) (xy 58.093832 -286.201031) (xy 58.051211 -286.176424)
			(xy 58.01309 -286.145299) (xy 57.980455 -286.108462) (xy 57.954152 -286.066866) (xy 57.934861 -286.02159)
			(xy 57.923084 -285.973806) (xy 57.919124 -285.924752) (xy 57.580276 -285.924752) (xy 57.579781 -285.949359)
			(xy 57.571886 -285.997936) (xy 57.556302 -286.044617) (xy 57.533431 -286.088194) (xy 57.503866 -286.127538)
			(xy 57.468373 -286.16163) (xy 57.42787 -286.189586) (xy 57.383408 -286.210684) (xy 57.336137 -286.224376)
			(xy 57.287282 -286.230308) (xy 57.238107 -286.228327) (xy 57.189888 -286.218483) (xy 57.143872 -286.201031)
			(xy 57.101251 -286.176424) (xy 57.06313 -286.145299) (xy 57.030495 -286.108462) (xy 57.004192 -286.066866)
			(xy 56.984901 -286.02159) (xy 56.973124 -285.973806) (xy 56.969164 -285.924752) (xy 56.630062 -285.924752)
			(xy 56.629567 -285.949359) (xy 56.621672 -285.997936) (xy 56.606088 -286.044617) (xy 56.583217 -286.088194)
			(xy 56.553652 -286.127538) (xy 56.518159 -286.16163) (xy 56.477656 -286.189586) (xy 56.433194 -286.210684)
			(xy 56.385923 -286.224376) (xy 56.337068 -286.230308) (xy 56.287893 -286.228327) (xy 56.239674 -286.218483)
			(xy 56.193658 -286.201031) (xy 56.151037 -286.176424) (xy 56.112916 -286.145299) (xy 56.080281 -286.108462)
			(xy 56.053978 -286.066866) (xy 56.034687 -286.02159) (xy 56.02291 -285.973806) (xy 56.01895 -285.924752)
			(xy 55.680102 -285.924752) (xy 55.679607 -285.949359) (xy 55.671712 -285.997936) (xy 55.656128 -286.044617)
			(xy 55.633257 -286.088194) (xy 55.603692 -286.127538) (xy 55.568199 -286.16163) (xy 55.527696 -286.189586)
			(xy 55.483234 -286.210684) (xy 55.435963 -286.224376) (xy 55.387108 -286.230308) (xy 55.337933 -286.228327)
			(xy 55.289714 -286.218483) (xy 55.243698 -286.201031) (xy 55.201077 -286.176424) (xy 55.162956 -286.145299)
			(xy 55.130321 -286.108462) (xy 55.104018 -286.066866) (xy 55.084727 -286.02159) (xy 55.07295 -285.973806)
			(xy 55.06899 -285.924752) (xy 54.730142 -285.924752) (xy 54.729647 -285.949359) (xy 54.721752 -285.997936)
			(xy 54.706168 -286.044617) (xy 54.683297 -286.088194) (xy 54.653732 -286.127538) (xy 54.618239 -286.16163)
			(xy 54.577736 -286.189586) (xy 54.533274 -286.210684) (xy 54.486003 -286.224376) (xy 54.437148 -286.230308)
			(xy 54.387973 -286.228327) (xy 54.339754 -286.218483) (xy 54.293738 -286.201031) (xy 54.251117 -286.176424)
			(xy 54.212996 -286.145299) (xy 54.180361 -286.108462) (xy 54.154058 -286.066866) (xy 54.134767 -286.02159)
			(xy 54.12299 -285.973806) (xy 54.11903 -285.924752) (xy 53.780182 -285.924752) (xy 53.779687 -285.949359)
			(xy 53.771792 -285.997936) (xy 53.756208 -286.044617) (xy 53.733337 -286.088194) (xy 53.703772 -286.127538)
			(xy 53.668279 -286.16163) (xy 53.627776 -286.189586) (xy 53.583314 -286.210684) (xy 53.536043 -286.224376)
			(xy 53.487188 -286.230308) (xy 53.438013 -286.228327) (xy 53.389794 -286.218483) (xy 53.343778 -286.201031)
			(xy 53.301157 -286.176424) (xy 53.263036 -286.145299) (xy 53.230401 -286.108462) (xy 53.204098 -286.066866)
			(xy 53.184807 -286.02159) (xy 53.17303 -285.973806) (xy 53.16907 -285.924752) (xy 52.830222 -285.924752)
			(xy 52.829727 -285.949359) (xy 52.821832 -285.997936) (xy 52.806248 -286.044617) (xy 52.783377 -286.088194)
			(xy 52.753812 -286.127538) (xy 52.718319 -286.16163) (xy 52.677816 -286.189586) (xy 52.633354 -286.210684)
			(xy 52.586083 -286.224376) (xy 52.537228 -286.230308) (xy 52.488053 -286.228327) (xy 52.439834 -286.218483)
			(xy 52.393818 -286.201031) (xy 52.351197 -286.176424) (xy 52.313076 -286.145299) (xy 52.280441 -286.108462)
			(xy 52.254138 -286.066866) (xy 52.234847 -286.02159) (xy 52.22307 -285.973806) (xy 52.21911 -285.924752)
			(xy 51.880262 -285.924752) (xy 51.879767 -285.949359) (xy 51.871872 -285.997936) (xy 51.856288 -286.044617)
			(xy 51.833417 -286.088194) (xy 51.803852 -286.127538) (xy 51.768359 -286.16163) (xy 51.727856 -286.189586)
			(xy 51.683394 -286.210684) (xy 51.636123 -286.224376) (xy 51.587268 -286.230308) (xy 51.538093 -286.228327)
			(xy 51.489874 -286.218483) (xy 51.443858 -286.201031) (xy 51.401237 -286.176424) (xy 51.363116 -286.145299)
			(xy 51.330481 -286.108462) (xy 51.304178 -286.066866) (xy 51.284887 -286.02159) (xy 51.27311 -285.973806)
			(xy 51.26915 -285.924752) (xy 50.930302 -285.924752) (xy 50.929807 -285.949359) (xy 50.921912 -285.997936)
			(xy 50.906328 -286.044617) (xy 50.883457 -286.088194) (xy 50.853892 -286.127538) (xy 50.818399 -286.16163)
			(xy 50.777896 -286.189586) (xy 50.733434 -286.210684) (xy 50.686163 -286.224376) (xy 50.637308 -286.230308)
			(xy 50.588133 -286.228327) (xy 50.539914 -286.218483) (xy 50.493898 -286.201031) (xy 50.451277 -286.176424)
			(xy 50.413156 -286.145299) (xy 50.380521 -286.108462) (xy 50.354218 -286.066866) (xy 50.334927 -286.02159)
			(xy 50.32315 -285.973806) (xy 50.31919 -285.924752) (xy 49.980088 -285.924752) (xy 49.979593 -285.949359)
			(xy 49.971698 -285.997936) (xy 49.956114 -286.044617) (xy 49.933243 -286.088194) (xy 49.903678 -286.127538)
			(xy 49.868185 -286.16163) (xy 49.827682 -286.189586) (xy 49.78322 -286.210684) (xy 49.735949 -286.224376)
			(xy 49.687094 -286.230308) (xy 49.637919 -286.228327) (xy 49.5897 -286.218483) (xy 49.543684 -286.201031)
			(xy 49.501063 -286.176424) (xy 49.462942 -286.145299) (xy 49.430307 -286.108462) (xy 49.404004 -286.066866)
			(xy 49.384713 -286.02159) (xy 49.372936 -285.973806) (xy 49.368976 -285.924752) (xy 49.030128 -285.924752)
			(xy 49.029633 -285.949359) (xy 49.021738 -285.997936) (xy 49.006154 -286.044617) (xy 48.983283 -286.088194)
			(xy 48.953718 -286.127538) (xy 48.918225 -286.16163) (xy 48.877722 -286.189586) (xy 48.83326 -286.210684)
			(xy 48.785989 -286.224376) (xy 48.737134 -286.230308) (xy 48.687959 -286.228327) (xy 48.63974 -286.218483)
			(xy 48.593724 -286.201031) (xy 48.551103 -286.176424) (xy 48.512982 -286.145299) (xy 48.480347 -286.108462)
			(xy 48.454044 -286.066866) (xy 48.434753 -286.02159) (xy 48.422976 -285.973806) (xy 48.419016 -285.924752)
			(xy 48.080168 -285.924752) (xy 48.079914 -285.935166) (xy 48.079914 -285.941516) (xy 48.07966 -285.946088)
			(xy 48.07966 -285.94685) (xy 48.078435 -285.961251) (xy 48.073599 -285.989746) (xy 48.070008 -286.003746)
			(xy 48.06823 -286.01035) (xy 48.06823 -286.399732) (xy 73.593972 -286.399732) (xy 73.597932 -286.350678)
			(xy 73.609709 -286.302894) (xy 73.629 -286.257618) (xy 73.655303 -286.216022) (xy 73.687938 -286.179185)
			(xy 73.726059 -286.14806) (xy 73.76868 -286.123453) (xy 73.814696 -286.106001) (xy 73.862915 -286.096157)
			(xy 73.91209 -286.094176) (xy 73.960945 -286.100108) (xy 74.008216 -286.1138) (xy 74.052678 -286.134898)
			(xy 74.093181 -286.162854) (xy 74.128674 -286.196946) (xy 74.158239 -286.23629) (xy 74.18111 -286.279867)
			(xy 74.196694 -286.326548) (xy 74.204589 -286.375125) (xy 74.205084 -286.399732) (xy 74.544186 -286.399732)
			(xy 74.548146 -286.350678) (xy 74.559923 -286.302894) (xy 74.579214 -286.257618) (xy 74.605517 -286.216022)
			(xy 74.638152 -286.179185) (xy 74.676273 -286.14806) (xy 74.718894 -286.123453) (xy 74.76491 -286.106001)
			(xy 74.813129 -286.096157) (xy 74.862304 -286.094176) (xy 74.911159 -286.100108) (xy 74.95843 -286.1138)
			(xy 75.002892 -286.134898) (xy 75.043395 -286.162854) (xy 75.078888 -286.196946) (xy 75.108453 -286.23629)
			(xy 75.131324 -286.279867) (xy 75.146908 -286.326548) (xy 75.154803 -286.375125) (xy 75.155298 -286.399732)
			(xy 75.494146 -286.399732) (xy 75.498106 -286.350678) (xy 75.509883 -286.302894) (xy 75.529174 -286.257618)
			(xy 75.555477 -286.216022) (xy 75.588112 -286.179185) (xy 75.626233 -286.14806) (xy 75.668854 -286.123453)
			(xy 75.71487 -286.106001) (xy 75.763089 -286.096157) (xy 75.812264 -286.094176) (xy 75.861119 -286.100108)
			(xy 75.90839 -286.1138) (xy 75.952852 -286.134898) (xy 75.993355 -286.162854) (xy 76.028848 -286.196946)
			(xy 76.058413 -286.23629) (xy 76.081284 -286.279867) (xy 76.096868 -286.326548) (xy 76.104763 -286.375125)
			(xy 76.105258 -286.399732) (xy 76.105253 -286.399986) (xy 76.444106 -286.399986) (xy 76.448066 -286.350932)
			(xy 76.459843 -286.303148) (xy 76.479134 -286.257872) (xy 76.505437 -286.216276) (xy 76.538072 -286.179439)
			(xy 76.576193 -286.148314) (xy 76.618814 -286.123707) (xy 76.66483 -286.106255) (xy 76.713049 -286.096411)
			(xy 76.762224 -286.09443) (xy 76.811079 -286.100362) (xy 76.85835 -286.114054) (xy 76.902812 -286.135152)
			(xy 76.943315 -286.163108) (xy 76.978808 -286.1972) (xy 77.008373 -286.236544) (xy 77.031244 -286.280121)
			(xy 77.046828 -286.326802) (xy 77.054723 -286.375379) (xy 77.055218 -286.399986) (xy 77.394066 -286.399986)
			(xy 77.398026 -286.350932) (xy 77.409803 -286.303148) (xy 77.429094 -286.257872) (xy 77.455397 -286.216276)
			(xy 77.488032 -286.179439) (xy 77.526153 -286.148314) (xy 77.568774 -286.123707) (xy 77.61479 -286.106255)
			(xy 77.663009 -286.096411) (xy 77.712184 -286.09443) (xy 77.761039 -286.100362) (xy 77.80831 -286.114054)
			(xy 77.852772 -286.135152) (xy 77.893275 -286.163108) (xy 77.928768 -286.1972) (xy 77.958333 -286.236544)
			(xy 77.981204 -286.280121) (xy 77.996788 -286.326802) (xy 78.004683 -286.375379) (xy 78.005173 -286.399732)
			(xy 78.344026 -286.399732) (xy 78.347986 -286.350678) (xy 78.359763 -286.302894) (xy 78.379054 -286.257618)
			(xy 78.405357 -286.216022) (xy 78.437992 -286.179185) (xy 78.476113 -286.14806) (xy 78.518734 -286.123453)
			(xy 78.56475 -286.106001) (xy 78.612969 -286.096157) (xy 78.662144 -286.094176) (xy 78.710999 -286.100108)
			(xy 78.75827 -286.1138) (xy 78.802732 -286.134898) (xy 78.843235 -286.162854) (xy 78.878728 -286.196946)
			(xy 78.908293 -286.23629) (xy 78.931164 -286.279867) (xy 78.946748 -286.326548) (xy 78.954643 -286.375125)
			(xy 78.955138 -286.399732) (xy 78.954643 -286.424339) (xy 78.954464 -286.42544) (xy 79.273142 -286.42544)
			(xy 79.273142 -286.374024) (xy 79.281185 -286.323242) (xy 79.297073 -286.274343) (xy 79.320416 -286.228531)
			(xy 79.350637 -286.186935) (xy 79.386993 -286.150579) (xy 79.428589 -286.120358) (xy 79.474401 -286.097015)
			(xy 79.5233 -286.081127) (xy 79.574082 -286.073084) (xy 79.625498 -286.073084) (xy 79.67628 -286.081127)
			(xy 79.725179 -286.097015) (xy 79.770991 -286.120358) (xy 79.812587 -286.150579) (xy 79.848943 -286.186935)
			(xy 79.879164 -286.228531) (xy 79.902507 -286.274343) (xy 79.918395 -286.323242) (xy 79.926438 -286.374024)
			(xy 79.926942 -286.399732) (xy 79.926438 -286.42544) (xy 80.223102 -286.42544) (xy 80.223102 -286.374024)
			(xy 80.231145 -286.323242) (xy 80.247033 -286.274343) (xy 80.270376 -286.228531) (xy 80.300597 -286.186935)
			(xy 80.336953 -286.150579) (xy 80.378549 -286.120358) (xy 80.424361 -286.097015) (xy 80.47326 -286.081127)
			(xy 80.524042 -286.073084) (xy 80.575458 -286.073084) (xy 80.62624 -286.081127) (xy 80.675139 -286.097015)
			(xy 80.720951 -286.120358) (xy 80.762547 -286.150579) (xy 80.798903 -286.186935) (xy 80.829124 -286.228531)
			(xy 80.852467 -286.274343) (xy 80.868355 -286.323242) (xy 80.876398 -286.374024) (xy 80.876902 -286.399732)
			(xy 81.19416 -286.399732) (xy 81.19812 -286.350678) (xy 81.209897 -286.302894) (xy 81.229188 -286.257618)
			(xy 81.255491 -286.216022) (xy 81.288126 -286.179185) (xy 81.326247 -286.14806) (xy 81.368868 -286.123453)
			(xy 81.414884 -286.106001) (xy 81.463103 -286.096157) (xy 81.512278 -286.094176) (xy 81.561133 -286.100108)
			(xy 81.608404 -286.1138) (xy 81.652866 -286.134898) (xy 81.693369 -286.162854) (xy 81.728862 -286.196946)
			(xy 81.758427 -286.23629) (xy 81.781298 -286.279867) (xy 81.796882 -286.326548) (xy 81.804777 -286.375125)
			(xy 81.805272 -286.399732) (xy 82.14412 -286.399732) (xy 82.14808 -286.350678) (xy 82.159857 -286.302894)
			(xy 82.179148 -286.257618) (xy 82.205451 -286.216022) (xy 82.238086 -286.179185) (xy 82.276207 -286.14806)
			(xy 82.318828 -286.123453) (xy 82.364844 -286.106001) (xy 82.413063 -286.096157) (xy 82.462238 -286.094176)
			(xy 82.511093 -286.100108) (xy 82.558364 -286.1138) (xy 82.602826 -286.134898) (xy 82.643329 -286.162854)
			(xy 82.678822 -286.196946) (xy 82.708387 -286.23629) (xy 82.731258 -286.279867) (xy 82.746842 -286.326548)
			(xy 82.754737 -286.375125) (xy 82.755232 -286.399732) (xy 82.754737 -286.424339) (xy 82.746842 -286.472916)
			(xy 82.731258 -286.519597) (xy 82.708387 -286.563174) (xy 82.678822 -286.602518) (xy 82.643329 -286.63661)
			(xy 82.602826 -286.664566) (xy 82.558364 -286.685664) (xy 82.511093 -286.699356) (xy 82.462238 -286.705288)
			(xy 82.413063 -286.703307) (xy 82.364844 -286.693463) (xy 82.318828 -286.676011) (xy 82.276207 -286.651404)
			(xy 82.238086 -286.620279) (xy 82.205451 -286.583442) (xy 82.179148 -286.541846) (xy 82.159857 -286.49657)
			(xy 82.14808 -286.448786) (xy 82.14412 -286.399732) (xy 81.805272 -286.399732) (xy 81.804777 -286.424339)
			(xy 81.796882 -286.472916) (xy 81.781298 -286.519597) (xy 81.758427 -286.563174) (xy 81.728862 -286.602518)
			(xy 81.693369 -286.63661) (xy 81.652866 -286.664566) (xy 81.608404 -286.685664) (xy 81.561133 -286.699356)
			(xy 81.512278 -286.705288) (xy 81.463103 -286.703307) (xy 81.414884 -286.693463) (xy 81.368868 -286.676011)
			(xy 81.326247 -286.651404) (xy 81.288126 -286.620279) (xy 81.255491 -286.583442) (xy 81.229188 -286.541846)
			(xy 81.209897 -286.49657) (xy 81.19812 -286.448786) (xy 81.19416 -286.399732) (xy 80.876902 -286.399732)
			(xy 80.876398 -286.42544) (xy 80.868355 -286.476222) (xy 80.852467 -286.525121) (xy 80.829124 -286.570933)
			(xy 80.798903 -286.612529) (xy 80.762547 -286.648885) (xy 80.720951 -286.679106) (xy 80.675139 -286.702449)
			(xy 80.62624 -286.718337) (xy 80.575458 -286.72638) (xy 80.524042 -286.72638) (xy 80.47326 -286.718337)
			(xy 80.424361 -286.702449) (xy 80.378549 -286.679106) (xy 80.336953 -286.648885) (xy 80.300597 -286.612529)
			(xy 80.270376 -286.570933) (xy 80.247033 -286.525121) (xy 80.231145 -286.476222) (xy 80.223102 -286.42544)
			(xy 79.926438 -286.42544) (xy 79.918395 -286.476222) (xy 79.902507 -286.525121) (xy 79.879164 -286.570933)
			(xy 79.848943 -286.612529) (xy 79.812587 -286.648885) (xy 79.770991 -286.679106) (xy 79.725179 -286.702449)
			(xy 79.67628 -286.718337) (xy 79.625498 -286.72638) (xy 79.574082 -286.72638) (xy 79.5233 -286.718337)
			(xy 79.474401 -286.702449) (xy 79.428589 -286.679106) (xy 79.386993 -286.648885) (xy 79.350637 -286.612529)
			(xy 79.320416 -286.570933) (xy 79.297073 -286.525121) (xy 79.281185 -286.476222) (xy 79.273142 -286.42544)
			(xy 78.954464 -286.42544) (xy 78.946748 -286.472916) (xy 78.931164 -286.519597) (xy 78.908293 -286.563174)
			(xy 78.878728 -286.602518) (xy 78.843235 -286.63661) (xy 78.802732 -286.664566) (xy 78.75827 -286.685664)
			(xy 78.710999 -286.699356) (xy 78.662144 -286.705288) (xy 78.612969 -286.703307) (xy 78.56475 -286.693463)
			(xy 78.518734 -286.676011) (xy 78.476113 -286.651404) (xy 78.437992 -286.620279) (xy 78.405357 -286.583442)
			(xy 78.379054 -286.541846) (xy 78.359763 -286.49657) (xy 78.347986 -286.448786) (xy 78.344026 -286.399732)
			(xy 78.005173 -286.399732) (xy 78.005178 -286.399986) (xy 78.004683 -286.424593) (xy 77.996788 -286.47317)
			(xy 77.981204 -286.519851) (xy 77.958333 -286.563428) (xy 77.928768 -286.602772) (xy 77.893275 -286.636864)
			(xy 77.852772 -286.66482) (xy 77.80831 -286.685918) (xy 77.761039 -286.69961) (xy 77.712184 -286.705542)
			(xy 77.663009 -286.703561) (xy 77.61479 -286.693717) (xy 77.568774 -286.676265) (xy 77.526153 -286.651658)
			(xy 77.488032 -286.620533) (xy 77.455397 -286.583696) (xy 77.429094 -286.5421) (xy 77.409803 -286.496824)
			(xy 77.398026 -286.44904) (xy 77.394066 -286.399986) (xy 77.055218 -286.399986) (xy 77.054723 -286.424593)
			(xy 77.046828 -286.47317) (xy 77.031244 -286.519851) (xy 77.008373 -286.563428) (xy 76.978808 -286.602772)
			(xy 76.943315 -286.636864) (xy 76.902812 -286.66482) (xy 76.85835 -286.685918) (xy 76.811079 -286.69961)
			(xy 76.762224 -286.705542) (xy 76.713049 -286.703561) (xy 76.66483 -286.693717) (xy 76.618814 -286.676265)
			(xy 76.576193 -286.651658) (xy 76.538072 -286.620533) (xy 76.505437 -286.583696) (xy 76.479134 -286.5421)
			(xy 76.459843 -286.496824) (xy 76.448066 -286.44904) (xy 76.444106 -286.399986) (xy 76.105253 -286.399986)
			(xy 76.104763 -286.424339) (xy 76.096868 -286.472916) (xy 76.081284 -286.519597) (xy 76.058413 -286.563174)
			(xy 76.028848 -286.602518) (xy 75.993355 -286.63661) (xy 75.952852 -286.664566) (xy 75.90839 -286.685664)
			(xy 75.861119 -286.699356) (xy 75.812264 -286.705288) (xy 75.763089 -286.703307) (xy 75.71487 -286.693463)
			(xy 75.668854 -286.676011) (xy 75.626233 -286.651404) (xy 75.588112 -286.620279) (xy 75.555477 -286.583442)
			(xy 75.529174 -286.541846) (xy 75.509883 -286.49657) (xy 75.498106 -286.448786) (xy 75.494146 -286.399732)
			(xy 75.155298 -286.399732) (xy 75.154803 -286.424339) (xy 75.146908 -286.472916) (xy 75.131324 -286.519597)
			(xy 75.108453 -286.563174) (xy 75.078888 -286.602518) (xy 75.043395 -286.63661) (xy 75.002892 -286.664566)
			(xy 74.95843 -286.685664) (xy 74.911159 -286.699356) (xy 74.862304 -286.705288) (xy 74.813129 -286.703307)
			(xy 74.76491 -286.693463) (xy 74.718894 -286.676011) (xy 74.676273 -286.651404) (xy 74.638152 -286.620279)
			(xy 74.605517 -286.583442) (xy 74.579214 -286.541846) (xy 74.559923 -286.49657) (xy 74.548146 -286.448786)
			(xy 74.544186 -286.399732) (xy 74.205084 -286.399732) (xy 74.204589 -286.424339) (xy 74.196694 -286.472916)
			(xy 74.18111 -286.519597) (xy 74.158239 -286.563174) (xy 74.128674 -286.602518) (xy 74.093181 -286.63661)
			(xy 74.052678 -286.664566) (xy 74.008216 -286.685664) (xy 73.960945 -286.699356) (xy 73.91209 -286.705288)
			(xy 73.862915 -286.703307) (xy 73.814696 -286.693463) (xy 73.76868 -286.676011) (xy 73.726059 -286.651404)
			(xy 73.687938 -286.620279) (xy 73.655303 -286.583442) (xy 73.629 -286.541846) (xy 73.609709 -286.49657)
			(xy 73.597932 -286.448786) (xy 73.593972 -286.399732) (xy 48.06823 -286.399732) (xy 48.06823 -286.783526)
			(xy 48.070008 -286.796734) (xy 48.07077 -286.799782) (xy 48.075167 -286.818266) (xy 48.079877 -286.855968)
			(xy 48.080168 -286.874966) (xy 48.419016 -286.874966) (xy 48.422976 -286.825912) (xy 48.434753 -286.778128)
			(xy 48.454044 -286.732852) (xy 48.480347 -286.691256) (xy 48.512982 -286.654419) (xy 48.551103 -286.623294)
			(xy 48.593724 -286.598687) (xy 48.63974 -286.581235) (xy 48.687959 -286.571391) (xy 48.737134 -286.56941)
			(xy 48.785989 -286.575342) (xy 48.83326 -286.589034) (xy 48.877722 -286.610132) (xy 48.918225 -286.638088)
			(xy 48.953718 -286.67218) (xy 48.983283 -286.711524) (xy 49.006154 -286.755101) (xy 49.021738 -286.801782)
			(xy 49.029633 -286.850359) (xy 49.030128 -286.874966) (xy 49.368976 -286.874966) (xy 49.372936 -286.825912)
			(xy 49.384713 -286.778128) (xy 49.404004 -286.732852) (xy 49.430307 -286.691256) (xy 49.462942 -286.654419)
			(xy 49.501063 -286.623294) (xy 49.543684 -286.598687) (xy 49.5897 -286.581235) (xy 49.637919 -286.571391)
			(xy 49.687094 -286.56941) (xy 49.735949 -286.575342) (xy 49.78322 -286.589034) (xy 49.827682 -286.610132)
			(xy 49.868185 -286.638088) (xy 49.903678 -286.67218) (xy 49.933243 -286.711524) (xy 49.956114 -286.755101)
			(xy 49.971698 -286.801782) (xy 49.979593 -286.850359) (xy 49.980088 -286.874966) (xy 50.31919 -286.874966)
			(xy 50.32315 -286.825912) (xy 50.334927 -286.778128) (xy 50.354218 -286.732852) (xy 50.380521 -286.691256)
			(xy 50.413156 -286.654419) (xy 50.451277 -286.623294) (xy 50.493898 -286.598687) (xy 50.539914 -286.581235)
			(xy 50.588133 -286.571391) (xy 50.637308 -286.56941) (xy 50.686163 -286.575342) (xy 50.733434 -286.589034)
			(xy 50.777896 -286.610132) (xy 50.818399 -286.638088) (xy 50.853892 -286.67218) (xy 50.883457 -286.711524)
			(xy 50.906328 -286.755101) (xy 50.921912 -286.801782) (xy 50.929807 -286.850359) (xy 50.930302 -286.874966)
			(xy 51.26915 -286.874966) (xy 51.27311 -286.825912) (xy 51.284887 -286.778128) (xy 51.304178 -286.732852)
			(xy 51.330481 -286.691256) (xy 51.363116 -286.654419) (xy 51.401237 -286.623294) (xy 51.443858 -286.598687)
			(xy 51.489874 -286.581235) (xy 51.538093 -286.571391) (xy 51.587268 -286.56941) (xy 51.636123 -286.575342)
			(xy 51.683394 -286.589034) (xy 51.727856 -286.610132) (xy 51.768359 -286.638088) (xy 51.803852 -286.67218)
			(xy 51.833417 -286.711524) (xy 51.856288 -286.755101) (xy 51.871872 -286.801782) (xy 51.879767 -286.850359)
			(xy 51.880262 -286.874966) (xy 52.21911 -286.874966) (xy 52.22307 -286.825912) (xy 52.234847 -286.778128)
			(xy 52.254138 -286.732852) (xy 52.280441 -286.691256) (xy 52.313076 -286.654419) (xy 52.351197 -286.623294)
			(xy 52.393818 -286.598687) (xy 52.439834 -286.581235) (xy 52.488053 -286.571391) (xy 52.537228 -286.56941)
			(xy 52.586083 -286.575342) (xy 52.633354 -286.589034) (xy 52.677816 -286.610132) (xy 52.718319 -286.638088)
			(xy 52.753812 -286.67218) (xy 52.783377 -286.711524) (xy 52.806248 -286.755101) (xy 52.821832 -286.801782)
			(xy 52.829727 -286.850359) (xy 52.830222 -286.874966) (xy 53.16907 -286.874966) (xy 53.17303 -286.825912)
			(xy 53.184807 -286.778128) (xy 53.204098 -286.732852) (xy 53.230401 -286.691256) (xy 53.263036 -286.654419)
			(xy 53.301157 -286.623294) (xy 53.343778 -286.598687) (xy 53.389794 -286.581235) (xy 53.438013 -286.571391)
			(xy 53.487188 -286.56941) (xy 53.536043 -286.575342) (xy 53.583314 -286.589034) (xy 53.627776 -286.610132)
			(xy 53.668279 -286.638088) (xy 53.703772 -286.67218) (xy 53.733337 -286.711524) (xy 53.756208 -286.755101)
			(xy 53.771792 -286.801782) (xy 53.779687 -286.850359) (xy 53.780182 -286.874966) (xy 54.11903 -286.874966)
			(xy 54.12299 -286.825912) (xy 54.134767 -286.778128) (xy 54.154058 -286.732852) (xy 54.180361 -286.691256)
			(xy 54.212996 -286.654419) (xy 54.251117 -286.623294) (xy 54.293738 -286.598687) (xy 54.339754 -286.581235)
			(xy 54.387973 -286.571391) (xy 54.437148 -286.56941) (xy 54.486003 -286.575342) (xy 54.533274 -286.589034)
			(xy 54.577736 -286.610132) (xy 54.618239 -286.638088) (xy 54.653732 -286.67218) (xy 54.683297 -286.711524)
			(xy 54.706168 -286.755101) (xy 54.721752 -286.801782) (xy 54.729647 -286.850359) (xy 54.730142 -286.874966)
			(xy 55.06899 -286.874966) (xy 55.07295 -286.825912) (xy 55.084727 -286.778128) (xy 55.104018 -286.732852)
			(xy 55.130321 -286.691256) (xy 55.162956 -286.654419) (xy 55.201077 -286.623294) (xy 55.243698 -286.598687)
			(xy 55.289714 -286.581235) (xy 55.337933 -286.571391) (xy 55.387108 -286.56941) (xy 55.435963 -286.575342)
			(xy 55.483234 -286.589034) (xy 55.527696 -286.610132) (xy 55.568199 -286.638088) (xy 55.603692 -286.67218)
			(xy 55.633257 -286.711524) (xy 55.656128 -286.755101) (xy 55.671712 -286.801782) (xy 55.679607 -286.850359)
			(xy 55.680102 -286.874966) (xy 56.01895 -286.874966) (xy 56.02291 -286.825912) (xy 56.034687 -286.778128)
			(xy 56.053978 -286.732852) (xy 56.080281 -286.691256) (xy 56.112916 -286.654419) (xy 56.151037 -286.623294)
			(xy 56.193658 -286.598687) (xy 56.239674 -286.581235) (xy 56.287893 -286.571391) (xy 56.337068 -286.56941)
			(xy 56.385923 -286.575342) (xy 56.433194 -286.589034) (xy 56.477656 -286.610132) (xy 56.518159 -286.638088)
			(xy 56.553652 -286.67218) (xy 56.583217 -286.711524) (xy 56.606088 -286.755101) (xy 56.621672 -286.801782)
			(xy 56.629567 -286.850359) (xy 56.630062 -286.874966) (xy 56.969164 -286.874966) (xy 56.973124 -286.825912)
			(xy 56.984901 -286.778128) (xy 57.004192 -286.732852) (xy 57.030495 -286.691256) (xy 57.06313 -286.654419)
			(xy 57.101251 -286.623294) (xy 57.143872 -286.598687) (xy 57.189888 -286.581235) (xy 57.238107 -286.571391)
			(xy 57.287282 -286.56941) (xy 57.336137 -286.575342) (xy 57.383408 -286.589034) (xy 57.42787 -286.610132)
			(xy 57.468373 -286.638088) (xy 57.503866 -286.67218) (xy 57.533431 -286.711524) (xy 57.556302 -286.755101)
			(xy 57.571886 -286.801782) (xy 57.579781 -286.850359) (xy 57.580276 -286.874966) (xy 57.919124 -286.874966)
			(xy 57.923084 -286.825912) (xy 57.934861 -286.778128) (xy 57.954152 -286.732852) (xy 57.980455 -286.691256)
			(xy 58.01309 -286.654419) (xy 58.051211 -286.623294) (xy 58.093832 -286.598687) (xy 58.139848 -286.581235)
			(xy 58.188067 -286.571391) (xy 58.237242 -286.56941) (xy 58.286097 -286.575342) (xy 58.333368 -286.589034)
			(xy 58.37783 -286.610132) (xy 58.418333 -286.638088) (xy 58.453826 -286.67218) (xy 58.483391 -286.711524)
			(xy 58.506262 -286.755101) (xy 58.521846 -286.801782) (xy 58.529741 -286.850359) (xy 58.530236 -286.874966)
			(xy 59.819044 -286.874966) (xy 59.823004 -286.825912) (xy 59.834781 -286.778128) (xy 59.854072 -286.732852)
			(xy 59.880375 -286.691256) (xy 59.91301 -286.654419) (xy 59.951131 -286.623294) (xy 59.993752 -286.598687)
			(xy 60.039768 -286.581235) (xy 60.087987 -286.571391) (xy 60.137162 -286.56941) (xy 60.186017 -286.575342)
			(xy 60.233288 -286.589034) (xy 60.27775 -286.610132) (xy 60.318253 -286.638088) (xy 60.353746 -286.67218)
			(xy 60.383311 -286.711524) (xy 60.406182 -286.755101) (xy 60.421766 -286.801782) (xy 60.429661 -286.850359)
			(xy 60.430156 -286.874966) (xy 60.769004 -286.874966) (xy 60.772964 -286.825912) (xy 60.784741 -286.778128)
			(xy 60.804032 -286.732852) (xy 60.830335 -286.691256) (xy 60.86297 -286.654419) (xy 60.901091 -286.623294)
			(xy 60.943712 -286.598687) (xy 60.989728 -286.581235) (xy 61.037947 -286.571391) (xy 61.087122 -286.56941)
			(xy 61.135977 -286.575342) (xy 61.183248 -286.589034) (xy 61.22771 -286.610132) (xy 61.268213 -286.638088)
			(xy 61.303706 -286.67218) (xy 61.333271 -286.711524) (xy 61.356142 -286.755101) (xy 61.371726 -286.801782)
			(xy 61.379621 -286.850359) (xy 61.380116 -286.874966) (xy 61.718964 -286.874966) (xy 61.722924 -286.825912)
			(xy 61.734701 -286.778128) (xy 61.753992 -286.732852) (xy 61.780295 -286.691256) (xy 61.81293 -286.654419)
			(xy 61.851051 -286.623294) (xy 61.893672 -286.598687) (xy 61.939688 -286.581235) (xy 61.987907 -286.571391)
			(xy 62.037082 -286.56941) (xy 62.085937 -286.575342) (xy 62.133208 -286.589034) (xy 62.17767 -286.610132)
			(xy 62.218173 -286.638088) (xy 62.253666 -286.67218) (xy 62.283231 -286.711524) (xy 62.306102 -286.755101)
			(xy 62.321686 -286.801782) (xy 62.329581 -286.850359) (xy 62.330076 -286.874966) (xy 62.669178 -286.874966)
			(xy 62.673138 -286.825912) (xy 62.684915 -286.778128) (xy 62.704206 -286.732852) (xy 62.730509 -286.691256)
			(xy 62.763144 -286.654419) (xy 62.801265 -286.623294) (xy 62.843886 -286.598687) (xy 62.889902 -286.581235)
			(xy 62.938121 -286.571391) (xy 62.987296 -286.56941) (xy 63.036151 -286.575342) (xy 63.083422 -286.589034)
			(xy 63.127884 -286.610132) (xy 63.168387 -286.638088) (xy 63.20388 -286.67218) (xy 63.233445 -286.711524)
			(xy 63.256316 -286.755101) (xy 63.2719 -286.801782) (xy 63.279795 -286.850359) (xy 63.28029 -286.874966)
			(xy 63.619138 -286.874966) (xy 63.623098 -286.825912) (xy 63.634875 -286.778128) (xy 63.654166 -286.732852)
			(xy 63.680469 -286.691256) (xy 63.713104 -286.654419) (xy 63.751225 -286.623294) (xy 63.793846 -286.598687)
			(xy 63.839862 -286.581235) (xy 63.888081 -286.571391) (xy 63.937256 -286.56941) (xy 63.986111 -286.575342)
			(xy 64.033382 -286.589034) (xy 64.077844 -286.610132) (xy 64.118347 -286.638088) (xy 64.15384 -286.67218)
			(xy 64.183405 -286.711524) (xy 64.206276 -286.755101) (xy 64.22186 -286.801782) (xy 64.229755 -286.850359)
			(xy 64.23025 -286.874966) (xy 64.569098 -286.874966) (xy 64.573058 -286.825912) (xy 64.584835 -286.778128)
			(xy 64.604126 -286.732852) (xy 64.630429 -286.691256) (xy 64.663064 -286.654419) (xy 64.701185 -286.623294)
			(xy 64.743806 -286.598687) (xy 64.789822 -286.581235) (xy 64.838041 -286.571391) (xy 64.887216 -286.56941)
			(xy 64.936071 -286.575342) (xy 64.983342 -286.589034) (xy 65.027804 -286.610132) (xy 65.068307 -286.638088)
			(xy 65.1038 -286.67218) (xy 65.133365 -286.711524) (xy 65.156236 -286.755101) (xy 65.17182 -286.801782)
			(xy 65.179715 -286.850359) (xy 65.18021 -286.874966) (xy 65.519058 -286.874966) (xy 65.523018 -286.825912)
			(xy 65.534795 -286.778128) (xy 65.554086 -286.732852) (xy 65.580389 -286.691256) (xy 65.613024 -286.654419)
			(xy 65.651145 -286.623294) (xy 65.693766 -286.598687) (xy 65.739782 -286.581235) (xy 65.788001 -286.571391)
			(xy 65.837176 -286.56941) (xy 65.886031 -286.575342) (xy 65.933302 -286.589034) (xy 65.977764 -286.610132)
			(xy 66.018267 -286.638088) (xy 66.05376 -286.67218) (xy 66.083325 -286.711524) (xy 66.106196 -286.755101)
			(xy 66.12178 -286.801782) (xy 66.129675 -286.850359) (xy 66.13017 -286.874966) (xy 66.469018 -286.874966)
			(xy 66.472978 -286.825912) (xy 66.484755 -286.778128) (xy 66.504046 -286.732852) (xy 66.530349 -286.691256)
			(xy 66.562984 -286.654419) (xy 66.601105 -286.623294) (xy 66.643726 -286.598687) (xy 66.689742 -286.581235)
			(xy 66.737961 -286.571391) (xy 66.787136 -286.56941) (xy 66.835991 -286.575342) (xy 66.883262 -286.589034)
			(xy 66.927724 -286.610132) (xy 66.968227 -286.638088) (xy 67.00372 -286.67218) (xy 67.033285 -286.711524)
			(xy 67.056156 -286.755101) (xy 67.07174 -286.801782) (xy 67.079635 -286.850359) (xy 67.08013 -286.874966)
			(xy 67.418978 -286.874966) (xy 67.422938 -286.825912) (xy 67.434715 -286.778128) (xy 67.454006 -286.732852)
			(xy 67.480309 -286.691256) (xy 67.512944 -286.654419) (xy 67.551065 -286.623294) (xy 67.593686 -286.598687)
			(xy 67.639702 -286.581235) (xy 67.687921 -286.571391) (xy 67.737096 -286.56941) (xy 67.785951 -286.575342)
			(xy 67.833222 -286.589034) (xy 67.877684 -286.610132) (xy 67.918187 -286.638088) (xy 67.95368 -286.67218)
			(xy 67.983245 -286.711524) (xy 68.006116 -286.755101) (xy 68.0217 -286.801782) (xy 68.029595 -286.850359)
			(xy 68.03009 -286.874966) (xy 68.368938 -286.874966) (xy 68.372898 -286.825912) (xy 68.384675 -286.778128)
			(xy 68.403966 -286.732852) (xy 68.430269 -286.691256) (xy 68.462904 -286.654419) (xy 68.501025 -286.623294)
			(xy 68.543646 -286.598687) (xy 68.589662 -286.581235) (xy 68.637881 -286.571391) (xy 68.687056 -286.56941)
			(xy 68.735911 -286.575342) (xy 68.783182 -286.589034) (xy 68.827644 -286.610132) (xy 68.868147 -286.638088)
			(xy 68.90364 -286.67218) (xy 68.933205 -286.711524) (xy 68.956076 -286.755101) (xy 68.97166 -286.801782)
			(xy 68.979555 -286.850359) (xy 68.98005 -286.874966) (xy 69.319152 -286.874966) (xy 69.323112 -286.825912)
			(xy 69.334889 -286.778128) (xy 69.35418 -286.732852) (xy 69.380483 -286.691256) (xy 69.413118 -286.654419)
			(xy 69.451239 -286.623294) (xy 69.49386 -286.598687) (xy 69.539876 -286.581235) (xy 69.588095 -286.571391)
			(xy 69.63727 -286.56941) (xy 69.686125 -286.575342) (xy 69.733396 -286.589034) (xy 69.777858 -286.610132)
			(xy 69.818361 -286.638088) (xy 69.853854 -286.67218) (xy 69.883419 -286.711524) (xy 69.90629 -286.755101)
			(xy 69.921874 -286.801782) (xy 69.929769 -286.850359) (xy 69.930264 -286.874966) (xy 70.269112 -286.874966)
			(xy 70.273072 -286.825912) (xy 70.284849 -286.778128) (xy 70.30414 -286.732852) (xy 70.330443 -286.691256)
			(xy 70.363078 -286.654419) (xy 70.401199 -286.623294) (xy 70.44382 -286.598687) (xy 70.489836 -286.581235)
			(xy 70.538055 -286.571391) (xy 70.58723 -286.56941) (xy 70.636085 -286.575342) (xy 70.683356 -286.589034)
			(xy 70.727818 -286.610132) (xy 70.768321 -286.638088) (xy 70.803814 -286.67218) (xy 70.833379 -286.711524)
			(xy 70.85625 -286.755101) (xy 70.871834 -286.801782) (xy 70.879729 -286.850359) (xy 70.880224 -286.874966)
			(xy 70.879729 -286.899573) (xy 70.871834 -286.94815) (xy 70.85625 -286.994831) (xy 70.833379 -287.038408)
			(xy 70.803814 -287.077752) (xy 70.768321 -287.111844) (xy 70.727818 -287.1398) (xy 70.683356 -287.160898)
			(xy 70.636085 -287.17459) (xy 70.58723 -287.180522) (xy 70.538055 -287.178541) (xy 70.489836 -287.168697)
			(xy 70.44382 -287.151245) (xy 70.401199 -287.126638) (xy 70.363078 -287.095513) (xy 70.330443 -287.058676)
			(xy 70.30414 -287.01708) (xy 70.284849 -286.971804) (xy 70.273072 -286.92402) (xy 70.269112 -286.874966)
			(xy 69.930264 -286.874966) (xy 69.929769 -286.899573) (xy 69.921874 -286.94815) (xy 69.90629 -286.994831)
			(xy 69.883419 -287.038408) (xy 69.853854 -287.077752) (xy 69.818361 -287.111844) (xy 69.777858 -287.1398)
			(xy 69.733396 -287.160898) (xy 69.686125 -287.17459) (xy 69.63727 -287.180522) (xy 69.588095 -287.178541)
			(xy 69.539876 -287.168697) (xy 69.49386 -287.151245) (xy 69.451239 -287.126638) (xy 69.413118 -287.095513)
			(xy 69.380483 -287.058676) (xy 69.35418 -287.01708) (xy 69.334889 -286.971804) (xy 69.323112 -286.92402)
			(xy 69.319152 -286.874966) (xy 68.98005 -286.874966) (xy 68.979555 -286.899573) (xy 68.97166 -286.94815)
			(xy 68.956076 -286.994831) (xy 68.933205 -287.038408) (xy 68.90364 -287.077752) (xy 68.868147 -287.111844)
			(xy 68.827644 -287.1398) (xy 68.783182 -287.160898) (xy 68.735911 -287.17459) (xy 68.687056 -287.180522)
			(xy 68.637881 -287.178541) (xy 68.589662 -287.168697) (xy 68.543646 -287.151245) (xy 68.501025 -287.126638)
			(xy 68.462904 -287.095513) (xy 68.430269 -287.058676) (xy 68.403966 -287.01708) (xy 68.384675 -286.971804)
			(xy 68.372898 -286.92402) (xy 68.368938 -286.874966) (xy 68.03009 -286.874966) (xy 68.029595 -286.899573)
			(xy 68.0217 -286.94815) (xy 68.006116 -286.994831) (xy 67.983245 -287.038408) (xy 67.95368 -287.077752)
			(xy 67.918187 -287.111844) (xy 67.877684 -287.1398) (xy 67.833222 -287.160898) (xy 67.785951 -287.17459)
			(xy 67.737096 -287.180522) (xy 67.687921 -287.178541) (xy 67.639702 -287.168697) (xy 67.593686 -287.151245)
			(xy 67.551065 -287.126638) (xy 67.512944 -287.095513) (xy 67.480309 -287.058676) (xy 67.454006 -287.01708)
			(xy 67.434715 -286.971804) (xy 67.422938 -286.92402) (xy 67.418978 -286.874966) (xy 67.08013 -286.874966)
			(xy 67.079635 -286.899573) (xy 67.07174 -286.94815) (xy 67.056156 -286.994831) (xy 67.033285 -287.038408)
			(xy 67.00372 -287.077752) (xy 66.968227 -287.111844) (xy 66.927724 -287.1398) (xy 66.883262 -287.160898)
			(xy 66.835991 -287.17459) (xy 66.787136 -287.180522) (xy 66.737961 -287.178541) (xy 66.689742 -287.168697)
			(xy 66.643726 -287.151245) (xy 66.601105 -287.126638) (xy 66.562984 -287.095513) (xy 66.530349 -287.058676)
			(xy 66.504046 -287.01708) (xy 66.484755 -286.971804) (xy 66.472978 -286.92402) (xy 66.469018 -286.874966)
			(xy 66.13017 -286.874966) (xy 66.129675 -286.899573) (xy 66.12178 -286.94815) (xy 66.106196 -286.994831)
			(xy 66.083325 -287.038408) (xy 66.05376 -287.077752) (xy 66.018267 -287.111844) (xy 65.977764 -287.1398)
			(xy 65.933302 -287.160898) (xy 65.886031 -287.17459) (xy 65.837176 -287.180522) (xy 65.788001 -287.178541)
			(xy 65.739782 -287.168697) (xy 65.693766 -287.151245) (xy 65.651145 -287.126638) (xy 65.613024 -287.095513)
			(xy 65.580389 -287.058676) (xy 65.554086 -287.01708) (xy 65.534795 -286.971804) (xy 65.523018 -286.92402)
			(xy 65.519058 -286.874966) (xy 65.18021 -286.874966) (xy 65.179715 -286.899573) (xy 65.17182 -286.94815)
			(xy 65.156236 -286.994831) (xy 65.133365 -287.038408) (xy 65.1038 -287.077752) (xy 65.068307 -287.111844)
			(xy 65.027804 -287.1398) (xy 64.983342 -287.160898) (xy 64.936071 -287.17459) (xy 64.887216 -287.180522)
			(xy 64.838041 -287.178541) (xy 64.789822 -287.168697) (xy 64.743806 -287.151245) (xy 64.701185 -287.126638)
			(xy 64.663064 -287.095513) (xy 64.630429 -287.058676) (xy 64.604126 -287.01708) (xy 64.584835 -286.971804)
			(xy 64.573058 -286.92402) (xy 64.569098 -286.874966) (xy 64.23025 -286.874966) (xy 64.229755 -286.899573)
			(xy 64.22186 -286.94815) (xy 64.206276 -286.994831) (xy 64.183405 -287.038408) (xy 64.15384 -287.077752)
			(xy 64.118347 -287.111844) (xy 64.077844 -287.1398) (xy 64.033382 -287.160898) (xy 63.986111 -287.17459)
			(xy 63.937256 -287.180522) (xy 63.888081 -287.178541) (xy 63.839862 -287.168697) (xy 63.793846 -287.151245)
			(xy 63.751225 -287.126638) (xy 63.713104 -287.095513) (xy 63.680469 -287.058676) (xy 63.654166 -287.01708)
			(xy 63.634875 -286.971804) (xy 63.623098 -286.92402) (xy 63.619138 -286.874966) (xy 63.28029 -286.874966)
			(xy 63.279795 -286.899573) (xy 63.2719 -286.94815) (xy 63.256316 -286.994831) (xy 63.233445 -287.038408)
			(xy 63.20388 -287.077752) (xy 63.168387 -287.111844) (xy 63.127884 -287.1398) (xy 63.083422 -287.160898)
			(xy 63.036151 -287.17459) (xy 62.987296 -287.180522) (xy 62.938121 -287.178541) (xy 62.889902 -287.168697)
			(xy 62.843886 -287.151245) (xy 62.801265 -287.126638) (xy 62.763144 -287.095513) (xy 62.730509 -287.058676)
			(xy 62.704206 -287.01708) (xy 62.684915 -286.971804) (xy 62.673138 -286.92402) (xy 62.669178 -286.874966)
			(xy 62.330076 -286.874966) (xy 62.329581 -286.899573) (xy 62.321686 -286.94815) (xy 62.306102 -286.994831)
			(xy 62.283231 -287.038408) (xy 62.253666 -287.077752) (xy 62.218173 -287.111844) (xy 62.17767 -287.1398)
			(xy 62.133208 -287.160898) (xy 62.085937 -287.17459) (xy 62.037082 -287.180522) (xy 61.987907 -287.178541)
			(xy 61.939688 -287.168697) (xy 61.893672 -287.151245) (xy 61.851051 -287.126638) (xy 61.81293 -287.095513)
			(xy 61.780295 -287.058676) (xy 61.753992 -287.01708) (xy 61.734701 -286.971804) (xy 61.722924 -286.92402)
			(xy 61.718964 -286.874966) (xy 61.380116 -286.874966) (xy 61.379621 -286.899573) (xy 61.371726 -286.94815)
			(xy 61.356142 -286.994831) (xy 61.333271 -287.038408) (xy 61.303706 -287.077752) (xy 61.268213 -287.111844)
			(xy 61.22771 -287.1398) (xy 61.183248 -287.160898) (xy 61.135977 -287.17459) (xy 61.087122 -287.180522)
			(xy 61.037947 -287.178541) (xy 60.989728 -287.168697) (xy 60.943712 -287.151245) (xy 60.901091 -287.126638)
			(xy 60.86297 -287.095513) (xy 60.830335 -287.058676) (xy 60.804032 -287.01708) (xy 60.784741 -286.971804)
			(xy 60.772964 -286.92402) (xy 60.769004 -286.874966) (xy 60.430156 -286.874966) (xy 60.429661 -286.899573)
			(xy 60.421766 -286.94815) (xy 60.406182 -286.994831) (xy 60.383311 -287.038408) (xy 60.353746 -287.077752)
			(xy 60.318253 -287.111844) (xy 60.27775 -287.1398) (xy 60.233288 -287.160898) (xy 60.186017 -287.17459)
			(xy 60.137162 -287.180522) (xy 60.087987 -287.178541) (xy 60.039768 -287.168697) (xy 59.993752 -287.151245)
			(xy 59.951131 -287.126638) (xy 59.91301 -287.095513) (xy 59.880375 -287.058676) (xy 59.854072 -287.01708)
			(xy 59.834781 -286.971804) (xy 59.823004 -286.92402) (xy 59.819044 -286.874966) (xy 58.530236 -286.874966)
			(xy 58.529741 -286.899573) (xy 58.521846 -286.94815) (xy 58.506262 -286.994831) (xy 58.483391 -287.038408)
			(xy 58.453826 -287.077752) (xy 58.418333 -287.111844) (xy 58.37783 -287.1398) (xy 58.333368 -287.160898)
			(xy 58.286097 -287.17459) (xy 58.237242 -287.180522) (xy 58.188067 -287.178541) (xy 58.139848 -287.168697)
			(xy 58.093832 -287.151245) (xy 58.051211 -287.126638) (xy 58.01309 -287.095513) (xy 57.980455 -287.058676)
			(xy 57.954152 -287.01708) (xy 57.934861 -286.971804) (xy 57.923084 -286.92402) (xy 57.919124 -286.874966)
			(xy 57.580276 -286.874966) (xy 57.579781 -286.899573) (xy 57.571886 -286.94815) (xy 57.556302 -286.994831)
			(xy 57.533431 -287.038408) (xy 57.503866 -287.077752) (xy 57.468373 -287.111844) (xy 57.42787 -287.1398)
			(xy 57.383408 -287.160898) (xy 57.336137 -287.17459) (xy 57.287282 -287.180522) (xy 57.238107 -287.178541)
			(xy 57.189888 -287.168697) (xy 57.143872 -287.151245) (xy 57.101251 -287.126638) (xy 57.06313 -287.095513)
			(xy 57.030495 -287.058676) (xy 57.004192 -287.01708) (xy 56.984901 -286.971804) (xy 56.973124 -286.92402)
			(xy 56.969164 -286.874966) (xy 56.630062 -286.874966) (xy 56.629567 -286.899573) (xy 56.621672 -286.94815)
			(xy 56.606088 -286.994831) (xy 56.583217 -287.038408) (xy 56.553652 -287.077752) (xy 56.518159 -287.111844)
			(xy 56.477656 -287.1398) (xy 56.433194 -287.160898) (xy 56.385923 -287.17459) (xy 56.337068 -287.180522)
			(xy 56.287893 -287.178541) (xy 56.239674 -287.168697) (xy 56.193658 -287.151245) (xy 56.151037 -287.126638)
			(xy 56.112916 -287.095513) (xy 56.080281 -287.058676) (xy 56.053978 -287.01708) (xy 56.034687 -286.971804)
			(xy 56.02291 -286.92402) (xy 56.01895 -286.874966) (xy 55.680102 -286.874966) (xy 55.679607 -286.899573)
			(xy 55.671712 -286.94815) (xy 55.656128 -286.994831) (xy 55.633257 -287.038408) (xy 55.603692 -287.077752)
			(xy 55.568199 -287.111844) (xy 55.527696 -287.1398) (xy 55.483234 -287.160898) (xy 55.435963 -287.17459)
			(xy 55.387108 -287.180522) (xy 55.337933 -287.178541) (xy 55.289714 -287.168697) (xy 55.243698 -287.151245)
			(xy 55.201077 -287.126638) (xy 55.162956 -287.095513) (xy 55.130321 -287.058676) (xy 55.104018 -287.01708)
			(xy 55.084727 -286.971804) (xy 55.07295 -286.92402) (xy 55.06899 -286.874966) (xy 54.730142 -286.874966)
			(xy 54.729647 -286.899573) (xy 54.721752 -286.94815) (xy 54.706168 -286.994831) (xy 54.683297 -287.038408)
			(xy 54.653732 -287.077752) (xy 54.618239 -287.111844) (xy 54.577736 -287.1398) (xy 54.533274 -287.160898)
			(xy 54.486003 -287.17459) (xy 54.437148 -287.180522) (xy 54.387973 -287.178541) (xy 54.339754 -287.168697)
			(xy 54.293738 -287.151245) (xy 54.251117 -287.126638) (xy 54.212996 -287.095513) (xy 54.180361 -287.058676)
			(xy 54.154058 -287.01708) (xy 54.134767 -286.971804) (xy 54.12299 -286.92402) (xy 54.11903 -286.874966)
			(xy 53.780182 -286.874966) (xy 53.779687 -286.899573) (xy 53.771792 -286.94815) (xy 53.756208 -286.994831)
			(xy 53.733337 -287.038408) (xy 53.703772 -287.077752) (xy 53.668279 -287.111844) (xy 53.627776 -287.1398)
			(xy 53.583314 -287.160898) (xy 53.536043 -287.17459) (xy 53.487188 -287.180522) (xy 53.438013 -287.178541)
			(xy 53.389794 -287.168697) (xy 53.343778 -287.151245) (xy 53.301157 -287.126638) (xy 53.263036 -287.095513)
			(xy 53.230401 -287.058676) (xy 53.204098 -287.01708) (xy 53.184807 -286.971804) (xy 53.17303 -286.92402)
			(xy 53.16907 -286.874966) (xy 52.830222 -286.874966) (xy 52.829727 -286.899573) (xy 52.821832 -286.94815)
			(xy 52.806248 -286.994831) (xy 52.783377 -287.038408) (xy 52.753812 -287.077752) (xy 52.718319 -287.111844)
			(xy 52.677816 -287.1398) (xy 52.633354 -287.160898) (xy 52.586083 -287.17459) (xy 52.537228 -287.180522)
			(xy 52.488053 -287.178541) (xy 52.439834 -287.168697) (xy 52.393818 -287.151245) (xy 52.351197 -287.126638)
			(xy 52.313076 -287.095513) (xy 52.280441 -287.058676) (xy 52.254138 -287.01708) (xy 52.234847 -286.971804)
			(xy 52.22307 -286.92402) (xy 52.21911 -286.874966) (xy 51.880262 -286.874966) (xy 51.879767 -286.899573)
			(xy 51.871872 -286.94815) (xy 51.856288 -286.994831) (xy 51.833417 -287.038408) (xy 51.803852 -287.077752)
			(xy 51.768359 -287.111844) (xy 51.727856 -287.1398) (xy 51.683394 -287.160898) (xy 51.636123 -287.17459)
			(xy 51.587268 -287.180522) (xy 51.538093 -287.178541) (xy 51.489874 -287.168697) (xy 51.443858 -287.151245)
			(xy 51.401237 -287.126638) (xy 51.363116 -287.095513) (xy 51.330481 -287.058676) (xy 51.304178 -287.01708)
			(xy 51.284887 -286.971804) (xy 51.27311 -286.92402) (xy 51.26915 -286.874966) (xy 50.930302 -286.874966)
			(xy 50.929807 -286.899573) (xy 50.921912 -286.94815) (xy 50.906328 -286.994831) (xy 50.883457 -287.038408)
			(xy 50.853892 -287.077752) (xy 50.818399 -287.111844) (xy 50.777896 -287.1398) (xy 50.733434 -287.160898)
			(xy 50.686163 -287.17459) (xy 50.637308 -287.180522) (xy 50.588133 -287.178541) (xy 50.539914 -287.168697)
			(xy 50.493898 -287.151245) (xy 50.451277 -287.126638) (xy 50.413156 -287.095513) (xy 50.380521 -287.058676)
			(xy 50.354218 -287.01708) (xy 50.334927 -286.971804) (xy 50.32315 -286.92402) (xy 50.31919 -286.874966)
			(xy 49.980088 -286.874966) (xy 49.979593 -286.899573) (xy 49.971698 -286.94815) (xy 49.956114 -286.994831)
			(xy 49.933243 -287.038408) (xy 49.903678 -287.077752) (xy 49.868185 -287.111844) (xy 49.827682 -287.1398)
			(xy 49.78322 -287.160898) (xy 49.735949 -287.17459) (xy 49.687094 -287.180522) (xy 49.637919 -287.178541)
			(xy 49.5897 -287.168697) (xy 49.543684 -287.151245) (xy 49.501063 -287.126638) (xy 49.462942 -287.095513)
			(xy 49.430307 -287.058676) (xy 49.404004 -287.01708) (xy 49.384713 -286.971804) (xy 49.372936 -286.92402)
			(xy 49.368976 -286.874966) (xy 49.030128 -286.874966) (xy 49.029633 -286.899573) (xy 49.021738 -286.94815)
			(xy 49.006154 -286.994831) (xy 48.983283 -287.038408) (xy 48.953718 -287.077752) (xy 48.918225 -287.111844)
			(xy 48.877722 -287.1398) (xy 48.83326 -287.160898) (xy 48.785989 -287.17459) (xy 48.737134 -287.180522)
			(xy 48.687959 -287.178541) (xy 48.63974 -287.168697) (xy 48.593724 -287.151245) (xy 48.551103 -287.126638)
			(xy 48.512982 -287.095513) (xy 48.480347 -287.058676) (xy 48.454044 -287.01708) (xy 48.434753 -286.971804)
			(xy 48.422976 -286.92402) (xy 48.419016 -286.874966) (xy 48.080168 -286.874966) (xy 48.079914 -286.88538)
			(xy 48.079914 -286.89173) (xy 48.07966 -286.896302) (xy 48.07966 -286.897064) (xy 48.078434 -286.911465)
			(xy 48.073597 -286.93996) (xy 48.070008 -286.95396) (xy 48.06823 -286.960564) (xy 48.06823 -287.349946)
			(xy 73.593972 -287.349946) (xy 73.597932 -287.300892) (xy 73.609709 -287.253108) (xy 73.629 -287.207832)
			(xy 73.655303 -287.166236) (xy 73.687938 -287.129399) (xy 73.726059 -287.098274) (xy 73.76868 -287.073667)
			(xy 73.814696 -287.056215) (xy 73.862915 -287.046371) (xy 73.91209 -287.04439) (xy 73.960945 -287.050322)
			(xy 74.008216 -287.064014) (xy 74.052678 -287.085112) (xy 74.093181 -287.113068) (xy 74.128674 -287.14716)
			(xy 74.158239 -287.186504) (xy 74.18111 -287.230081) (xy 74.196694 -287.276762) (xy 74.204589 -287.325339)
			(xy 74.205084 -287.349946) (xy 74.543932 -287.349946) (xy 74.547892 -287.300892) (xy 74.559669 -287.253108)
			(xy 74.57896 -287.207832) (xy 74.605263 -287.166236) (xy 74.637898 -287.129399) (xy 74.676019 -287.098274)
			(xy 74.71864 -287.073667) (xy 74.764656 -287.056215) (xy 74.812875 -287.046371) (xy 74.86205 -287.04439)
			(xy 74.910905 -287.050322) (xy 74.958176 -287.064014) (xy 75.002638 -287.085112) (xy 75.043141 -287.113068)
			(xy 75.078634 -287.14716) (xy 75.108199 -287.186504) (xy 75.13107 -287.230081) (xy 75.146654 -287.276762)
			(xy 75.154549 -287.325339) (xy 75.155044 -287.349946) (xy 75.494146 -287.349946) (xy 75.498106 -287.300892)
			(xy 75.509883 -287.253108) (xy 75.529174 -287.207832) (xy 75.555477 -287.166236) (xy 75.588112 -287.129399)
			(xy 75.626233 -287.098274) (xy 75.668854 -287.073667) (xy 75.71487 -287.056215) (xy 75.763089 -287.046371)
			(xy 75.812264 -287.04439) (xy 75.861119 -287.050322) (xy 75.90839 -287.064014) (xy 75.952852 -287.085112)
			(xy 75.993355 -287.113068) (xy 76.028848 -287.14716) (xy 76.058413 -287.186504) (xy 76.081284 -287.230081)
			(xy 76.096868 -287.276762) (xy 76.104763 -287.325339) (xy 76.105258 -287.349946) (xy 76.444106 -287.349946)
			(xy 76.448066 -287.300892) (xy 76.459843 -287.253108) (xy 76.479134 -287.207832) (xy 76.505437 -287.166236)
			(xy 76.538072 -287.129399) (xy 76.576193 -287.098274) (xy 76.618814 -287.073667) (xy 76.66483 -287.056215)
			(xy 76.713049 -287.046371) (xy 76.762224 -287.04439) (xy 76.811079 -287.050322) (xy 76.85835 -287.064014)
			(xy 76.902812 -287.085112) (xy 76.943315 -287.113068) (xy 76.978808 -287.14716) (xy 77.008373 -287.186504)
			(xy 77.031244 -287.230081) (xy 77.046828 -287.276762) (xy 77.054723 -287.325339) (xy 77.055218 -287.349946)
			(xy 77.394066 -287.349946) (xy 77.398026 -287.300892) (xy 77.409803 -287.253108) (xy 77.429094 -287.207832)
			(xy 77.455397 -287.166236) (xy 77.488032 -287.129399) (xy 77.526153 -287.098274) (xy 77.568774 -287.073667)
			(xy 77.61479 -287.056215) (xy 77.663009 -287.046371) (xy 77.712184 -287.04439) (xy 77.761039 -287.050322)
			(xy 77.80831 -287.064014) (xy 77.852772 -287.085112) (xy 77.893275 -287.113068) (xy 77.928768 -287.14716)
			(xy 77.958333 -287.186504) (xy 77.981204 -287.230081) (xy 77.996788 -287.276762) (xy 78.004683 -287.325339)
			(xy 78.005178 -287.349946) (xy 78.344026 -287.349946) (xy 78.347986 -287.300892) (xy 78.359763 -287.253108)
			(xy 78.379054 -287.207832) (xy 78.405357 -287.166236) (xy 78.437992 -287.129399) (xy 78.476113 -287.098274)
			(xy 78.518734 -287.073667) (xy 78.56475 -287.056215) (xy 78.612969 -287.046371) (xy 78.662144 -287.04439)
			(xy 78.710999 -287.050322) (xy 78.75827 -287.064014) (xy 78.802732 -287.085112) (xy 78.843235 -287.113068)
			(xy 78.878728 -287.14716) (xy 78.908293 -287.186504) (xy 78.931164 -287.230081) (xy 78.946748 -287.276762)
			(xy 78.954643 -287.325339) (xy 78.955138 -287.349946) (xy 79.293732 -287.349946) (xy 79.297692 -287.300892)
			(xy 79.309469 -287.253108) (xy 79.32876 -287.207832) (xy 79.355063 -287.166236) (xy 79.387698 -287.129399)
			(xy 79.425819 -287.098274) (xy 79.46844 -287.073667) (xy 79.514456 -287.056215) (xy 79.562675 -287.046371)
			(xy 79.61185 -287.04439) (xy 79.660705 -287.050322) (xy 79.707976 -287.064014) (xy 79.752438 -287.085112)
			(xy 79.792941 -287.113068) (xy 79.828434 -287.14716) (xy 79.857999 -287.186504) (xy 79.88087 -287.230081)
			(xy 79.896454 -287.276762) (xy 79.904349 -287.325339) (xy 79.904844 -287.349946) (xy 80.243946 -287.349946)
			(xy 80.247906 -287.300892) (xy 80.259683 -287.253108) (xy 80.278974 -287.207832) (xy 80.305277 -287.166236)
			(xy 80.337912 -287.129399) (xy 80.376033 -287.098274) (xy 80.418654 -287.073667) (xy 80.46467 -287.056215)
			(xy 80.512889 -287.046371) (xy 80.562064 -287.04439) (xy 80.610919 -287.050322) (xy 80.65819 -287.064014)
			(xy 80.702652 -287.085112) (xy 80.743155 -287.113068) (xy 80.778648 -287.14716) (xy 80.808213 -287.186504)
			(xy 80.831084 -287.230081) (xy 80.846668 -287.276762) (xy 80.854563 -287.325339) (xy 80.855058 -287.349946)
			(xy 80.854563 -287.374553) (xy 80.854384 -287.375654) (xy 81.173316 -287.375654) (xy 81.173316 -287.324238)
			(xy 81.181359 -287.273456) (xy 81.197247 -287.224557) (xy 81.22059 -287.178745) (xy 81.250811 -287.137149)
			(xy 81.287167 -287.100793) (xy 81.328763 -287.070572) (xy 81.374575 -287.047229) (xy 81.423474 -287.031341)
			(xy 81.474256 -287.023298) (xy 81.525672 -287.023298) (xy 81.576454 -287.031341) (xy 81.625353 -287.047229)
			(xy 81.671165 -287.070572) (xy 81.712761 -287.100793) (xy 81.749117 -287.137149) (xy 81.779338 -287.178745)
			(xy 81.802681 -287.224557) (xy 81.818569 -287.273456) (xy 81.826612 -287.324238) (xy 81.827116 -287.349946)
			(xy 81.826612 -287.375654) (xy 82.123276 -287.375654) (xy 82.123276 -287.324238) (xy 82.131319 -287.273456)
			(xy 82.147207 -287.224557) (xy 82.17055 -287.178745) (xy 82.200771 -287.137149) (xy 82.237127 -287.100793)
			(xy 82.278723 -287.070572) (xy 82.324535 -287.047229) (xy 82.373434 -287.031341) (xy 82.424216 -287.023298)
			(xy 82.475632 -287.023298) (xy 82.526414 -287.031341) (xy 82.575313 -287.047229) (xy 82.621125 -287.070572)
			(xy 82.662721 -287.100793) (xy 82.699077 -287.137149) (xy 82.729298 -287.178745) (xy 82.752641 -287.224557)
			(xy 82.768529 -287.273456) (xy 82.776572 -287.324238) (xy 82.777076 -287.349946) (xy 82.777071 -287.3502)
			(xy 83.094334 -287.3502) (xy 83.098294 -287.301146) (xy 83.110071 -287.253362) (xy 83.129362 -287.208086)
			(xy 83.155665 -287.16649) (xy 83.1883 -287.129653) (xy 83.226421 -287.098528) (xy 83.269042 -287.073921)
			(xy 83.315058 -287.056469) (xy 83.363277 -287.046625) (xy 83.412452 -287.044644) (xy 83.461307 -287.050576)
			(xy 83.508578 -287.064268) (xy 83.55304 -287.085366) (xy 83.593543 -287.113322) (xy 83.629036 -287.147414)
			(xy 83.658601 -287.186758) (xy 83.681472 -287.230335) (xy 83.697056 -287.277016) (xy 83.704951 -287.325593)
			(xy 83.705446 -287.3502) (xy 83.704951 -287.374807) (xy 83.697056 -287.423384) (xy 83.681472 -287.470065)
			(xy 83.658601 -287.513642) (xy 83.629036 -287.552986) (xy 83.593543 -287.587078) (xy 83.55304 -287.615034)
			(xy 83.508578 -287.636132) (xy 83.461307 -287.649824) (xy 83.412452 -287.655756) (xy 83.363277 -287.653775)
			(xy 83.315058 -287.643931) (xy 83.269042 -287.626479) (xy 83.226421 -287.601872) (xy 83.1883 -287.570747)
			(xy 83.155665 -287.53391) (xy 83.129362 -287.492314) (xy 83.110071 -287.447038) (xy 83.098294 -287.399254)
			(xy 83.094334 -287.3502) (xy 82.777071 -287.3502) (xy 82.776572 -287.375654) (xy 82.768529 -287.426436)
			(xy 82.752641 -287.475335) (xy 82.729298 -287.521147) (xy 82.699077 -287.562743) (xy 82.662721 -287.599099)
			(xy 82.621125 -287.62932) (xy 82.575313 -287.652663) (xy 82.526414 -287.668551) (xy 82.475632 -287.676594)
			(xy 82.424216 -287.676594) (xy 82.373434 -287.668551) (xy 82.324535 -287.652663) (xy 82.278723 -287.62932)
			(xy 82.237127 -287.599099) (xy 82.200771 -287.562743) (xy 82.17055 -287.521147) (xy 82.147207 -287.475335)
			(xy 82.131319 -287.426436) (xy 82.123276 -287.375654) (xy 81.826612 -287.375654) (xy 81.818569 -287.426436)
			(xy 81.802681 -287.475335) (xy 81.779338 -287.521147) (xy 81.749117 -287.562743) (xy 81.712761 -287.599099)
			(xy 81.671165 -287.62932) (xy 81.625353 -287.652663) (xy 81.576454 -287.668551) (xy 81.525672 -287.676594)
			(xy 81.474256 -287.676594) (xy 81.423474 -287.668551) (xy 81.374575 -287.652663) (xy 81.328763 -287.62932)
			(xy 81.287167 -287.599099) (xy 81.250811 -287.562743) (xy 81.22059 -287.521147) (xy 81.197247 -287.475335)
			(xy 81.181359 -287.426436) (xy 81.173316 -287.375654) (xy 80.854384 -287.375654) (xy 80.846668 -287.42313)
			(xy 80.831084 -287.469811) (xy 80.808213 -287.513388) (xy 80.778648 -287.552732) (xy 80.743155 -287.586824)
			(xy 80.702652 -287.61478) (xy 80.65819 -287.635878) (xy 80.610919 -287.64957) (xy 80.562064 -287.655502)
			(xy 80.512889 -287.653521) (xy 80.46467 -287.643677) (xy 80.418654 -287.626225) (xy 80.376033 -287.601618)
			(xy 80.337912 -287.570493) (xy 80.305277 -287.533656) (xy 80.278974 -287.49206) (xy 80.259683 -287.446784)
			(xy 80.247906 -287.399) (xy 80.243946 -287.349946) (xy 79.904844 -287.349946) (xy 79.904349 -287.374553)
			(xy 79.896454 -287.42313) (xy 79.88087 -287.469811) (xy 79.857999 -287.513388) (xy 79.828434 -287.552732)
			(xy 79.792941 -287.586824) (xy 79.752438 -287.61478) (xy 79.707976 -287.635878) (xy 79.660705 -287.64957)
			(xy 79.61185 -287.655502) (xy 79.562675 -287.653521) (xy 79.514456 -287.643677) (xy 79.46844 -287.626225)
			(xy 79.425819 -287.601618) (xy 79.387698 -287.570493) (xy 79.355063 -287.533656) (xy 79.32876 -287.49206)
			(xy 79.309469 -287.446784) (xy 79.297692 -287.399) (xy 79.293732 -287.349946) (xy 78.955138 -287.349946)
			(xy 78.954643 -287.374553) (xy 78.946748 -287.42313) (xy 78.931164 -287.469811) (xy 78.908293 -287.513388)
			(xy 78.878728 -287.552732) (xy 78.843235 -287.586824) (xy 78.802732 -287.61478) (xy 78.75827 -287.635878)
			(xy 78.710999 -287.64957) (xy 78.662144 -287.655502) (xy 78.612969 -287.653521) (xy 78.56475 -287.643677)
			(xy 78.518734 -287.626225) (xy 78.476113 -287.601618) (xy 78.437992 -287.570493) (xy 78.405357 -287.533656)
			(xy 78.379054 -287.49206) (xy 78.359763 -287.446784) (xy 78.347986 -287.399) (xy 78.344026 -287.349946)
			(xy 78.005178 -287.349946) (xy 78.004683 -287.374553) (xy 77.996788 -287.42313) (xy 77.981204 -287.469811)
			(xy 77.958333 -287.513388) (xy 77.928768 -287.552732) (xy 77.893275 -287.586824) (xy 77.852772 -287.61478)
			(xy 77.80831 -287.635878) (xy 77.761039 -287.64957) (xy 77.712184 -287.655502) (xy 77.663009 -287.653521)
			(xy 77.61479 -287.643677) (xy 77.568774 -287.626225) (xy 77.526153 -287.601618) (xy 77.488032 -287.570493)
			(xy 77.455397 -287.533656) (xy 77.429094 -287.49206) (xy 77.409803 -287.446784) (xy 77.398026 -287.399)
			(xy 77.394066 -287.349946) (xy 77.055218 -287.349946) (xy 77.054723 -287.374553) (xy 77.046828 -287.42313)
			(xy 77.031244 -287.469811) (xy 77.008373 -287.513388) (xy 76.978808 -287.552732) (xy 76.943315 -287.586824)
			(xy 76.902812 -287.61478) (xy 76.85835 -287.635878) (xy 76.811079 -287.64957) (xy 76.762224 -287.655502)
			(xy 76.713049 -287.653521) (xy 76.66483 -287.643677) (xy 76.618814 -287.626225) (xy 76.576193 -287.601618)
			(xy 76.538072 -287.570493) (xy 76.505437 -287.533656) (xy 76.479134 -287.49206) (xy 76.459843 -287.446784)
			(xy 76.448066 -287.399) (xy 76.444106 -287.349946) (xy 76.105258 -287.349946) (xy 76.104763 -287.374553)
			(xy 76.096868 -287.42313) (xy 76.081284 -287.469811) (xy 76.058413 -287.513388) (xy 76.028848 -287.552732)
			(xy 75.993355 -287.586824) (xy 75.952852 -287.61478) (xy 75.90839 -287.635878) (xy 75.861119 -287.64957)
			(xy 75.812264 -287.655502) (xy 75.763089 -287.653521) (xy 75.71487 -287.643677) (xy 75.668854 -287.626225)
			(xy 75.626233 -287.601618) (xy 75.588112 -287.570493) (xy 75.555477 -287.533656) (xy 75.529174 -287.49206)
			(xy 75.509883 -287.446784) (xy 75.498106 -287.399) (xy 75.494146 -287.349946) (xy 75.155044 -287.349946)
			(xy 75.154549 -287.374553) (xy 75.146654 -287.42313) (xy 75.13107 -287.469811) (xy 75.108199 -287.513388)
			(xy 75.078634 -287.552732) (xy 75.043141 -287.586824) (xy 75.002638 -287.61478) (xy 74.958176 -287.635878)
			(xy 74.910905 -287.64957) (xy 74.86205 -287.655502) (xy 74.812875 -287.653521) (xy 74.764656 -287.643677)
			(xy 74.71864 -287.626225) (xy 74.676019 -287.601618) (xy 74.637898 -287.570493) (xy 74.605263 -287.533656)
			(xy 74.57896 -287.49206) (xy 74.559669 -287.446784) (xy 74.547892 -287.399) (xy 74.543932 -287.349946)
			(xy 74.205084 -287.349946) (xy 74.204589 -287.374553) (xy 74.196694 -287.42313) (xy 74.18111 -287.469811)
			(xy 74.158239 -287.513388) (xy 74.128674 -287.552732) (xy 74.093181 -287.586824) (xy 74.052678 -287.61478)
			(xy 74.008216 -287.635878) (xy 73.960945 -287.64957) (xy 73.91209 -287.655502) (xy 73.862915 -287.653521)
			(xy 73.814696 -287.643677) (xy 73.76868 -287.626225) (xy 73.726059 -287.601618) (xy 73.687938 -287.570493)
			(xy 73.655303 -287.533656) (xy 73.629 -287.49206) (xy 73.609709 -287.446784) (xy 73.597932 -287.399)
			(xy 73.593972 -287.349946) (xy 48.06823 -287.349946) (xy 48.06823 -287.733486) (xy 48.070008 -287.746694)
			(xy 48.07077 -287.749742) (xy 48.075169 -287.768226) (xy 48.079884 -287.805928) (xy 48.080168 -287.824926)
			(xy 48.419016 -287.824926) (xy 48.422976 -287.775872) (xy 48.434753 -287.728088) (xy 48.454044 -287.682812)
			(xy 48.480347 -287.641216) (xy 48.512982 -287.604379) (xy 48.551103 -287.573254) (xy 48.593724 -287.548647)
			(xy 48.63974 -287.531195) (xy 48.687959 -287.521351) (xy 48.737134 -287.51937) (xy 48.785989 -287.525302)
			(xy 48.83326 -287.538994) (xy 48.877722 -287.560092) (xy 48.918225 -287.588048) (xy 48.953718 -287.62214)
			(xy 48.983283 -287.661484) (xy 49.006154 -287.705061) (xy 49.021738 -287.751742) (xy 49.029633 -287.800319)
			(xy 49.030128 -287.824926) (xy 49.368976 -287.824926) (xy 49.372936 -287.775872) (xy 49.384713 -287.728088)
			(xy 49.404004 -287.682812) (xy 49.430307 -287.641216) (xy 49.462942 -287.604379) (xy 49.501063 -287.573254)
			(xy 49.543684 -287.548647) (xy 49.5897 -287.531195) (xy 49.637919 -287.521351) (xy 49.687094 -287.51937)
			(xy 49.735949 -287.525302) (xy 49.78322 -287.538994) (xy 49.827682 -287.560092) (xy 49.868185 -287.588048)
			(xy 49.903678 -287.62214) (xy 49.933243 -287.661484) (xy 49.956114 -287.705061) (xy 49.971698 -287.751742)
			(xy 49.979593 -287.800319) (xy 49.980088 -287.824926) (xy 50.31919 -287.824926) (xy 50.32315 -287.775872)
			(xy 50.334927 -287.728088) (xy 50.354218 -287.682812) (xy 50.380521 -287.641216) (xy 50.413156 -287.604379)
			(xy 50.451277 -287.573254) (xy 50.493898 -287.548647) (xy 50.539914 -287.531195) (xy 50.588133 -287.521351)
			(xy 50.637308 -287.51937) (xy 50.686163 -287.525302) (xy 50.733434 -287.538994) (xy 50.777896 -287.560092)
			(xy 50.818399 -287.588048) (xy 50.853892 -287.62214) (xy 50.883457 -287.661484) (xy 50.906328 -287.705061)
			(xy 50.921912 -287.751742) (xy 50.929807 -287.800319) (xy 50.930302 -287.824926) (xy 51.26915 -287.824926)
			(xy 51.27311 -287.775872) (xy 51.284887 -287.728088) (xy 51.304178 -287.682812) (xy 51.330481 -287.641216)
			(xy 51.363116 -287.604379) (xy 51.401237 -287.573254) (xy 51.443858 -287.548647) (xy 51.489874 -287.531195)
			(xy 51.538093 -287.521351) (xy 51.587268 -287.51937) (xy 51.636123 -287.525302) (xy 51.683394 -287.538994)
			(xy 51.727856 -287.560092) (xy 51.768359 -287.588048) (xy 51.803852 -287.62214) (xy 51.833417 -287.661484)
			(xy 51.856288 -287.705061) (xy 51.871872 -287.751742) (xy 51.879767 -287.800319) (xy 51.880262 -287.824926)
			(xy 52.21911 -287.824926) (xy 52.22307 -287.775872) (xy 52.234847 -287.728088) (xy 52.254138 -287.682812)
			(xy 52.280441 -287.641216) (xy 52.313076 -287.604379) (xy 52.351197 -287.573254) (xy 52.393818 -287.548647)
			(xy 52.439834 -287.531195) (xy 52.488053 -287.521351) (xy 52.537228 -287.51937) (xy 52.586083 -287.525302)
			(xy 52.633354 -287.538994) (xy 52.677816 -287.560092) (xy 52.718319 -287.588048) (xy 52.753812 -287.62214)
			(xy 52.783377 -287.661484) (xy 52.806248 -287.705061) (xy 52.821832 -287.751742) (xy 52.829727 -287.800319)
			(xy 52.830222 -287.824926) (xy 53.16907 -287.824926) (xy 53.17303 -287.775872) (xy 53.184807 -287.728088)
			(xy 53.204098 -287.682812) (xy 53.230401 -287.641216) (xy 53.263036 -287.604379) (xy 53.301157 -287.573254)
			(xy 53.343778 -287.548647) (xy 53.389794 -287.531195) (xy 53.438013 -287.521351) (xy 53.487188 -287.51937)
			(xy 53.536043 -287.525302) (xy 53.583314 -287.538994) (xy 53.627776 -287.560092) (xy 53.668279 -287.588048)
			(xy 53.703772 -287.62214) (xy 53.733337 -287.661484) (xy 53.756208 -287.705061) (xy 53.771792 -287.751742)
			(xy 53.779687 -287.800319) (xy 53.780182 -287.824926) (xy 54.11903 -287.824926) (xy 54.12299 -287.775872)
			(xy 54.134767 -287.728088) (xy 54.154058 -287.682812) (xy 54.180361 -287.641216) (xy 54.212996 -287.604379)
			(xy 54.251117 -287.573254) (xy 54.293738 -287.548647) (xy 54.339754 -287.531195) (xy 54.387973 -287.521351)
			(xy 54.437148 -287.51937) (xy 54.486003 -287.525302) (xy 54.533274 -287.538994) (xy 54.577736 -287.560092)
			(xy 54.618239 -287.588048) (xy 54.653732 -287.62214) (xy 54.683297 -287.661484) (xy 54.706168 -287.705061)
			(xy 54.721752 -287.751742) (xy 54.729647 -287.800319) (xy 54.730142 -287.824926) (xy 55.06899 -287.824926)
			(xy 55.07295 -287.775872) (xy 55.084727 -287.728088) (xy 55.104018 -287.682812) (xy 55.130321 -287.641216)
			(xy 55.162956 -287.604379) (xy 55.201077 -287.573254) (xy 55.243698 -287.548647) (xy 55.289714 -287.531195)
			(xy 55.337933 -287.521351) (xy 55.387108 -287.51937) (xy 55.435963 -287.525302) (xy 55.483234 -287.538994)
			(xy 55.527696 -287.560092) (xy 55.568199 -287.588048) (xy 55.603692 -287.62214) (xy 55.633257 -287.661484)
			(xy 55.656128 -287.705061) (xy 55.671712 -287.751742) (xy 55.679607 -287.800319) (xy 55.680102 -287.824926)
			(xy 56.01895 -287.824926) (xy 56.02291 -287.775872) (xy 56.034687 -287.728088) (xy 56.053978 -287.682812)
			(xy 56.080281 -287.641216) (xy 56.112916 -287.604379) (xy 56.151037 -287.573254) (xy 56.193658 -287.548647)
			(xy 56.239674 -287.531195) (xy 56.287893 -287.521351) (xy 56.337068 -287.51937) (xy 56.385923 -287.525302)
			(xy 56.433194 -287.538994) (xy 56.477656 -287.560092) (xy 56.518159 -287.588048) (xy 56.553652 -287.62214)
			(xy 56.583217 -287.661484) (xy 56.606088 -287.705061) (xy 56.621672 -287.751742) (xy 56.629567 -287.800319)
			(xy 56.630062 -287.824926) (xy 56.969164 -287.824926) (xy 56.973124 -287.775872) (xy 56.984901 -287.728088)
			(xy 57.004192 -287.682812) (xy 57.030495 -287.641216) (xy 57.06313 -287.604379) (xy 57.101251 -287.573254)
			(xy 57.143872 -287.548647) (xy 57.189888 -287.531195) (xy 57.238107 -287.521351) (xy 57.287282 -287.51937)
			(xy 57.336137 -287.525302) (xy 57.383408 -287.538994) (xy 57.42787 -287.560092) (xy 57.468373 -287.588048)
			(xy 57.503866 -287.62214) (xy 57.533431 -287.661484) (xy 57.553624 -287.699958) (xy 57.944016 -287.699958)
			(xy 57.947976 -287.650904) (xy 57.959753 -287.60312) (xy 57.979044 -287.557844) (xy 58.005347 -287.516248)
			(xy 58.037982 -287.479411) (xy 58.076103 -287.448286) (xy 58.118724 -287.423679) (xy 58.16474 -287.406227)
			(xy 58.212959 -287.396383) (xy 58.262134 -287.394402) (xy 58.310989 -287.400334) (xy 58.35826 -287.414026)
			(xy 58.402722 -287.435124) (xy 58.443225 -287.46308) (xy 58.478718 -287.497172) (xy 58.508283 -287.536516)
			(xy 58.531154 -287.580093) (xy 58.546738 -287.626774) (xy 58.554633 -287.675351) (xy 58.555128 -287.699958)
			(xy 58.554633 -287.724565) (xy 58.546738 -287.773142) (xy 58.531154 -287.819823) (xy 58.508283 -287.8634)
			(xy 58.480888 -287.899856) (xy 59.819044 -287.899856) (xy 59.823004 -287.850802) (xy 59.834781 -287.803018)
			(xy 59.854072 -287.757742) (xy 59.880375 -287.716146) (xy 59.91301 -287.679309) (xy 59.951131 -287.648184)
			(xy 59.993752 -287.623577) (xy 60.039768 -287.606125) (xy 60.087987 -287.596281) (xy 60.137162 -287.5943)
			(xy 60.186017 -287.600232) (xy 60.233288 -287.613924) (xy 60.27775 -287.635022) (xy 60.318253 -287.662978)
			(xy 60.353746 -287.69707) (xy 60.383311 -287.736414) (xy 60.406182 -287.779991) (xy 60.421183 -287.824926)
			(xy 60.769004 -287.824926) (xy 60.772964 -287.775872) (xy 60.784741 -287.728088) (xy 60.804032 -287.682812)
			(xy 60.830335 -287.641216) (xy 60.86297 -287.604379) (xy 60.901091 -287.573254) (xy 60.943712 -287.548647)
			(xy 60.989728 -287.531195) (xy 61.037947 -287.521351) (xy 61.087122 -287.51937) (xy 61.135977 -287.525302)
			(xy 61.183248 -287.538994) (xy 61.22771 -287.560092) (xy 61.268213 -287.588048) (xy 61.303706 -287.62214)
			(xy 61.333271 -287.661484) (xy 61.356142 -287.705061) (xy 61.371726 -287.751742) (xy 61.379621 -287.800319)
			(xy 61.380116 -287.824926) (xy 61.718964 -287.824926) (xy 61.722924 -287.775872) (xy 61.734701 -287.728088)
			(xy 61.753992 -287.682812) (xy 61.780295 -287.641216) (xy 61.81293 -287.604379) (xy 61.851051 -287.573254)
			(xy 61.893672 -287.548647) (xy 61.939688 -287.531195) (xy 61.987907 -287.521351) (xy 62.037082 -287.51937)
			(xy 62.085937 -287.525302) (xy 62.133208 -287.538994) (xy 62.17767 -287.560092) (xy 62.218173 -287.588048)
			(xy 62.253666 -287.62214) (xy 62.283231 -287.661484) (xy 62.306102 -287.705061) (xy 62.321686 -287.751742)
			(xy 62.329581 -287.800319) (xy 62.330076 -287.824926) (xy 62.669178 -287.824926) (xy 62.673138 -287.775872)
			(xy 62.684915 -287.728088) (xy 62.704206 -287.682812) (xy 62.730509 -287.641216) (xy 62.763144 -287.604379)
			(xy 62.801265 -287.573254) (xy 62.843886 -287.548647) (xy 62.889902 -287.531195) (xy 62.938121 -287.521351)
			(xy 62.987296 -287.51937) (xy 63.036151 -287.525302) (xy 63.083422 -287.538994) (xy 63.127884 -287.560092)
			(xy 63.168387 -287.588048) (xy 63.20388 -287.62214) (xy 63.233445 -287.661484) (xy 63.256316 -287.705061)
			(xy 63.2719 -287.751742) (xy 63.279795 -287.800319) (xy 63.28029 -287.824926) (xy 63.619138 -287.824926)
			(xy 63.623098 -287.775872) (xy 63.634875 -287.728088) (xy 63.654166 -287.682812) (xy 63.680469 -287.641216)
			(xy 63.713104 -287.604379) (xy 63.751225 -287.573254) (xy 63.793846 -287.548647) (xy 63.839862 -287.531195)
			(xy 63.888081 -287.521351) (xy 63.937256 -287.51937) (xy 63.986111 -287.525302) (xy 64.033382 -287.538994)
			(xy 64.077844 -287.560092) (xy 64.118347 -287.588048) (xy 64.15384 -287.62214) (xy 64.183405 -287.661484)
			(xy 64.206276 -287.705061) (xy 64.22186 -287.751742) (xy 64.229755 -287.800319) (xy 64.23025 -287.824926)
			(xy 64.569098 -287.824926) (xy 64.573058 -287.775872) (xy 64.584835 -287.728088) (xy 64.604126 -287.682812)
			(xy 64.630429 -287.641216) (xy 64.663064 -287.604379) (xy 64.701185 -287.573254) (xy 64.743806 -287.548647)
			(xy 64.789822 -287.531195) (xy 64.838041 -287.521351) (xy 64.887216 -287.51937) (xy 64.936071 -287.525302)
			(xy 64.983342 -287.538994) (xy 65.027804 -287.560092) (xy 65.068307 -287.588048) (xy 65.1038 -287.62214)
			(xy 65.133365 -287.661484) (xy 65.156236 -287.705061) (xy 65.17182 -287.751742) (xy 65.179715 -287.800319)
			(xy 65.18021 -287.824926) (xy 65.519058 -287.824926) (xy 65.523018 -287.775872) (xy 65.534795 -287.728088)
			(xy 65.554086 -287.682812) (xy 65.580389 -287.641216) (xy 65.613024 -287.604379) (xy 65.651145 -287.573254)
			(xy 65.693766 -287.548647) (xy 65.739782 -287.531195) (xy 65.788001 -287.521351) (xy 65.837176 -287.51937)
			(xy 65.886031 -287.525302) (xy 65.933302 -287.538994) (xy 65.977764 -287.560092) (xy 66.018267 -287.588048)
			(xy 66.05376 -287.62214) (xy 66.083325 -287.661484) (xy 66.106196 -287.705061) (xy 66.12178 -287.751742)
			(xy 66.129675 -287.800319) (xy 66.13017 -287.824926) (xy 66.469018 -287.824926) (xy 66.472978 -287.775872)
			(xy 66.484755 -287.728088) (xy 66.504046 -287.682812) (xy 66.530349 -287.641216) (xy 66.562984 -287.604379)
			(xy 66.601105 -287.573254) (xy 66.643726 -287.548647) (xy 66.689742 -287.531195) (xy 66.737961 -287.521351)
			(xy 66.787136 -287.51937) (xy 66.835991 -287.525302) (xy 66.883262 -287.538994) (xy 66.927724 -287.560092)
			(xy 66.968227 -287.588048) (xy 67.00372 -287.62214) (xy 67.033285 -287.661484) (xy 67.056156 -287.705061)
			(xy 67.07174 -287.751742) (xy 67.079635 -287.800319) (xy 67.08013 -287.824926) (xy 67.418978 -287.824926)
			(xy 67.422938 -287.775872) (xy 67.434715 -287.728088) (xy 67.454006 -287.682812) (xy 67.480309 -287.641216)
			(xy 67.512944 -287.604379) (xy 67.551065 -287.573254) (xy 67.593686 -287.548647) (xy 67.639702 -287.531195)
			(xy 67.687921 -287.521351) (xy 67.737096 -287.51937) (xy 67.785951 -287.525302) (xy 67.833222 -287.538994)
			(xy 67.877684 -287.560092) (xy 67.918187 -287.588048) (xy 67.95368 -287.62214) (xy 67.983245 -287.661484)
			(xy 68.006116 -287.705061) (xy 68.0217 -287.751742) (xy 68.029595 -287.800319) (xy 68.03009 -287.824926)
			(xy 68.368938 -287.824926) (xy 68.372898 -287.775872) (xy 68.384675 -287.728088) (xy 68.403966 -287.682812)
			(xy 68.430269 -287.641216) (xy 68.462904 -287.604379) (xy 68.501025 -287.573254) (xy 68.543646 -287.548647)
			(xy 68.589662 -287.531195) (xy 68.637881 -287.521351) (xy 68.687056 -287.51937) (xy 68.735911 -287.525302)
			(xy 68.783182 -287.538994) (xy 68.827644 -287.560092) (xy 68.868147 -287.588048) (xy 68.90364 -287.62214)
			(xy 68.933205 -287.661484) (xy 68.956076 -287.705061) (xy 68.97166 -287.751742) (xy 68.979555 -287.800319)
			(xy 68.98005 -287.824926) (xy 70.269112 -287.824926) (xy 70.273072 -287.775872) (xy 70.284849 -287.728088)
			(xy 70.30414 -287.682812) (xy 70.330443 -287.641216) (xy 70.363078 -287.604379) (xy 70.401199 -287.573254)
			(xy 70.44382 -287.548647) (xy 70.489836 -287.531195) (xy 70.538055 -287.521351) (xy 70.58723 -287.51937)
			(xy 70.636085 -287.525302) (xy 70.683356 -287.538994) (xy 70.727818 -287.560092) (xy 70.768321 -287.588048)
			(xy 70.803814 -287.62214) (xy 70.833379 -287.661484) (xy 70.85625 -287.705061) (xy 70.871834 -287.751742)
			(xy 70.879729 -287.800319) (xy 70.880224 -287.824926) (xy 70.879729 -287.849533) (xy 70.871834 -287.89811)
			(xy 70.85625 -287.944791) (xy 70.833379 -287.988368) (xy 70.803814 -288.027712) (xy 70.768321 -288.061804)
			(xy 70.727818 -288.08976) (xy 70.683356 -288.110858) (xy 70.636085 -288.12455) (xy 70.58723 -288.130482)
			(xy 70.538055 -288.128501) (xy 70.489836 -288.118657) (xy 70.44382 -288.101205) (xy 70.401199 -288.076598)
			(xy 70.363078 -288.045473) (xy 70.330443 -288.008636) (xy 70.30414 -287.96704) (xy 70.284849 -287.921764)
			(xy 70.273072 -287.87398) (xy 70.269112 -287.824926) (xy 68.98005 -287.824926) (xy 68.979555 -287.849533)
			(xy 68.97166 -287.89811) (xy 68.956076 -287.944791) (xy 68.933205 -287.988368) (xy 68.90364 -288.027712)
			(xy 68.868147 -288.061804) (xy 68.827644 -288.08976) (xy 68.783182 -288.110858) (xy 68.735911 -288.12455)
			(xy 68.687056 -288.130482) (xy 68.637881 -288.128501) (xy 68.589662 -288.118657) (xy 68.543646 -288.101205)
			(xy 68.501025 -288.076598) (xy 68.462904 -288.045473) (xy 68.430269 -288.008636) (xy 68.403966 -287.96704)
			(xy 68.384675 -287.921764) (xy 68.372898 -287.87398) (xy 68.368938 -287.824926) (xy 68.03009 -287.824926)
			(xy 68.029595 -287.849533) (xy 68.0217 -287.89811) (xy 68.006116 -287.944791) (xy 67.983245 -287.988368)
			(xy 67.95368 -288.027712) (xy 67.918187 -288.061804) (xy 67.877684 -288.08976) (xy 67.833222 -288.110858)
			(xy 67.785951 -288.12455) (xy 67.737096 -288.130482) (xy 67.687921 -288.128501) (xy 67.639702 -288.118657)
			(xy 67.593686 -288.101205) (xy 67.551065 -288.076598) (xy 67.512944 -288.045473) (xy 67.480309 -288.008636)
			(xy 67.454006 -287.96704) (xy 67.434715 -287.921764) (xy 67.422938 -287.87398) (xy 67.418978 -287.824926)
			(xy 67.08013 -287.824926) (xy 67.079635 -287.849533) (xy 67.07174 -287.89811) (xy 67.056156 -287.944791)
			(xy 67.033285 -287.988368) (xy 67.00372 -288.027712) (xy 66.968227 -288.061804) (xy 66.927724 -288.08976)
			(xy 66.883262 -288.110858) (xy 66.835991 -288.12455) (xy 66.787136 -288.130482) (xy 66.737961 -288.128501)
			(xy 66.689742 -288.118657) (xy 66.643726 -288.101205) (xy 66.601105 -288.076598) (xy 66.562984 -288.045473)
			(xy 66.530349 -288.008636) (xy 66.504046 -287.96704) (xy 66.484755 -287.921764) (xy 66.472978 -287.87398)
			(xy 66.469018 -287.824926) (xy 66.13017 -287.824926) (xy 66.129675 -287.849533) (xy 66.12178 -287.89811)
			(xy 66.106196 -287.944791) (xy 66.083325 -287.988368) (xy 66.05376 -288.027712) (xy 66.018267 -288.061804)
			(xy 65.977764 -288.08976) (xy 65.933302 -288.110858) (xy 65.886031 -288.12455) (xy 65.837176 -288.130482)
			(xy 65.788001 -288.128501) (xy 65.739782 -288.118657) (xy 65.693766 -288.101205) (xy 65.651145 -288.076598)
			(xy 65.613024 -288.045473) (xy 65.580389 -288.008636) (xy 65.554086 -287.96704) (xy 65.534795 -287.921764)
			(xy 65.523018 -287.87398) (xy 65.519058 -287.824926) (xy 65.18021 -287.824926) (xy 65.179715 -287.849533)
			(xy 65.17182 -287.89811) (xy 65.156236 -287.944791) (xy 65.133365 -287.988368) (xy 65.1038 -288.027712)
			(xy 65.068307 -288.061804) (xy 65.027804 -288.08976) (xy 64.983342 -288.110858) (xy 64.936071 -288.12455)
			(xy 64.887216 -288.130482) (xy 64.838041 -288.128501) (xy 64.789822 -288.118657) (xy 64.743806 -288.101205)
			(xy 64.701185 -288.076598) (xy 64.663064 -288.045473) (xy 64.630429 -288.008636) (xy 64.604126 -287.96704)
			(xy 64.584835 -287.921764) (xy 64.573058 -287.87398) (xy 64.569098 -287.824926) (xy 64.23025 -287.824926)
			(xy 64.229755 -287.849533) (xy 64.22186 -287.89811) (xy 64.206276 -287.944791) (xy 64.183405 -287.988368)
			(xy 64.15384 -288.027712) (xy 64.118347 -288.061804) (xy 64.077844 -288.08976) (xy 64.033382 -288.110858)
			(xy 63.986111 -288.12455) (xy 63.937256 -288.130482) (xy 63.888081 -288.128501) (xy 63.839862 -288.118657)
			(xy 63.793846 -288.101205) (xy 63.751225 -288.076598) (xy 63.713104 -288.045473) (xy 63.680469 -288.008636)
			(xy 63.654166 -287.96704) (xy 63.634875 -287.921764) (xy 63.623098 -287.87398) (xy 63.619138 -287.824926)
			(xy 63.28029 -287.824926) (xy 63.279795 -287.849533) (xy 63.2719 -287.89811) (xy 63.256316 -287.944791)
			(xy 63.233445 -287.988368) (xy 63.20388 -288.027712) (xy 63.168387 -288.061804) (xy 63.127884 -288.08976)
			(xy 63.083422 -288.110858) (xy 63.036151 -288.12455) (xy 62.987296 -288.130482) (xy 62.938121 -288.128501)
			(xy 62.889902 -288.118657) (xy 62.843886 -288.101205) (xy 62.801265 -288.076598) (xy 62.763144 -288.045473)
			(xy 62.730509 -288.008636) (xy 62.704206 -287.96704) (xy 62.684915 -287.921764) (xy 62.673138 -287.87398)
			(xy 62.669178 -287.824926) (xy 62.330076 -287.824926) (xy 62.329581 -287.849533) (xy 62.321686 -287.89811)
			(xy 62.306102 -287.944791) (xy 62.283231 -287.988368) (xy 62.253666 -288.027712) (xy 62.218173 -288.061804)
			(xy 62.17767 -288.08976) (xy 62.133208 -288.110858) (xy 62.085937 -288.12455) (xy 62.037082 -288.130482)
			(xy 61.987907 -288.128501) (xy 61.939688 -288.118657) (xy 61.893672 -288.101205) (xy 61.851051 -288.076598)
			(xy 61.81293 -288.045473) (xy 61.780295 -288.008636) (xy 61.753992 -287.96704) (xy 61.734701 -287.921764)
			(xy 61.722924 -287.87398) (xy 61.718964 -287.824926) (xy 61.380116 -287.824926) (xy 61.379621 -287.849533)
			(xy 61.371726 -287.89811) (xy 61.356142 -287.944791) (xy 61.333271 -287.988368) (xy 61.303706 -288.027712)
			(xy 61.268213 -288.061804) (xy 61.22771 -288.08976) (xy 61.183248 -288.110858) (xy 61.135977 -288.12455)
			(xy 61.087122 -288.130482) (xy 61.037947 -288.128501) (xy 60.989728 -288.118657) (xy 60.943712 -288.101205)
			(xy 60.901091 -288.076598) (xy 60.86297 -288.045473) (xy 60.830335 -288.008636) (xy 60.804032 -287.96704)
			(xy 60.784741 -287.921764) (xy 60.772964 -287.87398) (xy 60.769004 -287.824926) (xy 60.421183 -287.824926)
			(xy 60.421766 -287.826672) (xy 60.429661 -287.875249) (xy 60.430156 -287.899856) (xy 60.429661 -287.924463)
			(xy 60.421766 -287.97304) (xy 60.406182 -288.019721) (xy 60.383311 -288.063298) (xy 60.353746 -288.102642)
			(xy 60.318253 -288.136734) (xy 60.27775 -288.16469) (xy 60.233288 -288.185788) (xy 60.186017 -288.19948)
			(xy 60.137162 -288.205412) (xy 60.087987 -288.203431) (xy 60.039768 -288.193587) (xy 59.993752 -288.176135)
			(xy 59.951131 -288.151528) (xy 59.91301 -288.120403) (xy 59.880375 -288.083566) (xy 59.854072 -288.04197)
			(xy 59.834781 -287.996694) (xy 59.823004 -287.94891) (xy 59.819044 -287.899856) (xy 58.480888 -287.899856)
			(xy 58.478718 -287.902744) (xy 58.443225 -287.936836) (xy 58.402722 -287.964792) (xy 58.35826 -287.98589)
			(xy 58.310989 -287.999582) (xy 58.262134 -288.005514) (xy 58.212959 -288.003533) (xy 58.16474 -287.993689)
			(xy 58.118724 -287.976237) (xy 58.076103 -287.95163) (xy 58.037982 -287.920505) (xy 58.005347 -287.883668)
			(xy 57.979044 -287.842072) (xy 57.959753 -287.796796) (xy 57.947976 -287.749012) (xy 57.944016 -287.699958)
			(xy 57.553624 -287.699958) (xy 57.556302 -287.705061) (xy 57.571886 -287.751742) (xy 57.579781 -287.800319)
			(xy 57.580276 -287.824926) (xy 57.579781 -287.849533) (xy 57.571886 -287.89811) (xy 57.556302 -287.944791)
			(xy 57.533431 -287.988368) (xy 57.503866 -288.027712) (xy 57.468373 -288.061804) (xy 57.42787 -288.08976)
			(xy 57.383408 -288.110858) (xy 57.336137 -288.12455) (xy 57.287282 -288.130482) (xy 57.238107 -288.128501)
			(xy 57.189888 -288.118657) (xy 57.143872 -288.101205) (xy 57.101251 -288.076598) (xy 57.06313 -288.045473)
			(xy 57.030495 -288.008636) (xy 57.004192 -287.96704) (xy 56.984901 -287.921764) (xy 56.973124 -287.87398)
			(xy 56.969164 -287.824926) (xy 56.630062 -287.824926) (xy 56.629567 -287.849533) (xy 56.621672 -287.89811)
			(xy 56.606088 -287.944791) (xy 56.583217 -287.988368) (xy 56.553652 -288.027712) (xy 56.518159 -288.061804)
			(xy 56.477656 -288.08976) (xy 56.433194 -288.110858) (xy 56.385923 -288.12455) (xy 56.337068 -288.130482)
			(xy 56.287893 -288.128501) (xy 56.239674 -288.118657) (xy 56.193658 -288.101205) (xy 56.151037 -288.076598)
			(xy 56.112916 -288.045473) (xy 56.080281 -288.008636) (xy 56.053978 -287.96704) (xy 56.034687 -287.921764)
			(xy 56.02291 -287.87398) (xy 56.01895 -287.824926) (xy 55.680102 -287.824926) (xy 55.679607 -287.849533)
			(xy 55.671712 -287.89811) (xy 55.656128 -287.944791) (xy 55.633257 -287.988368) (xy 55.603692 -288.027712)
			(xy 55.568199 -288.061804) (xy 55.527696 -288.08976) (xy 55.483234 -288.110858) (xy 55.435963 -288.12455)
			(xy 55.387108 -288.130482) (xy 55.337933 -288.128501) (xy 55.289714 -288.118657) (xy 55.243698 -288.101205)
			(xy 55.201077 -288.076598) (xy 55.162956 -288.045473) (xy 55.130321 -288.008636) (xy 55.104018 -287.96704)
			(xy 55.084727 -287.921764) (xy 55.07295 -287.87398) (xy 55.06899 -287.824926) (xy 54.730142 -287.824926)
			(xy 54.729647 -287.849533) (xy 54.721752 -287.89811) (xy 54.706168 -287.944791) (xy 54.683297 -287.988368)
			(xy 54.653732 -288.027712) (xy 54.618239 -288.061804) (xy 54.577736 -288.08976) (xy 54.533274 -288.110858)
			(xy 54.486003 -288.12455) (xy 54.437148 -288.130482) (xy 54.387973 -288.128501) (xy 54.339754 -288.118657)
			(xy 54.293738 -288.101205) (xy 54.251117 -288.076598) (xy 54.212996 -288.045473) (xy 54.180361 -288.008636)
			(xy 54.154058 -287.96704) (xy 54.134767 -287.921764) (xy 54.12299 -287.87398) (xy 54.11903 -287.824926)
			(xy 53.780182 -287.824926) (xy 53.779687 -287.849533) (xy 53.771792 -287.89811) (xy 53.756208 -287.944791)
			(xy 53.733337 -287.988368) (xy 53.703772 -288.027712) (xy 53.668279 -288.061804) (xy 53.627776 -288.08976)
			(xy 53.583314 -288.110858) (xy 53.536043 -288.12455) (xy 53.487188 -288.130482) (xy 53.438013 -288.128501)
			(xy 53.389794 -288.118657) (xy 53.343778 -288.101205) (xy 53.301157 -288.076598) (xy 53.263036 -288.045473)
			(xy 53.230401 -288.008636) (xy 53.204098 -287.96704) (xy 53.184807 -287.921764) (xy 53.17303 -287.87398)
			(xy 53.16907 -287.824926) (xy 52.830222 -287.824926) (xy 52.829727 -287.849533) (xy 52.821832 -287.89811)
			(xy 52.806248 -287.944791) (xy 52.783377 -287.988368) (xy 52.753812 -288.027712) (xy 52.718319 -288.061804)
			(xy 52.677816 -288.08976) (xy 52.633354 -288.110858) (xy 52.586083 -288.12455) (xy 52.537228 -288.130482)
			(xy 52.488053 -288.128501) (xy 52.439834 -288.118657) (xy 52.393818 -288.101205) (xy 52.351197 -288.076598)
			(xy 52.313076 -288.045473) (xy 52.280441 -288.008636) (xy 52.254138 -287.96704) (xy 52.234847 -287.921764)
			(xy 52.22307 -287.87398) (xy 52.21911 -287.824926) (xy 51.880262 -287.824926) (xy 51.879767 -287.849533)
			(xy 51.871872 -287.89811) (xy 51.856288 -287.944791) (xy 51.833417 -287.988368) (xy 51.803852 -288.027712)
			(xy 51.768359 -288.061804) (xy 51.727856 -288.08976) (xy 51.683394 -288.110858) (xy 51.636123 -288.12455)
			(xy 51.587268 -288.130482) (xy 51.538093 -288.128501) (xy 51.489874 -288.118657) (xy 51.443858 -288.101205)
			(xy 51.401237 -288.076598) (xy 51.363116 -288.045473) (xy 51.330481 -288.008636) (xy 51.304178 -287.96704)
			(xy 51.284887 -287.921764) (xy 51.27311 -287.87398) (xy 51.26915 -287.824926) (xy 50.930302 -287.824926)
			(xy 50.929807 -287.849533) (xy 50.921912 -287.89811) (xy 50.906328 -287.944791) (xy 50.883457 -287.988368)
			(xy 50.853892 -288.027712) (xy 50.818399 -288.061804) (xy 50.777896 -288.08976) (xy 50.733434 -288.110858)
			(xy 50.686163 -288.12455) (xy 50.637308 -288.130482) (xy 50.588133 -288.128501) (xy 50.539914 -288.118657)
			(xy 50.493898 -288.101205) (xy 50.451277 -288.076598) (xy 50.413156 -288.045473) (xy 50.380521 -288.008636)
			(xy 50.354218 -287.96704) (xy 50.334927 -287.921764) (xy 50.32315 -287.87398) (xy 50.31919 -287.824926)
			(xy 49.980088 -287.824926) (xy 49.979593 -287.849533) (xy 49.971698 -287.89811) (xy 49.956114 -287.944791)
			(xy 49.933243 -287.988368) (xy 49.903678 -288.027712) (xy 49.868185 -288.061804) (xy 49.827682 -288.08976)
			(xy 49.78322 -288.110858) (xy 49.735949 -288.12455) (xy 49.687094 -288.130482) (xy 49.637919 -288.128501)
			(xy 49.5897 -288.118657) (xy 49.543684 -288.101205) (xy 49.501063 -288.076598) (xy 49.462942 -288.045473)
			(xy 49.430307 -288.008636) (xy 49.404004 -287.96704) (xy 49.384713 -287.921764) (xy 49.372936 -287.87398)
			(xy 49.368976 -287.824926) (xy 49.030128 -287.824926) (xy 49.029633 -287.849533) (xy 49.021738 -287.89811)
			(xy 49.006154 -287.944791) (xy 48.983283 -287.988368) (xy 48.953718 -288.027712) (xy 48.918225 -288.061804)
			(xy 48.877722 -288.08976) (xy 48.83326 -288.110858) (xy 48.785989 -288.12455) (xy 48.737134 -288.130482)
			(xy 48.687959 -288.128501) (xy 48.63974 -288.118657) (xy 48.593724 -288.101205) (xy 48.551103 -288.076598)
			(xy 48.512982 -288.045473) (xy 48.480347 -288.008636) (xy 48.454044 -287.96704) (xy 48.434753 -287.921764)
			(xy 48.422976 -287.87398) (xy 48.419016 -287.824926) (xy 48.080168 -287.824926) (xy 48.079914 -287.83534)
			(xy 48.079914 -287.84169) (xy 48.07966 -287.846262) (xy 48.07966 -287.847024) (xy 48.078436 -287.861425)
			(xy 48.073602 -287.889921) (xy 48.070008 -287.90392) (xy 48.06823 -287.910524) (xy 48.06823 -288.299906)
			(xy 73.593972 -288.299906) (xy 73.597932 -288.250852) (xy 73.609709 -288.203068) (xy 73.629 -288.157792)
			(xy 73.655303 -288.116196) (xy 73.687938 -288.079359) (xy 73.726059 -288.048234) (xy 73.76868 -288.023627)
			(xy 73.814696 -288.006175) (xy 73.862915 -287.996331) (xy 73.91209 -287.99435) (xy 73.960945 -288.000282)
			(xy 74.008216 -288.013974) (xy 74.052678 -288.035072) (xy 74.093181 -288.063028) (xy 74.128674 -288.09712)
			(xy 74.158239 -288.136464) (xy 74.18111 -288.180041) (xy 74.196694 -288.226722) (xy 74.204589 -288.275299)
			(xy 74.205084 -288.299906) (xy 74.544186 -288.299906) (xy 74.548146 -288.250852) (xy 74.559923 -288.203068)
			(xy 74.579214 -288.157792) (xy 74.605517 -288.116196) (xy 74.638152 -288.079359) (xy 74.676273 -288.048234)
			(xy 74.718894 -288.023627) (xy 74.76491 -288.006175) (xy 74.813129 -287.996331) (xy 74.862304 -287.99435)
			(xy 74.911159 -288.000282) (xy 74.95843 -288.013974) (xy 75.002892 -288.035072) (xy 75.043395 -288.063028)
			(xy 75.078888 -288.09712) (xy 75.108453 -288.136464) (xy 75.131324 -288.180041) (xy 75.146908 -288.226722)
			(xy 75.154803 -288.275299) (xy 75.155298 -288.299906) (xy 75.494146 -288.299906) (xy 75.498106 -288.250852)
			(xy 75.509883 -288.203068) (xy 75.529174 -288.157792) (xy 75.555477 -288.116196) (xy 75.588112 -288.079359)
			(xy 75.626233 -288.048234) (xy 75.668854 -288.023627) (xy 75.71487 -288.006175) (xy 75.763089 -287.996331)
			(xy 75.812264 -287.99435) (xy 75.861119 -288.000282) (xy 75.90839 -288.013974) (xy 75.952852 -288.035072)
			(xy 75.993355 -288.063028) (xy 76.028848 -288.09712) (xy 76.058413 -288.136464) (xy 76.081284 -288.180041)
			(xy 76.096868 -288.226722) (xy 76.104763 -288.275299) (xy 76.105258 -288.299906) (xy 76.444106 -288.299906)
			(xy 76.448066 -288.250852) (xy 76.459843 -288.203068) (xy 76.479134 -288.157792) (xy 76.505437 -288.116196)
			(xy 76.538072 -288.079359) (xy 76.576193 -288.048234) (xy 76.618814 -288.023627) (xy 76.66483 -288.006175)
			(xy 76.713049 -287.996331) (xy 76.762224 -287.99435) (xy 76.811079 -288.000282) (xy 76.85835 -288.013974)
			(xy 76.902812 -288.035072) (xy 76.943315 -288.063028) (xy 76.978808 -288.09712) (xy 77.008373 -288.136464)
			(xy 77.031244 -288.180041) (xy 77.046828 -288.226722) (xy 77.054723 -288.275299) (xy 77.055218 -288.299906)
			(xy 77.394066 -288.299906) (xy 77.398026 -288.250852) (xy 77.409803 -288.203068) (xy 77.429094 -288.157792)
			(xy 77.455397 -288.116196) (xy 77.488032 -288.079359) (xy 77.526153 -288.048234) (xy 77.568774 -288.023627)
			(xy 77.61479 -288.006175) (xy 77.663009 -287.996331) (xy 77.712184 -287.99435) (xy 77.761039 -288.000282)
			(xy 77.80831 -288.013974) (xy 77.852772 -288.035072) (xy 77.893275 -288.063028) (xy 77.928768 -288.09712)
			(xy 77.958333 -288.136464) (xy 77.981204 -288.180041) (xy 77.996788 -288.226722) (xy 78.004683 -288.275299)
			(xy 78.005178 -288.299906) (xy 78.005011 -288.308201) (xy 78.344052 -288.308201) (xy 78.346737 -288.258626)
			(xy 78.357407 -288.210138) (xy 78.375781 -288.164015) (xy 78.401375 -288.121473) (xy 78.433515 -288.083632)
			(xy 78.471354 -288.051489) (xy 78.513894 -288.025892) (xy 78.560015 -288.007514) (xy 78.608502 -287.99684)
			(xy 78.658077 -287.994151) (xy 78.707434 -287.999518) (xy 78.755272 -288.0128) (xy 78.800331 -288.033646)
			(xy 78.841424 -288.061507) (xy 78.877468 -288.09565) (xy 78.907514 -288.135174) (xy 78.930769 -288.179039)
			(xy 78.946621 -288.226088) (xy 78.954652 -288.275082) (xy 78.955138 -288.299906) (xy 78.954945 -288.314025)
			(xy 78.952278 -288.342138) (xy 78.949804 -288.35604) (xy 78.947518 -288.368486) (xy 78.954884 -288.392362)
			(xy 79.032354 -288.469832) (xy 79.05623 -288.477198) (xy 79.068676 -288.474912) (xy 79.082581 -288.472455)
			(xy 79.110692 -288.46978) (xy 79.12481 -288.469578) (xy 79.125064 -288.469578) (xy 79.134871 -288.469656)
			(xy 79.154445 -288.470929) (xy 79.16418 -288.472118) (xy 79.176118 -288.473642) (xy 79.198724 -288.465768)
			(xy 79.263748 -288.398204) (xy 79.267821 -288.393739) (xy 79.273985 -288.383348) (xy 79.27594 -288.37763)
			(xy 79.279242 -288.366454) (xy 79.277464 -288.354516) (xy 79.277464 -288.354008) (xy 79.275348 -288.340646)
			(xy 79.273063 -288.313687) (xy 79.272892 -288.30016) (xy 79.272892 -288.299906) (xy 79.273396 -288.274218)
			(xy 79.281433 -288.223475) (xy 79.297309 -288.174614) (xy 79.320633 -288.128838) (xy 79.35083 -288.087274)
			(xy 79.387158 -288.050946) (xy 79.428722 -288.020749) (xy 79.474498 -287.997425) (xy 79.523359 -287.981549)
			(xy 79.574102 -287.973512) (xy 79.625478 -287.973512) (xy 79.676221 -287.981549) (xy 79.725082 -287.997425)
			(xy 79.770858 -288.020749) (xy 79.812422 -288.050946) (xy 79.84875 -288.087274) (xy 79.878947 -288.128838)
			(xy 79.902271 -288.174614) (xy 79.918147 -288.223475) (xy 79.926184 -288.274218) (xy 79.926688 -288.299906)
			(xy 79.926688 -288.30016) (xy 79.926529 -288.313688) (xy 79.924242 -288.340647) (xy 79.922116 -288.354008)
			(xy 79.922116 -288.354516) (xy 79.920338 -288.366454) (xy 79.92364 -288.37763) (xy 79.925539 -288.383374)
			(xy 79.93171 -288.393776) (xy 79.935832 -288.398204) (xy 80.000856 -288.465768) (xy 80.023462 -288.473642)
			(xy 80.0354 -288.472118) (xy 80.045199 -288.470925) (xy 80.064899 -288.469657) (xy 80.07477 -288.469578)
			(xy 80.084641 -288.469654) (xy 80.104342 -288.470923) (xy 80.11414 -288.472118) (xy 80.126078 -288.473642)
			(xy 80.148684 -288.465768) (xy 80.213708 -288.398204) (xy 80.217776 -288.393735) (xy 80.223944 -288.383347)
			(xy 80.2259 -288.37763) (xy 80.229202 -288.366454) (xy 80.227424 -288.354516) (xy 80.227424 -288.354008)
			(xy 80.225309 -288.340646) (xy 80.223023 -288.313687) (xy 80.222852 -288.30016) (xy 80.222852 -288.299906)
			(xy 80.223356 -288.274218) (xy 80.231393 -288.223475) (xy 80.247269 -288.174614) (xy 80.270593 -288.128838)
			(xy 80.30079 -288.087274) (xy 80.337118 -288.050946) (xy 80.378682 -288.020749) (xy 80.424458 -287.997425)
			(xy 80.473319 -287.981549) (xy 80.524062 -287.973512) (xy 80.575438 -287.973512) (xy 80.626181 -287.981549)
			(xy 80.675042 -287.997425) (xy 80.720818 -288.020749) (xy 80.762382 -288.050946) (xy 80.79871 -288.087274)
			(xy 80.828907 -288.128838) (xy 80.852231 -288.174614) (xy 80.868107 -288.223475) (xy 80.876144 -288.274218)
			(xy 80.876648 -288.299906) (xy 80.876648 -288.30016) (xy 80.876491 -288.313814) (xy 80.874204 -288.341028)
			(xy 80.872076 -288.354516) (xy 80.870044 -288.366454) (xy 80.877156 -288.389314) (xy 80.942434 -288.456878)
			(xy 80.951105 -288.465025) (xy 80.973494 -288.472979) (xy 80.98536 -288.472118) (xy 80.985614 -288.472118)
			(xy 80.99535 -288.470941) (xy 81.014923 -288.469667) (xy 81.02473 -288.469578) (xy 81.024984 -288.469578)
			(xy 81.039104 -288.46976) (xy 81.067216 -288.472434) (xy 81.081118 -288.474912) (xy 81.093564 -288.477198)
			(xy 81.11744 -288.469832) (xy 81.19491 -288.392362) (xy 81.202276 -288.368486) (xy 81.19999 -288.35604)
			(xy 81.197521 -288.342137) (xy 81.194854 -288.314025) (xy 81.194656 -288.299906) (xy 81.195178 -288.274651)
			(xy 81.203491 -288.224829) (xy 81.219892 -288.177055) (xy 81.243933 -288.132632) (xy 81.274957 -288.092772)
			(xy 81.312119 -288.058562) (xy 81.354405 -288.030936) (xy 81.400661 -288.010646) (xy 81.449626 -287.998246)
			(xy 81.499964 -287.994075) (xy 81.550302 -287.998246) (xy 81.599267 -288.010646) (xy 81.645523 -288.030936)
			(xy 81.687809 -288.058562) (xy 81.724971 -288.092772) (xy 81.755995 -288.132632) (xy 81.780036 -288.177055)
			(xy 81.796437 -288.224829) (xy 81.80475 -288.274651) (xy 81.805272 -288.299906) (xy 81.805079 -288.314025)
			(xy 81.802412 -288.342138) (xy 81.799938 -288.35604) (xy 81.797652 -288.368486) (xy 81.805018 -288.392362)
			(xy 81.882488 -288.469832) (xy 81.906364 -288.477198) (xy 81.91881 -288.474912) (xy 81.932714 -288.47245)
			(xy 81.960825 -288.469778) (xy 81.974944 -288.469578) (xy 81.989063 -288.469765) (xy 82.017176 -288.472436)
			(xy 82.031078 -288.474912) (xy 82.043524 -288.477198) (xy 82.0674 -288.469832) (xy 82.14487 -288.392362)
			(xy 82.152236 -288.368486) (xy 82.14995 -288.35604) (xy 82.147482 -288.342137) (xy 82.144814 -288.314025)
			(xy 82.144616 -288.299906) (xy 82.145138 -288.274651) (xy 82.153451 -288.224829) (xy 82.169852 -288.177055)
			(xy 82.193893 -288.132632) (xy 82.224917 -288.092772) (xy 82.262079 -288.058562) (xy 82.304365 -288.030936)
			(xy 82.350621 -288.010646) (xy 82.399586 -287.998246) (xy 82.449924 -287.994075) (xy 82.500262 -287.998246)
			(xy 82.549227 -288.010646) (xy 82.595483 -288.030936) (xy 82.637769 -288.058562) (xy 82.674931 -288.092772)
			(xy 82.705955 -288.132632) (xy 82.729996 -288.177055) (xy 82.746397 -288.224829) (xy 82.750339 -288.248452)
			(xy 87.595944 -288.248452) (xy 87.595944 -288.193948) (xy 87.6037 -288.139999) (xy 87.619055 -288.087702)
			(xy 87.641695 -288.038123) (xy 87.671161 -287.99227) (xy 87.706852 -287.951077) (xy 87.748041 -287.915382)
			(xy 87.793891 -287.885913) (xy 87.843468 -287.863267) (xy 87.895763 -287.847908) (xy 87.949712 -287.840146)
			(xy 87.976964 -287.839658) (xy 88.003079 -287.840142) (xy 88.054821 -287.847275) (xy 88.105106 -287.861398)
			(xy 88.152996 -287.882247) (xy 88.197594 -287.909433) (xy 88.238067 -287.942448) (xy 88.273659 -287.980675)
			(xy 88.303705 -288.023399) (xy 88.316054 -288.046414) (xy 88.322658 -288.059114) (xy 88.347042 -288.0741)
			(xy 88.465914 -288.0741) (xy 88.490298 -288.059114) (xy 88.496902 -288.046414) (xy 88.510808 -288.020644)
			(xy 88.54523 -287.973277) (xy 88.586492 -287.931731) (xy 88.633623 -287.896985) (xy 88.685513 -287.869857)
			(xy 88.740942 -287.850984) (xy 88.798605 -287.84081) (xy 88.827864 -287.839658) (xy 88.828118 -287.839658)
			(xy 88.839393 -287.838784) (xy 88.859569 -287.82864) (xy 88.86698 -287.8201) (xy 88.922606 -287.74898)
			(xy 88.927432 -287.727136) (xy 88.924892 -287.715706) (xy 88.920516 -287.695091) (xy 88.915803 -287.653212)
			(xy 88.915494 -287.63214) (xy 88.91598 -287.604889) (xy 88.923736 -287.550941) (xy 88.939091 -287.498646)
			(xy 88.961733 -287.449069) (xy 88.991199 -287.403219) (xy 89.02689 -287.362028) (xy 89.068081 -287.326337)
			(xy 89.113931 -287.296871) (xy 89.163508 -287.274229) (xy 89.215803 -287.258874) (xy 89.269751 -287.251118)
			(xy 89.324253 -287.251118) (xy 89.378201 -287.258874) (xy 89.430496 -287.274229) (xy 89.480073 -287.296871)
			(xy 89.525923 -287.326337) (xy 89.567114 -287.362028) (xy 89.602805 -287.403219) (xy 89.632271 -287.449069)
			(xy 89.654913 -287.498646) (xy 89.666664 -287.538668) (xy 90.024458 -287.538668) (xy 90.024944 -287.511417)
			(xy 90.0327 -287.457469) (xy 90.048055 -287.405174) (xy 90.070697 -287.355597) (xy 90.100163 -287.309747)
			(xy 90.135854 -287.268556) (xy 90.177045 -287.232865) (xy 90.222895 -287.203399) (xy 90.272472 -287.180757)
			(xy 90.324767 -287.165402) (xy 90.378715 -287.157646) (xy 90.433217 -287.157646) (xy 90.487165 -287.165402)
			(xy 90.53946 -287.180757) (xy 90.589037 -287.203399) (xy 90.634887 -287.232865) (xy 90.676078 -287.268556)
			(xy 90.711769 -287.309747) (xy 90.741235 -287.355597) (xy 90.763877 -287.405174) (xy 90.779232 -287.457469)
			(xy 90.786988 -287.511417) (xy 90.787474 -287.538668) (xy 90.786984 -287.565829) (xy 90.779256 -287.619599)
			(xy 90.763994 -287.671734) (xy 90.753184 -287.696656) (xy 90.747487 -287.710387) (xy 90.743457 -287.739827)
			(xy 90.748078 -287.769179) (xy 90.76096 -287.795956) (xy 90.781009 -287.817887) (xy 90.806526 -287.833113)
			(xy 90.835347 -287.840342) (xy 90.850212 -287.840166) (xy 90.85072 -287.840166) (xy 90.867992 -287.839658)
			(xy 90.868246 -287.839658) (xy 90.895484 -287.840202) (xy 90.949401 -287.847986) (xy 91.001662 -287.863361)
			(xy 91.051205 -287.886013) (xy 91.097022 -287.915482) (xy 91.138181 -287.951169) (xy 91.173845 -287.992348)
			(xy 91.203289 -288.038181) (xy 91.225913 -288.087737) (xy 91.241259 -288.140007) (xy 91.249013 -288.193928)
			(xy 91.2495 -288.221166) (xy 91.469716 -288.221166) (xy 91.473787 -288.165544) (xy 91.485913 -288.111107)
			(xy 91.505836 -288.059016) (xy 91.533132 -288.010381) (xy 91.567218 -287.966238) (xy 91.607367 -287.927529)
			(xy 91.652725 -287.895078) (xy 91.702325 -287.869577) (xy 91.755109 -287.85157) (xy 91.809952 -287.84144)
			(xy 91.865686 -287.839403) (xy 91.921123 -287.845503) (xy 91.97508 -287.859609) (xy 92.026409 -287.881421)
			(xy 92.074015 -287.910475) (xy 92.116883 -287.94615) (xy 92.1541 -287.987687) (xy 92.184873 -288.0342)
			(xy 92.208545 -288.084697) (xy 92.21873 -288.11855) (xy 92.517974 -288.11855) (xy 92.522045 -288.062928)
			(xy 92.534171 -288.008491) (xy 92.554094 -287.9564) (xy 92.58139 -287.907765) (xy 92.615476 -287.863622)
			(xy 92.655625 -287.824913) (xy 92.700983 -287.792462) (xy 92.750583 -287.766961) (xy 92.803367 -287.748954)
			(xy 92.85821 -287.738824) (xy 92.913944 -287.736787) (xy 92.969381 -287.742887) (xy 93.023338 -287.756993)
			(xy 93.074667 -287.778805) (xy 93.122273 -287.807859) (xy 93.165141 -287.843534) (xy 93.202358 -287.885071)
			(xy 93.233131 -287.931584) (xy 93.256803 -287.982081) (xy 93.272871 -288.035488) (xy 93.280991 -288.090664)
			(xy 93.2815 -288.11855) (xy 93.280991 -288.146436) (xy 93.272871 -288.201612) (xy 93.256803 -288.255019)
			(xy 93.233131 -288.305516) (xy 93.202358 -288.352029) (xy 93.165141 -288.393566) (xy 93.122273 -288.429241)
			(xy 93.074667 -288.458295) (xy 93.023338 -288.480107) (xy 92.969381 -288.494213) (xy 92.913944 -288.500313)
			(xy 92.85821 -288.498276) (xy 92.803367 -288.488146) (xy 92.750583 -288.470139) (xy 92.700983 -288.444638)
			(xy 92.655625 -288.412187) (xy 92.615476 -288.373478) (xy 92.58139 -288.329335) (xy 92.554094 -288.2807)
			(xy 92.534171 -288.228609) (xy 92.522045 -288.174172) (xy 92.517974 -288.11855) (xy 92.21873 -288.11855)
			(xy 92.224613 -288.138104) (xy 92.232733 -288.19328) (xy 92.233242 -288.221166) (xy 92.232733 -288.249052)
			(xy 92.224613 -288.304228) (xy 92.208545 -288.357635) (xy 92.184873 -288.408132) (xy 92.1541 -288.454645)
			(xy 92.116883 -288.496182) (xy 92.074015 -288.531857) (xy 92.026409 -288.560911) (xy 91.97508 -288.582723)
			(xy 91.921123 -288.596829) (xy 91.865686 -288.602929) (xy 91.809952 -288.600892) (xy 91.755109 -288.590762)
			(xy 91.702325 -288.572755) (xy 91.652725 -288.547254) (xy 91.607367 -288.514803) (xy 91.567218 -288.476094)
			(xy 91.533132 -288.431951) (xy 91.505836 -288.383316) (xy 91.485913 -288.331225) (xy 91.473787 -288.276788)
			(xy 91.469716 -288.221166) (xy 91.2495 -288.221166) (xy 91.249014 -288.248417) (xy 91.241258 -288.302365)
			(xy 91.225903 -288.35466) (xy 91.203261 -288.404237) (xy 91.173795 -288.450087) (xy 91.138104 -288.491278)
			(xy 91.096913 -288.526969) (xy 91.051063 -288.556435) (xy 91.001486 -288.579077) (xy 90.949191 -288.594432)
			(xy 90.895243 -288.602188) (xy 90.840741 -288.602188) (xy 90.786793 -288.594432) (xy 90.734498 -288.579077)
			(xy 90.684921 -288.556435) (xy 90.639071 -288.526969) (xy 90.59788 -288.491278) (xy 90.562189 -288.450087)
			(xy 90.532723 -288.404237) (xy 90.510081 -288.35466) (xy 90.494726 -288.302365) (xy 90.48697 -288.248417)
			(xy 90.486484 -288.221166) (xy 90.486989 -288.194006) (xy 90.494711 -288.140236) (xy 90.509967 -288.088101)
			(xy 90.520774 -288.063178) (xy 90.526495 -288.049459) (xy 90.530506 -288.020019) (xy 90.525873 -287.990671)
			(xy 90.512987 -287.963898) (xy 90.492939 -287.941969) (xy 90.467426 -287.92674) (xy 90.43861 -287.9195)
			(xy 90.423746 -287.919668) (xy 90.423238 -287.919668) (xy 90.405966 -287.920176) (xy 90.405712 -287.920176)
			(xy 90.37847 -287.919736) (xy 90.324546 -287.911945) (xy 90.272279 -287.896562) (xy 90.222731 -287.8739)
			(xy 90.176911 -287.84442) (xy 90.135751 -287.808722) (xy 90.100088 -287.767532) (xy 90.070646 -287.721688)
			(xy 90.048026 -287.672121) (xy 90.032687 -287.619841) (xy 90.024941 -287.56591) (xy 90.024458 -287.538668)
			(xy 89.666664 -287.538668) (xy 89.670268 -287.550941) (xy 89.678024 -287.604889) (xy 89.67851 -287.63214)
			(xy 89.67851 -287.632394) (xy 89.678181 -287.654965) (xy 89.672836 -287.699788) (xy 89.667842 -287.721802)
			(xy 89.665552 -287.734305) (xy 89.672077 -287.758835) (xy 89.680288 -287.768538) (xy 89.747598 -287.840166)
			(xy 89.771982 -287.84804) (xy 89.784682 -287.845754) (xy 89.801365 -287.842916) (xy 89.835071 -287.839863)
			(xy 89.851992 -287.839658) (xy 89.879246 -287.840147) (xy 89.9332 -287.847903) (xy 89.9855 -287.863259)
			(xy 90.035082 -287.885902) (xy 90.080938 -287.915371) (xy 90.122132 -287.951066) (xy 90.157828 -287.992261)
			(xy 90.187297 -288.038116) (xy 90.20994 -288.087698) (xy 90.225296 -288.139999) (xy 90.233053 -288.193952)
			(xy 90.233052 -288.24846) (xy 90.225294 -288.302413) (xy 90.209936 -288.354713) (xy 90.187291 -288.404295)
			(xy 90.157821 -288.450149) (xy 90.122124 -288.491342) (xy 90.080928 -288.527036) (xy 90.035072 -288.556504)
			(xy 89.985489 -288.579145) (xy 89.933188 -288.594499) (xy 89.879234 -288.602254) (xy 89.824726 -288.602251)
			(xy 89.770773 -288.594491) (xy 89.718474 -288.579131) (xy 89.668893 -288.556484) (xy 89.62304 -288.527012)
			(xy 89.581848 -288.491314) (xy 89.546155 -288.450117) (xy 89.51669 -288.40426) (xy 89.49405 -288.354675)
			(xy 89.478698 -288.302374) (xy 89.470945 -288.24842) (xy 89.470484 -288.221166) (xy 89.470484 -288.220912)
			(xy 89.470815 -288.198341) (xy 89.476158 -288.153518) (xy 89.481152 -288.131504) (xy 89.483439 -288.119)
			(xy 89.476916 -288.09447) (xy 89.468706 -288.084768) (xy 89.401142 -288.01314) (xy 89.377012 -288.005266)
			(xy 89.364312 -288.007552) (xy 89.349637 -288.010083) (xy 89.320013 -288.013137) (xy 89.30513 -288.013648)
			(xy 89.304876 -288.013648) (xy 89.2936 -288.014517) (xy 89.273425 -288.024664) (xy 89.266014 -288.033206)
			(xy 89.210388 -288.104326) (xy 89.205562 -288.12617) (xy 89.208102 -288.1376) (xy 89.21248 -288.158214)
			(xy 89.217191 -288.200094) (xy 89.2175 -288.221166) (xy 89.217013 -288.248418) (xy 89.20926 -288.302369)
			(xy 89.193908 -288.354667) (xy 89.171269 -288.404247) (xy 89.141804 -288.450101) (xy 89.106113 -288.491294)
			(xy 89.064922 -288.526988) (xy 89.01907 -288.556457) (xy 88.969491 -288.579099) (xy 88.917194 -288.594455)
			(xy 88.863244 -288.602211) (xy 88.835992 -288.602674) (xy 88.809874 -288.602262) (xy 88.758127 -288.595122)
			(xy 88.707839 -288.580991) (xy 88.659947 -288.560132) (xy 88.615349 -288.532936) (xy 88.574877 -288.49991)
			(xy 88.539288 -288.461673) (xy 88.509248 -288.418938) (xy 88.496902 -288.395918) (xy 88.490298 -288.383218)
			(xy 88.465914 -288.368232) (xy 88.347042 -288.368232) (xy 88.322658 -288.383218) (xy 88.316054 -288.395918)
			(xy 88.30371 -288.41894) (xy 88.273678 -288.461682) (xy 88.238093 -288.499925) (xy 88.197622 -288.532953)
			(xy 88.153021 -288.560148) (xy 88.105126 -288.581002) (xy 88.054833 -288.595123) (xy 88.003083 -288.602248)
			(xy 87.976964 -288.602674) (xy 87.949712 -288.602254) (xy 87.895763 -288.594492) (xy 87.843468 -288.579133)
			(xy 87.793891 -288.556487) (xy 87.748041 -288.527018) (xy 87.706852 -288.491323) (xy 87.671161 -288.45013)
			(xy 87.641695 -288.404277) (xy 87.619055 -288.354698) (xy 87.6037 -288.302401) (xy 87.595944 -288.248452)
			(xy 82.750339 -288.248452) (xy 82.75471 -288.274651) (xy 82.755232 -288.299906) (xy 82.755039 -288.314025)
			(xy 82.752372 -288.342138) (xy 82.749898 -288.35604) (xy 82.747612 -288.368486) (xy 82.754978 -288.392362)
			(xy 82.832448 -288.469832) (xy 82.856324 -288.477198) (xy 82.86877 -288.474912) (xy 82.882673 -288.472442)
			(xy 82.910785 -288.469775) (xy 82.924904 -288.469578) (xy 82.949725 -288.470082) (xy 82.998712 -288.478114)
			(xy 83.045755 -288.493965) (xy 83.089613 -288.517218) (xy 83.129132 -288.547261) (xy 83.163269 -288.583301)
			(xy 83.191127 -288.624389) (xy 83.21197 -288.669443) (xy 83.225249 -288.717275) (xy 83.230615 -288.766626)
			(xy 83.227926 -288.816194) (xy 83.217254 -288.864675) (xy 83.198878 -288.91079) (xy 83.173284 -288.953325)
			(xy 83.141146 -288.991159) (xy 83.10331 -289.023295) (xy 83.060774 -289.048886) (xy 83.014658 -289.067259)
			(xy 82.966176 -289.077929) (xy 82.916608 -289.080615) (xy 82.867257 -289.075246) (xy 82.819426 -289.061963)
			(xy 82.774373 -289.041118) (xy 82.733287 -289.013258) (xy 82.697249 -288.979118) (xy 82.667209 -288.939598)
			(xy 82.643958 -288.895738) (xy 82.62811 -288.848695) (xy 82.620081 -288.799707) (xy 82.619596 -288.774886)
			(xy 82.619787 -288.760767) (xy 82.622455 -288.732654) (xy 82.62493 -288.718752) (xy 82.627216 -288.706306)
			(xy 82.61985 -288.68243) (xy 82.54238 -288.60496) (xy 82.518504 -288.597594) (xy 82.506058 -288.59988)
			(xy 82.492155 -288.602346) (xy 82.464043 -288.605015) (xy 82.449924 -288.605214) (xy 82.435805 -288.605031)
			(xy 82.407692 -288.602357) (xy 82.39379 -288.59988) (xy 82.381344 -288.597594) (xy 82.357468 -288.60496)
			(xy 82.279998 -288.68243) (xy 82.272632 -288.706306) (xy 82.274918 -288.718752) (xy 82.277385 -288.732655)
			(xy 82.280054 -288.760767) (xy 82.280252 -288.774886) (xy 82.27973 -288.800141) (xy 82.271417 -288.849963)
			(xy 82.255016 -288.897737) (xy 82.230975 -288.94216) (xy 82.199951 -288.98202) (xy 82.162789 -289.01623)
			(xy 82.120503 -289.043856) (xy 82.074247 -289.064146) (xy 82.025282 -289.076546) (xy 81.974944 -289.080717)
			(xy 81.924606 -289.076546) (xy 81.875641 -289.064146) (xy 81.829385 -289.043856) (xy 81.787099 -289.01623)
			(xy 81.749937 -288.98202) (xy 81.718913 -288.94216) (xy 81.694872 -288.897737) (xy 81.678471 -288.849963)
			(xy 81.670158 -288.800141) (xy 81.669636 -288.774886) (xy 81.669828 -288.760767) (xy 81.672496 -288.732654)
			(xy 81.67497 -288.718752) (xy 81.677256 -288.706306) (xy 81.66989 -288.68243) (xy 81.59242 -288.60496)
			(xy 81.568544 -288.597594) (xy 81.556098 -288.59988) (xy 81.542194 -288.60234) (xy 81.514083 -288.605013)
			(xy 81.499964 -288.605214) (xy 81.485845 -288.605026) (xy 81.457732 -288.602355) (xy 81.44383 -288.59988)
			(xy 81.431384 -288.597594) (xy 81.407508 -288.60496) (xy 81.330038 -288.68243) (xy 81.322672 -288.706306)
			(xy 81.324958 -288.718752) (xy 81.327425 -288.732655) (xy 81.330094 -288.760767) (xy 81.330292 -288.774886)
			(xy 81.32977 -288.800141) (xy 81.321457 -288.849963) (xy 81.305056 -288.897737) (xy 81.281015 -288.94216)
			(xy 81.249991 -288.98202) (xy 81.212829 -289.01623) (xy 81.170543 -289.043856) (xy 81.124287 -289.064146)
			(xy 81.075322 -289.076546) (xy 81.024984 -289.080717) (xy 80.974646 -289.076546) (xy 80.925681 -289.064146)
			(xy 80.879425 -289.043856) (xy 80.837139 -289.01623) (xy 80.799977 -288.98202) (xy 80.768953 -288.94216)
			(xy 80.744912 -288.897737) (xy 80.728511 -288.849963) (xy 80.720198 -288.800141) (xy 80.719676 -288.774886)
			(xy 80.719676 -288.774632) (xy 80.719754 -288.764825) (xy 80.721027 -288.745251) (xy 80.722216 -288.735516)
			(xy 80.722724 -288.732214) (xy 80.722724 -288.728658) (xy 80.722168 -288.718451) (xy 80.714054 -288.69971)
			(xy 80.706976 -288.692336) (xy 80.648048 -288.635694) (xy 80.639067 -288.62792) (xy 80.616415 -288.62089)
			(xy 80.604614 -288.622232) (xy 80.60436 -288.622232) (xy 80.590873 -288.624375) (xy 80.563659 -288.626666)
			(xy 80.550004 -288.626804) (xy 80.549496 -288.626804) (xy 80.535969 -288.626631) (xy 80.509011 -288.624342)
			(xy 80.495648 -288.622232) (xy 80.49514 -288.622232) (xy 80.483202 -288.620454) (xy 80.472026 -288.623756)
			(xy 80.466287 -288.625668) (xy 80.455882 -288.63183) (xy 80.451452 -288.635948) (xy 80.383888 -288.700972)
			(xy 80.376014 -288.723578) (xy 80.377538 -288.735516) (xy 80.378715 -288.745252) (xy 80.379989 -288.764825)
			(xy 80.380078 -288.774632) (xy 80.380078 -288.774886) (xy 80.379556 -288.800141) (xy 80.371243 -288.849963)
			(xy 80.354842 -288.897737) (xy 80.330801 -288.94216) (xy 80.299777 -288.98202) (xy 80.262615 -289.01623)
			(xy 80.220329 -289.043856) (xy 80.174073 -289.064146) (xy 80.125108 -289.076546) (xy 80.07477 -289.080717)
			(xy 80.024432 -289.076546) (xy 79.975467 -289.064146) (xy 79.929211 -289.043856) (xy 79.886925 -289.01623)
			(xy 79.849763 -288.98202) (xy 79.818739 -288.94216) (xy 79.794698 -288.897737) (xy 79.778297 -288.849963)
			(xy 79.769984 -288.800141) (xy 79.769462 -288.774886) (xy 79.769462 -288.774632) (xy 79.76954 -288.764825)
			(xy 79.770813 -288.745251) (xy 79.772002 -288.735516) (xy 79.773526 -288.723578) (xy 79.765652 -288.700972)
			(xy 79.698088 -288.635948) (xy 79.693627 -288.631871) (xy 79.683233 -288.625709) (xy 79.677514 -288.623756)
			(xy 79.666338 -288.620454) (xy 79.6544 -288.622232) (xy 79.653892 -288.622232) (xy 79.640532 -288.624363)
			(xy 79.613572 -288.626649) (xy 79.600044 -288.626804) (xy 79.599536 -288.626804) (xy 79.586009 -288.626626)
			(xy 79.559051 -288.62434) (xy 79.545688 -288.622232) (xy 79.54518 -288.622232) (xy 79.533242 -288.620454)
			(xy 79.522066 -288.623756) (xy 79.516321 -288.625651) (xy 79.505919 -288.631824) (xy 79.501492 -288.635948)
			(xy 79.433928 -288.700972) (xy 79.426054 -288.723578) (xy 79.427578 -288.735516) (xy 79.428755 -288.745252)
			(xy 79.430029 -288.764825) (xy 79.430118 -288.774632) (xy 79.430118 -288.774886) (xy 79.429596 -288.800141)
			(xy 79.421283 -288.849963) (xy 79.404882 -288.897737) (xy 79.380841 -288.94216) (xy 79.349817 -288.98202)
			(xy 79.312655 -289.01623) (xy 79.270369 -289.043856) (xy 79.224113 -289.064146) (xy 79.175148 -289.076546)
			(xy 79.12481 -289.080717) (xy 79.074472 -289.076546) (xy 79.025507 -289.064146) (xy 78.979251 -289.043856)
			(xy 78.936965 -289.01623) (xy 78.899803 -288.98202) (xy 78.868779 -288.94216) (xy 78.844738 -288.897737)
			(xy 78.828337 -288.849963) (xy 78.820024 -288.800141) (xy 78.819502 -288.774886) (xy 78.819693 -288.760767)
			(xy 78.822361 -288.732654) (xy 78.824836 -288.718752) (xy 78.827122 -288.706306) (xy 78.819756 -288.68243)
			(xy 78.742286 -288.60496) (xy 78.71841 -288.597594) (xy 78.705964 -288.59988) (xy 78.692061 -288.602345)
			(xy 78.663949 -288.605015) (xy 78.64983 -288.605214) (xy 78.625006 -288.604754) (xy 78.576012 -288.596727)
			(xy 78.528961 -288.580879) (xy 78.485095 -288.557627) (xy 78.445568 -288.527584) (xy 78.411422 -288.491543)
			(xy 78.383558 -288.450452) (xy 78.362708 -288.405394) (xy 78.349423 -288.357557) (xy 78.344052 -288.308201)
			(xy 78.005011 -288.308201) (xy 78.004683 -288.324513) (xy 77.996788 -288.37309) (xy 77.981204 -288.419771)
			(xy 77.958333 -288.463348) (xy 77.928768 -288.502692) (xy 77.893275 -288.536784) (xy 77.852772 -288.56474)
			(xy 77.80831 -288.585838) (xy 77.761039 -288.59953) (xy 77.712184 -288.605462) (xy 77.663009 -288.603481)
			(xy 77.61479 -288.593637) (xy 77.568774 -288.576185) (xy 77.526153 -288.551578) (xy 77.488032 -288.520453)
			(xy 77.455397 -288.483616) (xy 77.429094 -288.44202) (xy 77.409803 -288.396744) (xy 77.398026 -288.34896)
			(xy 77.394066 -288.299906) (xy 77.055218 -288.299906) (xy 77.054723 -288.324513) (xy 77.046828 -288.37309)
			(xy 77.031244 -288.419771) (xy 77.008373 -288.463348) (xy 76.978808 -288.502692) (xy 76.943315 -288.536784)
			(xy 76.902812 -288.56474) (xy 76.85835 -288.585838) (xy 76.811079 -288.59953) (xy 76.762224 -288.605462)
			(xy 76.713049 -288.603481) (xy 76.66483 -288.593637) (xy 76.618814 -288.576185) (xy 76.576193 -288.551578)
			(xy 76.538072 -288.520453) (xy 76.505437 -288.483616) (xy 76.479134 -288.44202) (xy 76.459843 -288.396744)
			(xy 76.448066 -288.34896) (xy 76.444106 -288.299906) (xy 76.105258 -288.299906) (xy 76.104763 -288.324513)
			(xy 76.096868 -288.37309) (xy 76.081284 -288.419771) (xy 76.058413 -288.463348) (xy 76.028848 -288.502692)
			(xy 75.993355 -288.536784) (xy 75.952852 -288.56474) (xy 75.90839 -288.585838) (xy 75.861119 -288.59953)
			(xy 75.812264 -288.605462) (xy 75.763089 -288.603481) (xy 75.71487 -288.593637) (xy 75.668854 -288.576185)
			(xy 75.626233 -288.551578) (xy 75.588112 -288.520453) (xy 75.555477 -288.483616) (xy 75.529174 -288.44202)
			(xy 75.509883 -288.396744) (xy 75.498106 -288.34896) (xy 75.494146 -288.299906) (xy 75.155298 -288.299906)
			(xy 75.154803 -288.324513) (xy 75.146908 -288.37309) (xy 75.131324 -288.419771) (xy 75.108453 -288.463348)
			(xy 75.078888 -288.502692) (xy 75.043395 -288.536784) (xy 75.002892 -288.56474) (xy 74.95843 -288.585838)
			(xy 74.911159 -288.59953) (xy 74.862304 -288.605462) (xy 74.813129 -288.603481) (xy 74.76491 -288.593637)
			(xy 74.718894 -288.576185) (xy 74.676273 -288.551578) (xy 74.638152 -288.520453) (xy 74.605517 -288.483616)
			(xy 74.579214 -288.44202) (xy 74.559923 -288.396744) (xy 74.548146 -288.34896) (xy 74.544186 -288.299906)
			(xy 74.205084 -288.299906) (xy 74.204589 -288.324513) (xy 74.196694 -288.37309) (xy 74.18111 -288.419771)
			(xy 74.158239 -288.463348) (xy 74.128674 -288.502692) (xy 74.093181 -288.536784) (xy 74.052678 -288.56474)
			(xy 74.008216 -288.585838) (xy 73.960945 -288.59953) (xy 73.91209 -288.605462) (xy 73.862915 -288.603481)
			(xy 73.814696 -288.593637) (xy 73.76868 -288.576185) (xy 73.726059 -288.551578) (xy 73.687938 -288.520453)
			(xy 73.655303 -288.483616) (xy 73.629 -288.44202) (xy 73.609709 -288.396744) (xy 73.597932 -288.34896)
			(xy 73.593972 -288.299906) (xy 48.06823 -288.299906) (xy 48.06823 -288.683446) (xy 48.070008 -288.696654)
			(xy 48.07077 -288.699702) (xy 48.075166 -288.718186) (xy 48.079873 -288.755888) (xy 48.080168 -288.774886)
			(xy 48.419016 -288.774886) (xy 48.422976 -288.725832) (xy 48.434753 -288.678048) (xy 48.454044 -288.632772)
			(xy 48.480347 -288.591176) (xy 48.512982 -288.554339) (xy 48.551103 -288.523214) (xy 48.593724 -288.498607)
			(xy 48.63974 -288.481155) (xy 48.687959 -288.471311) (xy 48.737134 -288.46933) (xy 48.785989 -288.475262)
			(xy 48.83326 -288.488954) (xy 48.877722 -288.510052) (xy 48.918225 -288.538008) (xy 48.953718 -288.5721)
			(xy 48.983283 -288.611444) (xy 49.006154 -288.655021) (xy 49.021738 -288.701702) (xy 49.029633 -288.750279)
			(xy 49.030128 -288.774886) (xy 49.368976 -288.774886) (xy 49.372936 -288.725832) (xy 49.384713 -288.678048)
			(xy 49.404004 -288.632772) (xy 49.430307 -288.591176) (xy 49.462942 -288.554339) (xy 49.501063 -288.523214)
			(xy 49.543684 -288.498607) (xy 49.5897 -288.481155) (xy 49.637919 -288.471311) (xy 49.687094 -288.46933)
			(xy 49.735949 -288.475262) (xy 49.78322 -288.488954) (xy 49.827682 -288.510052) (xy 49.868185 -288.538008)
			(xy 49.903678 -288.5721) (xy 49.933243 -288.611444) (xy 49.956114 -288.655021) (xy 49.971698 -288.701702)
			(xy 49.979593 -288.750279) (xy 49.980088 -288.774886) (xy 50.31919 -288.774886) (xy 50.32315 -288.725832)
			(xy 50.334927 -288.678048) (xy 50.354218 -288.632772) (xy 50.380521 -288.591176) (xy 50.413156 -288.554339)
			(xy 50.451277 -288.523214) (xy 50.493898 -288.498607) (xy 50.539914 -288.481155) (xy 50.588133 -288.471311)
			(xy 50.637308 -288.46933) (xy 50.686163 -288.475262) (xy 50.733434 -288.488954) (xy 50.777896 -288.510052)
			(xy 50.818399 -288.538008) (xy 50.853892 -288.5721) (xy 50.883457 -288.611444) (xy 50.906328 -288.655021)
			(xy 50.921912 -288.701702) (xy 50.929807 -288.750279) (xy 50.930302 -288.774886) (xy 51.26915 -288.774886)
			(xy 51.27311 -288.725832) (xy 51.284887 -288.678048) (xy 51.304178 -288.632772) (xy 51.330481 -288.591176)
			(xy 51.363116 -288.554339) (xy 51.401237 -288.523214) (xy 51.443858 -288.498607) (xy 51.489874 -288.481155)
			(xy 51.538093 -288.471311) (xy 51.587268 -288.46933) (xy 51.636123 -288.475262) (xy 51.683394 -288.488954)
			(xy 51.727856 -288.510052) (xy 51.768359 -288.538008) (xy 51.803852 -288.5721) (xy 51.833417 -288.611444)
			(xy 51.856288 -288.655021) (xy 51.871872 -288.701702) (xy 51.879767 -288.750279) (xy 51.880262 -288.774886)
			(xy 52.21911 -288.774886) (xy 52.22307 -288.725832) (xy 52.234847 -288.678048) (xy 52.254138 -288.632772)
			(xy 52.280441 -288.591176) (xy 52.313076 -288.554339) (xy 52.351197 -288.523214) (xy 52.393818 -288.498607)
			(xy 52.439834 -288.481155) (xy 52.488053 -288.471311) (xy 52.537228 -288.46933) (xy 52.586083 -288.475262)
			(xy 52.633354 -288.488954) (xy 52.677816 -288.510052) (xy 52.718319 -288.538008) (xy 52.753812 -288.5721)
			(xy 52.783377 -288.611444) (xy 52.806248 -288.655021) (xy 52.821832 -288.701702) (xy 52.829727 -288.750279)
			(xy 52.830222 -288.774886) (xy 53.16907 -288.774886) (xy 53.17303 -288.725832) (xy 53.184807 -288.678048)
			(xy 53.204098 -288.632772) (xy 53.230401 -288.591176) (xy 53.263036 -288.554339) (xy 53.301157 -288.523214)
			(xy 53.343778 -288.498607) (xy 53.389794 -288.481155) (xy 53.438013 -288.471311) (xy 53.487188 -288.46933)
			(xy 53.536043 -288.475262) (xy 53.583314 -288.488954) (xy 53.627776 -288.510052) (xy 53.668279 -288.538008)
			(xy 53.703772 -288.5721) (xy 53.733337 -288.611444) (xy 53.756208 -288.655021) (xy 53.771792 -288.701702)
			(xy 53.779687 -288.750279) (xy 53.780182 -288.774886) (xy 54.11903 -288.774886) (xy 54.12299 -288.725832)
			(xy 54.134767 -288.678048) (xy 54.154058 -288.632772) (xy 54.180361 -288.591176) (xy 54.212996 -288.554339)
			(xy 54.251117 -288.523214) (xy 54.293738 -288.498607) (xy 54.339754 -288.481155) (xy 54.387973 -288.471311)
			(xy 54.437148 -288.46933) (xy 54.486003 -288.475262) (xy 54.533274 -288.488954) (xy 54.577736 -288.510052)
			(xy 54.618239 -288.538008) (xy 54.653732 -288.5721) (xy 54.683297 -288.611444) (xy 54.706168 -288.655021)
			(xy 54.721752 -288.701702) (xy 54.729647 -288.750279) (xy 54.730142 -288.774886) (xy 55.06899 -288.774886)
			(xy 55.07295 -288.725832) (xy 55.084727 -288.678048) (xy 55.104018 -288.632772) (xy 55.130321 -288.591176)
			(xy 55.162956 -288.554339) (xy 55.201077 -288.523214) (xy 55.243698 -288.498607) (xy 55.289714 -288.481155)
			(xy 55.337933 -288.471311) (xy 55.387108 -288.46933) (xy 55.435963 -288.475262) (xy 55.483234 -288.488954)
			(xy 55.527696 -288.510052) (xy 55.568199 -288.538008) (xy 55.603692 -288.5721) (xy 55.633257 -288.611444)
			(xy 55.656128 -288.655021) (xy 55.671712 -288.701702) (xy 55.679607 -288.750279) (xy 55.680102 -288.774886)
			(xy 56.01895 -288.774886) (xy 56.02291 -288.725832) (xy 56.034687 -288.678048) (xy 56.053978 -288.632772)
			(xy 56.080281 -288.591176) (xy 56.112916 -288.554339) (xy 56.151037 -288.523214) (xy 56.193658 -288.498607)
			(xy 56.239674 -288.481155) (xy 56.287893 -288.471311) (xy 56.337068 -288.46933) (xy 56.385923 -288.475262)
			(xy 56.433194 -288.488954) (xy 56.477656 -288.510052) (xy 56.518159 -288.538008) (xy 56.553652 -288.5721)
			(xy 56.583217 -288.611444) (xy 56.606088 -288.655021) (xy 56.621672 -288.701702) (xy 56.629567 -288.750279)
			(xy 56.630062 -288.774886) (xy 56.969164 -288.774886) (xy 56.973124 -288.725832) (xy 56.984901 -288.678048)
			(xy 57.004192 -288.632772) (xy 57.030495 -288.591176) (xy 57.06313 -288.554339) (xy 57.101251 -288.523214)
			(xy 57.143872 -288.498607) (xy 57.189888 -288.481155) (xy 57.238107 -288.471311) (xy 57.287282 -288.46933)
			(xy 57.336137 -288.475262) (xy 57.383408 -288.488954) (xy 57.42787 -288.510052) (xy 57.468373 -288.538008)
			(xy 57.503866 -288.5721) (xy 57.533431 -288.611444) (xy 57.556302 -288.655021) (xy 57.571886 -288.701702)
			(xy 57.579781 -288.750279) (xy 57.580276 -288.774886) (xy 57.919124 -288.774886) (xy 57.923084 -288.725832)
			(xy 57.934861 -288.678048) (xy 57.954152 -288.632772) (xy 57.980455 -288.591176) (xy 58.01309 -288.554339)
			(xy 58.051211 -288.523214) (xy 58.093832 -288.498607) (xy 58.139848 -288.481155) (xy 58.188067 -288.471311)
			(xy 58.237242 -288.46933) (xy 58.286097 -288.475262) (xy 58.333368 -288.488954) (xy 58.37783 -288.510052)
			(xy 58.418333 -288.538008) (xy 58.453826 -288.5721) (xy 58.483391 -288.611444) (xy 58.506262 -288.655021)
			(xy 58.521846 -288.701702) (xy 58.529741 -288.750279) (xy 58.530236 -288.774886) (xy 59.819044 -288.774886)
			(xy 59.823004 -288.725832) (xy 59.834781 -288.678048) (xy 59.854072 -288.632772) (xy 59.880375 -288.591176)
			(xy 59.91301 -288.554339) (xy 59.951131 -288.523214) (xy 59.993752 -288.498607) (xy 60.039768 -288.481155)
			(xy 60.087987 -288.471311) (xy 60.137162 -288.46933) (xy 60.186017 -288.475262) (xy 60.233288 -288.488954)
			(xy 60.27775 -288.510052) (xy 60.318253 -288.538008) (xy 60.353746 -288.5721) (xy 60.383311 -288.611444)
			(xy 60.406182 -288.655021) (xy 60.421766 -288.701702) (xy 60.429661 -288.750279) (xy 60.430156 -288.774886)
			(xy 60.769004 -288.774886) (xy 60.772964 -288.725832) (xy 60.784741 -288.678048) (xy 60.804032 -288.632772)
			(xy 60.830335 -288.591176) (xy 60.86297 -288.554339) (xy 60.901091 -288.523214) (xy 60.943712 -288.498607)
			(xy 60.989728 -288.481155) (xy 61.037947 -288.471311) (xy 61.087122 -288.46933) (xy 61.135977 -288.475262)
			(xy 61.183248 -288.488954) (xy 61.22771 -288.510052) (xy 61.268213 -288.538008) (xy 61.303706 -288.5721)
			(xy 61.333271 -288.611444) (xy 61.356142 -288.655021) (xy 61.371726 -288.701702) (xy 61.379621 -288.750279)
			(xy 61.380116 -288.774886) (xy 61.718964 -288.774886) (xy 61.722924 -288.725832) (xy 61.734701 -288.678048)
			(xy 61.753992 -288.632772) (xy 61.780295 -288.591176) (xy 61.81293 -288.554339) (xy 61.851051 -288.523214)
			(xy 61.893672 -288.498607) (xy 61.939688 -288.481155) (xy 61.987907 -288.471311) (xy 62.037082 -288.46933)
			(xy 62.085937 -288.475262) (xy 62.133208 -288.488954) (xy 62.17767 -288.510052) (xy 62.218173 -288.538008)
			(xy 62.253666 -288.5721) (xy 62.283231 -288.611444) (xy 62.306102 -288.655021) (xy 62.321686 -288.701702)
			(xy 62.329581 -288.750279) (xy 62.330076 -288.774886) (xy 62.669178 -288.774886) (xy 62.673138 -288.725832)
			(xy 62.684915 -288.678048) (xy 62.704206 -288.632772) (xy 62.730509 -288.591176) (xy 62.763144 -288.554339)
			(xy 62.801265 -288.523214) (xy 62.843886 -288.498607) (xy 62.889902 -288.481155) (xy 62.938121 -288.471311)
			(xy 62.987296 -288.46933) (xy 63.036151 -288.475262) (xy 63.083422 -288.488954) (xy 63.127884 -288.510052)
			(xy 63.168387 -288.538008) (xy 63.20388 -288.5721) (xy 63.233445 -288.611444) (xy 63.256316 -288.655021)
			(xy 63.2719 -288.701702) (xy 63.279795 -288.750279) (xy 63.28029 -288.774886) (xy 63.619138 -288.774886)
			(xy 63.623098 -288.725832) (xy 63.634875 -288.678048) (xy 63.654166 -288.632772) (xy 63.680469 -288.591176)
			(xy 63.713104 -288.554339) (xy 63.751225 -288.523214) (xy 63.793846 -288.498607) (xy 63.839862 -288.481155)
			(xy 63.888081 -288.471311) (xy 63.937256 -288.46933) (xy 63.986111 -288.475262) (xy 64.033382 -288.488954)
			(xy 64.077844 -288.510052) (xy 64.118347 -288.538008) (xy 64.15384 -288.5721) (xy 64.183405 -288.611444)
			(xy 64.206276 -288.655021) (xy 64.22186 -288.701702) (xy 64.229755 -288.750279) (xy 64.23025 -288.774886)
			(xy 64.569098 -288.774886) (xy 64.573058 -288.725832) (xy 64.584835 -288.678048) (xy 64.604126 -288.632772)
			(xy 64.630429 -288.591176) (xy 64.663064 -288.554339) (xy 64.701185 -288.523214) (xy 64.743806 -288.498607)
			(xy 64.789822 -288.481155) (xy 64.838041 -288.471311) (xy 64.887216 -288.46933) (xy 64.936071 -288.475262)
			(xy 64.983342 -288.488954) (xy 65.027804 -288.510052) (xy 65.068307 -288.538008) (xy 65.1038 -288.5721)
			(xy 65.133365 -288.611444) (xy 65.156236 -288.655021) (xy 65.17182 -288.701702) (xy 65.179715 -288.750279)
			(xy 65.18021 -288.774886) (xy 65.519058 -288.774886) (xy 65.523018 -288.725832) (xy 65.534795 -288.678048)
			(xy 65.554086 -288.632772) (xy 65.580389 -288.591176) (xy 65.613024 -288.554339) (xy 65.651145 -288.523214)
			(xy 65.693766 -288.498607) (xy 65.739782 -288.481155) (xy 65.788001 -288.471311) (xy 65.837176 -288.46933)
			(xy 65.886031 -288.475262) (xy 65.933302 -288.488954) (xy 65.977764 -288.510052) (xy 66.018267 -288.538008)
			(xy 66.05376 -288.5721) (xy 66.083325 -288.611444) (xy 66.106196 -288.655021) (xy 66.12178 -288.701702)
			(xy 66.129675 -288.750279) (xy 66.13017 -288.774886) (xy 66.469018 -288.774886) (xy 66.472978 -288.725832)
			(xy 66.484755 -288.678048) (xy 66.504046 -288.632772) (xy 66.530349 -288.591176) (xy 66.562984 -288.554339)
			(xy 66.601105 -288.523214) (xy 66.643726 -288.498607) (xy 66.689742 -288.481155) (xy 66.737961 -288.471311)
			(xy 66.787136 -288.46933) (xy 66.835991 -288.475262) (xy 66.883262 -288.488954) (xy 66.927724 -288.510052)
			(xy 66.968227 -288.538008) (xy 67.00372 -288.5721) (xy 67.033285 -288.611444) (xy 67.056156 -288.655021)
			(xy 67.07174 -288.701702) (xy 67.079635 -288.750279) (xy 67.08013 -288.774886) (xy 67.418978 -288.774886)
			(xy 67.422938 -288.725832) (xy 67.434715 -288.678048) (xy 67.454006 -288.632772) (xy 67.480309 -288.591176)
			(xy 67.512944 -288.554339) (xy 67.551065 -288.523214) (xy 67.593686 -288.498607) (xy 67.639702 -288.481155)
			(xy 67.687921 -288.471311) (xy 67.737096 -288.46933) (xy 67.785951 -288.475262) (xy 67.833222 -288.488954)
			(xy 67.877684 -288.510052) (xy 67.918187 -288.538008) (xy 67.95368 -288.5721) (xy 67.983245 -288.611444)
			(xy 68.006116 -288.655021) (xy 68.0217 -288.701702) (xy 68.029595 -288.750279) (xy 68.03009 -288.774886)
			(xy 68.368938 -288.774886) (xy 68.372898 -288.725832) (xy 68.384675 -288.678048) (xy 68.403966 -288.632772)
			(xy 68.430269 -288.591176) (xy 68.462904 -288.554339) (xy 68.501025 -288.523214) (xy 68.543646 -288.498607)
			(xy 68.589662 -288.481155) (xy 68.637881 -288.471311) (xy 68.687056 -288.46933) (xy 68.735911 -288.475262)
			(xy 68.783182 -288.488954) (xy 68.827644 -288.510052) (xy 68.868147 -288.538008) (xy 68.90364 -288.5721)
			(xy 68.933205 -288.611444) (xy 68.956076 -288.655021) (xy 68.97166 -288.701702) (xy 68.979555 -288.750279)
			(xy 68.98005 -288.774886) (xy 69.319152 -288.774886) (xy 69.323112 -288.725832) (xy 69.334889 -288.678048)
			(xy 69.35418 -288.632772) (xy 69.380483 -288.591176) (xy 69.413118 -288.554339) (xy 69.451239 -288.523214)
			(xy 69.49386 -288.498607) (xy 69.539876 -288.481155) (xy 69.588095 -288.471311) (xy 69.63727 -288.46933)
			(xy 69.686125 -288.475262) (xy 69.733396 -288.488954) (xy 69.777858 -288.510052) (xy 69.818361 -288.538008)
			(xy 69.853854 -288.5721) (xy 69.883419 -288.611444) (xy 69.90629 -288.655021) (xy 69.921874 -288.701702)
			(xy 69.929769 -288.750279) (xy 69.930264 -288.774886) (xy 70.269112 -288.774886) (xy 70.273072 -288.725832)
			(xy 70.284849 -288.678048) (xy 70.30414 -288.632772) (xy 70.330443 -288.591176) (xy 70.363078 -288.554339)
			(xy 70.401199 -288.523214) (xy 70.44382 -288.498607) (xy 70.489836 -288.481155) (xy 70.538055 -288.471311)
			(xy 70.58723 -288.46933) (xy 70.636085 -288.475262) (xy 70.683356 -288.488954) (xy 70.727818 -288.510052)
			(xy 70.768321 -288.538008) (xy 70.803814 -288.5721) (xy 70.833379 -288.611444) (xy 70.85625 -288.655021)
			(xy 70.871834 -288.701702) (xy 70.879729 -288.750279) (xy 70.880224 -288.774886) (xy 71.219072 -288.774886)
			(xy 71.223032 -288.725832) (xy 71.234809 -288.678048) (xy 71.2541 -288.632772) (xy 71.280403 -288.591176)
			(xy 71.313038 -288.554339) (xy 71.351159 -288.523214) (xy 71.39378 -288.498607) (xy 71.439796 -288.481155)
			(xy 71.488015 -288.471311) (xy 71.53719 -288.46933) (xy 71.586045 -288.475262) (xy 71.633316 -288.488954)
			(xy 71.677778 -288.510052) (xy 71.718281 -288.538008) (xy 71.753774 -288.5721) (xy 71.783339 -288.611444)
			(xy 71.80621 -288.655021) (xy 71.821794 -288.701702) (xy 71.829689 -288.750279) (xy 71.830184 -288.774886)
			(xy 72.169032 -288.774886) (xy 72.172992 -288.725832) (xy 72.184769 -288.678048) (xy 72.20406 -288.632772)
			(xy 72.230363 -288.591176) (xy 72.262998 -288.554339) (xy 72.301119 -288.523214) (xy 72.34374 -288.498607)
			(xy 72.389756 -288.481155) (xy 72.437975 -288.471311) (xy 72.48715 -288.46933) (xy 72.536005 -288.475262)
			(xy 72.583276 -288.488954) (xy 72.627738 -288.510052) (xy 72.668241 -288.538008) (xy 72.703734 -288.5721)
			(xy 72.733299 -288.611444) (xy 72.75617 -288.655021) (xy 72.771754 -288.701702) (xy 72.779649 -288.750279)
			(xy 72.780144 -288.774886) (xy 72.779649 -288.799493) (xy 72.771754 -288.84807) (xy 72.75617 -288.894751)
			(xy 72.733299 -288.938328) (xy 72.703734 -288.977672) (xy 72.668241 -289.011764) (xy 72.627738 -289.03972)
			(xy 72.583276 -289.060818) (xy 72.536005 -289.07451) (xy 72.48715 -289.080442) (xy 72.437975 -289.078461)
			(xy 72.389756 -289.068617) (xy 72.34374 -289.051165) (xy 72.301119 -289.026558) (xy 72.262998 -288.995433)
			(xy 72.230363 -288.958596) (xy 72.20406 -288.917) (xy 72.184769 -288.871724) (xy 72.172992 -288.82394)
			(xy 72.169032 -288.774886) (xy 71.830184 -288.774886) (xy 71.829689 -288.799493) (xy 71.821794 -288.84807)
			(xy 71.80621 -288.894751) (xy 71.783339 -288.938328) (xy 71.753774 -288.977672) (xy 71.718281 -289.011764)
			(xy 71.677778 -289.03972) (xy 71.633316 -289.060818) (xy 71.586045 -289.07451) (xy 71.53719 -289.080442)
			(xy 71.488015 -289.078461) (xy 71.439796 -289.068617) (xy 71.39378 -289.051165) (xy 71.351159 -289.026558)
			(xy 71.313038 -288.995433) (xy 71.280403 -288.958596) (xy 71.2541 -288.917) (xy 71.234809 -288.871724)
			(xy 71.223032 -288.82394) (xy 71.219072 -288.774886) (xy 70.880224 -288.774886) (xy 70.879729 -288.799493)
			(xy 70.871834 -288.84807) (xy 70.85625 -288.894751) (xy 70.833379 -288.938328) (xy 70.803814 -288.977672)
			(xy 70.768321 -289.011764) (xy 70.727818 -289.03972) (xy 70.683356 -289.060818) (xy 70.636085 -289.07451)
			(xy 70.58723 -289.080442) (xy 70.538055 -289.078461) (xy 70.489836 -289.068617) (xy 70.44382 -289.051165)
			(xy 70.401199 -289.026558) (xy 70.363078 -288.995433) (xy 70.330443 -288.958596) (xy 70.30414 -288.917)
			(xy 70.284849 -288.871724) (xy 70.273072 -288.82394) (xy 70.269112 -288.774886) (xy 69.930264 -288.774886)
			(xy 69.929769 -288.799493) (xy 69.921874 -288.84807) (xy 69.90629 -288.894751) (xy 69.883419 -288.938328)
			(xy 69.853854 -288.977672) (xy 69.818361 -289.011764) (xy 69.777858 -289.03972) (xy 69.733396 -289.060818)
			(xy 69.686125 -289.07451) (xy 69.63727 -289.080442) (xy 69.588095 -289.078461) (xy 69.539876 -289.068617)
			(xy 69.49386 -289.051165) (xy 69.451239 -289.026558) (xy 69.413118 -288.995433) (xy 69.380483 -288.958596)
			(xy 69.35418 -288.917) (xy 69.334889 -288.871724) (xy 69.323112 -288.82394) (xy 69.319152 -288.774886)
			(xy 68.98005 -288.774886) (xy 68.979555 -288.799493) (xy 68.97166 -288.84807) (xy 68.956076 -288.894751)
			(xy 68.933205 -288.938328) (xy 68.90364 -288.977672) (xy 68.868147 -289.011764) (xy 68.827644 -289.03972)
			(xy 68.783182 -289.060818) (xy 68.735911 -289.07451) (xy 68.687056 -289.080442) (xy 68.637881 -289.078461)
			(xy 68.589662 -289.068617) (xy 68.543646 -289.051165) (xy 68.501025 -289.026558) (xy 68.462904 -288.995433)
			(xy 68.430269 -288.958596) (xy 68.403966 -288.917) (xy 68.384675 -288.871724) (xy 68.372898 -288.82394)
			(xy 68.368938 -288.774886) (xy 68.03009 -288.774886) (xy 68.029595 -288.799493) (xy 68.0217 -288.84807)
			(xy 68.006116 -288.894751) (xy 67.983245 -288.938328) (xy 67.95368 -288.977672) (xy 67.918187 -289.011764)
			(xy 67.877684 -289.03972) (xy 67.833222 -289.060818) (xy 67.785951 -289.07451) (xy 67.737096 -289.080442)
			(xy 67.687921 -289.078461) (xy 67.639702 -289.068617) (xy 67.593686 -289.051165) (xy 67.551065 -289.026558)
			(xy 67.512944 -288.995433) (xy 67.480309 -288.958596) (xy 67.454006 -288.917) (xy 67.434715 -288.871724)
			(xy 67.422938 -288.82394) (xy 67.418978 -288.774886) (xy 67.08013 -288.774886) (xy 67.079635 -288.799493)
			(xy 67.07174 -288.84807) (xy 67.056156 -288.894751) (xy 67.033285 -288.938328) (xy 67.00372 -288.977672)
			(xy 66.968227 -289.011764) (xy 66.927724 -289.03972) (xy 66.883262 -289.060818) (xy 66.835991 -289.07451)
			(xy 66.787136 -289.080442) (xy 66.737961 -289.078461) (xy 66.689742 -289.068617) (xy 66.643726 -289.051165)
			(xy 66.601105 -289.026558) (xy 66.562984 -288.995433) (xy 66.530349 -288.958596) (xy 66.504046 -288.917)
			(xy 66.484755 -288.871724) (xy 66.472978 -288.82394) (xy 66.469018 -288.774886) (xy 66.13017 -288.774886)
			(xy 66.129675 -288.799493) (xy 66.12178 -288.84807) (xy 66.106196 -288.894751) (xy 66.083325 -288.938328)
			(xy 66.05376 -288.977672) (xy 66.018267 -289.011764) (xy 65.977764 -289.03972) (xy 65.933302 -289.060818)
			(xy 65.886031 -289.07451) (xy 65.837176 -289.080442) (xy 65.788001 -289.078461) (xy 65.739782 -289.068617)
			(xy 65.693766 -289.051165) (xy 65.651145 -289.026558) (xy 65.613024 -288.995433) (xy 65.580389 -288.958596)
			(xy 65.554086 -288.917) (xy 65.534795 -288.871724) (xy 65.523018 -288.82394) (xy 65.519058 -288.774886)
			(xy 65.18021 -288.774886) (xy 65.179715 -288.799493) (xy 65.17182 -288.84807) (xy 65.156236 -288.894751)
			(xy 65.133365 -288.938328) (xy 65.1038 -288.977672) (xy 65.068307 -289.011764) (xy 65.027804 -289.03972)
			(xy 64.983342 -289.060818) (xy 64.936071 -289.07451) (xy 64.887216 -289.080442) (xy 64.838041 -289.078461)
			(xy 64.789822 -289.068617) (xy 64.743806 -289.051165) (xy 64.701185 -289.026558) (xy 64.663064 -288.995433)
			(xy 64.630429 -288.958596) (xy 64.604126 -288.917) (xy 64.584835 -288.871724) (xy 64.573058 -288.82394)
			(xy 64.569098 -288.774886) (xy 64.23025 -288.774886) (xy 64.229755 -288.799493) (xy 64.22186 -288.84807)
			(xy 64.206276 -288.894751) (xy 64.183405 -288.938328) (xy 64.15384 -288.977672) (xy 64.118347 -289.011764)
			(xy 64.077844 -289.03972) (xy 64.033382 -289.060818) (xy 63.986111 -289.07451) (xy 63.937256 -289.080442)
			(xy 63.888081 -289.078461) (xy 63.839862 -289.068617) (xy 63.793846 -289.051165) (xy 63.751225 -289.026558)
			(xy 63.713104 -288.995433) (xy 63.680469 -288.958596) (xy 63.654166 -288.917) (xy 63.634875 -288.871724)
			(xy 63.623098 -288.82394) (xy 63.619138 -288.774886) (xy 63.28029 -288.774886) (xy 63.279795 -288.799493)
			(xy 63.2719 -288.84807) (xy 63.256316 -288.894751) (xy 63.233445 -288.938328) (xy 63.20388 -288.977672)
			(xy 63.168387 -289.011764) (xy 63.127884 -289.03972) (xy 63.083422 -289.060818) (xy 63.036151 -289.07451)
			(xy 62.987296 -289.080442) (xy 62.938121 -289.078461) (xy 62.889902 -289.068617) (xy 62.843886 -289.051165)
			(xy 62.801265 -289.026558) (xy 62.763144 -288.995433) (xy 62.730509 -288.958596) (xy 62.704206 -288.917)
			(xy 62.684915 -288.871724) (xy 62.673138 -288.82394) (xy 62.669178 -288.774886) (xy 62.330076 -288.774886)
			(xy 62.329581 -288.799493) (xy 62.321686 -288.84807) (xy 62.306102 -288.894751) (xy 62.283231 -288.938328)
			(xy 62.253666 -288.977672) (xy 62.218173 -289.011764) (xy 62.17767 -289.03972) (xy 62.133208 -289.060818)
			(xy 62.085937 -289.07451) (xy 62.037082 -289.080442) (xy 61.987907 -289.078461) (xy 61.939688 -289.068617)
			(xy 61.893672 -289.051165) (xy 61.851051 -289.026558) (xy 61.81293 -288.995433) (xy 61.780295 -288.958596)
			(xy 61.753992 -288.917) (xy 61.734701 -288.871724) (xy 61.722924 -288.82394) (xy 61.718964 -288.774886)
			(xy 61.380116 -288.774886) (xy 61.379621 -288.799493) (xy 61.371726 -288.84807) (xy 61.356142 -288.894751)
			(xy 61.333271 -288.938328) (xy 61.303706 -288.977672) (xy 61.268213 -289.011764) (xy 61.22771 -289.03972)
			(xy 61.183248 -289.060818) (xy 61.135977 -289.07451) (xy 61.087122 -289.080442) (xy 61.037947 -289.078461)
			(xy 60.989728 -289.068617) (xy 60.943712 -289.051165) (xy 60.901091 -289.026558) (xy 60.86297 -288.995433)
			(xy 60.830335 -288.958596) (xy 60.804032 -288.917) (xy 60.784741 -288.871724) (xy 60.772964 -288.82394)
			(xy 60.769004 -288.774886) (xy 60.430156 -288.774886) (xy 60.429661 -288.799493) (xy 60.421766 -288.84807)
			(xy 60.406182 -288.894751) (xy 60.383311 -288.938328) (xy 60.353746 -288.977672) (xy 60.318253 -289.011764)
			(xy 60.27775 -289.03972) (xy 60.233288 -289.060818) (xy 60.186017 -289.07451) (xy 60.137162 -289.080442)
			(xy 60.087987 -289.078461) (xy 60.039768 -289.068617) (xy 59.993752 -289.051165) (xy 59.951131 -289.026558)
			(xy 59.91301 -288.995433) (xy 59.880375 -288.958596) (xy 59.854072 -288.917) (xy 59.834781 -288.871724)
			(xy 59.823004 -288.82394) (xy 59.819044 -288.774886) (xy 58.530236 -288.774886) (xy 58.529741 -288.799493)
			(xy 58.521846 -288.84807) (xy 58.506262 -288.894751) (xy 58.483391 -288.938328) (xy 58.453826 -288.977672)
			(xy 58.418333 -289.011764) (xy 58.37783 -289.03972) (xy 58.333368 -289.060818) (xy 58.286097 -289.07451)
			(xy 58.237242 -289.080442) (xy 58.188067 -289.078461) (xy 58.139848 -289.068617) (xy 58.093832 -289.051165)
			(xy 58.051211 -289.026558) (xy 58.01309 -288.995433) (xy 57.980455 -288.958596) (xy 57.954152 -288.917)
			(xy 57.934861 -288.871724) (xy 57.923084 -288.82394) (xy 57.919124 -288.774886) (xy 57.580276 -288.774886)
			(xy 57.579781 -288.799493) (xy 57.571886 -288.84807) (xy 57.556302 -288.894751) (xy 57.533431 -288.938328)
			(xy 57.503866 -288.977672) (xy 57.468373 -289.011764) (xy 57.42787 -289.03972) (xy 57.383408 -289.060818)
			(xy 57.336137 -289.07451) (xy 57.287282 -289.080442) (xy 57.238107 -289.078461) (xy 57.189888 -289.068617)
			(xy 57.143872 -289.051165) (xy 57.101251 -289.026558) (xy 57.06313 -288.995433) (xy 57.030495 -288.958596)
			(xy 57.004192 -288.917) (xy 56.984901 -288.871724) (xy 56.973124 -288.82394) (xy 56.969164 -288.774886)
			(xy 56.630062 -288.774886) (xy 56.629567 -288.799493) (xy 56.621672 -288.84807) (xy 56.606088 -288.894751)
			(xy 56.583217 -288.938328) (xy 56.553652 -288.977672) (xy 56.518159 -289.011764) (xy 56.477656 -289.03972)
			(xy 56.433194 -289.060818) (xy 56.385923 -289.07451) (xy 56.337068 -289.080442) (xy 56.287893 -289.078461)
			(xy 56.239674 -289.068617) (xy 56.193658 -289.051165) (xy 56.151037 -289.026558) (xy 56.112916 -288.995433)
			(xy 56.080281 -288.958596) (xy 56.053978 -288.917) (xy 56.034687 -288.871724) (xy 56.02291 -288.82394)
			(xy 56.01895 -288.774886) (xy 55.680102 -288.774886) (xy 55.679607 -288.799493) (xy 55.671712 -288.84807)
			(xy 55.656128 -288.894751) (xy 55.633257 -288.938328) (xy 55.603692 -288.977672) (xy 55.568199 -289.011764)
			(xy 55.527696 -289.03972) (xy 55.483234 -289.060818) (xy 55.435963 -289.07451) (xy 55.387108 -289.080442)
			(xy 55.337933 -289.078461) (xy 55.289714 -289.068617) (xy 55.243698 -289.051165) (xy 55.201077 -289.026558)
			(xy 55.162956 -288.995433) (xy 55.130321 -288.958596) (xy 55.104018 -288.917) (xy 55.084727 -288.871724)
			(xy 55.07295 -288.82394) (xy 55.06899 -288.774886) (xy 54.730142 -288.774886) (xy 54.729647 -288.799493)
			(xy 54.721752 -288.84807) (xy 54.706168 -288.894751) (xy 54.683297 -288.938328) (xy 54.653732 -288.977672)
			(xy 54.618239 -289.011764) (xy 54.577736 -289.03972) (xy 54.533274 -289.060818) (xy 54.486003 -289.07451)
			(xy 54.437148 -289.080442) (xy 54.387973 -289.078461) (xy 54.339754 -289.068617) (xy 54.293738 -289.051165)
			(xy 54.251117 -289.026558) (xy 54.212996 -288.995433) (xy 54.180361 -288.958596) (xy 54.154058 -288.917)
			(xy 54.134767 -288.871724) (xy 54.12299 -288.82394) (xy 54.11903 -288.774886) (xy 53.780182 -288.774886)
			(xy 53.779687 -288.799493) (xy 53.771792 -288.84807) (xy 53.756208 -288.894751) (xy 53.733337 -288.938328)
			(xy 53.703772 -288.977672) (xy 53.668279 -289.011764) (xy 53.627776 -289.03972) (xy 53.583314 -289.060818)
			(xy 53.536043 -289.07451) (xy 53.487188 -289.080442) (xy 53.438013 -289.078461) (xy 53.389794 -289.068617)
			(xy 53.343778 -289.051165) (xy 53.301157 -289.026558) (xy 53.263036 -288.995433) (xy 53.230401 -288.958596)
			(xy 53.204098 -288.917) (xy 53.184807 -288.871724) (xy 53.17303 -288.82394) (xy 53.16907 -288.774886)
			(xy 52.830222 -288.774886) (xy 52.829727 -288.799493) (xy 52.821832 -288.84807) (xy 52.806248 -288.894751)
			(xy 52.783377 -288.938328) (xy 52.753812 -288.977672) (xy 52.718319 -289.011764) (xy 52.677816 -289.03972)
			(xy 52.633354 -289.060818) (xy 52.586083 -289.07451) (xy 52.537228 -289.080442) (xy 52.488053 -289.078461)
			(xy 52.439834 -289.068617) (xy 52.393818 -289.051165) (xy 52.351197 -289.026558) (xy 52.313076 -288.995433)
			(xy 52.280441 -288.958596) (xy 52.254138 -288.917) (xy 52.234847 -288.871724) (xy 52.22307 -288.82394)
			(xy 52.21911 -288.774886) (xy 51.880262 -288.774886) (xy 51.879767 -288.799493) (xy 51.871872 -288.84807)
			(xy 51.856288 -288.894751) (xy 51.833417 -288.938328) (xy 51.803852 -288.977672) (xy 51.768359 -289.011764)
			(xy 51.727856 -289.03972) (xy 51.683394 -289.060818) (xy 51.636123 -289.07451) (xy 51.587268 -289.080442)
			(xy 51.538093 -289.078461) (xy 51.489874 -289.068617) (xy 51.443858 -289.051165) (xy 51.401237 -289.026558)
			(xy 51.363116 -288.995433) (xy 51.330481 -288.958596) (xy 51.304178 -288.917) (xy 51.284887 -288.871724)
			(xy 51.27311 -288.82394) (xy 51.26915 -288.774886) (xy 50.930302 -288.774886) (xy 50.929807 -288.799493)
			(xy 50.921912 -288.84807) (xy 50.906328 -288.894751) (xy 50.883457 -288.938328) (xy 50.853892 -288.977672)
			(xy 50.818399 -289.011764) (xy 50.777896 -289.03972) (xy 50.733434 -289.060818) (xy 50.686163 -289.07451)
			(xy 50.637308 -289.080442) (xy 50.588133 -289.078461) (xy 50.539914 -289.068617) (xy 50.493898 -289.051165)
			(xy 50.451277 -289.026558) (xy 50.413156 -288.995433) (xy 50.380521 -288.958596) (xy 50.354218 -288.917)
			(xy 50.334927 -288.871724) (xy 50.32315 -288.82394) (xy 50.31919 -288.774886) (xy 49.980088 -288.774886)
			(xy 49.979593 -288.799493) (xy 49.971698 -288.84807) (xy 49.956114 -288.894751) (xy 49.933243 -288.938328)
			(xy 49.903678 -288.977672) (xy 49.868185 -289.011764) (xy 49.827682 -289.03972) (xy 49.78322 -289.060818)
			(xy 49.735949 -289.07451) (xy 49.687094 -289.080442) (xy 49.637919 -289.078461) (xy 49.5897 -289.068617)
			(xy 49.543684 -289.051165) (xy 49.501063 -289.026558) (xy 49.462942 -288.995433) (xy 49.430307 -288.958596)
			(xy 49.404004 -288.917) (xy 49.384713 -288.871724) (xy 49.372936 -288.82394) (xy 49.368976 -288.774886)
			(xy 49.030128 -288.774886) (xy 49.029633 -288.799493) (xy 49.021738 -288.84807) (xy 49.006154 -288.894751)
			(xy 48.983283 -288.938328) (xy 48.953718 -288.977672) (xy 48.918225 -289.011764) (xy 48.877722 -289.03972)
			(xy 48.83326 -289.060818) (xy 48.785989 -289.07451) (xy 48.737134 -289.080442) (xy 48.687959 -289.078461)
			(xy 48.63974 -289.068617) (xy 48.593724 -289.051165) (xy 48.551103 -289.026558) (xy 48.512982 -288.995433)
			(xy 48.480347 -288.958596) (xy 48.454044 -288.917) (xy 48.434753 -288.871724) (xy 48.422976 -288.82394)
			(xy 48.419016 -288.774886) (xy 48.080168 -288.774886) (xy 48.079914 -288.7853) (xy 48.079914 -288.79165)
			(xy 48.07966 -288.796222) (xy 48.07966 -288.796984) (xy 48.078438 -288.811385) (xy 48.073608 -288.839883)
			(xy 48.070008 -288.85388) (xy 48.06823 -288.860484) (xy 48.06823 -289.633406) (xy 48.070008 -289.64636)
			(xy 48.07077 -289.649154) (xy 48.07712 -289.681412) (xy 48.07839 -289.690048) (xy 48.080168 -289.722814)
			(xy 48.080168 -289.724846) (xy 48.419016 -289.724846) (xy 48.422976 -289.675792) (xy 48.434753 -289.628008)
			(xy 48.454044 -289.582732) (xy 48.480347 -289.541136) (xy 48.512982 -289.504299) (xy 48.551103 -289.473174)
			(xy 48.593724 -289.448567) (xy 48.63974 -289.431115) (xy 48.687959 -289.421271) (xy 48.737134 -289.41929)
			(xy 48.785989 -289.425222) (xy 48.83326 -289.438914) (xy 48.877722 -289.460012) (xy 48.918225 -289.487968)
			(xy 48.953718 -289.52206) (xy 48.983283 -289.561404) (xy 49.006154 -289.604981) (xy 49.021738 -289.651662)
			(xy 49.029633 -289.700239) (xy 49.030128 -289.724846) (xy 49.368976 -289.724846) (xy 49.372936 -289.675792)
			(xy 49.384713 -289.628008) (xy 49.404004 -289.582732) (xy 49.430307 -289.541136) (xy 49.462942 -289.504299)
			(xy 49.501063 -289.473174) (xy 49.543684 -289.448567) (xy 49.5897 -289.431115) (xy 49.637919 -289.421271)
			(xy 49.687094 -289.41929) (xy 49.735949 -289.425222) (xy 49.78322 -289.438914) (xy 49.827682 -289.460012)
			(xy 49.868185 -289.487968) (xy 49.903678 -289.52206) (xy 49.933243 -289.561404) (xy 49.956114 -289.604981)
			(xy 49.971698 -289.651662) (xy 49.979593 -289.700239) (xy 49.980088 -289.724846) (xy 50.31919 -289.724846)
			(xy 50.32315 -289.675792) (xy 50.334927 -289.628008) (xy 50.354218 -289.582732) (xy 50.380521 -289.541136)
			(xy 50.413156 -289.504299) (xy 50.451277 -289.473174) (xy 50.493898 -289.448567) (xy 50.539914 -289.431115)
			(xy 50.588133 -289.421271) (xy 50.637308 -289.41929) (xy 50.686163 -289.425222) (xy 50.733434 -289.438914)
			(xy 50.777896 -289.460012) (xy 50.818399 -289.487968) (xy 50.853892 -289.52206) (xy 50.883457 -289.561404)
			(xy 50.906328 -289.604981) (xy 50.921912 -289.651662) (xy 50.929807 -289.700239) (xy 50.930302 -289.724846)
			(xy 51.26915 -289.724846) (xy 51.27311 -289.675792) (xy 51.284887 -289.628008) (xy 51.304178 -289.582732)
			(xy 51.330481 -289.541136) (xy 51.363116 -289.504299) (xy 51.401237 -289.473174) (xy 51.443858 -289.448567)
			(xy 51.489874 -289.431115) (xy 51.538093 -289.421271) (xy 51.587268 -289.41929) (xy 51.636123 -289.425222)
			(xy 51.683394 -289.438914) (xy 51.727856 -289.460012) (xy 51.768359 -289.487968) (xy 51.803852 -289.52206)
			(xy 51.833417 -289.561404) (xy 51.856288 -289.604981) (xy 51.871872 -289.651662) (xy 51.879767 -289.700239)
			(xy 51.880262 -289.724846) (xy 52.21911 -289.724846) (xy 52.22307 -289.675792) (xy 52.234847 -289.628008)
			(xy 52.254138 -289.582732) (xy 52.280441 -289.541136) (xy 52.313076 -289.504299) (xy 52.351197 -289.473174)
			(xy 52.393818 -289.448567) (xy 52.439834 -289.431115) (xy 52.488053 -289.421271) (xy 52.537228 -289.41929)
			(xy 52.586083 -289.425222) (xy 52.633354 -289.438914) (xy 52.677816 -289.460012) (xy 52.718319 -289.487968)
			(xy 52.753812 -289.52206) (xy 52.783377 -289.561404) (xy 52.806248 -289.604981) (xy 52.821832 -289.651662)
			(xy 52.829727 -289.700239) (xy 52.830222 -289.724846) (xy 53.16907 -289.724846) (xy 53.17303 -289.675792)
			(xy 53.184807 -289.628008) (xy 53.204098 -289.582732) (xy 53.230401 -289.541136) (xy 53.263036 -289.504299)
			(xy 53.301157 -289.473174) (xy 53.343778 -289.448567) (xy 53.389794 -289.431115) (xy 53.438013 -289.421271)
			(xy 53.487188 -289.41929) (xy 53.536043 -289.425222) (xy 53.583314 -289.438914) (xy 53.627776 -289.460012)
			(xy 53.668279 -289.487968) (xy 53.703772 -289.52206) (xy 53.733337 -289.561404) (xy 53.756208 -289.604981)
			(xy 53.771792 -289.651662) (xy 53.779687 -289.700239) (xy 53.780182 -289.724846) (xy 54.11903 -289.724846)
			(xy 54.12299 -289.675792) (xy 54.134767 -289.628008) (xy 54.154058 -289.582732) (xy 54.180361 -289.541136)
			(xy 54.212996 -289.504299) (xy 54.251117 -289.473174) (xy 54.293738 -289.448567) (xy 54.339754 -289.431115)
			(xy 54.387973 -289.421271) (xy 54.437148 -289.41929) (xy 54.486003 -289.425222) (xy 54.533274 -289.438914)
			(xy 54.577736 -289.460012) (xy 54.618239 -289.487968) (xy 54.653732 -289.52206) (xy 54.683297 -289.561404)
			(xy 54.706168 -289.604981) (xy 54.721752 -289.651662) (xy 54.729647 -289.700239) (xy 54.730142 -289.724846)
			(xy 55.06899 -289.724846) (xy 55.07295 -289.675792) (xy 55.084727 -289.628008) (xy 55.104018 -289.582732)
			(xy 55.130321 -289.541136) (xy 55.162956 -289.504299) (xy 55.201077 -289.473174) (xy 55.243698 -289.448567)
			(xy 55.289714 -289.431115) (xy 55.337933 -289.421271) (xy 55.387108 -289.41929) (xy 55.435963 -289.425222)
			(xy 55.483234 -289.438914) (xy 55.527696 -289.460012) (xy 55.568199 -289.487968) (xy 55.603692 -289.52206)
			(xy 55.633257 -289.561404) (xy 55.656128 -289.604981) (xy 55.671712 -289.651662) (xy 55.679607 -289.700239)
			(xy 55.680102 -289.724846) (xy 56.01895 -289.724846) (xy 56.02291 -289.675792) (xy 56.034687 -289.628008)
			(xy 56.053978 -289.582732) (xy 56.080281 -289.541136) (xy 56.112916 -289.504299) (xy 56.151037 -289.473174)
			(xy 56.193658 -289.448567) (xy 56.239674 -289.431115) (xy 56.287893 -289.421271) (xy 56.337068 -289.41929)
			(xy 56.385923 -289.425222) (xy 56.433194 -289.438914) (xy 56.477656 -289.460012) (xy 56.518159 -289.487968)
			(xy 56.553652 -289.52206) (xy 56.583217 -289.561404) (xy 56.606088 -289.604981) (xy 56.621672 -289.651662)
			(xy 56.629567 -289.700239) (xy 56.630062 -289.724846) (xy 56.969164 -289.724846) (xy 56.973124 -289.675792)
			(xy 56.984901 -289.628008) (xy 57.004192 -289.582732) (xy 57.030495 -289.541136) (xy 57.06313 -289.504299)
			(xy 57.101251 -289.473174) (xy 57.143872 -289.448567) (xy 57.189888 -289.431115) (xy 57.238107 -289.421271)
			(xy 57.287282 -289.41929) (xy 57.336137 -289.425222) (xy 57.383408 -289.438914) (xy 57.42787 -289.460012)
			(xy 57.468373 -289.487968) (xy 57.503866 -289.52206) (xy 57.533431 -289.561404) (xy 57.556302 -289.604981)
			(xy 57.571886 -289.651662) (xy 57.579781 -289.700239) (xy 57.580276 -289.724846) (xy 57.919124 -289.724846)
			(xy 57.923084 -289.675792) (xy 57.934861 -289.628008) (xy 57.954152 -289.582732) (xy 57.980455 -289.541136)
			(xy 58.01309 -289.504299) (xy 58.051211 -289.473174) (xy 58.093832 -289.448567) (xy 58.139848 -289.431115)
			(xy 58.188067 -289.421271) (xy 58.237242 -289.41929) (xy 58.286097 -289.425222) (xy 58.333368 -289.438914)
			(xy 58.37783 -289.460012) (xy 58.418333 -289.487968) (xy 58.453826 -289.52206) (xy 58.483391 -289.561404)
			(xy 58.506262 -289.604981) (xy 58.521846 -289.651662) (xy 58.529741 -289.700239) (xy 58.530236 -289.724846)
			(xy 59.819044 -289.724846) (xy 59.823004 -289.675792) (xy 59.834781 -289.628008) (xy 59.854072 -289.582732)
			(xy 59.880375 -289.541136) (xy 59.91301 -289.504299) (xy 59.951131 -289.473174) (xy 59.993752 -289.448567)
			(xy 60.039768 -289.431115) (xy 60.087987 -289.421271) (xy 60.137162 -289.41929) (xy 60.186017 -289.425222)
			(xy 60.233288 -289.438914) (xy 60.27775 -289.460012) (xy 60.318253 -289.487968) (xy 60.353746 -289.52206)
			(xy 60.383311 -289.561404) (xy 60.406182 -289.604981) (xy 60.421766 -289.651662) (xy 60.429661 -289.700239)
			(xy 60.430156 -289.724846) (xy 60.769004 -289.724846) (xy 60.772964 -289.675792) (xy 60.784741 -289.628008)
			(xy 60.804032 -289.582732) (xy 60.830335 -289.541136) (xy 60.86297 -289.504299) (xy 60.901091 -289.473174)
			(xy 60.943712 -289.448567) (xy 60.989728 -289.431115) (xy 61.037947 -289.421271) (xy 61.087122 -289.41929)
			(xy 61.135977 -289.425222) (xy 61.183248 -289.438914) (xy 61.22771 -289.460012) (xy 61.268213 -289.487968)
			(xy 61.303706 -289.52206) (xy 61.333271 -289.561404) (xy 61.356142 -289.604981) (xy 61.371726 -289.651662)
			(xy 61.379621 -289.700239) (xy 61.380116 -289.724846) (xy 61.718964 -289.724846) (xy 61.722924 -289.675792)
			(xy 61.734701 -289.628008) (xy 61.753992 -289.582732) (xy 61.780295 -289.541136) (xy 61.81293 -289.504299)
			(xy 61.851051 -289.473174) (xy 61.893672 -289.448567) (xy 61.939688 -289.431115) (xy 61.987907 -289.421271)
			(xy 62.037082 -289.41929) (xy 62.085937 -289.425222) (xy 62.133208 -289.438914) (xy 62.17767 -289.460012)
			(xy 62.218173 -289.487968) (xy 62.253666 -289.52206) (xy 62.283231 -289.561404) (xy 62.306102 -289.604981)
			(xy 62.321686 -289.651662) (xy 62.329581 -289.700239) (xy 62.330076 -289.724846) (xy 62.669178 -289.724846)
			(xy 62.673138 -289.675792) (xy 62.684915 -289.628008) (xy 62.704206 -289.582732) (xy 62.730509 -289.541136)
			(xy 62.763144 -289.504299) (xy 62.801265 -289.473174) (xy 62.843886 -289.448567) (xy 62.889902 -289.431115)
			(xy 62.938121 -289.421271) (xy 62.987296 -289.41929) (xy 63.036151 -289.425222) (xy 63.083422 -289.438914)
			(xy 63.127884 -289.460012) (xy 63.168387 -289.487968) (xy 63.20388 -289.52206) (xy 63.233445 -289.561404)
			(xy 63.256316 -289.604981) (xy 63.2719 -289.651662) (xy 63.279795 -289.700239) (xy 63.28029 -289.724846)
			(xy 63.619138 -289.724846) (xy 63.623098 -289.675792) (xy 63.634875 -289.628008) (xy 63.654166 -289.582732)
			(xy 63.680469 -289.541136) (xy 63.713104 -289.504299) (xy 63.751225 -289.473174) (xy 63.793846 -289.448567)
			(xy 63.839862 -289.431115) (xy 63.888081 -289.421271) (xy 63.937256 -289.41929) (xy 63.986111 -289.425222)
			(xy 64.033382 -289.438914) (xy 64.077844 -289.460012) (xy 64.118347 -289.487968) (xy 64.15384 -289.52206)
			(xy 64.183405 -289.561404) (xy 64.206276 -289.604981) (xy 64.22186 -289.651662) (xy 64.229755 -289.700239)
			(xy 64.23025 -289.724846) (xy 64.569098 -289.724846) (xy 64.573058 -289.675792) (xy 64.584835 -289.628008)
			(xy 64.604126 -289.582732) (xy 64.630429 -289.541136) (xy 64.663064 -289.504299) (xy 64.701185 -289.473174)
			(xy 64.743806 -289.448567) (xy 64.789822 -289.431115) (xy 64.838041 -289.421271) (xy 64.887216 -289.41929)
			(xy 64.936071 -289.425222) (xy 64.983342 -289.438914) (xy 65.027804 -289.460012) (xy 65.068307 -289.487968)
			(xy 65.1038 -289.52206) (xy 65.133365 -289.561404) (xy 65.156236 -289.604981) (xy 65.17182 -289.651662)
			(xy 65.179715 -289.700239) (xy 65.18021 -289.724846) (xy 65.519058 -289.724846) (xy 65.523018 -289.675792)
			(xy 65.534795 -289.628008) (xy 65.554086 -289.582732) (xy 65.580389 -289.541136) (xy 65.613024 -289.504299)
			(xy 65.651145 -289.473174) (xy 65.693766 -289.448567) (xy 65.739782 -289.431115) (xy 65.788001 -289.421271)
			(xy 65.837176 -289.41929) (xy 65.886031 -289.425222) (xy 65.933302 -289.438914) (xy 65.977764 -289.460012)
			(xy 66.018267 -289.487968) (xy 66.05376 -289.52206) (xy 66.083325 -289.561404) (xy 66.106196 -289.604981)
			(xy 66.12178 -289.651662) (xy 66.129675 -289.700239) (xy 66.13017 -289.724846) (xy 66.469018 -289.724846)
			(xy 66.472978 -289.675792) (xy 66.484755 -289.628008) (xy 66.504046 -289.582732) (xy 66.530349 -289.541136)
			(xy 66.562984 -289.504299) (xy 66.601105 -289.473174) (xy 66.643726 -289.448567) (xy 66.689742 -289.431115)
			(xy 66.737961 -289.421271) (xy 66.787136 -289.41929) (xy 66.835991 -289.425222) (xy 66.883262 -289.438914)
			(xy 66.927724 -289.460012) (xy 66.968227 -289.487968) (xy 67.00372 -289.52206) (xy 67.033285 -289.561404)
			(xy 67.056156 -289.604981) (xy 67.07174 -289.651662) (xy 67.079635 -289.700239) (xy 67.08013 -289.724846)
			(xy 67.418978 -289.724846) (xy 67.422938 -289.675792) (xy 67.434715 -289.628008) (xy 67.454006 -289.582732)
			(xy 67.480309 -289.541136) (xy 67.512944 -289.504299) (xy 67.551065 -289.473174) (xy 67.593686 -289.448567)
			(xy 67.639702 -289.431115) (xy 67.687921 -289.421271) (xy 67.737096 -289.41929) (xy 67.785951 -289.425222)
			(xy 67.833222 -289.438914) (xy 67.877684 -289.460012) (xy 67.918187 -289.487968) (xy 67.95368 -289.52206)
			(xy 67.983245 -289.561404) (xy 68.006116 -289.604981) (xy 68.0217 -289.651662) (xy 68.029595 -289.700239)
			(xy 68.03009 -289.724846) (xy 68.368938 -289.724846) (xy 68.372898 -289.675792) (xy 68.384675 -289.628008)
			(xy 68.403966 -289.582732) (xy 68.430269 -289.541136) (xy 68.462904 -289.504299) (xy 68.501025 -289.473174)
			(xy 68.543646 -289.448567) (xy 68.589662 -289.431115) (xy 68.637881 -289.421271) (xy 68.687056 -289.41929)
			(xy 68.735911 -289.425222) (xy 68.783182 -289.438914) (xy 68.827644 -289.460012) (xy 68.868147 -289.487968)
			(xy 68.90364 -289.52206) (xy 68.933205 -289.561404) (xy 68.956076 -289.604981) (xy 68.97166 -289.651662)
			(xy 68.979555 -289.700239) (xy 68.98005 -289.724846) (xy 69.319152 -289.724846) (xy 69.323112 -289.675792)
			(xy 69.334889 -289.628008) (xy 69.35418 -289.582732) (xy 69.380483 -289.541136) (xy 69.413118 -289.504299)
			(xy 69.451239 -289.473174) (xy 69.49386 -289.448567) (xy 69.539876 -289.431115) (xy 69.588095 -289.421271)
			(xy 69.63727 -289.41929) (xy 69.686125 -289.425222) (xy 69.733396 -289.438914) (xy 69.777858 -289.460012)
			(xy 69.818361 -289.487968) (xy 69.853854 -289.52206) (xy 69.883419 -289.561404) (xy 69.90629 -289.604981)
			(xy 69.921874 -289.651662) (xy 69.929769 -289.700239) (xy 69.930264 -289.724846) (xy 70.269112 -289.724846)
			(xy 70.273072 -289.675792) (xy 70.284849 -289.628008) (xy 70.30414 -289.582732) (xy 70.330443 -289.541136)
			(xy 70.363078 -289.504299) (xy 70.401199 -289.473174) (xy 70.44382 -289.448567) (xy 70.489836 -289.431115)
			(xy 70.538055 -289.421271) (xy 70.58723 -289.41929) (xy 70.636085 -289.425222) (xy 70.683356 -289.438914)
			(xy 70.727818 -289.460012) (xy 70.768321 -289.487968) (xy 70.803814 -289.52206) (xy 70.833379 -289.561404)
			(xy 70.85625 -289.604981) (xy 70.871834 -289.651662) (xy 70.879729 -289.700239) (xy 70.880224 -289.724846)
			(xy 71.219072 -289.724846) (xy 71.223032 -289.675792) (xy 71.234809 -289.628008) (xy 71.2541 -289.582732)
			(xy 71.280403 -289.541136) (xy 71.313038 -289.504299) (xy 71.351159 -289.473174) (xy 71.39378 -289.448567)
			(xy 71.439796 -289.431115) (xy 71.488015 -289.421271) (xy 71.53719 -289.41929) (xy 71.586045 -289.425222)
			(xy 71.633316 -289.438914) (xy 71.677778 -289.460012) (xy 71.718281 -289.487968) (xy 71.753774 -289.52206)
			(xy 71.783339 -289.561404) (xy 71.80621 -289.604981) (xy 71.821794 -289.651662) (xy 71.829689 -289.700239)
			(xy 71.830184 -289.724846) (xy 72.169032 -289.724846) (xy 72.172992 -289.675792) (xy 72.184769 -289.628008)
			(xy 72.20406 -289.582732) (xy 72.230363 -289.541136) (xy 72.262998 -289.504299) (xy 72.301119 -289.473174)
			(xy 72.34374 -289.448567) (xy 72.389756 -289.431115) (xy 72.437975 -289.421271) (xy 72.48715 -289.41929)
			(xy 72.536005 -289.425222) (xy 72.583276 -289.438914) (xy 72.627738 -289.460012) (xy 72.668241 -289.487968)
			(xy 72.703734 -289.52206) (xy 72.733299 -289.561404) (xy 72.75617 -289.604981) (xy 72.771754 -289.651662)
			(xy 72.779649 -289.700239) (xy 72.779976 -289.716507) (xy 73.119127 -289.716507) (xy 73.124496 -289.667166)
			(xy 73.137775 -289.619343) (xy 73.158617 -289.574298) (xy 73.186471 -289.533218) (xy 73.220603 -289.497186)
			(xy 73.260116 -289.46715) (xy 73.303967 -289.443902) (xy 73.351001 -289.428054) (xy 73.39998 -289.420024)
			(xy 73.424796 -289.419538) (xy 73.438916 -289.419719) (xy 73.467028 -289.422394) (xy 73.48093 -289.424872)
			(xy 73.493376 -289.427158) (xy 73.517252 -289.419792) (xy 73.594722 -289.342322) (xy 73.602088 -289.318446)
			(xy 73.599802 -289.306) (xy 73.597342 -289.292096) (xy 73.594669 -289.263985) (xy 73.594468 -289.249866)
			(xy 73.59499 -289.224611) (xy 73.603303 -289.174789) (xy 73.619704 -289.127015) (xy 73.643745 -289.082592)
			(xy 73.674769 -289.042732) (xy 73.711931 -289.008522) (xy 73.754217 -288.980896) (xy 73.800473 -288.960606)
			(xy 73.849438 -288.948206) (xy 73.899776 -288.944035) (xy 73.950114 -288.948206) (xy 73.999079 -288.960606)
			(xy 74.045335 -288.980896) (xy 74.087621 -289.008522) (xy 74.124783 -289.042732) (xy 74.155807 -289.082592)
			(xy 74.157121 -289.08502) (xy 85.787736 -289.08502) (xy 85.791807 -289.029398) (xy 85.803933 -288.974961)
			(xy 85.823856 -288.92287) (xy 85.851152 -288.874235) (xy 85.885238 -288.830092) (xy 85.925387 -288.791383)
			(xy 85.970745 -288.758932) (xy 86.020345 -288.733431) (xy 86.073129 -288.715424) (xy 86.127972 -288.705294)
			(xy 86.183706 -288.703257) (xy 86.239143 -288.709357) (xy 86.2931 -288.723463) (xy 86.344429 -288.745275)
			(xy 86.392035 -288.774329) (xy 86.434903 -288.810004) (xy 86.47212 -288.851541) (xy 86.502893 -288.898054)
			(xy 86.526565 -288.948551) (xy 86.542633 -289.001958) (xy 86.550753 -289.057134) (xy 86.551262 -289.08502)
			(xy 86.550753 -289.112906) (xy 86.542633 -289.168082) (xy 86.526565 -289.221489) (xy 86.502893 -289.271986)
			(xy 86.47212 -289.318499) (xy 86.434903 -289.360036) (xy 86.392035 -289.395711) (xy 86.344429 -289.424765)
			(xy 86.2931 -289.446577) (xy 86.239143 -289.460683) (xy 86.183706 -289.466783) (xy 86.127972 -289.464746)
			(xy 86.073129 -289.454616) (xy 86.020345 -289.436609) (xy 85.970745 -289.411108) (xy 85.925387 -289.378657)
			(xy 85.885238 -289.339948) (xy 85.851152 -289.295805) (xy 85.823856 -289.24717) (xy 85.803933 -289.195079)
			(xy 85.791807 -289.140642) (xy 85.787736 -289.08502) (xy 74.157121 -289.08502) (xy 74.179848 -289.127015)
			(xy 74.196249 -289.174789) (xy 74.204562 -289.224611) (xy 74.205084 -289.249866) (xy 74.204903 -289.264049)
			(xy 74.202234 -289.292289) (xy 74.19975 -289.306254) (xy 74.198267 -289.318547) (xy 74.205548 -289.342167)
			(xy 74.21372 -289.351466) (xy 74.273156 -289.410902) (xy 74.277702 -289.415151) (xy 74.288355 -289.421575)
			(xy 74.294238 -289.423602) (xy 74.300197 -289.425228) (xy 74.312527 -289.425873) (xy 74.318622 -289.424872)
			(xy 74.332588 -289.422396) (xy 74.360827 -289.419724) (xy 74.37501 -289.419538) (xy 74.399829 -289.419989)
			(xy 74.448813 -289.42802) (xy 74.495853 -289.443871) (xy 74.539708 -289.467122) (xy 74.579225 -289.497162)
			(xy 74.613361 -289.5332) (xy 74.641217 -289.574284) (xy 74.66206 -289.619335) (xy 74.675341 -289.667163)
			(xy 74.680709 -289.71651) (xy 74.680257 -289.724846) (xy 75.969126 -289.724846) (xy 75.973086 -289.675792)
			(xy 75.984863 -289.628008) (xy 76.004154 -289.582732) (xy 76.030457 -289.541136) (xy 76.063092 -289.504299)
			(xy 76.101213 -289.473174) (xy 76.143834 -289.448567) (xy 76.18985 -289.431115) (xy 76.238069 -289.421271)
			(xy 76.287244 -289.41929) (xy 76.336099 -289.425222) (xy 76.38337 -289.438914) (xy 76.427832 -289.460012)
			(xy 76.468335 -289.487968) (xy 76.503828 -289.52206) (xy 76.533393 -289.561404) (xy 76.556264 -289.604981)
			(xy 76.571848 -289.651662) (xy 76.579743 -289.700239) (xy 76.580238 -289.724846) (xy 76.919086 -289.724846)
			(xy 76.923046 -289.675792) (xy 76.934823 -289.628008) (xy 76.954114 -289.582732) (xy 76.980417 -289.541136)
			(xy 77.013052 -289.504299) (xy 77.051173 -289.473174) (xy 77.093794 -289.448567) (xy 77.13981 -289.431115)
			(xy 77.188029 -289.421271) (xy 77.237204 -289.41929) (xy 77.286059 -289.425222) (xy 77.33333 -289.438914)
			(xy 77.377792 -289.460012) (xy 77.418295 -289.487968) (xy 77.453788 -289.52206) (xy 77.483353 -289.561404)
			(xy 77.506224 -289.604981) (xy 77.521808 -289.651662) (xy 77.529703 -289.700239) (xy 77.530198 -289.724846)
			(xy 77.869046 -289.724846) (xy 77.873006 -289.675792) (xy 77.884783 -289.628008) (xy 77.904074 -289.582732)
			(xy 77.930377 -289.541136) (xy 77.963012 -289.504299) (xy 78.001133 -289.473174) (xy 78.043754 -289.448567)
			(xy 78.08977 -289.431115) (xy 78.137989 -289.421271) (xy 78.187164 -289.41929) (xy 78.236019 -289.425222)
			(xy 78.28329 -289.438914) (xy 78.327752 -289.460012) (xy 78.368255 -289.487968) (xy 78.403748 -289.52206)
			(xy 78.433313 -289.561404) (xy 78.456184 -289.604981) (xy 78.471768 -289.651662) (xy 78.479663 -289.700239)
			(xy 78.480158 -289.724846) (xy 78.819006 -289.724846) (xy 78.822966 -289.675792) (xy 78.834743 -289.628008)
			(xy 78.854034 -289.582732) (xy 78.880337 -289.541136) (xy 78.912972 -289.504299) (xy 78.951093 -289.473174)
			(xy 78.993714 -289.448567) (xy 79.03973 -289.431115) (xy 79.087949 -289.421271) (xy 79.137124 -289.41929)
			(xy 79.185979 -289.425222) (xy 79.23325 -289.438914) (xy 79.277712 -289.460012) (xy 79.318215 -289.487968)
			(xy 79.353708 -289.52206) (xy 79.383273 -289.561404) (xy 79.406144 -289.604981) (xy 79.421728 -289.651662)
			(xy 79.429623 -289.700239) (xy 79.430118 -289.724846) (xy 79.768966 -289.724846) (xy 79.772926 -289.675792)
			(xy 79.784703 -289.628008) (xy 79.803994 -289.582732) (xy 79.830297 -289.541136) (xy 79.862932 -289.504299)
			(xy 79.901053 -289.473174) (xy 79.943674 -289.448567) (xy 79.98969 -289.431115) (xy 80.037909 -289.421271)
			(xy 80.087084 -289.41929) (xy 80.135939 -289.425222) (xy 80.18321 -289.438914) (xy 80.227672 -289.460012)
			(xy 80.268175 -289.487968) (xy 80.303668 -289.52206) (xy 80.333233 -289.561404) (xy 80.356104 -289.604981)
			(xy 80.371688 -289.651662) (xy 80.379583 -289.700239) (xy 80.380078 -289.724846) (xy 80.71918 -289.724846)
			(xy 80.72314 -289.675792) (xy 80.734917 -289.628008) (xy 80.754208 -289.582732) (xy 80.780511 -289.541136)
			(xy 80.813146 -289.504299) (xy 80.851267 -289.473174) (xy 80.893888 -289.448567) (xy 80.939904 -289.431115)
			(xy 80.988123 -289.421271) (xy 81.037298 -289.41929) (xy 81.086153 -289.425222) (xy 81.133424 -289.438914)
			(xy 81.177886 -289.460012) (xy 81.218389 -289.487968) (xy 81.253882 -289.52206) (xy 81.283447 -289.561404)
			(xy 81.306318 -289.604981) (xy 81.321902 -289.651662) (xy 81.329797 -289.700239) (xy 81.330292 -289.724846)
			(xy 81.66914 -289.724846) (xy 81.6731 -289.675792) (xy 81.684877 -289.628008) (xy 81.704168 -289.582732)
			(xy 81.730471 -289.541136) (xy 81.763106 -289.504299) (xy 81.801227 -289.473174) (xy 81.843848 -289.448567)
			(xy 81.889864 -289.431115) (xy 81.938083 -289.421271) (xy 81.987258 -289.41929) (xy 82.036113 -289.425222)
			(xy 82.083384 -289.438914) (xy 82.127846 -289.460012) (xy 82.168349 -289.487968) (xy 82.203842 -289.52206)
			(xy 82.233407 -289.561404) (xy 82.256278 -289.604981) (xy 82.271862 -289.651662) (xy 82.279757 -289.700239)
			(xy 82.280252 -289.724846) (xy 82.6191 -289.724846) (xy 82.62306 -289.675792) (xy 82.634837 -289.628008)
			(xy 82.654128 -289.582732) (xy 82.680431 -289.541136) (xy 82.713066 -289.504299) (xy 82.751187 -289.473174)
			(xy 82.793808 -289.448567) (xy 82.839824 -289.431115) (xy 82.888043 -289.421271) (xy 82.937218 -289.41929)
			(xy 82.986073 -289.425222) (xy 83.033344 -289.438914) (xy 83.077806 -289.460012) (xy 83.118309 -289.487968)
			(xy 83.153802 -289.52206) (xy 83.183367 -289.561404) (xy 83.206238 -289.604981) (xy 83.221822 -289.651662)
			(xy 83.229717 -289.700239) (xy 83.230212 -289.724846) (xy 83.229717 -289.749453) (xy 83.221822 -289.79803)
			(xy 83.206238 -289.844711) (xy 83.183367 -289.888288) (xy 83.153802 -289.927632) (xy 83.118309 -289.961724)
			(xy 83.077806 -289.98968) (xy 83.033344 -290.010778) (xy 82.986073 -290.02447) (xy 82.937218 -290.030402)
			(xy 82.888043 -290.028421) (xy 82.839824 -290.018577) (xy 82.793808 -290.001125) (xy 82.751187 -289.976518)
			(xy 82.713066 -289.945393) (xy 82.680431 -289.908556) (xy 82.654128 -289.86696) (xy 82.634837 -289.821684)
			(xy 82.62306 -289.7739) (xy 82.6191 -289.724846) (xy 82.280252 -289.724846) (xy 82.279757 -289.749453)
			(xy 82.271862 -289.79803) (xy 82.256278 -289.844711) (xy 82.233407 -289.888288) (xy 82.203842 -289.927632)
			(xy 82.168349 -289.961724) (xy 82.127846 -289.98968) (xy 82.083384 -290.010778) (xy 82.036113 -290.02447)
			(xy 81.987258 -290.030402) (xy 81.938083 -290.028421) (xy 81.889864 -290.018577) (xy 81.843848 -290.001125)
			(xy 81.801227 -289.976518) (xy 81.763106 -289.945393) (xy 81.730471 -289.908556) (xy 81.704168 -289.86696)
			(xy 81.684877 -289.821684) (xy 81.6731 -289.7739) (xy 81.66914 -289.724846) (xy 81.330292 -289.724846)
			(xy 81.329797 -289.749453) (xy 81.321902 -289.79803) (xy 81.306318 -289.844711) (xy 81.283447 -289.888288)
			(xy 81.253882 -289.927632) (xy 81.218389 -289.961724) (xy 81.177886 -289.98968) (xy 81.133424 -290.010778)
			(xy 81.086153 -290.02447) (xy 81.037298 -290.030402) (xy 80.988123 -290.028421) (xy 80.939904 -290.018577)
			(xy 80.893888 -290.001125) (xy 80.851267 -289.976518) (xy 80.813146 -289.945393) (xy 80.780511 -289.908556)
			(xy 80.754208 -289.86696) (xy 80.734917 -289.821684) (xy 80.72314 -289.7739) (xy 80.71918 -289.724846)
			(xy 80.380078 -289.724846) (xy 80.379583 -289.749453) (xy 80.371688 -289.79803) (xy 80.356104 -289.844711)
			(xy 80.333233 -289.888288) (xy 80.303668 -289.927632) (xy 80.268175 -289.961724) (xy 80.227672 -289.98968)
			(xy 80.18321 -290.010778) (xy 80.135939 -290.02447) (xy 80.087084 -290.030402) (xy 80.037909 -290.028421)
			(xy 79.98969 -290.018577) (xy 79.943674 -290.001125) (xy 79.901053 -289.976518) (xy 79.862932 -289.945393)
			(xy 79.830297 -289.908556) (xy 79.803994 -289.86696) (xy 79.784703 -289.821684) (xy 79.772926 -289.7739)
			(xy 79.768966 -289.724846) (xy 79.430118 -289.724846) (xy 79.429623 -289.749453) (xy 79.421728 -289.79803)
			(xy 79.406144 -289.844711) (xy 79.383273 -289.888288) (xy 79.353708 -289.927632) (xy 79.318215 -289.961724)
			(xy 79.277712 -289.98968) (xy 79.23325 -290.010778) (xy 79.185979 -290.02447) (xy 79.137124 -290.030402)
			(xy 79.087949 -290.028421) (xy 79.03973 -290.018577) (xy 78.993714 -290.001125) (xy 78.951093 -289.976518)
			(xy 78.912972 -289.945393) (xy 78.880337 -289.908556) (xy 78.854034 -289.86696) (xy 78.834743 -289.821684)
			(xy 78.822966 -289.7739) (xy 78.819006 -289.724846) (xy 78.480158 -289.724846) (xy 78.479663 -289.749453)
			(xy 78.471768 -289.79803) (xy 78.456184 -289.844711) (xy 78.433313 -289.888288) (xy 78.403748 -289.927632)
			(xy 78.368255 -289.961724) (xy 78.327752 -289.98968) (xy 78.28329 -290.010778) (xy 78.236019 -290.02447)
			(xy 78.187164 -290.030402) (xy 78.137989 -290.028421) (xy 78.08977 -290.018577) (xy 78.043754 -290.001125)
			(xy 78.001133 -289.976518) (xy 77.963012 -289.945393) (xy 77.930377 -289.908556) (xy 77.904074 -289.86696)
			(xy 77.884783 -289.821684) (xy 77.873006 -289.7739) (xy 77.869046 -289.724846) (xy 77.530198 -289.724846)
			(xy 77.529703 -289.749453) (xy 77.521808 -289.79803) (xy 77.506224 -289.844711) (xy 77.483353 -289.888288)
			(xy 77.453788 -289.927632) (xy 77.418295 -289.961724) (xy 77.377792 -289.98968) (xy 77.33333 -290.010778)
			(xy 77.286059 -290.02447) (xy 77.237204 -290.030402) (xy 77.188029 -290.028421) (xy 77.13981 -290.018577)
			(xy 77.093794 -290.001125) (xy 77.051173 -289.976518) (xy 77.013052 -289.945393) (xy 76.980417 -289.908556)
			(xy 76.954114 -289.86696) (xy 76.934823 -289.821684) (xy 76.923046 -289.7739) (xy 76.919086 -289.724846)
			(xy 76.580238 -289.724846) (xy 76.579743 -289.749453) (xy 76.571848 -289.79803) (xy 76.556264 -289.844711)
			(xy 76.533393 -289.888288) (xy 76.503828 -289.927632) (xy 76.468335 -289.961724) (xy 76.427832 -289.98968)
			(xy 76.38337 -290.010778) (xy 76.336099 -290.02447) (xy 76.287244 -290.030402) (xy 76.238069 -290.028421)
			(xy 76.18985 -290.018577) (xy 76.143834 -290.001125) (xy 76.101213 -289.976518) (xy 76.063092 -289.945393)
			(xy 76.030457 -289.908556) (xy 76.004154 -289.86696) (xy 75.984863 -289.821684) (xy 75.973086 -289.7739)
			(xy 75.969126 -289.724846) (xy 74.680257 -289.724846) (xy 74.678023 -289.766076) (xy 74.667354 -289.814554)
			(xy 74.648983 -289.860667) (xy 74.623394 -289.903201) (xy 74.591261 -289.941035) (xy 74.553431 -289.973173)
			(xy 74.510899 -289.998767) (xy 74.464788 -290.017143) (xy 74.416311 -290.027818) (xy 74.366746 -290.03051)
			(xy 74.317399 -290.025147) (xy 74.269568 -290.011873) (xy 74.224516 -289.991035) (xy 74.183428 -289.963183)
			(xy 74.147387 -289.929051) (xy 74.117342 -289.889539) (xy 74.094085 -289.845686) (xy 74.078229 -289.798648)
			(xy 74.070192 -289.749665) (xy 74.069702 -289.724846) (xy 74.069885 -289.710663) (xy 74.072553 -289.682423)
			(xy 74.075036 -289.668458) (xy 74.076581 -289.656168) (xy 74.069258 -289.632541) (xy 74.061066 -289.623246)
			(xy 74.00163 -289.56381) (xy 73.997097 -289.559546) (xy 73.986434 -289.553132) (xy 73.980548 -289.55111)
			(xy 73.974591 -289.549479) (xy 73.962259 -289.548837) (xy 73.956164 -289.54984) (xy 73.942198 -289.552317)
			(xy 73.913959 -289.554989) (xy 73.899776 -289.555174) (xy 73.885657 -289.554983) (xy 73.857544 -289.552314)
			(xy 73.843642 -289.54984) (xy 73.831196 -289.547554) (xy 73.80732 -289.55492) (xy 73.72985 -289.63239)
			(xy 73.722484 -289.656266) (xy 73.72477 -289.668712) (xy 73.727232 -289.682616) (xy 73.729904 -289.710727)
			(xy 73.730104 -289.724846) (xy 73.729573 -289.749662) (xy 73.721536 -289.79864) (xy 73.705682 -289.845672)
			(xy 73.682427 -289.88952) (xy 73.652386 -289.929028) (xy 73.616349 -289.963156) (xy 73.575265 -289.991004)
			(xy 73.530218 -290.011839) (xy 73.482393 -290.025112) (xy 73.433051 -290.030474) (xy 73.383491 -290.027782)
			(xy 73.33502 -290.017108) (xy 73.288914 -289.998733) (xy 73.246388 -289.973142) (xy 73.208562 -289.941008)
			(xy 73.176434 -289.903178) (xy 73.150848 -289.860648) (xy 73.13248 -289.81454) (xy 73.121812 -289.766067)
			(xy 73.119127 -289.716507) (xy 72.779976 -289.716507) (xy 72.780144 -289.724846) (xy 72.779649 -289.749453)
			(xy 72.771754 -289.79803) (xy 72.75617 -289.844711) (xy 72.733299 -289.888288) (xy 72.703734 -289.927632)
			(xy 72.668241 -289.961724) (xy 72.627738 -289.98968) (xy 72.583276 -290.010778) (xy 72.536005 -290.02447)
			(xy 72.48715 -290.030402) (xy 72.437975 -290.028421) (xy 72.389756 -290.018577) (xy 72.34374 -290.001125)
			(xy 72.301119 -289.976518) (xy 72.262998 -289.945393) (xy 72.230363 -289.908556) (xy 72.20406 -289.86696)
			(xy 72.184769 -289.821684) (xy 72.172992 -289.7739) (xy 72.169032 -289.724846) (xy 71.830184 -289.724846)
			(xy 71.829689 -289.749453) (xy 71.821794 -289.79803) (xy 71.80621 -289.844711) (xy 71.783339 -289.888288)
			(xy 71.753774 -289.927632) (xy 71.718281 -289.961724) (xy 71.677778 -289.98968) (xy 71.633316 -290.010778)
			(xy 71.586045 -290.02447) (xy 71.53719 -290.030402) (xy 71.488015 -290.028421) (xy 71.439796 -290.018577)
			(xy 71.39378 -290.001125) (xy 71.351159 -289.976518) (xy 71.313038 -289.945393) (xy 71.280403 -289.908556)
			(xy 71.2541 -289.86696) (xy 71.234809 -289.821684) (xy 71.223032 -289.7739) (xy 71.219072 -289.724846)
			(xy 70.880224 -289.724846) (xy 70.879729 -289.749453) (xy 70.871834 -289.79803) (xy 70.85625 -289.844711)
			(xy 70.833379 -289.888288) (xy 70.803814 -289.927632) (xy 70.768321 -289.961724) (xy 70.727818 -289.98968)
			(xy 70.683356 -290.010778) (xy 70.636085 -290.02447) (xy 70.58723 -290.030402) (xy 70.538055 -290.028421)
			(xy 70.489836 -290.018577) (xy 70.44382 -290.001125) (xy 70.401199 -289.976518) (xy 70.363078 -289.945393)
			(xy 70.330443 -289.908556) (xy 70.30414 -289.86696) (xy 70.284849 -289.821684) (xy 70.273072 -289.7739)
			(xy 70.269112 -289.724846) (xy 69.930264 -289.724846) (xy 69.929769 -289.749453) (xy 69.921874 -289.79803)
			(xy 69.90629 -289.844711) (xy 69.883419 -289.888288) (xy 69.853854 -289.927632) (xy 69.818361 -289.961724)
			(xy 69.777858 -289.98968) (xy 69.733396 -290.010778) (xy 69.686125 -290.02447) (xy 69.63727 -290.030402)
			(xy 69.588095 -290.028421) (xy 69.539876 -290.018577) (xy 69.49386 -290.001125) (xy 69.451239 -289.976518)
			(xy 69.413118 -289.945393) (xy 69.380483 -289.908556) (xy 69.35418 -289.86696) (xy 69.334889 -289.821684)
			(xy 69.323112 -289.7739) (xy 69.319152 -289.724846) (xy 68.98005 -289.724846) (xy 68.979555 -289.749453)
			(xy 68.97166 -289.79803) (xy 68.956076 -289.844711) (xy 68.933205 -289.888288) (xy 68.90364 -289.927632)
			(xy 68.868147 -289.961724) (xy 68.827644 -289.98968) (xy 68.783182 -290.010778) (xy 68.735911 -290.02447)
			(xy 68.687056 -290.030402) (xy 68.637881 -290.028421) (xy 68.589662 -290.018577) (xy 68.543646 -290.001125)
			(xy 68.501025 -289.976518) (xy 68.462904 -289.945393) (xy 68.430269 -289.908556) (xy 68.403966 -289.86696)
			(xy 68.384675 -289.821684) (xy 68.372898 -289.7739) (xy 68.368938 -289.724846) (xy 68.03009 -289.724846)
			(xy 68.029595 -289.749453) (xy 68.0217 -289.79803) (xy 68.006116 -289.844711) (xy 67.983245 -289.888288)
			(xy 67.95368 -289.927632) (xy 67.918187 -289.961724) (xy 67.877684 -289.98968) (xy 67.833222 -290.010778)
			(xy 67.785951 -290.02447) (xy 67.737096 -290.030402) (xy 67.687921 -290.028421) (xy 67.639702 -290.018577)
			(xy 67.593686 -290.001125) (xy 67.551065 -289.976518) (xy 67.512944 -289.945393) (xy 67.480309 -289.908556)
			(xy 67.454006 -289.86696) (xy 67.434715 -289.821684) (xy 67.422938 -289.7739) (xy 67.418978 -289.724846)
			(xy 67.08013 -289.724846) (xy 67.079635 -289.749453) (xy 67.07174 -289.79803) (xy 67.056156 -289.844711)
			(xy 67.033285 -289.888288) (xy 67.00372 -289.927632) (xy 66.968227 -289.961724) (xy 66.927724 -289.98968)
			(xy 66.883262 -290.010778) (xy 66.835991 -290.02447) (xy 66.787136 -290.030402) (xy 66.737961 -290.028421)
			(xy 66.689742 -290.018577) (xy 66.643726 -290.001125) (xy 66.601105 -289.976518) (xy 66.562984 -289.945393)
			(xy 66.530349 -289.908556) (xy 66.504046 -289.86696) (xy 66.484755 -289.821684) (xy 66.472978 -289.7739)
			(xy 66.469018 -289.724846) (xy 66.13017 -289.724846) (xy 66.129675 -289.749453) (xy 66.12178 -289.79803)
			(xy 66.106196 -289.844711) (xy 66.083325 -289.888288) (xy 66.05376 -289.927632) (xy 66.018267 -289.961724)
			(xy 65.977764 -289.98968) (xy 65.933302 -290.010778) (xy 65.886031 -290.02447) (xy 65.837176 -290.030402)
			(xy 65.788001 -290.028421) (xy 65.739782 -290.018577) (xy 65.693766 -290.001125) (xy 65.651145 -289.976518)
			(xy 65.613024 -289.945393) (xy 65.580389 -289.908556) (xy 65.554086 -289.86696) (xy 65.534795 -289.821684)
			(xy 65.523018 -289.7739) (xy 65.519058 -289.724846) (xy 65.18021 -289.724846) (xy 65.179715 -289.749453)
			(xy 65.17182 -289.79803) (xy 65.156236 -289.844711) (xy 65.133365 -289.888288) (xy 65.1038 -289.927632)
			(xy 65.068307 -289.961724) (xy 65.027804 -289.98968) (xy 64.983342 -290.010778) (xy 64.936071 -290.02447)
			(xy 64.887216 -290.030402) (xy 64.838041 -290.028421) (xy 64.789822 -290.018577) (xy 64.743806 -290.001125)
			(xy 64.701185 -289.976518) (xy 64.663064 -289.945393) (xy 64.630429 -289.908556) (xy 64.604126 -289.86696)
			(xy 64.584835 -289.821684) (xy 64.573058 -289.7739) (xy 64.569098 -289.724846) (xy 64.23025 -289.724846)
			(xy 64.229755 -289.749453) (xy 64.22186 -289.79803) (xy 64.206276 -289.844711) (xy 64.183405 -289.888288)
			(xy 64.15384 -289.927632) (xy 64.118347 -289.961724) (xy 64.077844 -289.98968) (xy 64.033382 -290.010778)
			(xy 63.986111 -290.02447) (xy 63.937256 -290.030402) (xy 63.888081 -290.028421) (xy 63.839862 -290.018577)
			(xy 63.793846 -290.001125) (xy 63.751225 -289.976518) (xy 63.713104 -289.945393) (xy 63.680469 -289.908556)
			(xy 63.654166 -289.86696) (xy 63.634875 -289.821684) (xy 63.623098 -289.7739) (xy 63.619138 -289.724846)
			(xy 63.28029 -289.724846) (xy 63.279795 -289.749453) (xy 63.2719 -289.79803) (xy 63.256316 -289.844711)
			(xy 63.233445 -289.888288) (xy 63.20388 -289.927632) (xy 63.168387 -289.961724) (xy 63.127884 -289.98968)
			(xy 63.083422 -290.010778) (xy 63.036151 -290.02447) (xy 62.987296 -290.030402) (xy 62.938121 -290.028421)
			(xy 62.889902 -290.018577) (xy 62.843886 -290.001125) (xy 62.801265 -289.976518) (xy 62.763144 -289.945393)
			(xy 62.730509 -289.908556) (xy 62.704206 -289.86696) (xy 62.684915 -289.821684) (xy 62.673138 -289.7739)
			(xy 62.669178 -289.724846) (xy 62.330076 -289.724846) (xy 62.329581 -289.749453) (xy 62.321686 -289.79803)
			(xy 62.306102 -289.844711) (xy 62.283231 -289.888288) (xy 62.253666 -289.927632) (xy 62.218173 -289.961724)
			(xy 62.17767 -289.98968) (xy 62.133208 -290.010778) (xy 62.085937 -290.02447) (xy 62.037082 -290.030402)
			(xy 61.987907 -290.028421) (xy 61.939688 -290.018577) (xy 61.893672 -290.001125) (xy 61.851051 -289.976518)
			(xy 61.81293 -289.945393) (xy 61.780295 -289.908556) (xy 61.753992 -289.86696) (xy 61.734701 -289.821684)
			(xy 61.722924 -289.7739) (xy 61.718964 -289.724846) (xy 61.380116 -289.724846) (xy 61.379621 -289.749453)
			(xy 61.371726 -289.79803) (xy 61.356142 -289.844711) (xy 61.333271 -289.888288) (xy 61.303706 -289.927632)
			(xy 61.268213 -289.961724) (xy 61.22771 -289.98968) (xy 61.183248 -290.010778) (xy 61.135977 -290.02447)
			(xy 61.087122 -290.030402) (xy 61.037947 -290.028421) (xy 60.989728 -290.018577) (xy 60.943712 -290.001125)
			(xy 60.901091 -289.976518) (xy 60.86297 -289.945393) (xy 60.830335 -289.908556) (xy 60.804032 -289.86696)
			(xy 60.784741 -289.821684) (xy 60.772964 -289.7739) (xy 60.769004 -289.724846) (xy 60.430156 -289.724846)
			(xy 60.429661 -289.749453) (xy 60.421766 -289.79803) (xy 60.406182 -289.844711) (xy 60.383311 -289.888288)
			(xy 60.353746 -289.927632) (xy 60.318253 -289.961724) (xy 60.27775 -289.98968) (xy 60.233288 -290.010778)
			(xy 60.186017 -290.02447) (xy 60.137162 -290.030402) (xy 60.087987 -290.028421) (xy 60.039768 -290.018577)
			(xy 59.993752 -290.001125) (xy 59.951131 -289.976518) (xy 59.91301 -289.945393) (xy 59.880375 -289.908556)
			(xy 59.854072 -289.86696) (xy 59.834781 -289.821684) (xy 59.823004 -289.7739) (xy 59.819044 -289.724846)
			(xy 58.530236 -289.724846) (xy 58.529741 -289.749453) (xy 58.521846 -289.79803) (xy 58.506262 -289.844711)
			(xy 58.483391 -289.888288) (xy 58.453826 -289.927632) (xy 58.418333 -289.961724) (xy 58.37783 -289.98968)
			(xy 58.333368 -290.010778) (xy 58.286097 -290.02447) (xy 58.237242 -290.030402) (xy 58.188067 -290.028421)
			(xy 58.139848 -290.018577) (xy 58.093832 -290.001125) (xy 58.051211 -289.976518) (xy 58.01309 -289.945393)
			(xy 57.980455 -289.908556) (xy 57.954152 -289.86696) (xy 57.934861 -289.821684) (xy 57.923084 -289.7739)
			(xy 57.919124 -289.724846) (xy 57.580276 -289.724846) (xy 57.579781 -289.749453) (xy 57.571886 -289.79803)
			(xy 57.556302 -289.844711) (xy 57.533431 -289.888288) (xy 57.503866 -289.927632) (xy 57.468373 -289.961724)
			(xy 57.42787 -289.98968) (xy 57.383408 -290.010778) (xy 57.336137 -290.02447) (xy 57.287282 -290.030402)
			(xy 57.238107 -290.028421) (xy 57.189888 -290.018577) (xy 57.143872 -290.001125) (xy 57.101251 -289.976518)
			(xy 57.06313 -289.945393) (xy 57.030495 -289.908556) (xy 57.004192 -289.86696) (xy 56.984901 -289.821684)
			(xy 56.973124 -289.7739) (xy 56.969164 -289.724846) (xy 56.630062 -289.724846) (xy 56.629567 -289.749453)
			(xy 56.621672 -289.79803) (xy 56.606088 -289.844711) (xy 56.583217 -289.888288) (xy 56.553652 -289.927632)
			(xy 56.518159 -289.961724) (xy 56.477656 -289.98968) (xy 56.433194 -290.010778) (xy 56.385923 -290.02447)
			(xy 56.337068 -290.030402) (xy 56.287893 -290.028421) (xy 56.239674 -290.018577) (xy 56.193658 -290.001125)
			(xy 56.151037 -289.976518) (xy 56.112916 -289.945393) (xy 56.080281 -289.908556) (xy 56.053978 -289.86696)
			(xy 56.034687 -289.821684) (xy 56.02291 -289.7739) (xy 56.01895 -289.724846) (xy 55.680102 -289.724846)
			(xy 55.679607 -289.749453) (xy 55.671712 -289.79803) (xy 55.656128 -289.844711) (xy 55.633257 -289.888288)
			(xy 55.603692 -289.927632) (xy 55.568199 -289.961724) (xy 55.527696 -289.98968) (xy 55.483234 -290.010778)
			(xy 55.435963 -290.02447) (xy 55.387108 -290.030402) (xy 55.337933 -290.028421) (xy 55.289714 -290.018577)
			(xy 55.243698 -290.001125) (xy 55.201077 -289.976518) (xy 55.162956 -289.945393) (xy 55.130321 -289.908556)
			(xy 55.104018 -289.86696) (xy 55.084727 -289.821684) (xy 55.07295 -289.7739) (xy 55.06899 -289.724846)
			(xy 54.730142 -289.724846) (xy 54.729647 -289.749453) (xy 54.721752 -289.79803) (xy 54.706168 -289.844711)
			(xy 54.683297 -289.888288) (xy 54.653732 -289.927632) (xy 54.618239 -289.961724) (xy 54.577736 -289.98968)
			(xy 54.533274 -290.010778) (xy 54.486003 -290.02447) (xy 54.437148 -290.030402) (xy 54.387973 -290.028421)
			(xy 54.339754 -290.018577) (xy 54.293738 -290.001125) (xy 54.251117 -289.976518) (xy 54.212996 -289.945393)
			(xy 54.180361 -289.908556) (xy 54.154058 -289.86696) (xy 54.134767 -289.821684) (xy 54.12299 -289.7739)
			(xy 54.11903 -289.724846) (xy 53.780182 -289.724846) (xy 53.779687 -289.749453) (xy 53.771792 -289.79803)
			(xy 53.756208 -289.844711) (xy 53.733337 -289.888288) (xy 53.703772 -289.927632) (xy 53.668279 -289.961724)
			(xy 53.627776 -289.98968) (xy 53.583314 -290.010778) (xy 53.536043 -290.02447) (xy 53.487188 -290.030402)
			(xy 53.438013 -290.028421) (xy 53.389794 -290.018577) (xy 53.343778 -290.001125) (xy 53.301157 -289.976518)
			(xy 53.263036 -289.945393) (xy 53.230401 -289.908556) (xy 53.204098 -289.86696) (xy 53.184807 -289.821684)
			(xy 53.17303 -289.7739) (xy 53.16907 -289.724846) (xy 52.830222 -289.724846) (xy 52.829727 -289.749453)
			(xy 52.821832 -289.79803) (xy 52.806248 -289.844711) (xy 52.783377 -289.888288) (xy 52.753812 -289.927632)
			(xy 52.718319 -289.961724) (xy 52.677816 -289.98968) (xy 52.633354 -290.010778) (xy 52.586083 -290.02447)
			(xy 52.537228 -290.030402) (xy 52.488053 -290.028421) (xy 52.439834 -290.018577) (xy 52.393818 -290.001125)
			(xy 52.351197 -289.976518) (xy 52.313076 -289.945393) (xy 52.280441 -289.908556) (xy 52.254138 -289.86696)
			(xy 52.234847 -289.821684) (xy 52.22307 -289.7739) (xy 52.21911 -289.724846) (xy 51.880262 -289.724846)
			(xy 51.879767 -289.749453) (xy 51.871872 -289.79803) (xy 51.856288 -289.844711) (xy 51.833417 -289.888288)
			(xy 51.803852 -289.927632) (xy 51.768359 -289.961724) (xy 51.727856 -289.98968) (xy 51.683394 -290.010778)
			(xy 51.636123 -290.02447) (xy 51.587268 -290.030402) (xy 51.538093 -290.028421) (xy 51.489874 -290.018577)
			(xy 51.443858 -290.001125) (xy 51.401237 -289.976518) (xy 51.363116 -289.945393) (xy 51.330481 -289.908556)
			(xy 51.304178 -289.86696) (xy 51.284887 -289.821684) (xy 51.27311 -289.7739) (xy 51.26915 -289.724846)
			(xy 50.930302 -289.724846) (xy 50.929807 -289.749453) (xy 50.921912 -289.79803) (xy 50.906328 -289.844711)
			(xy 50.883457 -289.888288) (xy 50.853892 -289.927632) (xy 50.818399 -289.961724) (xy 50.777896 -289.98968)
			(xy 50.733434 -290.010778) (xy 50.686163 -290.02447) (xy 50.637308 -290.030402) (xy 50.588133 -290.028421)
			(xy 50.539914 -290.018577) (xy 50.493898 -290.001125) (xy 50.451277 -289.976518) (xy 50.413156 -289.945393)
			(xy 50.380521 -289.908556) (xy 50.354218 -289.86696) (xy 50.334927 -289.821684) (xy 50.32315 -289.7739)
			(xy 50.31919 -289.724846) (xy 49.980088 -289.724846) (xy 49.979593 -289.749453) (xy 49.971698 -289.79803)
			(xy 49.956114 -289.844711) (xy 49.933243 -289.888288) (xy 49.903678 -289.927632) (xy 49.868185 -289.961724)
			(xy 49.827682 -289.98968) (xy 49.78322 -290.010778) (xy 49.735949 -290.02447) (xy 49.687094 -290.030402)
			(xy 49.637919 -290.028421) (xy 49.5897 -290.018577) (xy 49.543684 -290.001125) (xy 49.501063 -289.976518)
			(xy 49.462942 -289.945393) (xy 49.430307 -289.908556) (xy 49.404004 -289.86696) (xy 49.384713 -289.821684)
			(xy 49.372936 -289.7739) (xy 49.368976 -289.724846) (xy 49.030128 -289.724846) (xy 49.029633 -289.749453)
			(xy 49.021738 -289.79803) (xy 49.006154 -289.844711) (xy 48.983283 -289.888288) (xy 48.953718 -289.927632)
			(xy 48.918225 -289.961724) (xy 48.877722 -289.98968) (xy 48.83326 -290.010778) (xy 48.785989 -290.02447)
			(xy 48.737134 -290.030402) (xy 48.687959 -290.028421) (xy 48.63974 -290.018577) (xy 48.593724 -290.001125)
			(xy 48.551103 -289.976518) (xy 48.512982 -289.945393) (xy 48.480347 -289.908556) (xy 48.454044 -289.86696)
			(xy 48.434753 -289.821684) (xy 48.422976 -289.7739) (xy 48.419016 -289.724846) (xy 48.080168 -289.724846)
			(xy 48.080168 -289.7251) (xy 48.07985 -289.744296) (xy 48.075009 -289.782381) (xy 48.070516 -289.801046)
			(xy 48.069754 -289.804094) (xy 48.06823 -289.815524) (xy 48.06823 -289.820096) (xy 48.068667 -289.829791)
			(xy 48.075862 -289.847797) (xy 48.0822 -289.855148) (xy 48.082708 -289.855656) (xy 48.187356 -289.96005)
			(xy 48.199655 -289.97275) (xy 48.221556 -290.000504) (xy 48.231044 -290.015422) (xy 48.2346 -290.021264)
			(xy 48.235362 -290.022534) (xy 48.247554 -290.045394) (xy 48.252634 -290.05657) (xy 48.253904 -290.060126)
			(xy 48.254412 -290.061142) (xy 48.264156 -290.086773) (xy 48.275401 -290.140435) (xy 48.276764 -290.167822)
			(xy 48.276764 -290.276788) (xy 48.276982 -290.284267) (xy 48.281231 -290.298607) (xy 48.285146 -290.304982)
			(xy 48.30953 -290.341812) (xy 48.314671 -290.350343) (xy 48.318602 -290.369849) (xy 48.314787 -290.389377)
			(xy 48.303802 -290.405968) (xy 48.295814 -290.411916) (xy 48.187356 -290.485068) (xy 48.180752 -290.490402)
			(xy 48.168306 -290.50234) (xy 48.161194 -290.507928) (xy 48.151034 -290.514532) (xy 48.149002 -290.516818)
			(xy 48.105568 -290.547044) (xy 48.104806 -290.547552) (xy 48.092614 -290.556442) (xy 48.084912 -290.562554)
			(xy 48.074495 -290.579208) (xy 48.071151 -290.598565) (xy 48.072802 -290.608258) (xy 48.072802 -290.608766)
			(xy 48.076208 -290.625065) (xy 48.079903 -290.658157) (xy 48.080168 -290.674806) (xy 49.368976 -290.674806)
			(xy 49.372936 -290.625752) (xy 49.384713 -290.577968) (xy 49.404004 -290.532692) (xy 49.430307 -290.491096)
			(xy 49.462942 -290.454259) (xy 49.501063 -290.423134) (xy 49.543684 -290.398527) (xy 49.5897 -290.381075)
			(xy 49.637919 -290.371231) (xy 49.687094 -290.36925) (xy 49.735949 -290.375182) (xy 49.78322 -290.388874)
			(xy 49.827682 -290.409972) (xy 49.868185 -290.437928) (xy 49.903678 -290.47202) (xy 49.933243 -290.511364)
			(xy 49.956114 -290.554941) (xy 49.971698 -290.601622) (xy 49.979593 -290.650199) (xy 49.980088 -290.674806)
			(xy 50.31919 -290.674806) (xy 50.32315 -290.625752) (xy 50.334927 -290.577968) (xy 50.354218 -290.532692)
			(xy 50.380521 -290.491096) (xy 50.413156 -290.454259) (xy 50.451277 -290.423134) (xy 50.493898 -290.398527)
			(xy 50.539914 -290.381075) (xy 50.588133 -290.371231) (xy 50.637308 -290.36925) (xy 50.686163 -290.375182)
			(xy 50.733434 -290.388874) (xy 50.777896 -290.409972) (xy 50.818399 -290.437928) (xy 50.853892 -290.47202)
			(xy 50.883457 -290.511364) (xy 50.906328 -290.554941) (xy 50.921912 -290.601622) (xy 50.929807 -290.650199)
			(xy 50.930302 -290.674806) (xy 51.26915 -290.674806) (xy 51.27311 -290.625752) (xy 51.284887 -290.577968)
			(xy 51.304178 -290.532692) (xy 51.330481 -290.491096) (xy 51.363116 -290.454259) (xy 51.401237 -290.423134)
			(xy 51.443858 -290.398527) (xy 51.489874 -290.381075) (xy 51.538093 -290.371231) (xy 51.587268 -290.36925)
			(xy 51.636123 -290.375182) (xy 51.683394 -290.388874) (xy 51.727856 -290.409972) (xy 51.768359 -290.437928)
			(xy 51.803852 -290.47202) (xy 51.833417 -290.511364) (xy 51.856288 -290.554941) (xy 51.871872 -290.601622)
			(xy 51.879767 -290.650199) (xy 51.880262 -290.674806) (xy 52.21911 -290.674806) (xy 52.22307 -290.625752)
			(xy 52.234847 -290.577968) (xy 52.254138 -290.532692) (xy 52.280441 -290.491096) (xy 52.313076 -290.454259)
			(xy 52.351197 -290.423134) (xy 52.393818 -290.398527) (xy 52.439834 -290.381075) (xy 52.488053 -290.371231)
			(xy 52.537228 -290.36925) (xy 52.586083 -290.375182) (xy 52.633354 -290.388874) (xy 52.677816 -290.409972)
			(xy 52.718319 -290.437928) (xy 52.753812 -290.47202) (xy 52.783377 -290.511364) (xy 52.806248 -290.554941)
			(xy 52.821832 -290.601622) (xy 52.829727 -290.650199) (xy 52.830222 -290.674806) (xy 53.16907 -290.674806)
			(xy 53.17303 -290.625752) (xy 53.184807 -290.577968) (xy 53.204098 -290.532692) (xy 53.230401 -290.491096)
			(xy 53.263036 -290.454259) (xy 53.301157 -290.423134) (xy 53.343778 -290.398527) (xy 53.389794 -290.381075)
			(xy 53.438013 -290.371231) (xy 53.487188 -290.36925) (xy 53.536043 -290.375182) (xy 53.583314 -290.388874)
			(xy 53.627776 -290.409972) (xy 53.668279 -290.437928) (xy 53.703772 -290.47202) (xy 53.733337 -290.511364)
			(xy 53.756208 -290.554941) (xy 53.771792 -290.601622) (xy 53.779687 -290.650199) (xy 53.780182 -290.674806)
			(xy 54.11903 -290.674806) (xy 54.12299 -290.625752) (xy 54.134767 -290.577968) (xy 54.154058 -290.532692)
			(xy 54.180361 -290.491096) (xy 54.212996 -290.454259) (xy 54.251117 -290.423134) (xy 54.293738 -290.398527)
			(xy 54.339754 -290.381075) (xy 54.387973 -290.371231) (xy 54.437148 -290.36925) (xy 54.486003 -290.375182)
			(xy 54.533274 -290.388874) (xy 54.577736 -290.409972) (xy 54.618239 -290.437928) (xy 54.653732 -290.47202)
			(xy 54.683297 -290.511364) (xy 54.706168 -290.554941) (xy 54.721752 -290.601622) (xy 54.729647 -290.650199)
			(xy 54.730142 -290.674806) (xy 55.06899 -290.674806) (xy 55.07295 -290.625752) (xy 55.084727 -290.577968)
			(xy 55.104018 -290.532692) (xy 55.130321 -290.491096) (xy 55.162956 -290.454259) (xy 55.201077 -290.423134)
			(xy 55.243698 -290.398527) (xy 55.289714 -290.381075) (xy 55.337933 -290.371231) (xy 55.387108 -290.36925)
			(xy 55.435963 -290.375182) (xy 55.483234 -290.388874) (xy 55.527696 -290.409972) (xy 55.568199 -290.437928)
			(xy 55.603692 -290.47202) (xy 55.633257 -290.511364) (xy 55.656128 -290.554941) (xy 55.671712 -290.601622)
			(xy 55.679607 -290.650199) (xy 55.680102 -290.674806) (xy 56.01895 -290.674806) (xy 56.02291 -290.625752)
			(xy 56.034687 -290.577968) (xy 56.053978 -290.532692) (xy 56.080281 -290.491096) (xy 56.112916 -290.454259)
			(xy 56.151037 -290.423134) (xy 56.193658 -290.398527) (xy 56.239674 -290.381075) (xy 56.287893 -290.371231)
			(xy 56.337068 -290.36925) (xy 56.385923 -290.375182) (xy 56.433194 -290.388874) (xy 56.477656 -290.409972)
			(xy 56.518159 -290.437928) (xy 56.553652 -290.47202) (xy 56.583217 -290.511364) (xy 56.606088 -290.554941)
			(xy 56.621672 -290.601622) (xy 56.629567 -290.650199) (xy 56.630062 -290.674806) (xy 56.969164 -290.674806)
			(xy 56.973124 -290.625752) (xy 56.984901 -290.577968) (xy 57.004192 -290.532692) (xy 57.030495 -290.491096)
			(xy 57.06313 -290.454259) (xy 57.101251 -290.423134) (xy 57.143872 -290.398527) (xy 57.189888 -290.381075)
			(xy 57.238107 -290.371231) (xy 57.287282 -290.36925) (xy 57.336137 -290.375182) (xy 57.383408 -290.388874)
			(xy 57.42787 -290.409972) (xy 57.468373 -290.437928) (xy 57.503866 -290.47202) (xy 57.533431 -290.511364)
			(xy 57.556302 -290.554941) (xy 57.571886 -290.601622) (xy 57.579781 -290.650199) (xy 57.580276 -290.674806)
			(xy 57.919124 -290.674806) (xy 57.923084 -290.625752) (xy 57.934861 -290.577968) (xy 57.954152 -290.532692)
			(xy 57.980455 -290.491096) (xy 58.01309 -290.454259) (xy 58.051211 -290.423134) (xy 58.093832 -290.398527)
			(xy 58.139848 -290.381075) (xy 58.188067 -290.371231) (xy 58.237242 -290.36925) (xy 58.286097 -290.375182)
			(xy 58.333368 -290.388874) (xy 58.37783 -290.409972) (xy 58.418333 -290.437928) (xy 58.453826 -290.47202)
			(xy 58.483391 -290.511364) (xy 58.506262 -290.554941) (xy 58.521846 -290.601622) (xy 58.529741 -290.650199)
			(xy 58.530236 -290.674806) (xy 59.819044 -290.674806) (xy 59.823004 -290.625752) (xy 59.834781 -290.577968)
			(xy 59.854072 -290.532692) (xy 59.880375 -290.491096) (xy 59.91301 -290.454259) (xy 59.951131 -290.423134)
			(xy 59.993752 -290.398527) (xy 60.039768 -290.381075) (xy 60.087987 -290.371231) (xy 60.137162 -290.36925)
			(xy 60.186017 -290.375182) (xy 60.233288 -290.388874) (xy 60.27775 -290.409972) (xy 60.318253 -290.437928)
			(xy 60.353746 -290.47202) (xy 60.383311 -290.511364) (xy 60.406182 -290.554941) (xy 60.421766 -290.601622)
			(xy 60.429661 -290.650199) (xy 60.430156 -290.674806) (xy 60.769004 -290.674806) (xy 60.772964 -290.625752)
			(xy 60.784741 -290.577968) (xy 60.804032 -290.532692) (xy 60.830335 -290.491096) (xy 60.86297 -290.454259)
			(xy 60.901091 -290.423134) (xy 60.943712 -290.398527) (xy 60.989728 -290.381075) (xy 61.037947 -290.371231)
			(xy 61.087122 -290.36925) (xy 61.135977 -290.375182) (xy 61.183248 -290.388874) (xy 61.22771 -290.409972)
			(xy 61.268213 -290.437928) (xy 61.303706 -290.47202) (xy 61.333271 -290.511364) (xy 61.356142 -290.554941)
			(xy 61.371726 -290.601622) (xy 61.379621 -290.650199) (xy 61.380116 -290.674806) (xy 61.718964 -290.674806)
			(xy 61.722924 -290.625752) (xy 61.734701 -290.577968) (xy 61.753992 -290.532692) (xy 61.780295 -290.491096)
			(xy 61.81293 -290.454259) (xy 61.851051 -290.423134) (xy 61.893672 -290.398527) (xy 61.939688 -290.381075)
			(xy 61.987907 -290.371231) (xy 62.037082 -290.36925) (xy 62.085937 -290.375182) (xy 62.133208 -290.388874)
			(xy 62.17767 -290.409972) (xy 62.218173 -290.437928) (xy 62.253666 -290.47202) (xy 62.283231 -290.511364)
			(xy 62.306102 -290.554941) (xy 62.321686 -290.601622) (xy 62.329581 -290.650199) (xy 62.330076 -290.674806)
			(xy 62.669178 -290.674806) (xy 62.673138 -290.625752) (xy 62.684915 -290.577968) (xy 62.704206 -290.532692)
			(xy 62.730509 -290.491096) (xy 62.763144 -290.454259) (xy 62.801265 -290.423134) (xy 62.843886 -290.398527)
			(xy 62.889902 -290.381075) (xy 62.938121 -290.371231) (xy 62.987296 -290.36925) (xy 63.036151 -290.375182)
			(xy 63.083422 -290.388874) (xy 63.127884 -290.409972) (xy 63.168387 -290.437928) (xy 63.20388 -290.47202)
			(xy 63.233445 -290.511364) (xy 63.256316 -290.554941) (xy 63.2719 -290.601622) (xy 63.279795 -290.650199)
			(xy 63.28029 -290.674806) (xy 63.619138 -290.674806) (xy 63.623098 -290.625752) (xy 63.634875 -290.577968)
			(xy 63.654166 -290.532692) (xy 63.680469 -290.491096) (xy 63.713104 -290.454259) (xy 63.751225 -290.423134)
			(xy 63.793846 -290.398527) (xy 63.839862 -290.381075) (xy 63.888081 -290.371231) (xy 63.937256 -290.36925)
			(xy 63.986111 -290.375182) (xy 64.033382 -290.388874) (xy 64.077844 -290.409972) (xy 64.118347 -290.437928)
			(xy 64.15384 -290.47202) (xy 64.183405 -290.511364) (xy 64.206276 -290.554941) (xy 64.22186 -290.601622)
			(xy 64.229755 -290.650199) (xy 64.23025 -290.674806) (xy 64.569098 -290.674806) (xy 64.573058 -290.625752)
			(xy 64.584835 -290.577968) (xy 64.604126 -290.532692) (xy 64.630429 -290.491096) (xy 64.663064 -290.454259)
			(xy 64.701185 -290.423134) (xy 64.743806 -290.398527) (xy 64.789822 -290.381075) (xy 64.838041 -290.371231)
			(xy 64.887216 -290.36925) (xy 64.936071 -290.375182) (xy 64.983342 -290.388874) (xy 65.027804 -290.409972)
			(xy 65.068307 -290.437928) (xy 65.1038 -290.47202) (xy 65.133365 -290.511364) (xy 65.156236 -290.554941)
			(xy 65.17182 -290.601622) (xy 65.179715 -290.650199) (xy 65.18021 -290.674806) (xy 65.519058 -290.674806)
			(xy 65.523018 -290.625752) (xy 65.534795 -290.577968) (xy 65.554086 -290.532692) (xy 65.580389 -290.491096)
			(xy 65.613024 -290.454259) (xy 65.651145 -290.423134) (xy 65.693766 -290.398527) (xy 65.739782 -290.381075)
			(xy 65.788001 -290.371231) (xy 65.837176 -290.36925) (xy 65.886031 -290.375182) (xy 65.933302 -290.388874)
			(xy 65.977764 -290.409972) (xy 66.018267 -290.437928) (xy 66.05376 -290.47202) (xy 66.083325 -290.511364)
			(xy 66.106196 -290.554941) (xy 66.12178 -290.601622) (xy 66.129675 -290.650199) (xy 66.13017 -290.674806)
			(xy 66.469018 -290.674806) (xy 66.472978 -290.625752) (xy 66.484755 -290.577968) (xy 66.504046 -290.532692)
			(xy 66.530349 -290.491096) (xy 66.562984 -290.454259) (xy 66.601105 -290.423134) (xy 66.643726 -290.398527)
			(xy 66.689742 -290.381075) (xy 66.737961 -290.371231) (xy 66.787136 -290.36925) (xy 66.835991 -290.375182)
			(xy 66.883262 -290.388874) (xy 66.927724 -290.409972) (xy 66.968227 -290.437928) (xy 67.00372 -290.47202)
			(xy 67.033285 -290.511364) (xy 67.056156 -290.554941) (xy 67.07174 -290.601622) (xy 67.079635 -290.650199)
			(xy 67.08013 -290.674806) (xy 67.418978 -290.674806) (xy 67.422938 -290.625752) (xy 67.434715 -290.577968)
			(xy 67.454006 -290.532692) (xy 67.480309 -290.491096) (xy 67.512944 -290.454259) (xy 67.551065 -290.423134)
			(xy 67.593686 -290.398527) (xy 67.639702 -290.381075) (xy 67.687921 -290.371231) (xy 67.737096 -290.36925)
			(xy 67.785951 -290.375182) (xy 67.833222 -290.388874) (xy 67.877684 -290.409972) (xy 67.918187 -290.437928)
			(xy 67.95368 -290.47202) (xy 67.983245 -290.511364) (xy 68.006116 -290.554941) (xy 68.0217 -290.601622)
			(xy 68.029595 -290.650199) (xy 68.03009 -290.674806) (xy 68.368938 -290.674806) (xy 68.372898 -290.625752)
			(xy 68.384675 -290.577968) (xy 68.403966 -290.532692) (xy 68.430269 -290.491096) (xy 68.462904 -290.454259)
			(xy 68.501025 -290.423134) (xy 68.543646 -290.398527) (xy 68.589662 -290.381075) (xy 68.637881 -290.371231)
			(xy 68.687056 -290.36925) (xy 68.735911 -290.375182) (xy 68.783182 -290.388874) (xy 68.827644 -290.409972)
			(xy 68.868147 -290.437928) (xy 68.90364 -290.47202) (xy 68.933205 -290.511364) (xy 68.956076 -290.554941)
			(xy 68.97166 -290.601622) (xy 68.979555 -290.650199) (xy 68.98005 -290.674806) (xy 69.319152 -290.674806)
			(xy 69.323112 -290.625752) (xy 69.334889 -290.577968) (xy 69.35418 -290.532692) (xy 69.380483 -290.491096)
			(xy 69.413118 -290.454259) (xy 69.451239 -290.423134) (xy 69.49386 -290.398527) (xy 69.539876 -290.381075)
			(xy 69.588095 -290.371231) (xy 69.63727 -290.36925) (xy 69.686125 -290.375182) (xy 69.733396 -290.388874)
			(xy 69.777858 -290.409972) (xy 69.818361 -290.437928) (xy 69.853854 -290.47202) (xy 69.883419 -290.511364)
			(xy 69.90629 -290.554941) (xy 69.921874 -290.601622) (xy 69.929769 -290.650199) (xy 69.930264 -290.674806)
			(xy 70.269112 -290.674806) (xy 70.273072 -290.625752) (xy 70.284849 -290.577968) (xy 70.30414 -290.532692)
			(xy 70.330443 -290.491096) (xy 70.363078 -290.454259) (xy 70.401199 -290.423134) (xy 70.44382 -290.398527)
			(xy 70.489836 -290.381075) (xy 70.538055 -290.371231) (xy 70.58723 -290.36925) (xy 70.636085 -290.375182)
			(xy 70.683356 -290.388874) (xy 70.727818 -290.409972) (xy 70.768321 -290.437928) (xy 70.803814 -290.47202)
			(xy 70.833379 -290.511364) (xy 70.85625 -290.554941) (xy 70.871834 -290.601622) (xy 70.879729 -290.650199)
			(xy 70.880224 -290.674806) (xy 71.219072 -290.674806) (xy 71.223032 -290.625752) (xy 71.234809 -290.577968)
			(xy 71.2541 -290.532692) (xy 71.280403 -290.491096) (xy 71.313038 -290.454259) (xy 71.351159 -290.423134)
			(xy 71.39378 -290.398527) (xy 71.439796 -290.381075) (xy 71.488015 -290.371231) (xy 71.53719 -290.36925)
			(xy 71.586045 -290.375182) (xy 71.633316 -290.388874) (xy 71.677778 -290.409972) (xy 71.718281 -290.437928)
			(xy 71.753774 -290.47202) (xy 71.783339 -290.511364) (xy 71.80621 -290.554941) (xy 71.821794 -290.601622)
			(xy 71.829689 -290.650199) (xy 71.830184 -290.674806) (xy 72.169032 -290.674806) (xy 72.172992 -290.625752)
			(xy 72.184769 -290.577968) (xy 72.20406 -290.532692) (xy 72.230363 -290.491096) (xy 72.262998 -290.454259)
			(xy 72.301119 -290.423134) (xy 72.34374 -290.398527) (xy 72.389756 -290.381075) (xy 72.437975 -290.371231)
			(xy 72.48715 -290.36925) (xy 72.536005 -290.375182) (xy 72.583276 -290.388874) (xy 72.627738 -290.409972)
			(xy 72.668241 -290.437928) (xy 72.703734 -290.47202) (xy 72.733299 -290.511364) (xy 72.75617 -290.554941)
			(xy 72.771754 -290.601622) (xy 72.779649 -290.650199) (xy 72.780144 -290.674806) (xy 73.118992 -290.674806)
			(xy 73.122952 -290.625752) (xy 73.134729 -290.577968) (xy 73.15402 -290.532692) (xy 73.180323 -290.491096)
			(xy 73.212958 -290.454259) (xy 73.251079 -290.423134) (xy 73.2937 -290.398527) (xy 73.339716 -290.381075)
			(xy 73.387935 -290.371231) (xy 73.43711 -290.36925) (xy 73.485965 -290.375182) (xy 73.533236 -290.388874)
			(xy 73.577698 -290.409972) (xy 73.618201 -290.437928) (xy 73.653694 -290.47202) (xy 73.683259 -290.511364)
			(xy 73.70613 -290.554941) (xy 73.721714 -290.601622) (xy 73.729609 -290.650199) (xy 73.730104 -290.674806)
			(xy 74.068952 -290.674806) (xy 74.072912 -290.625752) (xy 74.084689 -290.577968) (xy 74.10398 -290.532692)
			(xy 74.130283 -290.491096) (xy 74.162918 -290.454259) (xy 74.201039 -290.423134) (xy 74.24366 -290.398527)
			(xy 74.289676 -290.381075) (xy 74.337895 -290.371231) (xy 74.38707 -290.36925) (xy 74.435925 -290.375182)
			(xy 74.483196 -290.388874) (xy 74.527658 -290.409972) (xy 74.568161 -290.437928) (xy 74.603654 -290.47202)
			(xy 74.633219 -290.511364) (xy 74.65609 -290.554941) (xy 74.671674 -290.601622) (xy 74.679569 -290.650199)
			(xy 74.680064 -290.674806) (xy 75.019166 -290.674806) (xy 75.023126 -290.625752) (xy 75.034903 -290.577968)
			(xy 75.054194 -290.532692) (xy 75.080497 -290.491096) (xy 75.113132 -290.454259) (xy 75.151253 -290.423134)
			(xy 75.193874 -290.398527) (xy 75.23989 -290.381075) (xy 75.288109 -290.371231) (xy 75.337284 -290.36925)
			(xy 75.386139 -290.375182) (xy 75.43341 -290.388874) (xy 75.477872 -290.409972) (xy 75.518375 -290.437928)
			(xy 75.553868 -290.47202) (xy 75.583433 -290.511364) (xy 75.606304 -290.554941) (xy 75.621888 -290.601622)
			(xy 75.629783 -290.650199) (xy 75.630278 -290.674806) (xy 75.969126 -290.674806) (xy 75.973086 -290.625752)
			(xy 75.984863 -290.577968) (xy 76.004154 -290.532692) (xy 76.030457 -290.491096) (xy 76.063092 -290.454259)
			(xy 76.101213 -290.423134) (xy 76.143834 -290.398527) (xy 76.18985 -290.381075) (xy 76.238069 -290.371231)
			(xy 76.287244 -290.36925) (xy 76.336099 -290.375182) (xy 76.38337 -290.388874) (xy 76.427832 -290.409972)
			(xy 76.468335 -290.437928) (xy 76.503828 -290.47202) (xy 76.533393 -290.511364) (xy 76.556264 -290.554941)
			(xy 76.571848 -290.601622) (xy 76.579743 -290.650199) (xy 76.580238 -290.674806) (xy 76.919086 -290.674806)
			(xy 76.923046 -290.625752) (xy 76.934823 -290.577968) (xy 76.954114 -290.532692) (xy 76.980417 -290.491096)
			(xy 77.013052 -290.454259) (xy 77.051173 -290.423134) (xy 77.093794 -290.398527) (xy 77.13981 -290.381075)
			(xy 77.188029 -290.371231) (xy 77.237204 -290.36925) (xy 77.286059 -290.375182) (xy 77.33333 -290.388874)
			(xy 77.377792 -290.409972) (xy 77.418295 -290.437928) (xy 77.453788 -290.47202) (xy 77.483353 -290.511364)
			(xy 77.506224 -290.554941) (xy 77.521808 -290.601622) (xy 77.529703 -290.650199) (xy 77.530198 -290.674806)
			(xy 77.869046 -290.674806) (xy 77.873006 -290.625752) (xy 77.884783 -290.577968) (xy 77.904074 -290.532692)
			(xy 77.930377 -290.491096) (xy 77.963012 -290.454259) (xy 78.001133 -290.423134) (xy 78.043754 -290.398527)
			(xy 78.08977 -290.381075) (xy 78.137989 -290.371231) (xy 78.187164 -290.36925) (xy 78.236019 -290.375182)
			(xy 78.28329 -290.388874) (xy 78.327752 -290.409972) (xy 78.368255 -290.437928) (xy 78.403748 -290.47202)
			(xy 78.433313 -290.511364) (xy 78.456184 -290.554941) (xy 78.471768 -290.601622) (xy 78.479663 -290.650199)
			(xy 78.480158 -290.674806) (xy 78.819006 -290.674806) (xy 78.822966 -290.625752) (xy 78.834743 -290.577968)
			(xy 78.854034 -290.532692) (xy 78.880337 -290.491096) (xy 78.912972 -290.454259) (xy 78.951093 -290.423134)
			(xy 78.993714 -290.398527) (xy 79.03973 -290.381075) (xy 79.087949 -290.371231) (xy 79.137124 -290.36925)
			(xy 79.185979 -290.375182) (xy 79.23325 -290.388874) (xy 79.277712 -290.409972) (xy 79.318215 -290.437928)
			(xy 79.353708 -290.47202) (xy 79.383273 -290.511364) (xy 79.406144 -290.554941) (xy 79.421728 -290.601622)
			(xy 79.429623 -290.650199) (xy 79.430118 -290.674806) (xy 79.768966 -290.674806) (xy 79.772926 -290.625752)
			(xy 79.784703 -290.577968) (xy 79.803994 -290.532692) (xy 79.830297 -290.491096) (xy 79.862932 -290.454259)
			(xy 79.901053 -290.423134) (xy 79.943674 -290.398527) (xy 79.98969 -290.381075) (xy 80.037909 -290.371231)
			(xy 80.087084 -290.36925) (xy 80.135939 -290.375182) (xy 80.18321 -290.388874) (xy 80.227672 -290.409972)
			(xy 80.268175 -290.437928) (xy 80.303668 -290.47202) (xy 80.333233 -290.511364) (xy 80.356104 -290.554941)
			(xy 80.371688 -290.601622) (xy 80.379583 -290.650199) (xy 80.380078 -290.674806) (xy 80.71918 -290.674806)
			(xy 80.72314 -290.625752) (xy 80.734917 -290.577968) (xy 80.754208 -290.532692) (xy 80.780511 -290.491096)
			(xy 80.813146 -290.454259) (xy 80.851267 -290.423134) (xy 80.893888 -290.398527) (xy 80.939904 -290.381075)
			(xy 80.988123 -290.371231) (xy 81.037298 -290.36925) (xy 81.086153 -290.375182) (xy 81.133424 -290.388874)
			(xy 81.177886 -290.409972) (xy 81.218389 -290.437928) (xy 81.253882 -290.47202) (xy 81.283447 -290.511364)
			(xy 81.306318 -290.554941) (xy 81.321902 -290.601622) (xy 81.329797 -290.650199) (xy 81.330292 -290.674806)
			(xy 81.66914 -290.674806) (xy 81.6731 -290.625752) (xy 81.684877 -290.577968) (xy 81.704168 -290.532692)
			(xy 81.730471 -290.491096) (xy 81.763106 -290.454259) (xy 81.801227 -290.423134) (xy 81.843848 -290.398527)
			(xy 81.889864 -290.381075) (xy 81.938083 -290.371231) (xy 81.987258 -290.36925) (xy 82.036113 -290.375182)
			(xy 82.083384 -290.388874) (xy 82.127846 -290.409972) (xy 82.168349 -290.437928) (xy 82.203842 -290.47202)
			(xy 82.233407 -290.511364) (xy 82.256278 -290.554941) (xy 82.271862 -290.601622) (xy 82.279757 -290.650199)
			(xy 82.280252 -290.674806) (xy 82.6191 -290.674806) (xy 82.62306 -290.625752) (xy 82.634837 -290.577968)
			(xy 82.654128 -290.532692) (xy 82.680431 -290.491096) (xy 82.713066 -290.454259) (xy 82.751187 -290.423134)
			(xy 82.793808 -290.398527) (xy 82.839824 -290.381075) (xy 82.888043 -290.371231) (xy 82.937218 -290.36925)
			(xy 82.986073 -290.375182) (xy 83.033344 -290.388874) (xy 83.077806 -290.409972) (xy 83.118309 -290.437928)
			(xy 83.126927 -290.446206) (xy 85.153752 -290.446206) (xy 85.157823 -290.390584) (xy 85.169949 -290.336147)
			(xy 85.189872 -290.284056) (xy 85.217168 -290.235421) (xy 85.251254 -290.191278) (xy 85.291403 -290.152569)
			(xy 85.336761 -290.120118) (xy 85.386361 -290.094617) (xy 85.439145 -290.07661) (xy 85.493988 -290.06648)
			(xy 85.549722 -290.064443) (xy 85.605159 -290.070543) (xy 85.659116 -290.084649) (xy 85.710445 -290.106461)
			(xy 85.758051 -290.135515) (xy 85.800919 -290.17119) (xy 85.838136 -290.212727) (xy 85.854304 -290.237164)
			(xy 89.164412 -290.237164) (xy 89.168483 -290.181542) (xy 89.180609 -290.127105) (xy 89.200532 -290.075014)
			(xy 89.227828 -290.026379) (xy 89.261914 -289.982236) (xy 89.302063 -289.943527) (xy 89.347421 -289.911076)
			(xy 89.397021 -289.885575) (xy 89.449805 -289.867568) (xy 89.504648 -289.857438) (xy 89.560382 -289.855401)
			(xy 89.615819 -289.861501) (xy 89.669776 -289.875607) (xy 89.721105 -289.897419) (xy 89.768711 -289.926473)
			(xy 89.811579 -289.962148) (xy 89.848796 -290.003685) (xy 89.879569 -290.050198) (xy 89.903241 -290.100695)
			(xy 89.919309 -290.154102) (xy 89.927429 -290.209278) (xy 89.927938 -290.237164) (xy 89.927429 -290.26505)
			(xy 89.919309 -290.320226) (xy 89.903241 -290.373633) (xy 89.879569 -290.42413) (xy 89.848796 -290.470643)
			(xy 89.811579 -290.51218) (xy 89.768711 -290.547855) (xy 89.721105 -290.576909) (xy 89.669776 -290.598721)
			(xy 89.615819 -290.612827) (xy 89.560382 -290.618927) (xy 89.504648 -290.61689) (xy 89.449805 -290.60676)
			(xy 89.397021 -290.588753) (xy 89.347421 -290.563252) (xy 89.302063 -290.530801) (xy 89.261914 -290.492092)
			(xy 89.227828 -290.447949) (xy 89.200532 -290.399314) (xy 89.180609 -290.347223) (xy 89.168483 -290.292786)
			(xy 89.164412 -290.237164) (xy 85.854304 -290.237164) (xy 85.868909 -290.25924) (xy 85.892581 -290.309737)
			(xy 85.908649 -290.363144) (xy 85.916769 -290.41832) (xy 85.917278 -290.446206) (xy 85.916769 -290.474092)
			(xy 85.908649 -290.529268) (xy 85.892581 -290.582675) (xy 85.868909 -290.633172) (xy 85.838136 -290.679685)
			(xy 85.800919 -290.721222) (xy 85.758051 -290.756897) (xy 85.710445 -290.785951) (xy 85.659116 -290.807763)
			(xy 85.605159 -290.821869) (xy 85.549722 -290.827969) (xy 85.493988 -290.825932) (xy 85.439145 -290.815802)
			(xy 85.386361 -290.797795) (xy 85.336761 -290.772294) (xy 85.291403 -290.739843) (xy 85.251254 -290.701134)
			(xy 85.217168 -290.656991) (xy 85.189872 -290.608356) (xy 85.169949 -290.556265) (xy 85.157823 -290.501828)
			(xy 85.153752 -290.446206) (xy 83.126927 -290.446206) (xy 83.153802 -290.47202) (xy 83.183367 -290.511364)
			(xy 83.206238 -290.554941) (xy 83.221822 -290.601622) (xy 83.229717 -290.650199) (xy 83.230212 -290.674806)
			(xy 83.229717 -290.699413) (xy 83.221822 -290.74799) (xy 83.206238 -290.794671) (xy 83.183367 -290.838248)
			(xy 83.153802 -290.877592) (xy 83.118309 -290.911684) (xy 83.077806 -290.93964) (xy 83.033344 -290.960738)
			(xy 82.986073 -290.97443) (xy 82.937218 -290.980362) (xy 82.888043 -290.978381) (xy 82.839824 -290.968537)
			(xy 82.793808 -290.951085) (xy 82.751187 -290.926478) (xy 82.713066 -290.895353) (xy 82.680431 -290.858516)
			(xy 82.654128 -290.81692) (xy 82.634837 -290.771644) (xy 82.62306 -290.72386) (xy 82.6191 -290.674806)
			(xy 82.280252 -290.674806) (xy 82.279757 -290.699413) (xy 82.271862 -290.74799) (xy 82.256278 -290.794671)
			(xy 82.233407 -290.838248) (xy 82.203842 -290.877592) (xy 82.168349 -290.911684) (xy 82.127846 -290.93964)
			(xy 82.083384 -290.960738) (xy 82.036113 -290.97443) (xy 81.987258 -290.980362) (xy 81.938083 -290.978381)
			(xy 81.889864 -290.968537) (xy 81.843848 -290.951085) (xy 81.801227 -290.926478) (xy 81.763106 -290.895353)
			(xy 81.730471 -290.858516) (xy 81.704168 -290.81692) (xy 81.684877 -290.771644) (xy 81.6731 -290.72386)
			(xy 81.66914 -290.674806) (xy 81.330292 -290.674806) (xy 81.329797 -290.699413) (xy 81.321902 -290.74799)
			(xy 81.306318 -290.794671) (xy 81.283447 -290.838248) (xy 81.253882 -290.877592) (xy 81.218389 -290.911684)
			(xy 81.177886 -290.93964) (xy 81.133424 -290.960738) (xy 81.086153 -290.97443) (xy 81.037298 -290.980362)
			(xy 80.988123 -290.978381) (xy 80.939904 -290.968537) (xy 80.893888 -290.951085) (xy 80.851267 -290.926478)
			(xy 80.813146 -290.895353) (xy 80.780511 -290.858516) (xy 80.754208 -290.81692) (xy 80.734917 -290.771644)
			(xy 80.72314 -290.72386) (xy 80.71918 -290.674806) (xy 80.380078 -290.674806) (xy 80.379583 -290.699413)
			(xy 80.371688 -290.74799) (xy 80.356104 -290.794671) (xy 80.333233 -290.838248) (xy 80.303668 -290.877592)
			(xy 80.268175 -290.911684) (xy 80.227672 -290.93964) (xy 80.18321 -290.960738) (xy 80.135939 -290.97443)
			(xy 80.087084 -290.980362) (xy 80.037909 -290.978381) (xy 79.98969 -290.968537) (xy 79.943674 -290.951085)
			(xy 79.901053 -290.926478) (xy 79.862932 -290.895353) (xy 79.830297 -290.858516) (xy 79.803994 -290.81692)
			(xy 79.784703 -290.771644) (xy 79.772926 -290.72386) (xy 79.768966 -290.674806) (xy 79.430118 -290.674806)
			(xy 79.429623 -290.699413) (xy 79.421728 -290.74799) (xy 79.406144 -290.794671) (xy 79.383273 -290.838248)
			(xy 79.353708 -290.877592) (xy 79.318215 -290.911684) (xy 79.277712 -290.93964) (xy 79.23325 -290.960738)
			(xy 79.185979 -290.97443) (xy 79.137124 -290.980362) (xy 79.087949 -290.978381) (xy 79.03973 -290.968537)
			(xy 78.993714 -290.951085) (xy 78.951093 -290.926478) (xy 78.912972 -290.895353) (xy 78.880337 -290.858516)
			(xy 78.854034 -290.81692) (xy 78.834743 -290.771644) (xy 78.822966 -290.72386) (xy 78.819006 -290.674806)
			(xy 78.480158 -290.674806) (xy 78.479663 -290.699413) (xy 78.471768 -290.74799) (xy 78.456184 -290.794671)
			(xy 78.433313 -290.838248) (xy 78.403748 -290.877592) (xy 78.368255 -290.911684) (xy 78.327752 -290.93964)
			(xy 78.28329 -290.960738) (xy 78.236019 -290.97443) (xy 78.187164 -290.980362) (xy 78.137989 -290.978381)
			(xy 78.08977 -290.968537) (xy 78.043754 -290.951085) (xy 78.001133 -290.926478) (xy 77.963012 -290.895353)
			(xy 77.930377 -290.858516) (xy 77.904074 -290.81692) (xy 77.884783 -290.771644) (xy 77.873006 -290.72386)
			(xy 77.869046 -290.674806) (xy 77.530198 -290.674806) (xy 77.529703 -290.699413) (xy 77.521808 -290.74799)
			(xy 77.506224 -290.794671) (xy 77.483353 -290.838248) (xy 77.453788 -290.877592) (xy 77.418295 -290.911684)
			(xy 77.377792 -290.93964) (xy 77.33333 -290.960738) (xy 77.286059 -290.97443) (xy 77.237204 -290.980362)
			(xy 77.188029 -290.978381) (xy 77.13981 -290.968537) (xy 77.093794 -290.951085) (xy 77.051173 -290.926478)
			(xy 77.013052 -290.895353) (xy 76.980417 -290.858516) (xy 76.954114 -290.81692) (xy 76.934823 -290.771644)
			(xy 76.923046 -290.72386) (xy 76.919086 -290.674806) (xy 76.580238 -290.674806) (xy 76.579743 -290.699413)
			(xy 76.571848 -290.74799) (xy 76.556264 -290.794671) (xy 76.533393 -290.838248) (xy 76.503828 -290.877592)
			(xy 76.468335 -290.911684) (xy 76.427832 -290.93964) (xy 76.38337 -290.960738) (xy 76.336099 -290.97443)
			(xy 76.287244 -290.980362) (xy 76.238069 -290.978381) (xy 76.18985 -290.968537) (xy 76.143834 -290.951085)
			(xy 76.101213 -290.926478) (xy 76.063092 -290.895353) (xy 76.030457 -290.858516) (xy 76.004154 -290.81692)
			(xy 75.984863 -290.771644) (xy 75.973086 -290.72386) (xy 75.969126 -290.674806) (xy 75.630278 -290.674806)
			(xy 75.629783 -290.699413) (xy 75.621888 -290.74799) (xy 75.606304 -290.794671) (xy 75.583433 -290.838248)
			(xy 75.553868 -290.877592) (xy 75.518375 -290.911684) (xy 75.477872 -290.93964) (xy 75.43341 -290.960738)
			(xy 75.386139 -290.97443) (xy 75.337284 -290.980362) (xy 75.288109 -290.978381) (xy 75.23989 -290.968537)
			(xy 75.193874 -290.951085) (xy 75.151253 -290.926478) (xy 75.113132 -290.895353) (xy 75.080497 -290.858516)
			(xy 75.054194 -290.81692) (xy 75.034903 -290.771644) (xy 75.023126 -290.72386) (xy 75.019166 -290.674806)
			(xy 74.680064 -290.674806) (xy 74.679569 -290.699413) (xy 74.671674 -290.74799) (xy 74.65609 -290.794671)
			(xy 74.633219 -290.838248) (xy 74.603654 -290.877592) (xy 74.568161 -290.911684) (xy 74.527658 -290.93964)
			(xy 74.483196 -290.960738) (xy 74.435925 -290.97443) (xy 74.38707 -290.980362) (xy 74.337895 -290.978381)
			(xy 74.289676 -290.968537) (xy 74.24366 -290.951085) (xy 74.201039 -290.926478) (xy 74.162918 -290.895353)
			(xy 74.130283 -290.858516) (xy 74.10398 -290.81692) (xy 74.084689 -290.771644) (xy 74.072912 -290.72386)
			(xy 74.068952 -290.674806) (xy 73.730104 -290.674806) (xy 73.729609 -290.699413) (xy 73.721714 -290.74799)
			(xy 73.70613 -290.794671) (xy 73.683259 -290.838248) (xy 73.653694 -290.877592) (xy 73.618201 -290.911684)
			(xy 73.577698 -290.93964) (xy 73.533236 -290.960738) (xy 73.485965 -290.97443) (xy 73.43711 -290.980362)
			(xy 73.387935 -290.978381) (xy 73.339716 -290.968537) (xy 73.2937 -290.951085) (xy 73.251079 -290.926478)
			(xy 73.212958 -290.895353) (xy 73.180323 -290.858516) (xy 73.15402 -290.81692) (xy 73.134729 -290.771644)
			(xy 73.122952 -290.72386) (xy 73.118992 -290.674806) (xy 72.780144 -290.674806) (xy 72.779649 -290.699413)
			(xy 72.771754 -290.74799) (xy 72.75617 -290.794671) (xy 72.733299 -290.838248) (xy 72.703734 -290.877592)
			(xy 72.668241 -290.911684) (xy 72.627738 -290.93964) (xy 72.583276 -290.960738) (xy 72.536005 -290.97443)
			(xy 72.48715 -290.980362) (xy 72.437975 -290.978381) (xy 72.389756 -290.968537) (xy 72.34374 -290.951085)
			(xy 72.301119 -290.926478) (xy 72.262998 -290.895353) (xy 72.230363 -290.858516) (xy 72.20406 -290.81692)
			(xy 72.184769 -290.771644) (xy 72.172992 -290.72386) (xy 72.169032 -290.674806) (xy 71.830184 -290.674806)
			(xy 71.829689 -290.699413) (xy 71.821794 -290.74799) (xy 71.80621 -290.794671) (xy 71.783339 -290.838248)
			(xy 71.753774 -290.877592) (xy 71.718281 -290.911684) (xy 71.677778 -290.93964) (xy 71.633316 -290.960738)
			(xy 71.586045 -290.97443) (xy 71.53719 -290.980362) (xy 71.488015 -290.978381) (xy 71.439796 -290.968537)
			(xy 71.39378 -290.951085) (xy 71.351159 -290.926478) (xy 71.313038 -290.895353) (xy 71.280403 -290.858516)
			(xy 71.2541 -290.81692) (xy 71.234809 -290.771644) (xy 71.223032 -290.72386) (xy 71.219072 -290.674806)
			(xy 70.880224 -290.674806) (xy 70.879729 -290.699413) (xy 70.871834 -290.74799) (xy 70.85625 -290.794671)
			(xy 70.833379 -290.838248) (xy 70.803814 -290.877592) (xy 70.768321 -290.911684) (xy 70.727818 -290.93964)
			(xy 70.683356 -290.960738) (xy 70.636085 -290.97443) (xy 70.58723 -290.980362) (xy 70.538055 -290.978381)
			(xy 70.489836 -290.968537) (xy 70.44382 -290.951085) (xy 70.401199 -290.926478) (xy 70.363078 -290.895353)
			(xy 70.330443 -290.858516) (xy 70.30414 -290.81692) (xy 70.284849 -290.771644) (xy 70.273072 -290.72386)
			(xy 70.269112 -290.674806) (xy 69.930264 -290.674806) (xy 69.929769 -290.699413) (xy 69.921874 -290.74799)
			(xy 69.90629 -290.794671) (xy 69.883419 -290.838248) (xy 69.853854 -290.877592) (xy 69.818361 -290.911684)
			(xy 69.777858 -290.93964) (xy 69.733396 -290.960738) (xy 69.686125 -290.97443) (xy 69.63727 -290.980362)
			(xy 69.588095 -290.978381) (xy 69.539876 -290.968537) (xy 69.49386 -290.951085) (xy 69.451239 -290.926478)
			(xy 69.413118 -290.895353) (xy 69.380483 -290.858516) (xy 69.35418 -290.81692) (xy 69.334889 -290.771644)
			(xy 69.323112 -290.72386) (xy 69.319152 -290.674806) (xy 68.98005 -290.674806) (xy 68.979555 -290.699413)
			(xy 68.97166 -290.74799) (xy 68.956076 -290.794671) (xy 68.933205 -290.838248) (xy 68.90364 -290.877592)
			(xy 68.868147 -290.911684) (xy 68.827644 -290.93964) (xy 68.783182 -290.960738) (xy 68.735911 -290.97443)
			(xy 68.687056 -290.980362) (xy 68.637881 -290.978381) (xy 68.589662 -290.968537) (xy 68.543646 -290.951085)
			(xy 68.501025 -290.926478) (xy 68.462904 -290.895353) (xy 68.430269 -290.858516) (xy 68.403966 -290.81692)
			(xy 68.384675 -290.771644) (xy 68.372898 -290.72386) (xy 68.368938 -290.674806) (xy 68.03009 -290.674806)
			(xy 68.029595 -290.699413) (xy 68.0217 -290.74799) (xy 68.006116 -290.794671) (xy 67.983245 -290.838248)
			(xy 67.95368 -290.877592) (xy 67.918187 -290.911684) (xy 67.877684 -290.93964) (xy 67.833222 -290.960738)
			(xy 67.785951 -290.97443) (xy 67.737096 -290.980362) (xy 67.687921 -290.978381) (xy 67.639702 -290.968537)
			(xy 67.593686 -290.951085) (xy 67.551065 -290.926478) (xy 67.512944 -290.895353) (xy 67.480309 -290.858516)
			(xy 67.454006 -290.81692) (xy 67.434715 -290.771644) (xy 67.422938 -290.72386) (xy 67.418978 -290.674806)
			(xy 67.08013 -290.674806) (xy 67.079635 -290.699413) (xy 67.07174 -290.74799) (xy 67.056156 -290.794671)
			(xy 67.033285 -290.838248) (xy 67.00372 -290.877592) (xy 66.968227 -290.911684) (xy 66.927724 -290.93964)
			(xy 66.883262 -290.960738) (xy 66.835991 -290.97443) (xy 66.787136 -290.980362) (xy 66.737961 -290.978381)
			(xy 66.689742 -290.968537) (xy 66.643726 -290.951085) (xy 66.601105 -290.926478) (xy 66.562984 -290.895353)
			(xy 66.530349 -290.858516) (xy 66.504046 -290.81692) (xy 66.484755 -290.771644) (xy 66.472978 -290.72386)
			(xy 66.469018 -290.674806) (xy 66.13017 -290.674806) (xy 66.129675 -290.699413) (xy 66.12178 -290.74799)
			(xy 66.106196 -290.794671) (xy 66.083325 -290.838248) (xy 66.05376 -290.877592) (xy 66.018267 -290.911684)
			(xy 65.977764 -290.93964) (xy 65.933302 -290.960738) (xy 65.886031 -290.97443) (xy 65.837176 -290.980362)
			(xy 65.788001 -290.978381) (xy 65.739782 -290.968537) (xy 65.693766 -290.951085) (xy 65.651145 -290.926478)
			(xy 65.613024 -290.895353) (xy 65.580389 -290.858516) (xy 65.554086 -290.81692) (xy 65.534795 -290.771644)
			(xy 65.523018 -290.72386) (xy 65.519058 -290.674806) (xy 65.18021 -290.674806) (xy 65.179715 -290.699413)
			(xy 65.17182 -290.74799) (xy 65.156236 -290.794671) (xy 65.133365 -290.838248) (xy 65.1038 -290.877592)
			(xy 65.068307 -290.911684) (xy 65.027804 -290.93964) (xy 64.983342 -290.960738) (xy 64.936071 -290.97443)
			(xy 64.887216 -290.980362) (xy 64.838041 -290.978381) (xy 64.789822 -290.968537) (xy 64.743806 -290.951085)
			(xy 64.701185 -290.926478) (xy 64.663064 -290.895353) (xy 64.630429 -290.858516) (xy 64.604126 -290.81692)
			(xy 64.584835 -290.771644) (xy 64.573058 -290.72386) (xy 64.569098 -290.674806) (xy 64.23025 -290.674806)
			(xy 64.229755 -290.699413) (xy 64.22186 -290.74799) (xy 64.206276 -290.794671) (xy 64.183405 -290.838248)
			(xy 64.15384 -290.877592) (xy 64.118347 -290.911684) (xy 64.077844 -290.93964) (xy 64.033382 -290.960738)
			(xy 63.986111 -290.97443) (xy 63.937256 -290.980362) (xy 63.888081 -290.978381) (xy 63.839862 -290.968537)
			(xy 63.793846 -290.951085) (xy 63.751225 -290.926478) (xy 63.713104 -290.895353) (xy 63.680469 -290.858516)
			(xy 63.654166 -290.81692) (xy 63.634875 -290.771644) (xy 63.623098 -290.72386) (xy 63.619138 -290.674806)
			(xy 63.28029 -290.674806) (xy 63.279795 -290.699413) (xy 63.2719 -290.74799) (xy 63.256316 -290.794671)
			(xy 63.233445 -290.838248) (xy 63.20388 -290.877592) (xy 63.168387 -290.911684) (xy 63.127884 -290.93964)
			(xy 63.083422 -290.960738) (xy 63.036151 -290.97443) (xy 62.987296 -290.980362) (xy 62.938121 -290.978381)
			(xy 62.889902 -290.968537) (xy 62.843886 -290.951085) (xy 62.801265 -290.926478) (xy 62.763144 -290.895353)
			(xy 62.730509 -290.858516) (xy 62.704206 -290.81692) (xy 62.684915 -290.771644) (xy 62.673138 -290.72386)
			(xy 62.669178 -290.674806) (xy 62.330076 -290.674806) (xy 62.329581 -290.699413) (xy 62.321686 -290.74799)
			(xy 62.306102 -290.794671) (xy 62.283231 -290.838248) (xy 62.253666 -290.877592) (xy 62.218173 -290.911684)
			(xy 62.17767 -290.93964) (xy 62.133208 -290.960738) (xy 62.085937 -290.97443) (xy 62.037082 -290.980362)
			(xy 61.987907 -290.978381) (xy 61.939688 -290.968537) (xy 61.893672 -290.951085) (xy 61.851051 -290.926478)
			(xy 61.81293 -290.895353) (xy 61.780295 -290.858516) (xy 61.753992 -290.81692) (xy 61.734701 -290.771644)
			(xy 61.722924 -290.72386) (xy 61.718964 -290.674806) (xy 61.380116 -290.674806) (xy 61.379621 -290.699413)
			(xy 61.371726 -290.74799) (xy 61.356142 -290.794671) (xy 61.333271 -290.838248) (xy 61.303706 -290.877592)
			(xy 61.268213 -290.911684) (xy 61.22771 -290.93964) (xy 61.183248 -290.960738) (xy 61.135977 -290.97443)
			(xy 61.087122 -290.980362) (xy 61.037947 -290.978381) (xy 60.989728 -290.968537) (xy 60.943712 -290.951085)
			(xy 60.901091 -290.926478) (xy 60.86297 -290.895353) (xy 60.830335 -290.858516) (xy 60.804032 -290.81692)
			(xy 60.784741 -290.771644) (xy 60.772964 -290.72386) (xy 60.769004 -290.674806) (xy 60.430156 -290.674806)
			(xy 60.429661 -290.699413) (xy 60.421766 -290.74799) (xy 60.406182 -290.794671) (xy 60.383311 -290.838248)
			(xy 60.353746 -290.877592) (xy 60.318253 -290.911684) (xy 60.27775 -290.93964) (xy 60.233288 -290.960738)
			(xy 60.186017 -290.97443) (xy 60.137162 -290.980362) (xy 60.087987 -290.978381) (xy 60.039768 -290.968537)
			(xy 59.993752 -290.951085) (xy 59.951131 -290.926478) (xy 59.91301 -290.895353) (xy 59.880375 -290.858516)
			(xy 59.854072 -290.81692) (xy 59.834781 -290.771644) (xy 59.823004 -290.72386) (xy 59.819044 -290.674806)
			(xy 58.530236 -290.674806) (xy 58.529741 -290.699413) (xy 58.521846 -290.74799) (xy 58.506262 -290.794671)
			(xy 58.483391 -290.838248) (xy 58.453826 -290.877592) (xy 58.418333 -290.911684) (xy 58.37783 -290.93964)
			(xy 58.333368 -290.960738) (xy 58.286097 -290.97443) (xy 58.237242 -290.980362) (xy 58.188067 -290.978381)
			(xy 58.139848 -290.968537) (xy 58.093832 -290.951085) (xy 58.051211 -290.926478) (xy 58.01309 -290.895353)
			(xy 57.980455 -290.858516) (xy 57.954152 -290.81692) (xy 57.934861 -290.771644) (xy 57.923084 -290.72386)
			(xy 57.919124 -290.674806) (xy 57.580276 -290.674806) (xy 57.579781 -290.699413) (xy 57.571886 -290.74799)
			(xy 57.556302 -290.794671) (xy 57.533431 -290.838248) (xy 57.503866 -290.877592) (xy 57.468373 -290.911684)
			(xy 57.42787 -290.93964) (xy 57.383408 -290.960738) (xy 57.336137 -290.97443) (xy 57.287282 -290.980362)
			(xy 57.238107 -290.978381) (xy 57.189888 -290.968537) (xy 57.143872 -290.951085) (xy 57.101251 -290.926478)
			(xy 57.06313 -290.895353) (xy 57.030495 -290.858516) (xy 57.004192 -290.81692) (xy 56.984901 -290.771644)
			(xy 56.973124 -290.72386) (xy 56.969164 -290.674806) (xy 56.630062 -290.674806) (xy 56.629567 -290.699413)
			(xy 56.621672 -290.74799) (xy 56.606088 -290.794671) (xy 56.583217 -290.838248) (xy 56.553652 -290.877592)
			(xy 56.518159 -290.911684) (xy 56.477656 -290.93964) (xy 56.433194 -290.960738) (xy 56.385923 -290.97443)
			(xy 56.337068 -290.980362) (xy 56.287893 -290.978381) (xy 56.239674 -290.968537) (xy 56.193658 -290.951085)
			(xy 56.151037 -290.926478) (xy 56.112916 -290.895353) (xy 56.080281 -290.858516) (xy 56.053978 -290.81692)
			(xy 56.034687 -290.771644) (xy 56.02291 -290.72386) (xy 56.01895 -290.674806) (xy 55.680102 -290.674806)
			(xy 55.679607 -290.699413) (xy 55.671712 -290.74799) (xy 55.656128 -290.794671) (xy 55.633257 -290.838248)
			(xy 55.603692 -290.877592) (xy 55.568199 -290.911684) (xy 55.527696 -290.93964) (xy 55.483234 -290.960738)
			(xy 55.435963 -290.97443) (xy 55.387108 -290.980362) (xy 55.337933 -290.978381) (xy 55.289714 -290.968537)
			(xy 55.243698 -290.951085) (xy 55.201077 -290.926478) (xy 55.162956 -290.895353) (xy 55.130321 -290.858516)
			(xy 55.104018 -290.81692) (xy 55.084727 -290.771644) (xy 55.07295 -290.72386) (xy 55.06899 -290.674806)
			(xy 54.730142 -290.674806) (xy 54.729647 -290.699413) (xy 54.721752 -290.74799) (xy 54.706168 -290.794671)
			(xy 54.683297 -290.838248) (xy 54.653732 -290.877592) (xy 54.618239 -290.911684) (xy 54.577736 -290.93964)
			(xy 54.533274 -290.960738) (xy 54.486003 -290.97443) (xy 54.437148 -290.980362) (xy 54.387973 -290.978381)
			(xy 54.339754 -290.968537) (xy 54.293738 -290.951085) (xy 54.251117 -290.926478) (xy 54.212996 -290.895353)
			(xy 54.180361 -290.858516) (xy 54.154058 -290.81692) (xy 54.134767 -290.771644) (xy 54.12299 -290.72386)
			(xy 54.11903 -290.674806) (xy 53.780182 -290.674806) (xy 53.779687 -290.699413) (xy 53.771792 -290.74799)
			(xy 53.756208 -290.794671) (xy 53.733337 -290.838248) (xy 53.703772 -290.877592) (xy 53.668279 -290.911684)
			(xy 53.627776 -290.93964) (xy 53.583314 -290.960738) (xy 53.536043 -290.97443) (xy 53.487188 -290.980362)
			(xy 53.438013 -290.978381) (xy 53.389794 -290.968537) (xy 53.343778 -290.951085) (xy 53.301157 -290.926478)
			(xy 53.263036 -290.895353) (xy 53.230401 -290.858516) (xy 53.204098 -290.81692) (xy 53.184807 -290.771644)
			(xy 53.17303 -290.72386) (xy 53.16907 -290.674806) (xy 52.830222 -290.674806) (xy 52.829727 -290.699413)
			(xy 52.821832 -290.74799) (xy 52.806248 -290.794671) (xy 52.783377 -290.838248) (xy 52.753812 -290.877592)
			(xy 52.718319 -290.911684) (xy 52.677816 -290.93964) (xy 52.633354 -290.960738) (xy 52.586083 -290.97443)
			(xy 52.537228 -290.980362) (xy 52.488053 -290.978381) (xy 52.439834 -290.968537) (xy 52.393818 -290.951085)
			(xy 52.351197 -290.926478) (xy 52.313076 -290.895353) (xy 52.280441 -290.858516) (xy 52.254138 -290.81692)
			(xy 52.234847 -290.771644) (xy 52.22307 -290.72386) (xy 52.21911 -290.674806) (xy 51.880262 -290.674806)
			(xy 51.879767 -290.699413) (xy 51.871872 -290.74799) (xy 51.856288 -290.794671) (xy 51.833417 -290.838248)
			(xy 51.803852 -290.877592) (xy 51.768359 -290.911684) (xy 51.727856 -290.93964) (xy 51.683394 -290.960738)
			(xy 51.636123 -290.97443) (xy 51.587268 -290.980362) (xy 51.538093 -290.978381) (xy 51.489874 -290.968537)
			(xy 51.443858 -290.951085) (xy 51.401237 -290.926478) (xy 51.363116 -290.895353) (xy 51.330481 -290.858516)
			(xy 51.304178 -290.81692) (xy 51.284887 -290.771644) (xy 51.27311 -290.72386) (xy 51.26915 -290.674806)
			(xy 50.930302 -290.674806) (xy 50.929807 -290.699413) (xy 50.921912 -290.74799) (xy 50.906328 -290.794671)
			(xy 50.883457 -290.838248) (xy 50.853892 -290.877592) (xy 50.818399 -290.911684) (xy 50.777896 -290.93964)
			(xy 50.733434 -290.960738) (xy 50.686163 -290.97443) (xy 50.637308 -290.980362) (xy 50.588133 -290.978381)
			(xy 50.539914 -290.968537) (xy 50.493898 -290.951085) (xy 50.451277 -290.926478) (xy 50.413156 -290.895353)
			(xy 50.380521 -290.858516) (xy 50.354218 -290.81692) (xy 50.334927 -290.771644) (xy 50.32315 -290.72386)
			(xy 50.31919 -290.674806) (xy 49.980088 -290.674806) (xy 49.979593 -290.699413) (xy 49.971698 -290.74799)
			(xy 49.956114 -290.794671) (xy 49.933243 -290.838248) (xy 49.903678 -290.877592) (xy 49.868185 -290.911684)
			(xy 49.827682 -290.93964) (xy 49.78322 -290.960738) (xy 49.735949 -290.97443) (xy 49.687094 -290.980362)
			(xy 49.637919 -290.978381) (xy 49.5897 -290.968537) (xy 49.543684 -290.951085) (xy 49.501063 -290.926478)
			(xy 49.462942 -290.895353) (xy 49.430307 -290.858516) (xy 49.404004 -290.81692) (xy 49.384713 -290.771644)
			(xy 49.372936 -290.72386) (xy 49.368976 -290.674806) (xy 48.080168 -290.674806) (xy 48.079948 -290.691583)
			(xy 48.076254 -290.724934) (xy 48.072802 -290.741354) (xy 48.0695 -290.75634) (xy 48.080422 -290.784788)
			(xy 48.104552 -290.80206) (xy 48.112426 -290.807648) (xy 48.124618 -290.81603) (xy 48.125888 -290.817046)
			(xy 48.12792 -290.818316) (xy 48.133508 -290.82238) (xy 48.143668 -290.829492) (xy 48.149256 -290.833302)
			(xy 48.170592 -290.850066) (xy 48.17237 -290.851844) (xy 48.175164 -290.853876) (xy 48.179736 -290.85794)
			(xy 48.193452 -290.87191) (xy 48.194468 -290.87318) (xy 48.196246 -290.874958) (xy 48.209454 -290.88969)
			(xy 48.21936 -290.903152) (xy 48.232854 -290.922734) (xy 48.254264 -290.965196) (xy 48.268852 -291.010457)
			(xy 48.276265 -291.05743) (xy 48.276764 -291.081206) (xy 48.276764 -291.226748) (xy 48.276991 -291.234225)
			(xy 48.281253 -291.248555) (xy 48.285146 -291.254942) (xy 48.30953 -291.291772) (xy 48.314659 -291.300301)
			(xy 48.318569 -291.319793) (xy 48.31474 -291.339301) (xy 48.303753 -291.35587) (xy 48.295814 -291.361876)
			(xy 48.187356 -291.435028) (xy 48.180752 -291.440362) (xy 48.168306 -291.4523) (xy 48.161194 -291.457888)
			(xy 48.151034 -291.464492) (xy 48.149002 -291.466778) (xy 48.105568 -291.497004) (xy 48.104806 -291.497512)
			(xy 48.092614 -291.506402) (xy 48.084907 -291.512513) (xy 48.074476 -291.529167) (xy 48.071118 -291.548528)
			(xy 48.072802 -291.558218) (xy 48.072802 -291.558726) (xy 48.076204 -291.575025) (xy 48.079893 -291.608118)
			(xy 48.080168 -291.624766) (xy 48.419016 -291.624766) (xy 48.422976 -291.575712) (xy 48.434753 -291.527928)
			(xy 48.454044 -291.482652) (xy 48.480347 -291.441056) (xy 48.512982 -291.404219) (xy 48.551103 -291.373094)
			(xy 48.593724 -291.348487) (xy 48.63974 -291.331035) (xy 48.687959 -291.321191) (xy 48.737134 -291.31921)
			(xy 48.785989 -291.325142) (xy 48.83326 -291.338834) (xy 48.877722 -291.359932) (xy 48.918225 -291.387888)
			(xy 48.953718 -291.42198) (xy 48.983283 -291.461324) (xy 49.006154 -291.504901) (xy 49.021738 -291.551582)
			(xy 49.029633 -291.600159) (xy 49.030128 -291.624766) (xy 50.31919 -291.624766) (xy 50.32315 -291.575712)
			(xy 50.334927 -291.527928) (xy 50.354218 -291.482652) (xy 50.380521 -291.441056) (xy 50.413156 -291.404219)
			(xy 50.451277 -291.373094) (xy 50.493898 -291.348487) (xy 50.539914 -291.331035) (xy 50.588133 -291.321191)
			(xy 50.637308 -291.31921) (xy 50.686163 -291.325142) (xy 50.733434 -291.338834) (xy 50.777896 -291.359932)
			(xy 50.818399 -291.387888) (xy 50.853892 -291.42198) (xy 50.883457 -291.461324) (xy 50.906328 -291.504901)
			(xy 50.921912 -291.551582) (xy 50.929807 -291.600159) (xy 50.930302 -291.624766) (xy 51.26915 -291.624766)
			(xy 51.27311 -291.575712) (xy 51.284887 -291.527928) (xy 51.304178 -291.482652) (xy 51.330481 -291.441056)
			(xy 51.363116 -291.404219) (xy 51.401237 -291.373094) (xy 51.443858 -291.348487) (xy 51.489874 -291.331035)
			(xy 51.538093 -291.321191) (xy 51.587268 -291.31921) (xy 51.636123 -291.325142) (xy 51.683394 -291.338834)
			(xy 51.727856 -291.359932) (xy 51.768359 -291.387888) (xy 51.803852 -291.42198) (xy 51.833417 -291.461324)
			(xy 51.856288 -291.504901) (xy 51.871872 -291.551582) (xy 51.879767 -291.600159) (xy 51.880262 -291.624766)
			(xy 52.21911 -291.624766) (xy 52.22307 -291.575712) (xy 52.234847 -291.527928) (xy 52.254138 -291.482652)
			(xy 52.280441 -291.441056) (xy 52.313076 -291.404219) (xy 52.351197 -291.373094) (xy 52.393818 -291.348487)
			(xy 52.439834 -291.331035) (xy 52.488053 -291.321191) (xy 52.537228 -291.31921) (xy 52.586083 -291.325142)
			(xy 52.633354 -291.338834) (xy 52.677816 -291.359932) (xy 52.718319 -291.387888) (xy 52.753812 -291.42198)
			(xy 52.783377 -291.461324) (xy 52.806248 -291.504901) (xy 52.821832 -291.551582) (xy 52.829727 -291.600159)
			(xy 52.830222 -291.624766) (xy 53.16907 -291.624766) (xy 53.17303 -291.575712) (xy 53.184807 -291.527928)
			(xy 53.204098 -291.482652) (xy 53.230401 -291.441056) (xy 53.263036 -291.404219) (xy 53.301157 -291.373094)
			(xy 53.343778 -291.348487) (xy 53.389794 -291.331035) (xy 53.438013 -291.321191) (xy 53.487188 -291.31921)
			(xy 53.536043 -291.325142) (xy 53.583314 -291.338834) (xy 53.627776 -291.359932) (xy 53.668279 -291.387888)
			(xy 53.703772 -291.42198) (xy 53.733337 -291.461324) (xy 53.756208 -291.504901) (xy 53.771792 -291.551582)
			(xy 53.779687 -291.600159) (xy 53.780182 -291.624766) (xy 54.11903 -291.624766) (xy 54.12299 -291.575712)
			(xy 54.134767 -291.527928) (xy 54.154058 -291.482652) (xy 54.180361 -291.441056) (xy 54.212996 -291.404219)
			(xy 54.251117 -291.373094) (xy 54.293738 -291.348487) (xy 54.339754 -291.331035) (xy 54.387973 -291.321191)
			(xy 54.437148 -291.31921) (xy 54.486003 -291.325142) (xy 54.533274 -291.338834) (xy 54.577736 -291.359932)
			(xy 54.618239 -291.387888) (xy 54.653732 -291.42198) (xy 54.683297 -291.461324) (xy 54.706168 -291.504901)
			(xy 54.721752 -291.551582) (xy 54.729647 -291.600159) (xy 54.730142 -291.624766) (xy 55.06899 -291.624766)
			(xy 55.07295 -291.575712) (xy 55.084727 -291.527928) (xy 55.104018 -291.482652) (xy 55.130321 -291.441056)
			(xy 55.162956 -291.404219) (xy 55.201077 -291.373094) (xy 55.243698 -291.348487) (xy 55.289714 -291.331035)
			(xy 55.337933 -291.321191) (xy 55.387108 -291.31921) (xy 55.435963 -291.325142) (xy 55.483234 -291.338834)
			(xy 55.527696 -291.359932) (xy 55.568199 -291.387888) (xy 55.603692 -291.42198) (xy 55.633257 -291.461324)
			(xy 55.656128 -291.504901) (xy 55.671712 -291.551582) (xy 55.679607 -291.600159) (xy 55.680102 -291.624766)
			(xy 56.01895 -291.624766) (xy 56.02291 -291.575712) (xy 56.034687 -291.527928) (xy 56.053978 -291.482652)
			(xy 56.080281 -291.441056) (xy 56.112916 -291.404219) (xy 56.151037 -291.373094) (xy 56.193658 -291.348487)
			(xy 56.239674 -291.331035) (xy 56.287893 -291.321191) (xy 56.337068 -291.31921) (xy 56.385923 -291.325142)
			(xy 56.433194 -291.338834) (xy 56.477656 -291.359932) (xy 56.518159 -291.387888) (xy 56.553652 -291.42198)
			(xy 56.583217 -291.461324) (xy 56.606088 -291.504901) (xy 56.621672 -291.551582) (xy 56.629567 -291.600159)
			(xy 56.630062 -291.624766) (xy 56.969164 -291.624766) (xy 56.973124 -291.575712) (xy 56.984901 -291.527928)
			(xy 57.004192 -291.482652) (xy 57.030495 -291.441056) (xy 57.06313 -291.404219) (xy 57.101251 -291.373094)
			(xy 57.143872 -291.348487) (xy 57.189888 -291.331035) (xy 57.238107 -291.321191) (xy 57.287282 -291.31921)
			(xy 57.336137 -291.325142) (xy 57.383408 -291.338834) (xy 57.42787 -291.359932) (xy 57.468373 -291.387888)
			(xy 57.503866 -291.42198) (xy 57.533431 -291.461324) (xy 57.556302 -291.504901) (xy 57.571886 -291.551582)
			(xy 57.579781 -291.600159) (xy 57.580276 -291.624766) (xy 57.919124 -291.624766) (xy 57.923084 -291.575712)
			(xy 57.934861 -291.527928) (xy 57.954152 -291.482652) (xy 57.980455 -291.441056) (xy 58.01309 -291.404219)
			(xy 58.051211 -291.373094) (xy 58.093832 -291.348487) (xy 58.139848 -291.331035) (xy 58.188067 -291.321191)
			(xy 58.237242 -291.31921) (xy 58.286097 -291.325142) (xy 58.333368 -291.338834) (xy 58.37783 -291.359932)
			(xy 58.418333 -291.387888) (xy 58.453826 -291.42198) (xy 58.483391 -291.461324) (xy 58.506262 -291.504901)
			(xy 58.521846 -291.551582) (xy 58.529741 -291.600159) (xy 58.530236 -291.624766) (xy 59.819044 -291.624766)
			(xy 59.823004 -291.575712) (xy 59.834781 -291.527928) (xy 59.854072 -291.482652) (xy 59.880375 -291.441056)
			(xy 59.91301 -291.404219) (xy 59.951131 -291.373094) (xy 59.993752 -291.348487) (xy 60.039768 -291.331035)
			(xy 60.087987 -291.321191) (xy 60.137162 -291.31921) (xy 60.186017 -291.325142) (xy 60.233288 -291.338834)
			(xy 60.27775 -291.359932) (xy 60.318253 -291.387888) (xy 60.353746 -291.42198) (xy 60.383311 -291.461324)
			(xy 60.406182 -291.504901) (xy 60.421766 -291.551582) (xy 60.429661 -291.600159) (xy 60.430156 -291.624766)
			(xy 60.769004 -291.624766) (xy 60.772964 -291.575712) (xy 60.784741 -291.527928) (xy 60.804032 -291.482652)
			(xy 60.830335 -291.441056) (xy 60.86297 -291.404219) (xy 60.901091 -291.373094) (xy 60.943712 -291.348487)
			(xy 60.989728 -291.331035) (xy 61.037947 -291.321191) (xy 61.087122 -291.31921) (xy 61.135977 -291.325142)
			(xy 61.183248 -291.338834) (xy 61.22771 -291.359932) (xy 61.268213 -291.387888) (xy 61.303706 -291.42198)
			(xy 61.333271 -291.461324) (xy 61.356142 -291.504901) (xy 61.371726 -291.551582) (xy 61.379621 -291.600159)
			(xy 61.380116 -291.624766) (xy 61.718964 -291.624766) (xy 61.722924 -291.575712) (xy 61.734701 -291.527928)
			(xy 61.753992 -291.482652) (xy 61.780295 -291.441056) (xy 61.81293 -291.404219) (xy 61.851051 -291.373094)
			(xy 61.893672 -291.348487) (xy 61.939688 -291.331035) (xy 61.987907 -291.321191) (xy 62.037082 -291.31921)
			(xy 62.085937 -291.325142) (xy 62.133208 -291.338834) (xy 62.17767 -291.359932) (xy 62.218173 -291.387888)
			(xy 62.253666 -291.42198) (xy 62.283231 -291.461324) (xy 62.306102 -291.504901) (xy 62.321686 -291.551582)
			(xy 62.329581 -291.600159) (xy 62.330076 -291.624766) (xy 62.669178 -291.624766) (xy 62.673138 -291.575712)
			(xy 62.684915 -291.527928) (xy 62.704206 -291.482652) (xy 62.730509 -291.441056) (xy 62.763144 -291.404219)
			(xy 62.801265 -291.373094) (xy 62.843886 -291.348487) (xy 62.889902 -291.331035) (xy 62.938121 -291.321191)
			(xy 62.987296 -291.31921) (xy 63.036151 -291.325142) (xy 63.083422 -291.338834) (xy 63.127884 -291.359932)
			(xy 63.168387 -291.387888) (xy 63.20388 -291.42198) (xy 63.233445 -291.461324) (xy 63.256316 -291.504901)
			(xy 63.2719 -291.551582) (xy 63.279795 -291.600159) (xy 63.28029 -291.624766) (xy 63.619138 -291.624766)
			(xy 63.623098 -291.575712) (xy 63.634875 -291.527928) (xy 63.654166 -291.482652) (xy 63.680469 -291.441056)
			(xy 63.713104 -291.404219) (xy 63.751225 -291.373094) (xy 63.793846 -291.348487) (xy 63.839862 -291.331035)
			(xy 63.888081 -291.321191) (xy 63.937256 -291.31921) (xy 63.986111 -291.325142) (xy 64.033382 -291.338834)
			(xy 64.077844 -291.359932) (xy 64.118347 -291.387888) (xy 64.15384 -291.42198) (xy 64.183405 -291.461324)
			(xy 64.206276 -291.504901) (xy 64.22186 -291.551582) (xy 64.229755 -291.600159) (xy 64.23025 -291.624766)
			(xy 64.569098 -291.624766) (xy 64.573058 -291.575712) (xy 64.584835 -291.527928) (xy 64.604126 -291.482652)
			(xy 64.630429 -291.441056) (xy 64.663064 -291.404219) (xy 64.701185 -291.373094) (xy 64.743806 -291.348487)
			(xy 64.789822 -291.331035) (xy 64.838041 -291.321191) (xy 64.887216 -291.31921) (xy 64.936071 -291.325142)
			(xy 64.983342 -291.338834) (xy 65.027804 -291.359932) (xy 65.068307 -291.387888) (xy 65.1038 -291.42198)
			(xy 65.133365 -291.461324) (xy 65.156236 -291.504901) (xy 65.17182 -291.551582) (xy 65.179715 -291.600159)
			(xy 65.18021 -291.624766) (xy 65.519058 -291.624766) (xy 65.523018 -291.575712) (xy 65.534795 -291.527928)
			(xy 65.554086 -291.482652) (xy 65.580389 -291.441056) (xy 65.613024 -291.404219) (xy 65.651145 -291.373094)
			(xy 65.693766 -291.348487) (xy 65.739782 -291.331035) (xy 65.788001 -291.321191) (xy 65.837176 -291.31921)
			(xy 65.886031 -291.325142) (xy 65.933302 -291.338834) (xy 65.977764 -291.359932) (xy 66.018267 -291.387888)
			(xy 66.05376 -291.42198) (xy 66.083325 -291.461324) (xy 66.106196 -291.504901) (xy 66.12178 -291.551582)
			(xy 66.129675 -291.600159) (xy 66.13017 -291.624766) (xy 66.469018 -291.624766) (xy 66.472978 -291.575712)
			(xy 66.484755 -291.527928) (xy 66.504046 -291.482652) (xy 66.530349 -291.441056) (xy 66.562984 -291.404219)
			(xy 66.601105 -291.373094) (xy 66.643726 -291.348487) (xy 66.689742 -291.331035) (xy 66.737961 -291.321191)
			(xy 66.787136 -291.31921) (xy 66.835991 -291.325142) (xy 66.883262 -291.338834) (xy 66.927724 -291.359932)
			(xy 66.968227 -291.387888) (xy 67.00372 -291.42198) (xy 67.033285 -291.461324) (xy 67.056156 -291.504901)
			(xy 67.07174 -291.551582) (xy 67.079635 -291.600159) (xy 67.08013 -291.624766) (xy 67.418978 -291.624766)
			(xy 67.422938 -291.575712) (xy 67.434715 -291.527928) (xy 67.454006 -291.482652) (xy 67.480309 -291.441056)
			(xy 67.512944 -291.404219) (xy 67.551065 -291.373094) (xy 67.593686 -291.348487) (xy 67.639702 -291.331035)
			(xy 67.687921 -291.321191) (xy 67.737096 -291.31921) (xy 67.785951 -291.325142) (xy 67.833222 -291.338834)
			(xy 67.877684 -291.359932) (xy 67.918187 -291.387888) (xy 67.95368 -291.42198) (xy 67.983245 -291.461324)
			(xy 68.006116 -291.504901) (xy 68.0217 -291.551582) (xy 68.029595 -291.600159) (xy 68.03009 -291.624766)
			(xy 68.368938 -291.624766) (xy 68.372898 -291.575712) (xy 68.384675 -291.527928) (xy 68.403966 -291.482652)
			(xy 68.430269 -291.441056) (xy 68.462904 -291.404219) (xy 68.501025 -291.373094) (xy 68.543646 -291.348487)
			(xy 68.589662 -291.331035) (xy 68.637881 -291.321191) (xy 68.687056 -291.31921) (xy 68.735911 -291.325142)
			(xy 68.783182 -291.338834) (xy 68.827644 -291.359932) (xy 68.868147 -291.387888) (xy 68.90364 -291.42198)
			(xy 68.933205 -291.461324) (xy 68.956076 -291.504901) (xy 68.97166 -291.551582) (xy 68.979555 -291.600159)
			(xy 68.98005 -291.624766) (xy 69.319152 -291.624766) (xy 69.323112 -291.575712) (xy 69.334889 -291.527928)
			(xy 69.35418 -291.482652) (xy 69.380483 -291.441056) (xy 69.413118 -291.404219) (xy 69.451239 -291.373094)
			(xy 69.49386 -291.348487) (xy 69.539876 -291.331035) (xy 69.588095 -291.321191) (xy 69.63727 -291.31921)
			(xy 69.686125 -291.325142) (xy 69.733396 -291.338834) (xy 69.777858 -291.359932) (xy 69.818361 -291.387888)
			(xy 69.853854 -291.42198) (xy 69.883419 -291.461324) (xy 69.90629 -291.504901) (xy 69.921874 -291.551582)
			(xy 69.929769 -291.600159) (xy 69.930264 -291.624766) (xy 70.269112 -291.624766) (xy 70.273072 -291.575712)
			(xy 70.284849 -291.527928) (xy 70.30414 -291.482652) (xy 70.330443 -291.441056) (xy 70.363078 -291.404219)
			(xy 70.401199 -291.373094) (xy 70.44382 -291.348487) (xy 70.489836 -291.331035) (xy 70.538055 -291.321191)
			(xy 70.58723 -291.31921) (xy 70.636085 -291.325142) (xy 70.683356 -291.338834) (xy 70.727818 -291.359932)
			(xy 70.768321 -291.387888) (xy 70.803814 -291.42198) (xy 70.833379 -291.461324) (xy 70.85625 -291.504901)
			(xy 70.871834 -291.551582) (xy 70.879729 -291.600159) (xy 70.880224 -291.624766) (xy 71.219072 -291.624766)
			(xy 71.223032 -291.575712) (xy 71.234809 -291.527928) (xy 71.2541 -291.482652) (xy 71.280403 -291.441056)
			(xy 71.313038 -291.404219) (xy 71.351159 -291.373094) (xy 71.39378 -291.348487) (xy 71.439796 -291.331035)
			(xy 71.488015 -291.321191) (xy 71.53719 -291.31921) (xy 71.586045 -291.325142) (xy 71.633316 -291.338834)
			(xy 71.677778 -291.359932) (xy 71.718281 -291.387888) (xy 71.753774 -291.42198) (xy 71.783339 -291.461324)
			(xy 71.80621 -291.504901) (xy 71.821794 -291.551582) (xy 71.829689 -291.600159) (xy 71.830184 -291.624766)
			(xy 72.169032 -291.624766) (xy 72.172992 -291.575712) (xy 72.184769 -291.527928) (xy 72.20406 -291.482652)
			(xy 72.230363 -291.441056) (xy 72.262998 -291.404219) (xy 72.301119 -291.373094) (xy 72.34374 -291.348487)
			(xy 72.389756 -291.331035) (xy 72.437975 -291.321191) (xy 72.48715 -291.31921) (xy 72.536005 -291.325142)
			(xy 72.583276 -291.338834) (xy 72.627738 -291.359932) (xy 72.668241 -291.387888) (xy 72.703734 -291.42198)
			(xy 72.733299 -291.461324) (xy 72.75617 -291.504901) (xy 72.771754 -291.551582) (xy 72.779649 -291.600159)
			(xy 72.780144 -291.624766) (xy 73.118992 -291.624766) (xy 73.122952 -291.575712) (xy 73.134729 -291.527928)
			(xy 73.15402 -291.482652) (xy 73.180323 -291.441056) (xy 73.212958 -291.404219) (xy 73.251079 -291.373094)
			(xy 73.2937 -291.348487) (xy 73.339716 -291.331035) (xy 73.387935 -291.321191) (xy 73.43711 -291.31921)
			(xy 73.485965 -291.325142) (xy 73.533236 -291.338834) (xy 73.577698 -291.359932) (xy 73.618201 -291.387888)
			(xy 73.653694 -291.42198) (xy 73.683259 -291.461324) (xy 73.70613 -291.504901) (xy 73.721714 -291.551582)
			(xy 73.729609 -291.600159) (xy 73.730104 -291.624766) (xy 74.069206 -291.624766) (xy 74.073166 -291.575712)
			(xy 74.084943 -291.527928) (xy 74.104234 -291.482652) (xy 74.130537 -291.441056) (xy 74.163172 -291.404219)
			(xy 74.201293 -291.373094) (xy 74.243914 -291.348487) (xy 74.28993 -291.331035) (xy 74.338149 -291.321191)
			(xy 74.387324 -291.31921) (xy 74.436179 -291.325142) (xy 74.48345 -291.338834) (xy 74.527912 -291.359932)
			(xy 74.568415 -291.387888) (xy 74.603908 -291.42198) (xy 74.633473 -291.461324) (xy 74.656344 -291.504901)
			(xy 74.671928 -291.551582) (xy 74.679823 -291.600159) (xy 74.680318 -291.624766) (xy 75.969126 -291.624766)
			(xy 75.973086 -291.575712) (xy 75.984863 -291.527928) (xy 76.004154 -291.482652) (xy 76.030457 -291.441056)
			(xy 76.063092 -291.404219) (xy 76.101213 -291.373094) (xy 76.143834 -291.348487) (xy 76.18985 -291.331035)
			(xy 76.238069 -291.321191) (xy 76.287244 -291.31921) (xy 76.336099 -291.325142) (xy 76.38337 -291.338834)
			(xy 76.427832 -291.359932) (xy 76.468335 -291.387888) (xy 76.503828 -291.42198) (xy 76.533393 -291.461324)
			(xy 76.556264 -291.504901) (xy 76.571848 -291.551582) (xy 76.579743 -291.600159) (xy 76.580238 -291.624766)
			(xy 76.919086 -291.624766) (xy 76.923046 -291.575712) (xy 76.934823 -291.527928) (xy 76.954114 -291.482652)
			(xy 76.980417 -291.441056) (xy 77.013052 -291.404219) (xy 77.051173 -291.373094) (xy 77.093794 -291.348487)
			(xy 77.13981 -291.331035) (xy 77.188029 -291.321191) (xy 77.237204 -291.31921) (xy 77.286059 -291.325142)
			(xy 77.33333 -291.338834) (xy 77.377792 -291.359932) (xy 77.418295 -291.387888) (xy 77.453788 -291.42198)
			(xy 77.483353 -291.461324) (xy 77.506224 -291.504901) (xy 77.521808 -291.551582) (xy 77.529703 -291.600159)
			(xy 77.530198 -291.624766) (xy 77.869046 -291.624766) (xy 77.873006 -291.575712) (xy 77.884783 -291.527928)
			(xy 77.904074 -291.482652) (xy 77.930377 -291.441056) (xy 77.963012 -291.404219) (xy 78.001133 -291.373094)
			(xy 78.043754 -291.348487) (xy 78.08977 -291.331035) (xy 78.137989 -291.321191) (xy 78.187164 -291.31921)
			(xy 78.236019 -291.325142) (xy 78.28329 -291.338834) (xy 78.327752 -291.359932) (xy 78.368255 -291.387888)
			(xy 78.403748 -291.42198) (xy 78.433313 -291.461324) (xy 78.456184 -291.504901) (xy 78.471768 -291.551582)
			(xy 78.479663 -291.600159) (xy 78.480158 -291.624766) (xy 78.819006 -291.624766) (xy 78.822966 -291.575712)
			(xy 78.834743 -291.527928) (xy 78.854034 -291.482652) (xy 78.880337 -291.441056) (xy 78.912972 -291.404219)
			(xy 78.951093 -291.373094) (xy 78.993714 -291.348487) (xy 79.03973 -291.331035) (xy 79.087949 -291.321191)
			(xy 79.137124 -291.31921) (xy 79.185979 -291.325142) (xy 79.23325 -291.338834) (xy 79.277712 -291.359932)
			(xy 79.318215 -291.387888) (xy 79.353708 -291.42198) (xy 79.383273 -291.461324) (xy 79.406144 -291.504901)
			(xy 79.421728 -291.551582) (xy 79.429623 -291.600159) (xy 79.430118 -291.624766) (xy 79.768966 -291.624766)
			(xy 79.772926 -291.575712) (xy 79.784703 -291.527928) (xy 79.803994 -291.482652) (xy 79.830297 -291.441056)
			(xy 79.862932 -291.404219) (xy 79.901053 -291.373094) (xy 79.943674 -291.348487) (xy 79.98969 -291.331035)
			(xy 80.037909 -291.321191) (xy 80.087084 -291.31921) (xy 80.135939 -291.325142) (xy 80.18321 -291.338834)
			(xy 80.227672 -291.359932) (xy 80.268175 -291.387888) (xy 80.303668 -291.42198) (xy 80.333233 -291.461324)
			(xy 80.356104 -291.504901) (xy 80.371688 -291.551582) (xy 80.379583 -291.600159) (xy 80.380078 -291.624766)
			(xy 80.71918 -291.624766) (xy 80.72314 -291.575712) (xy 80.734917 -291.527928) (xy 80.754208 -291.482652)
			(xy 80.780511 -291.441056) (xy 80.813146 -291.404219) (xy 80.851267 -291.373094) (xy 80.893888 -291.348487)
			(xy 80.939904 -291.331035) (xy 80.988123 -291.321191) (xy 81.037298 -291.31921) (xy 81.086153 -291.325142)
			(xy 81.133424 -291.338834) (xy 81.177886 -291.359932) (xy 81.218389 -291.387888) (xy 81.253882 -291.42198)
			(xy 81.283447 -291.461324) (xy 81.306318 -291.504901) (xy 81.321902 -291.551582) (xy 81.329797 -291.600159)
			(xy 81.330292 -291.624766) (xy 81.66914 -291.624766) (xy 81.6731 -291.575712) (xy 81.684877 -291.527928)
			(xy 81.704168 -291.482652) (xy 81.730471 -291.441056) (xy 81.763106 -291.404219) (xy 81.801227 -291.373094)
			(xy 81.843848 -291.348487) (xy 81.889864 -291.331035) (xy 81.938083 -291.321191) (xy 81.987258 -291.31921)
			(xy 82.036113 -291.325142) (xy 82.083384 -291.338834) (xy 82.127846 -291.359932) (xy 82.168349 -291.387888)
			(xy 82.203842 -291.42198) (xy 82.233407 -291.461324) (xy 82.256278 -291.504901) (xy 82.271862 -291.551582)
			(xy 82.279757 -291.600159) (xy 82.280252 -291.624766) (xy 82.6191 -291.624766) (xy 82.62306 -291.575712)
			(xy 82.634837 -291.527928) (xy 82.654128 -291.482652) (xy 82.680431 -291.441056) (xy 82.713066 -291.404219)
			(xy 82.751187 -291.373094) (xy 82.793808 -291.348487) (xy 82.839824 -291.331035) (xy 82.888043 -291.321191)
			(xy 82.937218 -291.31921) (xy 82.986073 -291.325142) (xy 83.033344 -291.338834) (xy 83.077806 -291.359932)
			(xy 83.118309 -291.387888) (xy 83.153802 -291.42198) (xy 83.183367 -291.461324) (xy 83.185296 -291.465)
			(xy 86.104982 -291.465) (xy 86.109053 -291.409378) (xy 86.121179 -291.354941) (xy 86.141102 -291.30285)
			(xy 86.168398 -291.254215) (xy 86.202484 -291.210072) (xy 86.242633 -291.171363) (xy 86.287991 -291.138912)
			(xy 86.337591 -291.113411) (xy 86.390375 -291.095404) (xy 86.445218 -291.085274) (xy 86.500952 -291.083237)
			(xy 86.556389 -291.089337) (xy 86.610346 -291.103443) (xy 86.661675 -291.125255) (xy 86.709281 -291.154309)
			(xy 86.752149 -291.189984) (xy 86.789366 -291.231521) (xy 86.820139 -291.278034) (xy 86.843811 -291.328531)
			(xy 86.859879 -291.381938) (xy 86.867999 -291.437114) (xy 86.868508 -291.465) (xy 86.867999 -291.492886)
			(xy 86.859879 -291.548062) (xy 86.84666 -291.592) (xy 88.441782 -291.592) (xy 88.445853 -291.536378)
			(xy 88.457979 -291.481941) (xy 88.477902 -291.42985) (xy 88.505198 -291.381215) (xy 88.539284 -291.337072)
			(xy 88.579433 -291.298363) (xy 88.624791 -291.265912) (xy 88.674391 -291.240411) (xy 88.727175 -291.222404)
			(xy 88.782018 -291.212274) (xy 88.837752 -291.210237) (xy 88.893189 -291.216337) (xy 88.947146 -291.230443)
			(xy 88.998475 -291.252255) (xy 89.046081 -291.281309) (xy 89.088949 -291.316984) (xy 89.126166 -291.358521)
			(xy 89.156939 -291.405034) (xy 89.180611 -291.455531) (xy 89.196679 -291.508938) (xy 89.204799 -291.564114)
			(xy 89.205308 -291.592) (xy 89.204799 -291.619886) (xy 89.196679 -291.675062) (xy 89.180611 -291.728469)
			(xy 89.156939 -291.778966) (xy 89.126166 -291.825479) (xy 89.088949 -291.867016) (xy 89.046081 -291.902691)
			(xy 88.998475 -291.931745) (xy 88.947146 -291.953557) (xy 88.893189 -291.967663) (xy 88.837752 -291.973763)
			(xy 88.782018 -291.971726) (xy 88.727175 -291.961596) (xy 88.674391 -291.943589) (xy 88.624791 -291.918088)
			(xy 88.579433 -291.885637) (xy 88.539284 -291.846928) (xy 88.505198 -291.802785) (xy 88.477902 -291.75415)
			(xy 88.457979 -291.702059) (xy 88.445853 -291.647622) (xy 88.441782 -291.592) (xy 86.84666 -291.592)
			(xy 86.843811 -291.601469) (xy 86.820139 -291.651966) (xy 86.789366 -291.698479) (xy 86.752149 -291.740016)
			(xy 86.709281 -291.775691) (xy 86.661675 -291.804745) (xy 86.610346 -291.826557) (xy 86.556389 -291.840663)
			(xy 86.500952 -291.846763) (xy 86.445218 -291.844726) (xy 86.390375 -291.834596) (xy 86.337591 -291.816589)
			(xy 86.287991 -291.791088) (xy 86.242633 -291.758637) (xy 86.202484 -291.719928) (xy 86.168398 -291.675785)
			(xy 86.141102 -291.62715) (xy 86.121179 -291.575059) (xy 86.109053 -291.520622) (xy 86.104982 -291.465)
			(xy 83.185296 -291.465) (xy 83.206238 -291.504901) (xy 83.221822 -291.551582) (xy 83.229717 -291.600159)
			(xy 83.230212 -291.624766) (xy 83.229717 -291.649373) (xy 83.221822 -291.69795) (xy 83.206238 -291.744631)
			(xy 83.183367 -291.788208) (xy 83.153802 -291.827552) (xy 83.118309 -291.861644) (xy 83.077806 -291.8896)
			(xy 83.033344 -291.910698) (xy 82.986073 -291.92439) (xy 82.937218 -291.930322) (xy 82.888043 -291.928341)
			(xy 82.839824 -291.918497) (xy 82.793808 -291.901045) (xy 82.751187 -291.876438) (xy 82.713066 -291.845313)
			(xy 82.680431 -291.808476) (xy 82.654128 -291.76688) (xy 82.634837 -291.721604) (xy 82.62306 -291.67382)
			(xy 82.6191 -291.624766) (xy 82.280252 -291.624766) (xy 82.279757 -291.649373) (xy 82.271862 -291.69795)
			(xy 82.256278 -291.744631) (xy 82.233407 -291.788208) (xy 82.203842 -291.827552) (xy 82.168349 -291.861644)
			(xy 82.127846 -291.8896) (xy 82.083384 -291.910698) (xy 82.036113 -291.92439) (xy 81.987258 -291.930322)
			(xy 81.938083 -291.928341) (xy 81.889864 -291.918497) (xy 81.843848 -291.901045) (xy 81.801227 -291.876438)
			(xy 81.763106 -291.845313) (xy 81.730471 -291.808476) (xy 81.704168 -291.76688) (xy 81.684877 -291.721604)
			(xy 81.6731 -291.67382) (xy 81.66914 -291.624766) (xy 81.330292 -291.624766) (xy 81.329797 -291.649373)
			(xy 81.321902 -291.69795) (xy 81.306318 -291.744631) (xy 81.283447 -291.788208) (xy 81.253882 -291.827552)
			(xy 81.218389 -291.861644) (xy 81.177886 -291.8896) (xy 81.133424 -291.910698) (xy 81.086153 -291.92439)
			(xy 81.037298 -291.930322) (xy 80.988123 -291.928341) (xy 80.939904 -291.918497) (xy 80.893888 -291.901045)
			(xy 80.851267 -291.876438) (xy 80.813146 -291.845313) (xy 80.780511 -291.808476) (xy 80.754208 -291.76688)
			(xy 80.734917 -291.721604) (xy 80.72314 -291.67382) (xy 80.71918 -291.624766) (xy 80.380078 -291.624766)
			(xy 80.379583 -291.649373) (xy 80.371688 -291.69795) (xy 80.356104 -291.744631) (xy 80.333233 -291.788208)
			(xy 80.303668 -291.827552) (xy 80.268175 -291.861644) (xy 80.227672 -291.8896) (xy 80.18321 -291.910698)
			(xy 80.135939 -291.92439) (xy 80.087084 -291.930322) (xy 80.037909 -291.928341) (xy 79.98969 -291.918497)
			(xy 79.943674 -291.901045) (xy 79.901053 -291.876438) (xy 79.862932 -291.845313) (xy 79.830297 -291.808476)
			(xy 79.803994 -291.76688) (xy 79.784703 -291.721604) (xy 79.772926 -291.67382) (xy 79.768966 -291.624766)
			(xy 79.430118 -291.624766) (xy 79.429623 -291.649373) (xy 79.421728 -291.69795) (xy 79.406144 -291.744631)
			(xy 79.383273 -291.788208) (xy 79.353708 -291.827552) (xy 79.318215 -291.861644) (xy 79.277712 -291.8896)
			(xy 79.23325 -291.910698) (xy 79.185979 -291.92439) (xy 79.137124 -291.930322) (xy 79.087949 -291.928341)
			(xy 79.03973 -291.918497) (xy 78.993714 -291.901045) (xy 78.951093 -291.876438) (xy 78.912972 -291.845313)
			(xy 78.880337 -291.808476) (xy 78.854034 -291.76688) (xy 78.834743 -291.721604) (xy 78.822966 -291.67382)
			(xy 78.819006 -291.624766) (xy 78.480158 -291.624766) (xy 78.479663 -291.649373) (xy 78.471768 -291.69795)
			(xy 78.456184 -291.744631) (xy 78.433313 -291.788208) (xy 78.403748 -291.827552) (xy 78.368255 -291.861644)
			(xy 78.327752 -291.8896) (xy 78.28329 -291.910698) (xy 78.236019 -291.92439) (xy 78.187164 -291.930322)
			(xy 78.137989 -291.928341) (xy 78.08977 -291.918497) (xy 78.043754 -291.901045) (xy 78.001133 -291.876438)
			(xy 77.963012 -291.845313) (xy 77.930377 -291.808476) (xy 77.904074 -291.76688) (xy 77.884783 -291.721604)
			(xy 77.873006 -291.67382) (xy 77.869046 -291.624766) (xy 77.530198 -291.624766) (xy 77.529703 -291.649373)
			(xy 77.521808 -291.69795) (xy 77.506224 -291.744631) (xy 77.483353 -291.788208) (xy 77.453788 -291.827552)
			(xy 77.418295 -291.861644) (xy 77.377792 -291.8896) (xy 77.33333 -291.910698) (xy 77.286059 -291.92439)
			(xy 77.237204 -291.930322) (xy 77.188029 -291.928341) (xy 77.13981 -291.918497) (xy 77.093794 -291.901045)
			(xy 77.051173 -291.876438) (xy 77.013052 -291.845313) (xy 76.980417 -291.808476) (xy 76.954114 -291.76688)
			(xy 76.934823 -291.721604) (xy 76.923046 -291.67382) (xy 76.919086 -291.624766) (xy 76.580238 -291.624766)
			(xy 76.579743 -291.649373) (xy 76.571848 -291.69795) (xy 76.556264 -291.744631) (xy 76.533393 -291.788208)
			(xy 76.503828 -291.827552) (xy 76.468335 -291.861644) (xy 76.427832 -291.8896) (xy 76.38337 -291.910698)
			(xy 76.336099 -291.92439) (xy 76.287244 -291.930322) (xy 76.238069 -291.928341) (xy 76.18985 -291.918497)
			(xy 76.143834 -291.901045) (xy 76.101213 -291.876438) (xy 76.063092 -291.845313) (xy 76.030457 -291.808476)
			(xy 76.004154 -291.76688) (xy 75.984863 -291.721604) (xy 75.973086 -291.67382) (xy 75.969126 -291.624766)
			(xy 74.680318 -291.624766) (xy 74.679823 -291.649373) (xy 74.671928 -291.69795) (xy 74.656344 -291.744631)
			(xy 74.633473 -291.788208) (xy 74.603908 -291.827552) (xy 74.568415 -291.861644) (xy 74.527912 -291.8896)
			(xy 74.48345 -291.910698) (xy 74.436179 -291.92439) (xy 74.387324 -291.930322) (xy 74.338149 -291.928341)
			(xy 74.28993 -291.918497) (xy 74.243914 -291.901045) (xy 74.201293 -291.876438) (xy 74.163172 -291.845313)
			(xy 74.130537 -291.808476) (xy 74.104234 -291.76688) (xy 74.084943 -291.721604) (xy 74.073166 -291.67382)
			(xy 74.069206 -291.624766) (xy 73.730104 -291.624766) (xy 73.729609 -291.649373) (xy 73.721714 -291.69795)
			(xy 73.70613 -291.744631) (xy 73.683259 -291.788208) (xy 73.653694 -291.827552) (xy 73.618201 -291.861644)
			(xy 73.577698 -291.8896) (xy 73.533236 -291.910698) (xy 73.485965 -291.92439) (xy 73.43711 -291.930322)
			(xy 73.387935 -291.928341) (xy 73.339716 -291.918497) (xy 73.2937 -291.901045) (xy 73.251079 -291.876438)
			(xy 73.212958 -291.845313) (xy 73.180323 -291.808476) (xy 73.15402 -291.76688) (xy 73.134729 -291.721604)
			(xy 73.122952 -291.67382) (xy 73.118992 -291.624766) (xy 72.780144 -291.624766) (xy 72.779649 -291.649373)
			(xy 72.771754 -291.69795) (xy 72.75617 -291.744631) (xy 72.733299 -291.788208) (xy 72.703734 -291.827552)
			(xy 72.668241 -291.861644) (xy 72.627738 -291.8896) (xy 72.583276 -291.910698) (xy 72.536005 -291.92439)
			(xy 72.48715 -291.930322) (xy 72.437975 -291.928341) (xy 72.389756 -291.918497) (xy 72.34374 -291.901045)
			(xy 72.301119 -291.876438) (xy 72.262998 -291.845313) (xy 72.230363 -291.808476) (xy 72.20406 -291.76688)
			(xy 72.184769 -291.721604) (xy 72.172992 -291.67382) (xy 72.169032 -291.624766) (xy 71.830184 -291.624766)
			(xy 71.829689 -291.649373) (xy 71.821794 -291.69795) (xy 71.80621 -291.744631) (xy 71.783339 -291.788208)
			(xy 71.753774 -291.827552) (xy 71.718281 -291.861644) (xy 71.677778 -291.8896) (xy 71.633316 -291.910698)
			(xy 71.586045 -291.92439) (xy 71.53719 -291.930322) (xy 71.488015 -291.928341) (xy 71.439796 -291.918497)
			(xy 71.39378 -291.901045) (xy 71.351159 -291.876438) (xy 71.313038 -291.845313) (xy 71.280403 -291.808476)
			(xy 71.2541 -291.76688) (xy 71.234809 -291.721604) (xy 71.223032 -291.67382) (xy 71.219072 -291.624766)
			(xy 70.880224 -291.624766) (xy 70.879729 -291.649373) (xy 70.871834 -291.69795) (xy 70.85625 -291.744631)
			(xy 70.833379 -291.788208) (xy 70.803814 -291.827552) (xy 70.768321 -291.861644) (xy 70.727818 -291.8896)
			(xy 70.683356 -291.910698) (xy 70.636085 -291.92439) (xy 70.58723 -291.930322) (xy 70.538055 -291.928341)
			(xy 70.489836 -291.918497) (xy 70.44382 -291.901045) (xy 70.401199 -291.876438) (xy 70.363078 -291.845313)
			(xy 70.330443 -291.808476) (xy 70.30414 -291.76688) (xy 70.284849 -291.721604) (xy 70.273072 -291.67382)
			(xy 70.269112 -291.624766) (xy 69.930264 -291.624766) (xy 69.929769 -291.649373) (xy 69.921874 -291.69795)
			(xy 69.90629 -291.744631) (xy 69.883419 -291.788208) (xy 69.853854 -291.827552) (xy 69.818361 -291.861644)
			(xy 69.777858 -291.8896) (xy 69.733396 -291.910698) (xy 69.686125 -291.92439) (xy 69.63727 -291.930322)
			(xy 69.588095 -291.928341) (xy 69.539876 -291.918497) (xy 69.49386 -291.901045) (xy 69.451239 -291.876438)
			(xy 69.413118 -291.845313) (xy 69.380483 -291.808476) (xy 69.35418 -291.76688) (xy 69.334889 -291.721604)
			(xy 69.323112 -291.67382) (xy 69.319152 -291.624766) (xy 68.98005 -291.624766) (xy 68.979555 -291.649373)
			(xy 68.97166 -291.69795) (xy 68.956076 -291.744631) (xy 68.933205 -291.788208) (xy 68.90364 -291.827552)
			(xy 68.868147 -291.861644) (xy 68.827644 -291.8896) (xy 68.783182 -291.910698) (xy 68.735911 -291.92439)
			(xy 68.687056 -291.930322) (xy 68.637881 -291.928341) (xy 68.589662 -291.918497) (xy 68.543646 -291.901045)
			(xy 68.501025 -291.876438) (xy 68.462904 -291.845313) (xy 68.430269 -291.808476) (xy 68.403966 -291.76688)
			(xy 68.384675 -291.721604) (xy 68.372898 -291.67382) (xy 68.368938 -291.624766) (xy 68.03009 -291.624766)
			(xy 68.029595 -291.649373) (xy 68.0217 -291.69795) (xy 68.006116 -291.744631) (xy 67.983245 -291.788208)
			(xy 67.95368 -291.827552) (xy 67.918187 -291.861644) (xy 67.877684 -291.8896) (xy 67.833222 -291.910698)
			(xy 67.785951 -291.92439) (xy 67.737096 -291.930322) (xy 67.687921 -291.928341) (xy 67.639702 -291.918497)
			(xy 67.593686 -291.901045) (xy 67.551065 -291.876438) (xy 67.512944 -291.845313) (xy 67.480309 -291.808476)
			(xy 67.454006 -291.76688) (xy 67.434715 -291.721604) (xy 67.422938 -291.67382) (xy 67.418978 -291.624766)
			(xy 67.08013 -291.624766) (xy 67.079635 -291.649373) (xy 67.07174 -291.69795) (xy 67.056156 -291.744631)
			(xy 67.033285 -291.788208) (xy 67.00372 -291.827552) (xy 66.968227 -291.861644) (xy 66.927724 -291.8896)
			(xy 66.883262 -291.910698) (xy 66.835991 -291.92439) (xy 66.787136 -291.930322) (xy 66.737961 -291.928341)
			(xy 66.689742 -291.918497) (xy 66.643726 -291.901045) (xy 66.601105 -291.876438) (xy 66.562984 -291.845313)
			(xy 66.530349 -291.808476) (xy 66.504046 -291.76688) (xy 66.484755 -291.721604) (xy 66.472978 -291.67382)
			(xy 66.469018 -291.624766) (xy 66.13017 -291.624766) (xy 66.129675 -291.649373) (xy 66.12178 -291.69795)
			(xy 66.106196 -291.744631) (xy 66.083325 -291.788208) (xy 66.05376 -291.827552) (xy 66.018267 -291.861644)
			(xy 65.977764 -291.8896) (xy 65.933302 -291.910698) (xy 65.886031 -291.92439) (xy 65.837176 -291.930322)
			(xy 65.788001 -291.928341) (xy 65.739782 -291.918497) (xy 65.693766 -291.901045) (xy 65.651145 -291.876438)
			(xy 65.613024 -291.845313) (xy 65.580389 -291.808476) (xy 65.554086 -291.76688) (xy 65.534795 -291.721604)
			(xy 65.523018 -291.67382) (xy 65.519058 -291.624766) (xy 65.18021 -291.624766) (xy 65.179715 -291.649373)
			(xy 65.17182 -291.69795) (xy 65.156236 -291.744631) (xy 65.133365 -291.788208) (xy 65.1038 -291.827552)
			(xy 65.068307 -291.861644) (xy 65.027804 -291.8896) (xy 64.983342 -291.910698) (xy 64.936071 -291.92439)
			(xy 64.887216 -291.930322) (xy 64.838041 -291.928341) (xy 64.789822 -291.918497) (xy 64.743806 -291.901045)
			(xy 64.701185 -291.876438) (xy 64.663064 -291.845313) (xy 64.630429 -291.808476) (xy 64.604126 -291.76688)
			(xy 64.584835 -291.721604) (xy 64.573058 -291.67382) (xy 64.569098 -291.624766) (xy 64.23025 -291.624766)
			(xy 64.229755 -291.649373) (xy 64.22186 -291.69795) (xy 64.206276 -291.744631) (xy 64.183405 -291.788208)
			(xy 64.15384 -291.827552) (xy 64.118347 -291.861644) (xy 64.077844 -291.8896) (xy 64.033382 -291.910698)
			(xy 63.986111 -291.92439) (xy 63.937256 -291.930322) (xy 63.888081 -291.928341) (xy 63.839862 -291.918497)
			(xy 63.793846 -291.901045) (xy 63.751225 -291.876438) (xy 63.713104 -291.845313) (xy 63.680469 -291.808476)
			(xy 63.654166 -291.76688) (xy 63.634875 -291.721604) (xy 63.623098 -291.67382) (xy 63.619138 -291.624766)
			(xy 63.28029 -291.624766) (xy 63.279795 -291.649373) (xy 63.2719 -291.69795) (xy 63.256316 -291.744631)
			(xy 63.233445 -291.788208) (xy 63.20388 -291.827552) (xy 63.168387 -291.861644) (xy 63.127884 -291.8896)
			(xy 63.083422 -291.910698) (xy 63.036151 -291.92439) (xy 62.987296 -291.930322) (xy 62.938121 -291.928341)
			(xy 62.889902 -291.918497) (xy 62.843886 -291.901045) (xy 62.801265 -291.876438) (xy 62.763144 -291.845313)
			(xy 62.730509 -291.808476) (xy 62.704206 -291.76688) (xy 62.684915 -291.721604) (xy 62.673138 -291.67382)
			(xy 62.669178 -291.624766) (xy 62.330076 -291.624766) (xy 62.329581 -291.649373) (xy 62.321686 -291.69795)
			(xy 62.306102 -291.744631) (xy 62.283231 -291.788208) (xy 62.253666 -291.827552) (xy 62.218173 -291.861644)
			(xy 62.17767 -291.8896) (xy 62.133208 -291.910698) (xy 62.085937 -291.92439) (xy 62.037082 -291.930322)
			(xy 61.987907 -291.928341) (xy 61.939688 -291.918497) (xy 61.893672 -291.901045) (xy 61.851051 -291.876438)
			(xy 61.81293 -291.845313) (xy 61.780295 -291.808476) (xy 61.753992 -291.76688) (xy 61.734701 -291.721604)
			(xy 61.722924 -291.67382) (xy 61.718964 -291.624766) (xy 61.380116 -291.624766) (xy 61.379621 -291.649373)
			(xy 61.371726 -291.69795) (xy 61.356142 -291.744631) (xy 61.333271 -291.788208) (xy 61.303706 -291.827552)
			(xy 61.268213 -291.861644) (xy 61.22771 -291.8896) (xy 61.183248 -291.910698) (xy 61.135977 -291.92439)
			(xy 61.087122 -291.930322) (xy 61.037947 -291.928341) (xy 60.989728 -291.918497) (xy 60.943712 -291.901045)
			(xy 60.901091 -291.876438) (xy 60.86297 -291.845313) (xy 60.830335 -291.808476) (xy 60.804032 -291.76688)
			(xy 60.784741 -291.721604) (xy 60.772964 -291.67382) (xy 60.769004 -291.624766) (xy 60.430156 -291.624766)
			(xy 60.429661 -291.649373) (xy 60.421766 -291.69795) (xy 60.406182 -291.744631) (xy 60.383311 -291.788208)
			(xy 60.353746 -291.827552) (xy 60.318253 -291.861644) (xy 60.27775 -291.8896) (xy 60.233288 -291.910698)
			(xy 60.186017 -291.92439) (xy 60.137162 -291.930322) (xy 60.087987 -291.928341) (xy 60.039768 -291.918497)
			(xy 59.993752 -291.901045) (xy 59.951131 -291.876438) (xy 59.91301 -291.845313) (xy 59.880375 -291.808476)
			(xy 59.854072 -291.76688) (xy 59.834781 -291.721604) (xy 59.823004 -291.67382) (xy 59.819044 -291.624766)
			(xy 58.530236 -291.624766) (xy 58.529741 -291.649373) (xy 58.521846 -291.69795) (xy 58.506262 -291.744631)
			(xy 58.483391 -291.788208) (xy 58.453826 -291.827552) (xy 58.418333 -291.861644) (xy 58.37783 -291.8896)
			(xy 58.333368 -291.910698) (xy 58.286097 -291.92439) (xy 58.237242 -291.930322) (xy 58.188067 -291.928341)
			(xy 58.139848 -291.918497) (xy 58.093832 -291.901045) (xy 58.051211 -291.876438) (xy 58.01309 -291.845313)
			(xy 57.980455 -291.808476) (xy 57.954152 -291.76688) (xy 57.934861 -291.721604) (xy 57.923084 -291.67382)
			(xy 57.919124 -291.624766) (xy 57.580276 -291.624766) (xy 57.579781 -291.649373) (xy 57.571886 -291.69795)
			(xy 57.556302 -291.744631) (xy 57.533431 -291.788208) (xy 57.503866 -291.827552) (xy 57.468373 -291.861644)
			(xy 57.42787 -291.8896) (xy 57.383408 -291.910698) (xy 57.336137 -291.92439) (xy 57.287282 -291.930322)
			(xy 57.238107 -291.928341) (xy 57.189888 -291.918497) (xy 57.143872 -291.901045) (xy 57.101251 -291.876438)
			(xy 57.06313 -291.845313) (xy 57.030495 -291.808476) (xy 57.004192 -291.76688) (xy 56.984901 -291.721604)
			(xy 56.973124 -291.67382) (xy 56.969164 -291.624766) (xy 56.630062 -291.624766) (xy 56.629567 -291.649373)
			(xy 56.621672 -291.69795) (xy 56.606088 -291.744631) (xy 56.583217 -291.788208) (xy 56.553652 -291.827552)
			(xy 56.518159 -291.861644) (xy 56.477656 -291.8896) (xy 56.433194 -291.910698) (xy 56.385923 -291.92439)
			(xy 56.337068 -291.930322) (xy 56.287893 -291.928341) (xy 56.239674 -291.918497) (xy 56.193658 -291.901045)
			(xy 56.151037 -291.876438) (xy 56.112916 -291.845313) (xy 56.080281 -291.808476) (xy 56.053978 -291.76688)
			(xy 56.034687 -291.721604) (xy 56.02291 -291.67382) (xy 56.01895 -291.624766) (xy 55.680102 -291.624766)
			(xy 55.679607 -291.649373) (xy 55.671712 -291.69795) (xy 55.656128 -291.744631) (xy 55.633257 -291.788208)
			(xy 55.603692 -291.827552) (xy 55.568199 -291.861644) (xy 55.527696 -291.8896) (xy 55.483234 -291.910698)
			(xy 55.435963 -291.92439) (xy 55.387108 -291.930322) (xy 55.337933 -291.928341) (xy 55.289714 -291.918497)
			(xy 55.243698 -291.901045) (xy 55.201077 -291.876438) (xy 55.162956 -291.845313) (xy 55.130321 -291.808476)
			(xy 55.104018 -291.76688) (xy 55.084727 -291.721604) (xy 55.07295 -291.67382) (xy 55.06899 -291.624766)
			(xy 54.730142 -291.624766) (xy 54.729647 -291.649373) (xy 54.721752 -291.69795) (xy 54.706168 -291.744631)
			(xy 54.683297 -291.788208) (xy 54.653732 -291.827552) (xy 54.618239 -291.861644) (xy 54.577736 -291.8896)
			(xy 54.533274 -291.910698) (xy 54.486003 -291.92439) (xy 54.437148 -291.930322) (xy 54.387973 -291.928341)
			(xy 54.339754 -291.918497) (xy 54.293738 -291.901045) (xy 54.251117 -291.876438) (xy 54.212996 -291.845313)
			(xy 54.180361 -291.808476) (xy 54.154058 -291.76688) (xy 54.134767 -291.721604) (xy 54.12299 -291.67382)
			(xy 54.11903 -291.624766) (xy 53.780182 -291.624766) (xy 53.779687 -291.649373) (xy 53.771792 -291.69795)
			(xy 53.756208 -291.744631) (xy 53.733337 -291.788208) (xy 53.703772 -291.827552) (xy 53.668279 -291.861644)
			(xy 53.627776 -291.8896) (xy 53.583314 -291.910698) (xy 53.536043 -291.92439) (xy 53.487188 -291.930322)
			(xy 53.438013 -291.928341) (xy 53.389794 -291.918497) (xy 53.343778 -291.901045) (xy 53.301157 -291.876438)
			(xy 53.263036 -291.845313) (xy 53.230401 -291.808476) (xy 53.204098 -291.76688) (xy 53.184807 -291.721604)
			(xy 53.17303 -291.67382) (xy 53.16907 -291.624766) (xy 52.830222 -291.624766) (xy 52.829727 -291.649373)
			(xy 52.821832 -291.69795) (xy 52.806248 -291.744631) (xy 52.783377 -291.788208) (xy 52.753812 -291.827552)
			(xy 52.718319 -291.861644) (xy 52.677816 -291.8896) (xy 52.633354 -291.910698) (xy 52.586083 -291.92439)
			(xy 52.537228 -291.930322) (xy 52.488053 -291.928341) (xy 52.439834 -291.918497) (xy 52.393818 -291.901045)
			(xy 52.351197 -291.876438) (xy 52.313076 -291.845313) (xy 52.280441 -291.808476) (xy 52.254138 -291.76688)
			(xy 52.234847 -291.721604) (xy 52.22307 -291.67382) (xy 52.21911 -291.624766) (xy 51.880262 -291.624766)
			(xy 51.879767 -291.649373) (xy 51.871872 -291.69795) (xy 51.856288 -291.744631) (xy 51.833417 -291.788208)
			(xy 51.803852 -291.827552) (xy 51.768359 -291.861644) (xy 51.727856 -291.8896) (xy 51.683394 -291.910698)
			(xy 51.636123 -291.92439) (xy 51.587268 -291.930322) (xy 51.538093 -291.928341) (xy 51.489874 -291.918497)
			(xy 51.443858 -291.901045) (xy 51.401237 -291.876438) (xy 51.363116 -291.845313) (xy 51.330481 -291.808476)
			(xy 51.304178 -291.76688) (xy 51.284887 -291.721604) (xy 51.27311 -291.67382) (xy 51.26915 -291.624766)
			(xy 50.930302 -291.624766) (xy 50.929807 -291.649373) (xy 50.921912 -291.69795) (xy 50.906328 -291.744631)
			(xy 50.883457 -291.788208) (xy 50.853892 -291.827552) (xy 50.818399 -291.861644) (xy 50.777896 -291.8896)
			(xy 50.733434 -291.910698) (xy 50.686163 -291.92439) (xy 50.637308 -291.930322) (xy 50.588133 -291.928341)
			(xy 50.539914 -291.918497) (xy 50.493898 -291.901045) (xy 50.451277 -291.876438) (xy 50.413156 -291.845313)
			(xy 50.380521 -291.808476) (xy 50.354218 -291.76688) (xy 50.334927 -291.721604) (xy 50.32315 -291.67382)
			(xy 50.31919 -291.624766) (xy 49.030128 -291.624766) (xy 49.029633 -291.649373) (xy 49.021738 -291.69795)
			(xy 49.006154 -291.744631) (xy 48.983283 -291.788208) (xy 48.953718 -291.827552) (xy 48.918225 -291.861644)
			(xy 48.877722 -291.8896) (xy 48.83326 -291.910698) (xy 48.785989 -291.92439) (xy 48.737134 -291.930322)
			(xy 48.687959 -291.928341) (xy 48.63974 -291.918497) (xy 48.593724 -291.901045) (xy 48.551103 -291.876438)
			(xy 48.512982 -291.845313) (xy 48.480347 -291.808476) (xy 48.454044 -291.76688) (xy 48.434753 -291.721604)
			(xy 48.422976 -291.67382) (xy 48.419016 -291.624766) (xy 48.080168 -291.624766) (xy 48.07995 -291.641544)
			(xy 48.076261 -291.674895) (xy 48.072802 -291.691314) (xy 48.0695 -291.7063) (xy 48.080422 -291.734748)
			(xy 48.104552 -291.75202) (xy 48.112426 -291.757608) (xy 48.124618 -291.76599) (xy 48.125888 -291.767006)
			(xy 48.12792 -291.768276) (xy 48.133508 -291.77234) (xy 48.143668 -291.779452) (xy 48.149256 -291.783262)
			(xy 48.170592 -291.800026) (xy 48.17237 -291.801804) (xy 48.175164 -291.803836) (xy 48.179736 -291.8079)
			(xy 48.193452 -291.82187) (xy 48.194468 -291.82314) (xy 48.196246 -291.824918) (xy 48.209454 -291.83965)
			(xy 48.21936 -291.853112) (xy 48.232856 -291.872694) (xy 48.254272 -291.915154) (xy 48.268866 -291.960415)
			(xy 48.276285 -292.007389) (xy 48.276764 -292.031166) (xy 48.276764 -292.122098) (xy 93.25737 -292.122098)
			(xy 93.257787 -292.095493) (xy 93.26517 -292.042797) (xy 93.279808 -291.991639) (xy 93.301415 -291.943013)
			(xy 93.329572 -291.897863) (xy 93.363732 -291.857065) (xy 93.403233 -291.821413) (xy 93.42501 -291.806122)
			(xy 93.436442 -291.797727) (xy 93.454643 -291.775997) (xy 93.466161 -291.750097) (xy 93.470107 -291.722027)
			(xy 93.466176 -291.693955) (xy 93.454672 -291.668049) (xy 93.436483 -291.646309) (xy 93.42501 -291.637974)
			(xy 93.403212 -291.622717) (xy 93.363735 -291.587043) (xy 93.329595 -291.546233) (xy 93.301453 -291.501076)
			(xy 93.279855 -291.452449) (xy 93.26522 -291.401294) (xy 93.257831 -291.348602) (xy 93.25737 -291.321998)
			(xy 93.257856 -291.294747) (xy 93.265612 -291.240799) (xy 93.280967 -291.188504) (xy 93.303609 -291.138927)
			(xy 93.333075 -291.093077) (xy 93.368766 -291.051886) (xy 93.409957 -291.016195) (xy 93.455807 -290.986729)
			(xy 93.505384 -290.964087) (xy 93.557679 -290.948732) (xy 93.611627 -290.940976) (xy 93.666129 -290.940976)
			(xy 93.720077 -290.948732) (xy 93.772372 -290.964087) (xy 93.821949 -290.986729) (xy 93.867799 -291.016195)
			(xy 93.90899 -291.051886) (xy 93.944681 -291.093077) (xy 93.974147 -291.138927) (xy 93.996789 -291.188504)
			(xy 94.012144 -291.240799) (xy 94.0199 -291.294747) (xy 94.020386 -291.321998) (xy 94.019942 -291.348602)
			(xy 94.01256 -291.401296) (xy 93.997925 -291.452452) (xy 93.976322 -291.501077) (xy 93.94817 -291.546227)
			(xy 93.914015 -291.587026) (xy 93.87452 -291.622681) (xy 93.852746 -291.637974) (xy 93.841215 -291.646246)
			(xy 93.823002 -291.668001) (xy 93.811482 -291.693929) (xy 93.807545 -291.722027) (xy 93.811497 -291.750123)
			(xy 93.82303 -291.776045) (xy 93.841255 -291.79779) (xy 93.852746 -291.806122) (xy 93.874532 -291.821395)
			(xy 93.914012 -291.857065) (xy 93.948154 -291.897872) (xy 93.976298 -291.943025) (xy 93.997898 -291.99165)
			(xy 94.012535 -292.042804) (xy 94.019925 -292.095495) (xy 94.020386 -292.122098) (xy 94.0199 -292.149349)
			(xy 94.012144 -292.203297) (xy 93.996789 -292.255592) (xy 93.974147 -292.305169) (xy 93.944681 -292.351019)
			(xy 93.90899 -292.39221) (xy 93.867799 -292.427901) (xy 93.821949 -292.457367) (xy 93.772372 -292.480009)
			(xy 93.720077 -292.495364) (xy 93.666129 -292.50312) (xy 93.611627 -292.50312) (xy 93.557679 -292.495364)
			(xy 93.505384 -292.480009) (xy 93.455807 -292.457367) (xy 93.409957 -292.427901) (xy 93.368766 -292.39221)
			(xy 93.333075 -292.351019) (xy 93.303609 -292.305169) (xy 93.280967 -292.255592) (xy 93.265612 -292.203297)
			(xy 93.257856 -292.149349) (xy 93.25737 -292.122098) (xy 48.276764 -292.122098) (xy 48.276764 -292.176962)
			(xy 48.276993 -292.184438) (xy 48.281259 -292.198766) (xy 48.285146 -292.205156) (xy 48.30953 -292.241986)
			(xy 48.314677 -292.250518) (xy 48.318617 -292.270029) (xy 48.314807 -292.289566) (xy 48.303823 -292.306167)
			(xy 48.295814 -292.31209) (xy 48.187356 -292.385242) (xy 48.180752 -292.390576) (xy 48.168306 -292.402514)
			(xy 48.161194 -292.408102) (xy 48.151034 -292.414706) (xy 48.149002 -292.416992) (xy 48.105568 -292.447218)
			(xy 48.104806 -292.447726) (xy 48.092614 -292.456616) (xy 48.084909 -292.462728) (xy 48.074483 -292.479381)
			(xy 48.07113 -292.498741) (xy 48.072802 -292.508432) (xy 48.072802 -292.50894) (xy 48.076204 -292.525239)
			(xy 48.079891 -292.558332) (xy 48.080164 -292.574726) (xy 49.368976 -292.574726) (xy 49.372936 -292.525672)
			(xy 49.384713 -292.477888) (xy 49.404004 -292.432612) (xy 49.430307 -292.391016) (xy 49.462942 -292.354179)
			(xy 49.501063 -292.323054) (xy 49.543684 -292.298447) (xy 49.5897 -292.280995) (xy 49.637919 -292.271151)
			(xy 49.687094 -292.26917) (xy 49.735949 -292.275102) (xy 49.78322 -292.288794) (xy 49.827682 -292.309892)
			(xy 49.868185 -292.337848) (xy 49.903678 -292.37194) (xy 49.933243 -292.411284) (xy 49.956114 -292.454861)
			(xy 49.971698 -292.501542) (xy 49.979593 -292.550119) (xy 49.980088 -292.574726) (xy 49.980083 -292.57498)
			(xy 50.31919 -292.57498) (xy 50.32315 -292.525926) (xy 50.334927 -292.478142) (xy 50.354218 -292.432866)
			(xy 50.380521 -292.39127) (xy 50.413156 -292.354433) (xy 50.451277 -292.323308) (xy 50.493898 -292.298701)
			(xy 50.539914 -292.281249) (xy 50.588133 -292.271405) (xy 50.637308 -292.269424) (xy 50.686163 -292.275356)
			(xy 50.733434 -292.289048) (xy 50.777896 -292.310146) (xy 50.818399 -292.338102) (xy 50.853892 -292.372194)
			(xy 50.883457 -292.411538) (xy 50.906328 -292.455115) (xy 50.921912 -292.501796) (xy 50.929807 -292.550373)
			(xy 50.930302 -292.57498) (xy 51.26915 -292.57498) (xy 51.27311 -292.525926) (xy 51.284887 -292.478142)
			(xy 51.304178 -292.432866) (xy 51.330481 -292.39127) (xy 51.363116 -292.354433) (xy 51.401237 -292.323308)
			(xy 51.443858 -292.298701) (xy 51.489874 -292.281249) (xy 51.538093 -292.271405) (xy 51.587268 -292.269424)
			(xy 51.636123 -292.275356) (xy 51.683394 -292.289048) (xy 51.727856 -292.310146) (xy 51.768359 -292.338102)
			(xy 51.803852 -292.372194) (xy 51.833417 -292.411538) (xy 51.856288 -292.455115) (xy 51.871872 -292.501796)
			(xy 51.879767 -292.550373) (xy 51.880262 -292.57498) (xy 52.21911 -292.57498) (xy 52.22307 -292.525926)
			(xy 52.234847 -292.478142) (xy 52.254138 -292.432866) (xy 52.280441 -292.39127) (xy 52.313076 -292.354433)
			(xy 52.351197 -292.323308) (xy 52.393818 -292.298701) (xy 52.439834 -292.281249) (xy 52.488053 -292.271405)
			(xy 52.537228 -292.269424) (xy 52.586083 -292.275356) (xy 52.633354 -292.289048) (xy 52.677816 -292.310146)
			(xy 52.718319 -292.338102) (xy 52.753812 -292.372194) (xy 52.783377 -292.411538) (xy 52.806248 -292.455115)
			(xy 52.821832 -292.501796) (xy 52.829727 -292.550373) (xy 52.830222 -292.57498) (xy 53.16907 -292.57498)
			(xy 53.17303 -292.525926) (xy 53.184807 -292.478142) (xy 53.204098 -292.432866) (xy 53.230401 -292.39127)
			(xy 53.263036 -292.354433) (xy 53.301157 -292.323308) (xy 53.343778 -292.298701) (xy 53.389794 -292.281249)
			(xy 53.438013 -292.271405) (xy 53.487188 -292.269424) (xy 53.536043 -292.275356) (xy 53.583314 -292.289048)
			(xy 53.627776 -292.310146) (xy 53.668279 -292.338102) (xy 53.703772 -292.372194) (xy 53.733337 -292.411538)
			(xy 53.756208 -292.455115) (xy 53.771792 -292.501796) (xy 53.779687 -292.550373) (xy 53.780182 -292.57498)
			(xy 54.11903 -292.57498) (xy 54.12299 -292.525926) (xy 54.134767 -292.478142) (xy 54.154058 -292.432866)
			(xy 54.180361 -292.39127) (xy 54.212996 -292.354433) (xy 54.251117 -292.323308) (xy 54.293738 -292.298701)
			(xy 54.339754 -292.281249) (xy 54.387973 -292.271405) (xy 54.437148 -292.269424) (xy 54.486003 -292.275356)
			(xy 54.533274 -292.289048) (xy 54.577736 -292.310146) (xy 54.618239 -292.338102) (xy 54.653732 -292.372194)
			(xy 54.683297 -292.411538) (xy 54.706168 -292.455115) (xy 54.721752 -292.501796) (xy 54.729647 -292.550373)
			(xy 54.730142 -292.57498) (xy 55.06899 -292.57498) (xy 55.07295 -292.525926) (xy 55.084727 -292.478142)
			(xy 55.104018 -292.432866) (xy 55.130321 -292.39127) (xy 55.162956 -292.354433) (xy 55.201077 -292.323308)
			(xy 55.243698 -292.298701) (xy 55.289714 -292.281249) (xy 55.337933 -292.271405) (xy 55.387108 -292.269424)
			(xy 55.435963 -292.275356) (xy 55.483234 -292.289048) (xy 55.527696 -292.310146) (xy 55.568199 -292.338102)
			(xy 55.603692 -292.372194) (xy 55.633257 -292.411538) (xy 55.656128 -292.455115) (xy 55.671712 -292.501796)
			(xy 55.679607 -292.550373) (xy 55.680102 -292.57498) (xy 56.019204 -292.57498) (xy 56.023164 -292.525926)
			(xy 56.034941 -292.478142) (xy 56.054232 -292.432866) (xy 56.080535 -292.39127) (xy 56.11317 -292.354433)
			(xy 56.151291 -292.323308) (xy 56.193912 -292.298701) (xy 56.239928 -292.281249) (xy 56.288147 -292.271405)
			(xy 56.337322 -292.269424) (xy 56.386177 -292.275356) (xy 56.433448 -292.289048) (xy 56.47791 -292.310146)
			(xy 56.518413 -292.338102) (xy 56.553906 -292.372194) (xy 56.583471 -292.411538) (xy 56.606342 -292.455115)
			(xy 56.621926 -292.501796) (xy 56.629821 -292.550373) (xy 56.630316 -292.57498) (xy 56.969164 -292.57498)
			(xy 56.973124 -292.525926) (xy 56.984901 -292.478142) (xy 57.004192 -292.432866) (xy 57.030495 -292.39127)
			(xy 57.06313 -292.354433) (xy 57.101251 -292.323308) (xy 57.143872 -292.298701) (xy 57.189888 -292.281249)
			(xy 57.238107 -292.271405) (xy 57.287282 -292.269424) (xy 57.336137 -292.275356) (xy 57.383408 -292.289048)
			(xy 57.42787 -292.310146) (xy 57.468373 -292.338102) (xy 57.503866 -292.372194) (xy 57.533431 -292.411538)
			(xy 57.556302 -292.455115) (xy 57.571886 -292.501796) (xy 57.579781 -292.550373) (xy 57.580276 -292.57498)
			(xy 57.919124 -292.57498) (xy 57.923084 -292.525926) (xy 57.934861 -292.478142) (xy 57.954152 -292.432866)
			(xy 57.980455 -292.39127) (xy 58.01309 -292.354433) (xy 58.051211 -292.323308) (xy 58.093832 -292.298701)
			(xy 58.139848 -292.281249) (xy 58.188067 -292.271405) (xy 58.237242 -292.269424) (xy 58.286097 -292.275356)
			(xy 58.333368 -292.289048) (xy 58.37783 -292.310146) (xy 58.418333 -292.338102) (xy 58.453826 -292.372194)
			(xy 58.483391 -292.411538) (xy 58.506262 -292.455115) (xy 58.521846 -292.501796) (xy 58.529741 -292.550373)
			(xy 58.530231 -292.574726) (xy 59.819044 -292.574726) (xy 59.823004 -292.525672) (xy 59.834781 -292.477888)
			(xy 59.854072 -292.432612) (xy 59.880375 -292.391016) (xy 59.91301 -292.354179) (xy 59.951131 -292.323054)
			(xy 59.993752 -292.298447) (xy 60.039768 -292.280995) (xy 60.087987 -292.271151) (xy 60.137162 -292.26917)
			(xy 60.186017 -292.275102) (xy 60.233288 -292.288794) (xy 60.27775 -292.309892) (xy 60.318253 -292.337848)
			(xy 60.353746 -292.37194) (xy 60.383311 -292.411284) (xy 60.406182 -292.454861) (xy 60.421766 -292.501542)
			(xy 60.429661 -292.550119) (xy 60.430156 -292.574726) (xy 60.769004 -292.574726) (xy 60.772964 -292.525672)
			(xy 60.784741 -292.477888) (xy 60.804032 -292.432612) (xy 60.830335 -292.391016) (xy 60.86297 -292.354179)
			(xy 60.901091 -292.323054) (xy 60.943712 -292.298447) (xy 60.989728 -292.280995) (xy 61.037947 -292.271151)
			(xy 61.087122 -292.26917) (xy 61.135977 -292.275102) (xy 61.183248 -292.288794) (xy 61.22771 -292.309892)
			(xy 61.268213 -292.337848) (xy 61.303706 -292.37194) (xy 61.333271 -292.411284) (xy 61.356142 -292.454861)
			(xy 61.371726 -292.501542) (xy 61.379621 -292.550119) (xy 61.380116 -292.574726) (xy 61.718964 -292.574726)
			(xy 61.722924 -292.525672) (xy 61.734701 -292.477888) (xy 61.753992 -292.432612) (xy 61.780295 -292.391016)
			(xy 61.81293 -292.354179) (xy 61.851051 -292.323054) (xy 61.893672 -292.298447) (xy 61.939688 -292.280995)
			(xy 61.987907 -292.271151) (xy 62.037082 -292.26917) (xy 62.085937 -292.275102) (xy 62.133208 -292.288794)
			(xy 62.17767 -292.309892) (xy 62.218173 -292.337848) (xy 62.253666 -292.37194) (xy 62.283231 -292.411284)
			(xy 62.306102 -292.454861) (xy 62.321686 -292.501542) (xy 62.329581 -292.550119) (xy 62.330076 -292.574726)
			(xy 62.669178 -292.574726) (xy 62.673138 -292.525672) (xy 62.684915 -292.477888) (xy 62.704206 -292.432612)
			(xy 62.730509 -292.391016) (xy 62.763144 -292.354179) (xy 62.801265 -292.323054) (xy 62.843886 -292.298447)
			(xy 62.889902 -292.280995) (xy 62.938121 -292.271151) (xy 62.987296 -292.26917) (xy 63.036151 -292.275102)
			(xy 63.083422 -292.288794) (xy 63.127884 -292.309892) (xy 63.168387 -292.337848) (xy 63.20388 -292.37194)
			(xy 63.233445 -292.411284) (xy 63.256316 -292.454861) (xy 63.2719 -292.501542) (xy 63.279795 -292.550119)
			(xy 63.28029 -292.574726) (xy 63.619138 -292.574726) (xy 63.623098 -292.525672) (xy 63.634875 -292.477888)
			(xy 63.654166 -292.432612) (xy 63.680469 -292.391016) (xy 63.713104 -292.354179) (xy 63.751225 -292.323054)
			(xy 63.793846 -292.298447) (xy 63.839862 -292.280995) (xy 63.888081 -292.271151) (xy 63.937256 -292.26917)
			(xy 63.986111 -292.275102) (xy 64.033382 -292.288794) (xy 64.077844 -292.309892) (xy 64.118347 -292.337848)
			(xy 64.15384 -292.37194) (xy 64.183405 -292.411284) (xy 64.206276 -292.454861) (xy 64.22186 -292.501542)
			(xy 64.229755 -292.550119) (xy 64.23025 -292.574726) (xy 64.569098 -292.574726) (xy 64.573058 -292.525672)
			(xy 64.584835 -292.477888) (xy 64.604126 -292.432612) (xy 64.630429 -292.391016) (xy 64.663064 -292.354179)
			(xy 64.701185 -292.323054) (xy 64.743806 -292.298447) (xy 64.789822 -292.280995) (xy 64.838041 -292.271151)
			(xy 64.887216 -292.26917) (xy 64.936071 -292.275102) (xy 64.983342 -292.288794) (xy 65.027804 -292.309892)
			(xy 65.068307 -292.337848) (xy 65.1038 -292.37194) (xy 65.133365 -292.411284) (xy 65.156236 -292.454861)
			(xy 65.17182 -292.501542) (xy 65.179715 -292.550119) (xy 65.18021 -292.574726) (xy 65.519058 -292.574726)
			(xy 65.523018 -292.525672) (xy 65.534795 -292.477888) (xy 65.554086 -292.432612) (xy 65.580389 -292.391016)
			(xy 65.613024 -292.354179) (xy 65.651145 -292.323054) (xy 65.693766 -292.298447) (xy 65.739782 -292.280995)
			(xy 65.788001 -292.271151) (xy 65.837176 -292.26917) (xy 65.886031 -292.275102) (xy 65.933302 -292.288794)
			(xy 65.977764 -292.309892) (xy 66.018267 -292.337848) (xy 66.05376 -292.37194) (xy 66.083325 -292.411284)
			(xy 66.106196 -292.454861) (xy 66.12178 -292.501542) (xy 66.129675 -292.550119) (xy 66.13017 -292.574726)
			(xy 66.469018 -292.574726) (xy 66.472978 -292.525672) (xy 66.484755 -292.477888) (xy 66.504046 -292.432612)
			(xy 66.530349 -292.391016) (xy 66.562984 -292.354179) (xy 66.601105 -292.323054) (xy 66.643726 -292.298447)
			(xy 66.689742 -292.280995) (xy 66.737961 -292.271151) (xy 66.787136 -292.26917) (xy 66.835991 -292.275102)
			(xy 66.883262 -292.288794) (xy 66.927724 -292.309892) (xy 66.968227 -292.337848) (xy 67.00372 -292.37194)
			(xy 67.033285 -292.411284) (xy 67.056156 -292.454861) (xy 67.07174 -292.501542) (xy 67.079635 -292.550119)
			(xy 67.08013 -292.574726) (xy 67.418978 -292.574726) (xy 67.422938 -292.525672) (xy 67.434715 -292.477888)
			(xy 67.454006 -292.432612) (xy 67.480309 -292.391016) (xy 67.512944 -292.354179) (xy 67.551065 -292.323054)
			(xy 67.593686 -292.298447) (xy 67.639702 -292.280995) (xy 67.687921 -292.271151) (xy 67.737096 -292.26917)
			(xy 67.785951 -292.275102) (xy 67.833222 -292.288794) (xy 67.877684 -292.309892) (xy 67.918187 -292.337848)
			(xy 67.95368 -292.37194) (xy 67.983245 -292.411284) (xy 68.006116 -292.454861) (xy 68.0217 -292.501542)
			(xy 68.029595 -292.550119) (xy 68.03009 -292.574726) (xy 68.368938 -292.574726) (xy 68.372898 -292.525672)
			(xy 68.384675 -292.477888) (xy 68.403966 -292.432612) (xy 68.430269 -292.391016) (xy 68.462904 -292.354179)
			(xy 68.501025 -292.323054) (xy 68.543646 -292.298447) (xy 68.589662 -292.280995) (xy 68.637881 -292.271151)
			(xy 68.687056 -292.26917) (xy 68.735911 -292.275102) (xy 68.783182 -292.288794) (xy 68.827644 -292.309892)
			(xy 68.868147 -292.337848) (xy 68.90364 -292.37194) (xy 68.933205 -292.411284) (xy 68.956076 -292.454861)
			(xy 68.97166 -292.501542) (xy 68.979555 -292.550119) (xy 68.98005 -292.574726) (xy 69.319152 -292.574726)
			(xy 69.323112 -292.525672) (xy 69.334889 -292.477888) (xy 69.35418 -292.432612) (xy 69.380483 -292.391016)
			(xy 69.413118 -292.354179) (xy 69.451239 -292.323054) (xy 69.49386 -292.298447) (xy 69.539876 -292.280995)
			(xy 69.588095 -292.271151) (xy 69.63727 -292.26917) (xy 69.686125 -292.275102) (xy 69.733396 -292.288794)
			(xy 69.777858 -292.309892) (xy 69.818361 -292.337848) (xy 69.853854 -292.37194) (xy 69.883419 -292.411284)
			(xy 69.90629 -292.454861) (xy 69.921874 -292.501542) (xy 69.929769 -292.550119) (xy 69.930264 -292.574726)
			(xy 69.930259 -292.57498) (xy 70.269112 -292.57498) (xy 70.273072 -292.525926) (xy 70.284849 -292.478142)
			(xy 70.30414 -292.432866) (xy 70.330443 -292.39127) (xy 70.363078 -292.354433) (xy 70.401199 -292.323308)
			(xy 70.44382 -292.298701) (xy 70.489836 -292.281249) (xy 70.538055 -292.271405) (xy 70.58723 -292.269424)
			(xy 70.636085 -292.275356) (xy 70.683356 -292.289048) (xy 70.727818 -292.310146) (xy 70.768321 -292.338102)
			(xy 70.803814 -292.372194) (xy 70.833379 -292.411538) (xy 70.85625 -292.455115) (xy 70.871834 -292.501796)
			(xy 70.879729 -292.550373) (xy 70.880219 -292.574726) (xy 71.219072 -292.574726) (xy 71.223032 -292.525672)
			(xy 71.234809 -292.477888) (xy 71.2541 -292.432612) (xy 71.280403 -292.391016) (xy 71.313038 -292.354179)
			(xy 71.351159 -292.323054) (xy 71.39378 -292.298447) (xy 71.439796 -292.280995) (xy 71.488015 -292.271151)
			(xy 71.53719 -292.26917) (xy 71.586045 -292.275102) (xy 71.633316 -292.288794) (xy 71.677778 -292.309892)
			(xy 71.718281 -292.337848) (xy 71.753774 -292.37194) (xy 71.783339 -292.411284) (xy 71.80621 -292.454861)
			(xy 71.821794 -292.501542) (xy 71.829689 -292.550119) (xy 71.830184 -292.574726) (xy 72.169032 -292.574726)
			(xy 72.172992 -292.525672) (xy 72.184769 -292.477888) (xy 72.20406 -292.432612) (xy 72.230363 -292.391016)
			(xy 72.262998 -292.354179) (xy 72.301119 -292.323054) (xy 72.34374 -292.298447) (xy 72.389756 -292.280995)
			(xy 72.437975 -292.271151) (xy 72.48715 -292.26917) (xy 72.536005 -292.275102) (xy 72.583276 -292.288794)
			(xy 72.627738 -292.309892) (xy 72.668241 -292.337848) (xy 72.703734 -292.37194) (xy 72.733299 -292.411284)
			(xy 72.75617 -292.454861) (xy 72.771754 -292.501542) (xy 72.779649 -292.550119) (xy 72.780144 -292.574726)
			(xy 73.118992 -292.574726) (xy 73.122952 -292.525672) (xy 73.134729 -292.477888) (xy 73.15402 -292.432612)
			(xy 73.180323 -292.391016) (xy 73.212958 -292.354179) (xy 73.251079 -292.323054) (xy 73.2937 -292.298447)
			(xy 73.339716 -292.280995) (xy 73.387935 -292.271151) (xy 73.43711 -292.26917) (xy 73.485965 -292.275102)
			(xy 73.533236 -292.288794) (xy 73.577698 -292.309892) (xy 73.618201 -292.337848) (xy 73.653694 -292.37194)
			(xy 73.683259 -292.411284) (xy 73.70613 -292.454861) (xy 73.721714 -292.501542) (xy 73.729609 -292.550119)
			(xy 73.730104 -292.574726) (xy 74.068952 -292.574726) (xy 74.072912 -292.525672) (xy 74.084689 -292.477888)
			(xy 74.10398 -292.432612) (xy 74.130283 -292.391016) (xy 74.162918 -292.354179) (xy 74.201039 -292.323054)
			(xy 74.24366 -292.298447) (xy 74.289676 -292.280995) (xy 74.337895 -292.271151) (xy 74.38707 -292.26917)
			(xy 74.435925 -292.275102) (xy 74.483196 -292.288794) (xy 74.527658 -292.309892) (xy 74.568161 -292.337848)
			(xy 74.603654 -292.37194) (xy 74.633219 -292.411284) (xy 74.65609 -292.454861) (xy 74.671674 -292.501542)
			(xy 74.679569 -292.550119) (xy 74.680064 -292.574726) (xy 75.019166 -292.574726) (xy 75.023126 -292.525672)
			(xy 75.034903 -292.477888) (xy 75.054194 -292.432612) (xy 75.080497 -292.391016) (xy 75.113132 -292.354179)
			(xy 75.151253 -292.323054) (xy 75.193874 -292.298447) (xy 75.23989 -292.280995) (xy 75.288109 -292.271151)
			(xy 75.337284 -292.26917) (xy 75.386139 -292.275102) (xy 75.43341 -292.288794) (xy 75.477872 -292.309892)
			(xy 75.518375 -292.337848) (xy 75.553868 -292.37194) (xy 75.583433 -292.411284) (xy 75.606304 -292.454861)
			(xy 75.621888 -292.501542) (xy 75.629783 -292.550119) (xy 75.630278 -292.574726) (xy 75.969126 -292.574726)
			(xy 75.973086 -292.525672) (xy 75.984863 -292.477888) (xy 76.004154 -292.432612) (xy 76.030457 -292.391016)
			(xy 76.063092 -292.354179) (xy 76.101213 -292.323054) (xy 76.143834 -292.298447) (xy 76.18985 -292.280995)
			(xy 76.238069 -292.271151) (xy 76.287244 -292.26917) (xy 76.336099 -292.275102) (xy 76.38337 -292.288794)
			(xy 76.427832 -292.309892) (xy 76.468335 -292.337848) (xy 76.503828 -292.37194) (xy 76.533393 -292.411284)
			(xy 76.556264 -292.454861) (xy 76.571848 -292.501542) (xy 76.579743 -292.550119) (xy 76.580238 -292.574726)
			(xy 76.919086 -292.574726) (xy 76.923046 -292.525672) (xy 76.934823 -292.477888) (xy 76.954114 -292.432612)
			(xy 76.980417 -292.391016) (xy 77.013052 -292.354179) (xy 77.051173 -292.323054) (xy 77.093794 -292.298447)
			(xy 77.13981 -292.280995) (xy 77.188029 -292.271151) (xy 77.237204 -292.26917) (xy 77.286059 -292.275102)
			(xy 77.33333 -292.288794) (xy 77.377792 -292.309892) (xy 77.418295 -292.337848) (xy 77.453788 -292.37194)
			(xy 77.483353 -292.411284) (xy 77.506224 -292.454861) (xy 77.521808 -292.501542) (xy 77.529703 -292.550119)
			(xy 77.530198 -292.574726) (xy 77.869046 -292.574726) (xy 77.873006 -292.525672) (xy 77.884783 -292.477888)
			(xy 77.904074 -292.432612) (xy 77.930377 -292.391016) (xy 77.963012 -292.354179) (xy 78.001133 -292.323054)
			(xy 78.043754 -292.298447) (xy 78.08977 -292.280995) (xy 78.137989 -292.271151) (xy 78.187164 -292.26917)
			(xy 78.236019 -292.275102) (xy 78.28329 -292.288794) (xy 78.327752 -292.309892) (xy 78.368255 -292.337848)
			(xy 78.403748 -292.37194) (xy 78.433313 -292.411284) (xy 78.456184 -292.454861) (xy 78.471768 -292.501542)
			(xy 78.479663 -292.550119) (xy 78.480158 -292.574726) (xy 78.819006 -292.574726) (xy 78.822966 -292.525672)
			(xy 78.834743 -292.477888) (xy 78.854034 -292.432612) (xy 78.880337 -292.391016) (xy 78.912972 -292.354179)
			(xy 78.951093 -292.323054) (xy 78.993714 -292.298447) (xy 79.03973 -292.280995) (xy 79.087949 -292.271151)
			(xy 79.137124 -292.26917) (xy 79.185979 -292.275102) (xy 79.23325 -292.288794) (xy 79.277712 -292.309892)
			(xy 79.318215 -292.337848) (xy 79.353708 -292.37194) (xy 79.383273 -292.411284) (xy 79.406144 -292.454861)
			(xy 79.421728 -292.501542) (xy 79.429623 -292.550119) (xy 79.430118 -292.574726) (xy 79.768966 -292.574726)
			(xy 79.772926 -292.525672) (xy 79.784703 -292.477888) (xy 79.803994 -292.432612) (xy 79.830297 -292.391016)
			(xy 79.862932 -292.354179) (xy 79.901053 -292.323054) (xy 79.943674 -292.298447) (xy 79.98969 -292.280995)
			(xy 80.037909 -292.271151) (xy 80.087084 -292.26917) (xy 80.135939 -292.275102) (xy 80.18321 -292.288794)
			(xy 80.227672 -292.309892) (xy 80.268175 -292.337848) (xy 80.303668 -292.37194) (xy 80.333233 -292.411284)
			(xy 80.356104 -292.454861) (xy 80.371688 -292.501542) (xy 80.379583 -292.550119) (xy 80.380078 -292.574726)
			(xy 80.71918 -292.574726) (xy 80.72314 -292.525672) (xy 80.734917 -292.477888) (xy 80.754208 -292.432612)
			(xy 80.780511 -292.391016) (xy 80.813146 -292.354179) (xy 80.851267 -292.323054) (xy 80.893888 -292.298447)
			(xy 80.939904 -292.280995) (xy 80.988123 -292.271151) (xy 81.037298 -292.26917) (xy 81.086153 -292.275102)
			(xy 81.133424 -292.288794) (xy 81.177886 -292.309892) (xy 81.218389 -292.337848) (xy 81.253882 -292.37194)
			(xy 81.283447 -292.411284) (xy 81.306318 -292.454861) (xy 81.321902 -292.501542) (xy 81.329797 -292.550119)
			(xy 81.330292 -292.574726) (xy 81.330287 -292.57498) (xy 81.66914 -292.57498) (xy 81.6731 -292.525926)
			(xy 81.684877 -292.478142) (xy 81.704168 -292.432866) (xy 81.730471 -292.39127) (xy 81.763106 -292.354433)
			(xy 81.801227 -292.323308) (xy 81.843848 -292.298701) (xy 81.889864 -292.281249) (xy 81.938083 -292.271405)
			(xy 81.987258 -292.269424) (xy 82.036113 -292.275356) (xy 82.083384 -292.289048) (xy 82.127846 -292.310146)
			(xy 82.168349 -292.338102) (xy 82.203842 -292.372194) (xy 82.233407 -292.411538) (xy 82.256278 -292.455115)
			(xy 82.271862 -292.501796) (xy 82.279757 -292.550373) (xy 82.280252 -292.57498) (xy 82.6191 -292.57498)
			(xy 82.62306 -292.525926) (xy 82.634837 -292.478142) (xy 82.654128 -292.432866) (xy 82.680431 -292.39127)
			(xy 82.713066 -292.354433) (xy 82.751187 -292.323308) (xy 82.793808 -292.298701) (xy 82.839824 -292.281249)
			(xy 82.888043 -292.271405) (xy 82.937218 -292.269424) (xy 82.986073 -292.275356) (xy 83.033344 -292.289048)
			(xy 83.077806 -292.310146) (xy 83.118309 -292.338102) (xy 83.153802 -292.372194) (xy 83.183367 -292.411538)
			(xy 83.206238 -292.455115) (xy 83.221822 -292.501796) (xy 83.229717 -292.550373) (xy 83.230212 -292.57498)
			(xy 83.229717 -292.599587) (xy 83.221822 -292.648164) (xy 83.206238 -292.694845) (xy 83.183367 -292.738422)
			(xy 83.153802 -292.777766) (xy 83.118309 -292.811858) (xy 83.077806 -292.839814) (xy 83.033344 -292.860912)
			(xy 82.986073 -292.874604) (xy 82.937218 -292.880536) (xy 82.888043 -292.878555) (xy 82.839824 -292.868711)
			(xy 82.793808 -292.851259) (xy 82.751187 -292.826652) (xy 82.713066 -292.795527) (xy 82.680431 -292.75869)
			(xy 82.654128 -292.717094) (xy 82.634837 -292.671818) (xy 82.62306 -292.624034) (xy 82.6191 -292.57498)
			(xy 82.280252 -292.57498) (xy 82.279757 -292.599587) (xy 82.271862 -292.648164) (xy 82.256278 -292.694845)
			(xy 82.233407 -292.738422) (xy 82.203842 -292.777766) (xy 82.168349 -292.811858) (xy 82.127846 -292.839814)
			(xy 82.083384 -292.860912) (xy 82.036113 -292.874604) (xy 81.987258 -292.880536) (xy 81.938083 -292.878555)
			(xy 81.889864 -292.868711) (xy 81.843848 -292.851259) (xy 81.801227 -292.826652) (xy 81.763106 -292.795527)
			(xy 81.730471 -292.75869) (xy 81.704168 -292.717094) (xy 81.684877 -292.671818) (xy 81.6731 -292.624034)
			(xy 81.66914 -292.57498) (xy 81.330287 -292.57498) (xy 81.329797 -292.599333) (xy 81.321902 -292.64791)
			(xy 81.306318 -292.694591) (xy 81.283447 -292.738168) (xy 81.253882 -292.777512) (xy 81.218389 -292.811604)
			(xy 81.177886 -292.83956) (xy 81.133424 -292.860658) (xy 81.086153 -292.87435) (xy 81.037298 -292.880282)
			(xy 80.988123 -292.878301) (xy 80.939904 -292.868457) (xy 80.893888 -292.851005) (xy 80.851267 -292.826398)
			(xy 80.813146 -292.795273) (xy 80.780511 -292.758436) (xy 80.754208 -292.71684) (xy 80.734917 -292.671564)
			(xy 80.72314 -292.62378) (xy 80.71918 -292.574726) (xy 80.380078 -292.574726) (xy 80.379583 -292.599333)
			(xy 80.371688 -292.64791) (xy 80.356104 -292.694591) (xy 80.333233 -292.738168) (xy 80.303668 -292.777512)
			(xy 80.268175 -292.811604) (xy 80.227672 -292.83956) (xy 80.18321 -292.860658) (xy 80.135939 -292.87435)
			(xy 80.087084 -292.880282) (xy 80.037909 -292.878301) (xy 79.98969 -292.868457) (xy 79.943674 -292.851005)
			(xy 79.901053 -292.826398) (xy 79.862932 -292.795273) (xy 79.830297 -292.758436) (xy 79.803994 -292.71684)
			(xy 79.784703 -292.671564) (xy 79.772926 -292.62378) (xy 79.768966 -292.574726) (xy 79.430118 -292.574726)
			(xy 79.429623 -292.599333) (xy 79.421728 -292.64791) (xy 79.406144 -292.694591) (xy 79.383273 -292.738168)
			(xy 79.353708 -292.777512) (xy 79.318215 -292.811604) (xy 79.277712 -292.83956) (xy 79.23325 -292.860658)
			(xy 79.185979 -292.87435) (xy 79.137124 -292.880282) (xy 79.087949 -292.878301) (xy 79.03973 -292.868457)
			(xy 78.993714 -292.851005) (xy 78.951093 -292.826398) (xy 78.912972 -292.795273) (xy 78.880337 -292.758436)
			(xy 78.854034 -292.71684) (xy 78.834743 -292.671564) (xy 78.822966 -292.62378) (xy 78.819006 -292.574726)
			(xy 78.480158 -292.574726) (xy 78.479663 -292.599333) (xy 78.471768 -292.64791) (xy 78.456184 -292.694591)
			(xy 78.433313 -292.738168) (xy 78.403748 -292.777512) (xy 78.368255 -292.811604) (xy 78.327752 -292.83956)
			(xy 78.28329 -292.860658) (xy 78.236019 -292.87435) (xy 78.187164 -292.880282) (xy 78.137989 -292.878301)
			(xy 78.08977 -292.868457) (xy 78.043754 -292.851005) (xy 78.001133 -292.826398) (xy 77.963012 -292.795273)
			(xy 77.930377 -292.758436) (xy 77.904074 -292.71684) (xy 77.884783 -292.671564) (xy 77.873006 -292.62378)
			(xy 77.869046 -292.574726) (xy 77.530198 -292.574726) (xy 77.529703 -292.599333) (xy 77.521808 -292.64791)
			(xy 77.506224 -292.694591) (xy 77.483353 -292.738168) (xy 77.453788 -292.777512) (xy 77.418295 -292.811604)
			(xy 77.377792 -292.83956) (xy 77.33333 -292.860658) (xy 77.286059 -292.87435) (xy 77.237204 -292.880282)
			(xy 77.188029 -292.878301) (xy 77.13981 -292.868457) (xy 77.093794 -292.851005) (xy 77.051173 -292.826398)
			(xy 77.013052 -292.795273) (xy 76.980417 -292.758436) (xy 76.954114 -292.71684) (xy 76.934823 -292.671564)
			(xy 76.923046 -292.62378) (xy 76.919086 -292.574726) (xy 76.580238 -292.574726) (xy 76.579743 -292.599333)
			(xy 76.571848 -292.64791) (xy 76.556264 -292.694591) (xy 76.533393 -292.738168) (xy 76.503828 -292.777512)
			(xy 76.468335 -292.811604) (xy 76.427832 -292.83956) (xy 76.38337 -292.860658) (xy 76.336099 -292.87435)
			(xy 76.287244 -292.880282) (xy 76.238069 -292.878301) (xy 76.18985 -292.868457) (xy 76.143834 -292.851005)
			(xy 76.101213 -292.826398) (xy 76.063092 -292.795273) (xy 76.030457 -292.758436) (xy 76.004154 -292.71684)
			(xy 75.984863 -292.671564) (xy 75.973086 -292.62378) (xy 75.969126 -292.574726) (xy 75.630278 -292.574726)
			(xy 75.629783 -292.599333) (xy 75.621888 -292.64791) (xy 75.606304 -292.694591) (xy 75.583433 -292.738168)
			(xy 75.553868 -292.777512) (xy 75.518375 -292.811604) (xy 75.477872 -292.83956) (xy 75.43341 -292.860658)
			(xy 75.386139 -292.87435) (xy 75.337284 -292.880282) (xy 75.288109 -292.878301) (xy 75.23989 -292.868457)
			(xy 75.193874 -292.851005) (xy 75.151253 -292.826398) (xy 75.113132 -292.795273) (xy 75.080497 -292.758436)
			(xy 75.054194 -292.71684) (xy 75.034903 -292.671564) (xy 75.023126 -292.62378) (xy 75.019166 -292.574726)
			(xy 74.680064 -292.574726) (xy 74.679569 -292.599333) (xy 74.671674 -292.64791) (xy 74.65609 -292.694591)
			(xy 74.633219 -292.738168) (xy 74.603654 -292.777512) (xy 74.568161 -292.811604) (xy 74.527658 -292.83956)
			(xy 74.483196 -292.860658) (xy 74.435925 -292.87435) (xy 74.38707 -292.880282) (xy 74.337895 -292.878301)
			(xy 74.289676 -292.868457) (xy 74.24366 -292.851005) (xy 74.201039 -292.826398) (xy 74.162918 -292.795273)
			(xy 74.130283 -292.758436) (xy 74.10398 -292.71684) (xy 74.084689 -292.671564) (xy 74.072912 -292.62378)
			(xy 74.068952 -292.574726) (xy 73.730104 -292.574726) (xy 73.729609 -292.599333) (xy 73.721714 -292.64791)
			(xy 73.70613 -292.694591) (xy 73.683259 -292.738168) (xy 73.653694 -292.777512) (xy 73.618201 -292.811604)
			(xy 73.577698 -292.83956) (xy 73.533236 -292.860658) (xy 73.485965 -292.87435) (xy 73.43711 -292.880282)
			(xy 73.387935 -292.878301) (xy 73.339716 -292.868457) (xy 73.2937 -292.851005) (xy 73.251079 -292.826398)
			(xy 73.212958 -292.795273) (xy 73.180323 -292.758436) (xy 73.15402 -292.71684) (xy 73.134729 -292.671564)
			(xy 73.122952 -292.62378) (xy 73.118992 -292.574726) (xy 72.780144 -292.574726) (xy 72.779649 -292.599333)
			(xy 72.771754 -292.64791) (xy 72.75617 -292.694591) (xy 72.733299 -292.738168) (xy 72.703734 -292.777512)
			(xy 72.668241 -292.811604) (xy 72.627738 -292.83956) (xy 72.583276 -292.860658) (xy 72.536005 -292.87435)
			(xy 72.48715 -292.880282) (xy 72.437975 -292.878301) (xy 72.389756 -292.868457) (xy 72.34374 -292.851005)
			(xy 72.301119 -292.826398) (xy 72.262998 -292.795273) (xy 72.230363 -292.758436) (xy 72.20406 -292.71684)
			(xy 72.184769 -292.671564) (xy 72.172992 -292.62378) (xy 72.169032 -292.574726) (xy 71.830184 -292.574726)
			(xy 71.829689 -292.599333) (xy 71.821794 -292.64791) (xy 71.80621 -292.694591) (xy 71.783339 -292.738168)
			(xy 71.753774 -292.777512) (xy 71.718281 -292.811604) (xy 71.677778 -292.83956) (xy 71.633316 -292.860658)
			(xy 71.586045 -292.87435) (xy 71.53719 -292.880282) (xy 71.488015 -292.878301) (xy 71.439796 -292.868457)
			(xy 71.39378 -292.851005) (xy 71.351159 -292.826398) (xy 71.313038 -292.795273) (xy 71.280403 -292.758436)
			(xy 71.2541 -292.71684) (xy 71.234809 -292.671564) (xy 71.223032 -292.62378) (xy 71.219072 -292.574726)
			(xy 70.880219 -292.574726) (xy 70.880224 -292.57498) (xy 70.879729 -292.599587) (xy 70.871834 -292.648164)
			(xy 70.85625 -292.694845) (xy 70.833379 -292.738422) (xy 70.803814 -292.777766) (xy 70.768321 -292.811858)
			(xy 70.727818 -292.839814) (xy 70.683356 -292.860912) (xy 70.636085 -292.874604) (xy 70.58723 -292.880536)
			(xy 70.538055 -292.878555) (xy 70.489836 -292.868711) (xy 70.44382 -292.851259) (xy 70.401199 -292.826652)
			(xy 70.363078 -292.795527) (xy 70.330443 -292.75869) (xy 70.30414 -292.717094) (xy 70.284849 -292.671818)
			(xy 70.273072 -292.624034) (xy 70.269112 -292.57498) (xy 69.930259 -292.57498) (xy 69.929769 -292.599333)
			(xy 69.921874 -292.64791) (xy 69.90629 -292.694591) (xy 69.883419 -292.738168) (xy 69.853854 -292.777512)
			(xy 69.818361 -292.811604) (xy 69.777858 -292.83956) (xy 69.733396 -292.860658) (xy 69.686125 -292.87435)
			(xy 69.63727 -292.880282) (xy 69.588095 -292.878301) (xy 69.539876 -292.868457) (xy 69.49386 -292.851005)
			(xy 69.451239 -292.826398) (xy 69.413118 -292.795273) (xy 69.380483 -292.758436) (xy 69.35418 -292.71684)
			(xy 69.334889 -292.671564) (xy 69.323112 -292.62378) (xy 69.319152 -292.574726) (xy 68.98005 -292.574726)
			(xy 68.979555 -292.599333) (xy 68.97166 -292.64791) (xy 68.956076 -292.694591) (xy 68.933205 -292.738168)
			(xy 68.90364 -292.777512) (xy 68.868147 -292.811604) (xy 68.827644 -292.83956) (xy 68.783182 -292.860658)
			(xy 68.735911 -292.87435) (xy 68.687056 -292.880282) (xy 68.637881 -292.878301) (xy 68.589662 -292.868457)
			(xy 68.543646 -292.851005) (xy 68.501025 -292.826398) (xy 68.462904 -292.795273) (xy 68.430269 -292.758436)
			(xy 68.403966 -292.71684) (xy 68.384675 -292.671564) (xy 68.372898 -292.62378) (xy 68.368938 -292.574726)
			(xy 68.03009 -292.574726) (xy 68.029595 -292.599333) (xy 68.0217 -292.64791) (xy 68.006116 -292.694591)
			(xy 67.983245 -292.738168) (xy 67.95368 -292.777512) (xy 67.918187 -292.811604) (xy 67.877684 -292.83956)
			(xy 67.833222 -292.860658) (xy 67.785951 -292.87435) (xy 67.737096 -292.880282) (xy 67.687921 -292.878301)
			(xy 67.639702 -292.868457) (xy 67.593686 -292.851005) (xy 67.551065 -292.826398) (xy 67.512944 -292.795273)
			(xy 67.480309 -292.758436) (xy 67.454006 -292.71684) (xy 67.434715 -292.671564) (xy 67.422938 -292.62378)
			(xy 67.418978 -292.574726) (xy 67.08013 -292.574726) (xy 67.079635 -292.599333) (xy 67.07174 -292.64791)
			(xy 67.056156 -292.694591) (xy 67.033285 -292.738168) (xy 67.00372 -292.777512) (xy 66.968227 -292.811604)
			(xy 66.927724 -292.83956) (xy 66.883262 -292.860658) (xy 66.835991 -292.87435) (xy 66.787136 -292.880282)
			(xy 66.737961 -292.878301) (xy 66.689742 -292.868457) (xy 66.643726 -292.851005) (xy 66.601105 -292.826398)
			(xy 66.562984 -292.795273) (xy 66.530349 -292.758436) (xy 66.504046 -292.71684) (xy 66.484755 -292.671564)
			(xy 66.472978 -292.62378) (xy 66.469018 -292.574726) (xy 66.13017 -292.574726) (xy 66.129675 -292.599333)
			(xy 66.12178 -292.64791) (xy 66.106196 -292.694591) (xy 66.083325 -292.738168) (xy 66.05376 -292.777512)
			(xy 66.018267 -292.811604) (xy 65.977764 -292.83956) (xy 65.933302 -292.860658) (xy 65.886031 -292.87435)
			(xy 65.837176 -292.880282) (xy 65.788001 -292.878301) (xy 65.739782 -292.868457) (xy 65.693766 -292.851005)
			(xy 65.651145 -292.826398) (xy 65.613024 -292.795273) (xy 65.580389 -292.758436) (xy 65.554086 -292.71684)
			(xy 65.534795 -292.671564) (xy 65.523018 -292.62378) (xy 65.519058 -292.574726) (xy 65.18021 -292.574726)
			(xy 65.179715 -292.599333) (xy 65.17182 -292.64791) (xy 65.156236 -292.694591) (xy 65.133365 -292.738168)
			(xy 65.1038 -292.777512) (xy 65.068307 -292.811604) (xy 65.027804 -292.83956) (xy 64.983342 -292.860658)
			(xy 64.936071 -292.87435) (xy 64.887216 -292.880282) (xy 64.838041 -292.878301) (xy 64.789822 -292.868457)
			(xy 64.743806 -292.851005) (xy 64.701185 -292.826398) (xy 64.663064 -292.795273) (xy 64.630429 -292.758436)
			(xy 64.604126 -292.71684) (xy 64.584835 -292.671564) (xy 64.573058 -292.62378) (xy 64.569098 -292.574726)
			(xy 64.23025 -292.574726) (xy 64.229755 -292.599333) (xy 64.22186 -292.64791) (xy 64.206276 -292.694591)
			(xy 64.183405 -292.738168) (xy 64.15384 -292.777512) (xy 64.118347 -292.811604) (xy 64.077844 -292.83956)
			(xy 64.033382 -292.860658) (xy 63.986111 -292.87435) (xy 63.937256 -292.880282) (xy 63.888081 -292.878301)
			(xy 63.839862 -292.868457) (xy 63.793846 -292.851005) (xy 63.751225 -292.826398) (xy 63.713104 -292.795273)
			(xy 63.680469 -292.758436) (xy 63.654166 -292.71684) (xy 63.634875 -292.671564) (xy 63.623098 -292.62378)
			(xy 63.619138 -292.574726) (xy 63.28029 -292.574726) (xy 63.279795 -292.599333) (xy 63.2719 -292.64791)
			(xy 63.256316 -292.694591) (xy 63.233445 -292.738168) (xy 63.20388 -292.777512) (xy 63.168387 -292.811604)
			(xy 63.127884 -292.83956) (xy 63.083422 -292.860658) (xy 63.036151 -292.87435) (xy 62.987296 -292.880282)
			(xy 62.938121 -292.878301) (xy 62.889902 -292.868457) (xy 62.843886 -292.851005) (xy 62.801265 -292.826398)
			(xy 62.763144 -292.795273) (xy 62.730509 -292.758436) (xy 62.704206 -292.71684) (xy 62.684915 -292.671564)
			(xy 62.673138 -292.62378) (xy 62.669178 -292.574726) (xy 62.330076 -292.574726) (xy 62.329581 -292.599333)
			(xy 62.321686 -292.64791) (xy 62.306102 -292.694591) (xy 62.283231 -292.738168) (xy 62.253666 -292.777512)
			(xy 62.218173 -292.811604) (xy 62.17767 -292.83956) (xy 62.133208 -292.860658) (xy 62.085937 -292.87435)
			(xy 62.037082 -292.880282) (xy 61.987907 -292.878301) (xy 61.939688 -292.868457) (xy 61.893672 -292.851005)
			(xy 61.851051 -292.826398) (xy 61.81293 -292.795273) (xy 61.780295 -292.758436) (xy 61.753992 -292.71684)
			(xy 61.734701 -292.671564) (xy 61.722924 -292.62378) (xy 61.718964 -292.574726) (xy 61.380116 -292.574726)
			(xy 61.379621 -292.599333) (xy 61.371726 -292.64791) (xy 61.356142 -292.694591) (xy 61.333271 -292.738168)
			(xy 61.303706 -292.777512) (xy 61.268213 -292.811604) (xy 61.22771 -292.83956) (xy 61.183248 -292.860658)
			(xy 61.135977 -292.87435) (xy 61.087122 -292.880282) (xy 61.037947 -292.878301) (xy 60.989728 -292.868457)
			(xy 60.943712 -292.851005) (xy 60.901091 -292.826398) (xy 60.86297 -292.795273) (xy 60.830335 -292.758436)
			(xy 60.804032 -292.71684) (xy 60.784741 -292.671564) (xy 60.772964 -292.62378) (xy 60.769004 -292.574726)
			(xy 60.430156 -292.574726) (xy 60.429661 -292.599333) (xy 60.421766 -292.64791) (xy 60.406182 -292.694591)
			(xy 60.383311 -292.738168) (xy 60.353746 -292.777512) (xy 60.318253 -292.811604) (xy 60.27775 -292.83956)
			(xy 60.233288 -292.860658) (xy 60.186017 -292.87435) (xy 60.137162 -292.880282) (xy 60.087987 -292.878301)
			(xy 60.039768 -292.868457) (xy 59.993752 -292.851005) (xy 59.951131 -292.826398) (xy 59.91301 -292.795273)
			(xy 59.880375 -292.758436) (xy 59.854072 -292.71684) (xy 59.834781 -292.671564) (xy 59.823004 -292.62378)
			(xy 59.819044 -292.574726) (xy 58.530231 -292.574726) (xy 58.530236 -292.57498) (xy 58.529741 -292.599587)
			(xy 58.521846 -292.648164) (xy 58.506262 -292.694845) (xy 58.483391 -292.738422) (xy 58.453826 -292.777766)
			(xy 58.418333 -292.811858) (xy 58.37783 -292.839814) (xy 58.333368 -292.860912) (xy 58.286097 -292.874604)
			(xy 58.237242 -292.880536) (xy 58.188067 -292.878555) (xy 58.139848 -292.868711) (xy 58.093832 -292.851259)
			(xy 58.051211 -292.826652) (xy 58.01309 -292.795527) (xy 57.980455 -292.75869) (xy 57.954152 -292.717094)
			(xy 57.934861 -292.671818) (xy 57.923084 -292.624034) (xy 57.919124 -292.57498) (xy 57.580276 -292.57498)
			(xy 57.579781 -292.599587) (xy 57.571886 -292.648164) (xy 57.556302 -292.694845) (xy 57.533431 -292.738422)
			(xy 57.503866 -292.777766) (xy 57.468373 -292.811858) (xy 57.42787 -292.839814) (xy 57.383408 -292.860912)
			(xy 57.336137 -292.874604) (xy 57.287282 -292.880536) (xy 57.238107 -292.878555) (xy 57.189888 -292.868711)
			(xy 57.143872 -292.851259) (xy 57.101251 -292.826652) (xy 57.06313 -292.795527) (xy 57.030495 -292.75869)
			(xy 57.004192 -292.717094) (xy 56.984901 -292.671818) (xy 56.973124 -292.624034) (xy 56.969164 -292.57498)
			(xy 56.630316 -292.57498) (xy 56.629821 -292.599587) (xy 56.621926 -292.648164) (xy 56.606342 -292.694845)
			(xy 56.583471 -292.738422) (xy 56.553906 -292.777766) (xy 56.518413 -292.811858) (xy 56.47791 -292.839814)
			(xy 56.433448 -292.860912) (xy 56.386177 -292.874604) (xy 56.337322 -292.880536) (xy 56.288147 -292.878555)
			(xy 56.239928 -292.868711) (xy 56.193912 -292.851259) (xy 56.151291 -292.826652) (xy 56.11317 -292.795527)
			(xy 56.080535 -292.75869) (xy 56.054232 -292.717094) (xy 56.034941 -292.671818) (xy 56.023164 -292.624034)
			(xy 56.019204 -292.57498) (xy 55.680102 -292.57498) (xy 55.679607 -292.599587) (xy 55.671712 -292.648164)
			(xy 55.656128 -292.694845) (xy 55.633257 -292.738422) (xy 55.603692 -292.777766) (xy 55.568199 -292.811858)
			(xy 55.527696 -292.839814) (xy 55.483234 -292.860912) (xy 55.435963 -292.874604) (xy 55.387108 -292.880536)
			(xy 55.337933 -292.878555) (xy 55.289714 -292.868711) (xy 55.243698 -292.851259) (xy 55.201077 -292.826652)
			(xy 55.162956 -292.795527) (xy 55.130321 -292.75869) (xy 55.104018 -292.717094) (xy 55.084727 -292.671818)
			(xy 55.07295 -292.624034) (xy 55.06899 -292.57498) (xy 54.730142 -292.57498) (xy 54.729647 -292.599587)
			(xy 54.721752 -292.648164) (xy 54.706168 -292.694845) (xy 54.683297 -292.738422) (xy 54.653732 -292.777766)
			(xy 54.618239 -292.811858) (xy 54.577736 -292.839814) (xy 54.533274 -292.860912) (xy 54.486003 -292.874604)
			(xy 54.437148 -292.880536) (xy 54.387973 -292.878555) (xy 54.339754 -292.868711) (xy 54.293738 -292.851259)
			(xy 54.251117 -292.826652) (xy 54.212996 -292.795527) (xy 54.180361 -292.75869) (xy 54.154058 -292.717094)
			(xy 54.134767 -292.671818) (xy 54.12299 -292.624034) (xy 54.11903 -292.57498) (xy 53.780182 -292.57498)
			(xy 53.779687 -292.599587) (xy 53.771792 -292.648164) (xy 53.756208 -292.694845) (xy 53.733337 -292.738422)
			(xy 53.703772 -292.777766) (xy 53.668279 -292.811858) (xy 53.627776 -292.839814) (xy 53.583314 -292.860912)
			(xy 53.536043 -292.874604) (xy 53.487188 -292.880536) (xy 53.438013 -292.878555) (xy 53.389794 -292.868711)
			(xy 53.343778 -292.851259) (xy 53.301157 -292.826652) (xy 53.263036 -292.795527) (xy 53.230401 -292.75869)
			(xy 53.204098 -292.717094) (xy 53.184807 -292.671818) (xy 53.17303 -292.624034) (xy 53.16907 -292.57498)
			(xy 52.830222 -292.57498) (xy 52.829727 -292.599587) (xy 52.821832 -292.648164) (xy 52.806248 -292.694845)
			(xy 52.783377 -292.738422) (xy 52.753812 -292.777766) (xy 52.718319 -292.811858) (xy 52.677816 -292.839814)
			(xy 52.633354 -292.860912) (xy 52.586083 -292.874604) (xy 52.537228 -292.880536) (xy 52.488053 -292.878555)
			(xy 52.439834 -292.868711) (xy 52.393818 -292.851259) (xy 52.351197 -292.826652) (xy 52.313076 -292.795527)
			(xy 52.280441 -292.75869) (xy 52.254138 -292.717094) (xy 52.234847 -292.671818) (xy 52.22307 -292.624034)
			(xy 52.21911 -292.57498) (xy 51.880262 -292.57498) (xy 51.879767 -292.599587) (xy 51.871872 -292.648164)
			(xy 51.856288 -292.694845) (xy 51.833417 -292.738422) (xy 51.803852 -292.777766) (xy 51.768359 -292.811858)
			(xy 51.727856 -292.839814) (xy 51.683394 -292.860912) (xy 51.636123 -292.874604) (xy 51.587268 -292.880536)
			(xy 51.538093 -292.878555) (xy 51.489874 -292.868711) (xy 51.443858 -292.851259) (xy 51.401237 -292.826652)
			(xy 51.363116 -292.795527) (xy 51.330481 -292.75869) (xy 51.304178 -292.717094) (xy 51.284887 -292.671818)
			(xy 51.27311 -292.624034) (xy 51.26915 -292.57498) (xy 50.930302 -292.57498) (xy 50.929807 -292.599587)
			(xy 50.921912 -292.648164) (xy 50.906328 -292.694845) (xy 50.883457 -292.738422) (xy 50.853892 -292.777766)
			(xy 50.818399 -292.811858) (xy 50.777896 -292.839814) (xy 50.733434 -292.860912) (xy 50.686163 -292.874604)
			(xy 50.637308 -292.880536) (xy 50.588133 -292.878555) (xy 50.539914 -292.868711) (xy 50.493898 -292.851259)
			(xy 50.451277 -292.826652) (xy 50.413156 -292.795527) (xy 50.380521 -292.75869) (xy 50.354218 -292.717094)
			(xy 50.334927 -292.671818) (xy 50.32315 -292.624034) (xy 50.31919 -292.57498) (xy 49.980083 -292.57498)
			(xy 49.979593 -292.599333) (xy 49.971698 -292.64791) (xy 49.956114 -292.694591) (xy 49.933243 -292.738168)
			(xy 49.903678 -292.777512) (xy 49.868185 -292.811604) (xy 49.827682 -292.83956) (xy 49.78322 -292.860658)
			(xy 49.735949 -292.87435) (xy 49.687094 -292.880282) (xy 49.637919 -292.878301) (xy 49.5897 -292.868457)
			(xy 49.543684 -292.851005) (xy 49.501063 -292.826398) (xy 49.462942 -292.795273) (xy 49.430307 -292.758436)
			(xy 49.404004 -292.71684) (xy 49.384713 -292.671564) (xy 49.372936 -292.62378) (xy 49.368976 -292.574726)
			(xy 48.080164 -292.574726) (xy 48.080168 -292.57498) (xy 48.07995 -292.591758) (xy 48.076259 -292.625109)
			(xy 48.072802 -292.641528) (xy 48.0695 -292.656514) (xy 48.080422 -292.684962) (xy 48.104552 -292.702234)
			(xy 48.112426 -292.707822) (xy 48.124618 -292.716204) (xy 48.125888 -292.71722) (xy 48.12792 -292.71849)
			(xy 48.133508 -292.722554) (xy 48.143668 -292.729666) (xy 48.149256 -292.733476) (xy 48.170592 -292.75024)
			(xy 48.17237 -292.752018) (xy 48.175164 -292.75405) (xy 48.179736 -292.758114) (xy 48.193452 -292.772084)
			(xy 48.194468 -292.773354) (xy 48.196246 -292.775132) (xy 48.209454 -292.789864) (xy 48.21936 -292.803326)
			(xy 48.232855 -292.822908) (xy 48.25427 -292.865369) (xy 48.268861 -292.91063) (xy 48.276278 -292.957603)
			(xy 48.276764 -292.98138) (xy 48.276764 -293.52494) (xy 48.419016 -293.52494) (xy 48.422976 -293.475886)
			(xy 48.434753 -293.428102) (xy 48.454044 -293.382826) (xy 48.480347 -293.34123) (xy 48.512982 -293.304393)
			(xy 48.551103 -293.273268) (xy 48.593724 -293.248661) (xy 48.63974 -293.231209) (xy 48.687959 -293.221365)
			(xy 48.737134 -293.219384) (xy 48.785989 -293.225316) (xy 48.83326 -293.239008) (xy 48.877722 -293.260106)
			(xy 48.918225 -293.288062) (xy 48.953718 -293.322154) (xy 48.983283 -293.361498) (xy 49.006154 -293.405075)
			(xy 49.021738 -293.451756) (xy 49.029633 -293.500333) (xy 49.030128 -293.52494) (xy 50.31919 -293.52494)
			(xy 50.32315 -293.475886) (xy 50.334927 -293.428102) (xy 50.354218 -293.382826) (xy 50.380521 -293.34123)
			(xy 50.413156 -293.304393) (xy 50.451277 -293.273268) (xy 50.493898 -293.248661) (xy 50.539914 -293.231209)
			(xy 50.588133 -293.221365) (xy 50.637308 -293.219384) (xy 50.686163 -293.225316) (xy 50.733434 -293.239008)
			(xy 50.777896 -293.260106) (xy 50.818399 -293.288062) (xy 50.853892 -293.322154) (xy 50.883457 -293.361498)
			(xy 50.906328 -293.405075) (xy 50.921912 -293.451756) (xy 50.929807 -293.500333) (xy 50.930302 -293.52494)
			(xy 52.21911 -293.52494) (xy 52.22307 -293.475886) (xy 52.234847 -293.428102) (xy 52.254138 -293.382826)
			(xy 52.280441 -293.34123) (xy 52.313076 -293.304393) (xy 52.351197 -293.273268) (xy 52.393818 -293.248661)
			(xy 52.439834 -293.231209) (xy 52.488053 -293.221365) (xy 52.537228 -293.219384) (xy 52.586083 -293.225316)
			(xy 52.633354 -293.239008) (xy 52.677816 -293.260106) (xy 52.718319 -293.288062) (xy 52.753812 -293.322154)
			(xy 52.783377 -293.361498) (xy 52.806248 -293.405075) (xy 52.821832 -293.451756) (xy 52.829727 -293.500333)
			(xy 52.830222 -293.52494) (xy 54.11903 -293.52494) (xy 54.12299 -293.475886) (xy 54.134767 -293.428102)
			(xy 54.154058 -293.382826) (xy 54.180361 -293.34123) (xy 54.212996 -293.304393) (xy 54.251117 -293.273268)
			(xy 54.293738 -293.248661) (xy 54.339754 -293.231209) (xy 54.387973 -293.221365) (xy 54.437148 -293.219384)
			(xy 54.486003 -293.225316) (xy 54.533274 -293.239008) (xy 54.577736 -293.260106) (xy 54.618239 -293.288062)
			(xy 54.653732 -293.322154) (xy 54.683297 -293.361498) (xy 54.706168 -293.405075) (xy 54.721752 -293.451756)
			(xy 54.729647 -293.500333) (xy 54.730142 -293.52494) (xy 56.01895 -293.52494) (xy 56.02291 -293.475886)
			(xy 56.034687 -293.428102) (xy 56.053978 -293.382826) (xy 56.080281 -293.34123) (xy 56.112916 -293.304393)
			(xy 56.151037 -293.273268) (xy 56.193658 -293.248661) (xy 56.239674 -293.231209) (xy 56.287893 -293.221365)
			(xy 56.337068 -293.219384) (xy 56.385923 -293.225316) (xy 56.433194 -293.239008) (xy 56.477656 -293.260106)
			(xy 56.518159 -293.288062) (xy 56.553652 -293.322154) (xy 56.583217 -293.361498) (xy 56.606088 -293.405075)
			(xy 56.621672 -293.451756) (xy 56.629567 -293.500333) (xy 56.630062 -293.52494) (xy 57.919124 -293.52494)
			(xy 57.923084 -293.475886) (xy 57.934861 -293.428102) (xy 57.954152 -293.382826) (xy 57.980455 -293.34123)
			(xy 58.01309 -293.304393) (xy 58.051211 -293.273268) (xy 58.093832 -293.248661) (xy 58.139848 -293.231209)
			(xy 58.188067 -293.221365) (xy 58.237242 -293.219384) (xy 58.286097 -293.225316) (xy 58.333368 -293.239008)
			(xy 58.37783 -293.260106) (xy 58.418333 -293.288062) (xy 58.453826 -293.322154) (xy 58.483391 -293.361498)
			(xy 58.506262 -293.405075) (xy 58.521846 -293.451756) (xy 58.529741 -293.500333) (xy 58.530236 -293.52494)
			(xy 60.769004 -293.52494) (xy 60.772964 -293.475886) (xy 60.784741 -293.428102) (xy 60.804032 -293.382826)
			(xy 60.830335 -293.34123) (xy 60.86297 -293.304393) (xy 60.901091 -293.273268) (xy 60.943712 -293.248661)
			(xy 60.989728 -293.231209) (xy 61.037947 -293.221365) (xy 61.087122 -293.219384) (xy 61.135977 -293.225316)
			(xy 61.183248 -293.239008) (xy 61.22771 -293.260106) (xy 61.268213 -293.288062) (xy 61.303706 -293.322154)
			(xy 61.333271 -293.361498) (xy 61.356142 -293.405075) (xy 61.371726 -293.451756) (xy 61.379621 -293.500333)
			(xy 61.380116 -293.52494) (xy 62.669178 -293.52494) (xy 62.673138 -293.475886) (xy 62.684915 -293.428102)
			(xy 62.704206 -293.382826) (xy 62.730509 -293.34123) (xy 62.763144 -293.304393) (xy 62.801265 -293.273268)
			(xy 62.843886 -293.248661) (xy 62.889902 -293.231209) (xy 62.938121 -293.221365) (xy 62.987296 -293.219384)
			(xy 63.036151 -293.225316) (xy 63.083422 -293.239008) (xy 63.127884 -293.260106) (xy 63.168387 -293.288062)
			(xy 63.20388 -293.322154) (xy 63.233445 -293.361498) (xy 63.256316 -293.405075) (xy 63.2719 -293.451756)
			(xy 63.279795 -293.500333) (xy 63.28029 -293.52494) (xy 64.569098 -293.52494) (xy 64.573058 -293.475886)
			(xy 64.584835 -293.428102) (xy 64.604126 -293.382826) (xy 64.630429 -293.34123) (xy 64.663064 -293.304393)
			(xy 64.701185 -293.273268) (xy 64.743806 -293.248661) (xy 64.789822 -293.231209) (xy 64.838041 -293.221365)
			(xy 64.887216 -293.219384) (xy 64.936071 -293.225316) (xy 64.983342 -293.239008) (xy 65.027804 -293.260106)
			(xy 65.068307 -293.288062) (xy 65.1038 -293.322154) (xy 65.133365 -293.361498) (xy 65.156236 -293.405075)
			(xy 65.17182 -293.451756) (xy 65.179715 -293.500333) (xy 65.18021 -293.52494) (xy 66.469018 -293.52494)
			(xy 66.472978 -293.475886) (xy 66.484755 -293.428102) (xy 66.504046 -293.382826) (xy 66.530349 -293.34123)
			(xy 66.562984 -293.304393) (xy 66.601105 -293.273268) (xy 66.643726 -293.248661) (xy 66.689742 -293.231209)
			(xy 66.737961 -293.221365) (xy 66.787136 -293.219384) (xy 66.835991 -293.225316) (xy 66.883262 -293.239008)
			(xy 66.927724 -293.260106) (xy 66.968227 -293.288062) (xy 67.00372 -293.322154) (xy 67.033285 -293.361498)
			(xy 67.056156 -293.405075) (xy 67.07174 -293.451756) (xy 67.079635 -293.500333) (xy 67.08013 -293.52494)
			(xy 68.368938 -293.52494) (xy 68.372898 -293.475886) (xy 68.384675 -293.428102) (xy 68.403966 -293.382826)
			(xy 68.430269 -293.34123) (xy 68.462904 -293.304393) (xy 68.501025 -293.273268) (xy 68.543646 -293.248661)
			(xy 68.589662 -293.231209) (xy 68.637881 -293.221365) (xy 68.687056 -293.219384) (xy 68.735911 -293.225316)
			(xy 68.783182 -293.239008) (xy 68.827644 -293.260106) (xy 68.868147 -293.288062) (xy 68.90364 -293.322154)
			(xy 68.933205 -293.361498) (xy 68.956076 -293.405075) (xy 68.97166 -293.451756) (xy 68.979555 -293.500333)
			(xy 68.98005 -293.52494) (xy 69.319152 -293.52494) (xy 69.323112 -293.475886) (xy 69.334889 -293.428102)
			(xy 69.35418 -293.382826) (xy 69.380483 -293.34123) (xy 69.413118 -293.304393) (xy 69.451239 -293.273268)
			(xy 69.49386 -293.248661) (xy 69.539876 -293.231209) (xy 69.588095 -293.221365) (xy 69.63727 -293.219384)
			(xy 69.686125 -293.225316) (xy 69.733396 -293.239008) (xy 69.777858 -293.260106) (xy 69.818361 -293.288062)
			(xy 69.853854 -293.322154) (xy 69.883419 -293.361498) (xy 69.90629 -293.405075) (xy 69.921874 -293.451756)
			(xy 69.929769 -293.500333) (xy 69.930264 -293.52494) (xy 70.269112 -293.52494) (xy 70.273072 -293.475886)
			(xy 70.284849 -293.428102) (xy 70.30414 -293.382826) (xy 70.330443 -293.34123) (xy 70.363078 -293.304393)
			(xy 70.401199 -293.273268) (xy 70.44382 -293.248661) (xy 70.489836 -293.231209) (xy 70.538055 -293.221365)
			(xy 70.58723 -293.219384) (xy 70.636085 -293.225316) (xy 70.683356 -293.239008) (xy 70.727818 -293.260106)
			(xy 70.768321 -293.288062) (xy 70.803814 -293.322154) (xy 70.833379 -293.361498) (xy 70.85625 -293.405075)
			(xy 70.871834 -293.451756) (xy 70.879729 -293.500333) (xy 70.880224 -293.52494) (xy 71.219072 -293.52494)
			(xy 71.223032 -293.475886) (xy 71.234809 -293.428102) (xy 71.2541 -293.382826) (xy 71.280403 -293.34123)
			(xy 71.313038 -293.304393) (xy 71.351159 -293.273268) (xy 71.39378 -293.248661) (xy 71.439796 -293.231209)
			(xy 71.488015 -293.221365) (xy 71.53719 -293.219384) (xy 71.586045 -293.225316) (xy 71.633316 -293.239008)
			(xy 71.677778 -293.260106) (xy 71.718281 -293.288062) (xy 71.753774 -293.322154) (xy 71.783339 -293.361498)
			(xy 71.80621 -293.405075) (xy 71.821794 -293.451756) (xy 71.829689 -293.500333) (xy 71.830184 -293.52494)
			(xy 72.169032 -293.52494) (xy 72.172992 -293.475886) (xy 72.184769 -293.428102) (xy 72.20406 -293.382826)
			(xy 72.230363 -293.34123) (xy 72.262998 -293.304393) (xy 72.301119 -293.273268) (xy 72.34374 -293.248661)
			(xy 72.389756 -293.231209) (xy 72.437975 -293.221365) (xy 72.48715 -293.219384) (xy 72.536005 -293.225316)
			(xy 72.583276 -293.239008) (xy 72.627738 -293.260106) (xy 72.668241 -293.288062) (xy 72.703734 -293.322154)
			(xy 72.733299 -293.361498) (xy 72.75617 -293.405075) (xy 72.771754 -293.451756) (xy 72.779649 -293.500333)
			(xy 72.780144 -293.52494) (xy 73.118992 -293.52494) (xy 73.122952 -293.475886) (xy 73.134729 -293.428102)
			(xy 73.15402 -293.382826) (xy 73.180323 -293.34123) (xy 73.212958 -293.304393) (xy 73.251079 -293.273268)
			(xy 73.2937 -293.248661) (xy 73.339716 -293.231209) (xy 73.387935 -293.221365) (xy 73.43711 -293.219384)
			(xy 73.485965 -293.225316) (xy 73.533236 -293.239008) (xy 73.577698 -293.260106) (xy 73.618201 -293.288062)
			(xy 73.653694 -293.322154) (xy 73.683259 -293.361498) (xy 73.70613 -293.405075) (xy 73.721714 -293.451756)
			(xy 73.729609 -293.500333) (xy 73.730104 -293.52494) (xy 74.069206 -293.52494) (xy 74.073166 -293.475886)
			(xy 74.084943 -293.428102) (xy 74.104234 -293.382826) (xy 74.130537 -293.34123) (xy 74.163172 -293.304393)
			(xy 74.201293 -293.273268) (xy 74.243914 -293.248661) (xy 74.28993 -293.231209) (xy 74.338149 -293.221365)
			(xy 74.387324 -293.219384) (xy 74.436179 -293.225316) (xy 74.48345 -293.239008) (xy 74.527912 -293.260106)
			(xy 74.568415 -293.288062) (xy 74.603908 -293.322154) (xy 74.633473 -293.361498) (xy 74.656344 -293.405075)
			(xy 74.671928 -293.451756) (xy 74.679823 -293.500333) (xy 74.680318 -293.52494) (xy 75.019166 -293.52494)
			(xy 75.023126 -293.475886) (xy 75.034903 -293.428102) (xy 75.054194 -293.382826) (xy 75.080497 -293.34123)
			(xy 75.113132 -293.304393) (xy 75.151253 -293.273268) (xy 75.193874 -293.248661) (xy 75.23989 -293.231209)
			(xy 75.288109 -293.221365) (xy 75.337284 -293.219384) (xy 75.386139 -293.225316) (xy 75.43341 -293.239008)
			(xy 75.477872 -293.260106) (xy 75.518375 -293.288062) (xy 75.553868 -293.322154) (xy 75.583433 -293.361498)
			(xy 75.606304 -293.405075) (xy 75.621888 -293.451756) (xy 75.629783 -293.500333) (xy 75.630278 -293.52494)
			(xy 75.969126 -293.52494) (xy 75.973086 -293.475886) (xy 75.984863 -293.428102) (xy 76.004154 -293.382826)
			(xy 76.030457 -293.34123) (xy 76.063092 -293.304393) (xy 76.101213 -293.273268) (xy 76.143834 -293.248661)
			(xy 76.18985 -293.231209) (xy 76.238069 -293.221365) (xy 76.287244 -293.219384) (xy 76.336099 -293.225316)
			(xy 76.38337 -293.239008) (xy 76.427832 -293.260106) (xy 76.468335 -293.288062) (xy 76.503828 -293.322154)
			(xy 76.533393 -293.361498) (xy 76.556264 -293.405075) (xy 76.571848 -293.451756) (xy 76.579743 -293.500333)
			(xy 76.580238 -293.52494) (xy 76.919086 -293.52494) (xy 76.923046 -293.475886) (xy 76.934823 -293.428102)
			(xy 76.954114 -293.382826) (xy 76.980417 -293.34123) (xy 77.013052 -293.304393) (xy 77.051173 -293.273268)
			(xy 77.093794 -293.248661) (xy 77.13981 -293.231209) (xy 77.188029 -293.221365) (xy 77.237204 -293.219384)
			(xy 77.286059 -293.225316) (xy 77.33333 -293.239008) (xy 77.377792 -293.260106) (xy 77.418295 -293.288062)
			(xy 77.453788 -293.322154) (xy 77.483353 -293.361498) (xy 77.506224 -293.405075) (xy 77.521808 -293.451756)
			(xy 77.529703 -293.500333) (xy 77.530198 -293.52494) (xy 77.869046 -293.52494) (xy 77.873006 -293.475886)
			(xy 77.884783 -293.428102) (xy 77.904074 -293.382826) (xy 77.930377 -293.34123) (xy 77.963012 -293.304393)
			(xy 78.001133 -293.273268) (xy 78.043754 -293.248661) (xy 78.08977 -293.231209) (xy 78.137989 -293.221365)
			(xy 78.187164 -293.219384) (xy 78.236019 -293.225316) (xy 78.28329 -293.239008) (xy 78.327752 -293.260106)
			(xy 78.368255 -293.288062) (xy 78.403748 -293.322154) (xy 78.433313 -293.361498) (xy 78.456184 -293.405075)
			(xy 78.471768 -293.451756) (xy 78.479663 -293.500333) (xy 78.480158 -293.52494) (xy 78.819006 -293.52494)
			(xy 78.822966 -293.475886) (xy 78.834743 -293.428102) (xy 78.854034 -293.382826) (xy 78.880337 -293.34123)
			(xy 78.912972 -293.304393) (xy 78.951093 -293.273268) (xy 78.993714 -293.248661) (xy 79.03973 -293.231209)
			(xy 79.087949 -293.221365) (xy 79.137124 -293.219384) (xy 79.185979 -293.225316) (xy 79.23325 -293.239008)
			(xy 79.277712 -293.260106) (xy 79.318215 -293.288062) (xy 79.353708 -293.322154) (xy 79.383273 -293.361498)
			(xy 79.406144 -293.405075) (xy 79.421728 -293.451756) (xy 79.429623 -293.500333) (xy 79.430118 -293.52494)
			(xy 79.768966 -293.52494) (xy 79.772926 -293.475886) (xy 79.784703 -293.428102) (xy 79.803994 -293.382826)
			(xy 79.830297 -293.34123) (xy 79.862932 -293.304393) (xy 79.901053 -293.273268) (xy 79.943674 -293.248661)
			(xy 79.98969 -293.231209) (xy 80.037909 -293.221365) (xy 80.087084 -293.219384) (xy 80.135939 -293.225316)
			(xy 80.18321 -293.239008) (xy 80.227672 -293.260106) (xy 80.268175 -293.288062) (xy 80.303668 -293.322154)
			(xy 80.333233 -293.361498) (xy 80.356104 -293.405075) (xy 80.371688 -293.451756) (xy 80.379583 -293.500333)
			(xy 80.380078 -293.52494) (xy 80.71918 -293.52494) (xy 80.72314 -293.475886) (xy 80.734917 -293.428102)
			(xy 80.754208 -293.382826) (xy 80.780511 -293.34123) (xy 80.813146 -293.304393) (xy 80.851267 -293.273268)
			(xy 80.893888 -293.248661) (xy 80.939904 -293.231209) (xy 80.988123 -293.221365) (xy 81.037298 -293.219384)
			(xy 81.086153 -293.225316) (xy 81.133424 -293.239008) (xy 81.177886 -293.260106) (xy 81.218389 -293.288062)
			(xy 81.253882 -293.322154) (xy 81.283447 -293.361498) (xy 81.306318 -293.405075) (xy 81.321902 -293.451756)
			(xy 81.329797 -293.500333) (xy 81.330292 -293.52494) (xy 81.66914 -293.52494) (xy 81.6731 -293.475886)
			(xy 81.684877 -293.428102) (xy 81.704168 -293.382826) (xy 81.730471 -293.34123) (xy 81.763106 -293.304393)
			(xy 81.801227 -293.273268) (xy 81.843848 -293.248661) (xy 81.889864 -293.231209) (xy 81.938083 -293.221365)
			(xy 81.987258 -293.219384) (xy 82.036113 -293.225316) (xy 82.083384 -293.239008) (xy 82.127846 -293.260106)
			(xy 82.168349 -293.288062) (xy 82.203842 -293.322154) (xy 82.233407 -293.361498) (xy 82.256278 -293.405075)
			(xy 82.271862 -293.451756) (xy 82.279757 -293.500333) (xy 82.280252 -293.52494) (xy 82.6191 -293.52494)
			(xy 82.62306 -293.475886) (xy 82.634837 -293.428102) (xy 82.654128 -293.382826) (xy 82.680431 -293.34123)
			(xy 82.713066 -293.304393) (xy 82.751187 -293.273268) (xy 82.793808 -293.248661) (xy 82.839824 -293.231209)
			(xy 82.888043 -293.221365) (xy 82.937218 -293.219384) (xy 82.986073 -293.225316) (xy 83.033344 -293.239008)
			(xy 83.077806 -293.260106) (xy 83.118309 -293.288062) (xy 83.153802 -293.322154) (xy 83.183367 -293.361498)
			(xy 83.206238 -293.405075) (xy 83.221822 -293.451756) (xy 83.229717 -293.500333) (xy 83.230212 -293.52494)
			(xy 83.229717 -293.549547) (xy 83.221822 -293.598124) (xy 83.206238 -293.644805) (xy 83.183367 -293.688382)
			(xy 83.153802 -293.727726) (xy 83.118309 -293.761818) (xy 83.077806 -293.789774) (xy 83.033344 -293.810872)
			(xy 82.986073 -293.824564) (xy 82.937218 -293.830496) (xy 82.888043 -293.828515) (xy 82.839824 -293.818671)
			(xy 82.793808 -293.801219) (xy 82.751187 -293.776612) (xy 82.713066 -293.745487) (xy 82.680431 -293.70865)
			(xy 82.654128 -293.667054) (xy 82.634837 -293.621778) (xy 82.62306 -293.573994) (xy 82.6191 -293.52494)
			(xy 82.280252 -293.52494) (xy 82.279757 -293.549547) (xy 82.271862 -293.598124) (xy 82.256278 -293.644805)
			(xy 82.233407 -293.688382) (xy 82.203842 -293.727726) (xy 82.168349 -293.761818) (xy 82.127846 -293.789774)
			(xy 82.083384 -293.810872) (xy 82.036113 -293.824564) (xy 81.987258 -293.830496) (xy 81.938083 -293.828515)
			(xy 81.889864 -293.818671) (xy 81.843848 -293.801219) (xy 81.801227 -293.776612) (xy 81.763106 -293.745487)
			(xy 81.730471 -293.70865) (xy 81.704168 -293.667054) (xy 81.684877 -293.621778) (xy 81.6731 -293.573994)
			(xy 81.66914 -293.52494) (xy 81.330292 -293.52494) (xy 81.329797 -293.549547) (xy 81.321902 -293.598124)
			(xy 81.306318 -293.644805) (xy 81.283447 -293.688382) (xy 81.253882 -293.727726) (xy 81.218389 -293.761818)
			(xy 81.177886 -293.789774) (xy 81.133424 -293.810872) (xy 81.086153 -293.824564) (xy 81.037298 -293.830496)
			(xy 80.988123 -293.828515) (xy 80.939904 -293.818671) (xy 80.893888 -293.801219) (xy 80.851267 -293.776612)
			(xy 80.813146 -293.745487) (xy 80.780511 -293.70865) (xy 80.754208 -293.667054) (xy 80.734917 -293.621778)
			(xy 80.72314 -293.573994) (xy 80.71918 -293.52494) (xy 80.380078 -293.52494) (xy 80.379583 -293.549547)
			(xy 80.371688 -293.598124) (xy 80.356104 -293.644805) (xy 80.333233 -293.688382) (xy 80.303668 -293.727726)
			(xy 80.268175 -293.761818) (xy 80.227672 -293.789774) (xy 80.18321 -293.810872) (xy 80.135939 -293.824564)
			(xy 80.087084 -293.830496) (xy 80.037909 -293.828515) (xy 79.98969 -293.818671) (xy 79.943674 -293.801219)
			(xy 79.901053 -293.776612) (xy 79.862932 -293.745487) (xy 79.830297 -293.70865) (xy 79.803994 -293.667054)
			(xy 79.784703 -293.621778) (xy 79.772926 -293.573994) (xy 79.768966 -293.52494) (xy 79.430118 -293.52494)
			(xy 79.429623 -293.549547) (xy 79.421728 -293.598124) (xy 79.406144 -293.644805) (xy 79.383273 -293.688382)
			(xy 79.353708 -293.727726) (xy 79.318215 -293.761818) (xy 79.277712 -293.789774) (xy 79.23325 -293.810872)
			(xy 79.185979 -293.824564) (xy 79.137124 -293.830496) (xy 79.087949 -293.828515) (xy 79.03973 -293.818671)
			(xy 78.993714 -293.801219) (xy 78.951093 -293.776612) (xy 78.912972 -293.745487) (xy 78.880337 -293.70865)
			(xy 78.854034 -293.667054) (xy 78.834743 -293.621778) (xy 78.822966 -293.573994) (xy 78.819006 -293.52494)
			(xy 78.480158 -293.52494) (xy 78.479663 -293.549547) (xy 78.471768 -293.598124) (xy 78.456184 -293.644805)
			(xy 78.433313 -293.688382) (xy 78.403748 -293.727726) (xy 78.368255 -293.761818) (xy 78.327752 -293.789774)
			(xy 78.28329 -293.810872) (xy 78.236019 -293.824564) (xy 78.187164 -293.830496) (xy 78.137989 -293.828515)
			(xy 78.08977 -293.818671) (xy 78.043754 -293.801219) (xy 78.001133 -293.776612) (xy 77.963012 -293.745487)
			(xy 77.930377 -293.70865) (xy 77.904074 -293.667054) (xy 77.884783 -293.621778) (xy 77.873006 -293.573994)
			(xy 77.869046 -293.52494) (xy 77.530198 -293.52494) (xy 77.529703 -293.549547) (xy 77.521808 -293.598124)
			(xy 77.506224 -293.644805) (xy 77.483353 -293.688382) (xy 77.453788 -293.727726) (xy 77.418295 -293.761818)
			(xy 77.377792 -293.789774) (xy 77.33333 -293.810872) (xy 77.286059 -293.824564) (xy 77.237204 -293.830496)
			(xy 77.188029 -293.828515) (xy 77.13981 -293.818671) (xy 77.093794 -293.801219) (xy 77.051173 -293.776612)
			(xy 77.013052 -293.745487) (xy 76.980417 -293.70865) (xy 76.954114 -293.667054) (xy 76.934823 -293.621778)
			(xy 76.923046 -293.573994) (xy 76.919086 -293.52494) (xy 76.580238 -293.52494) (xy 76.579743 -293.549547)
			(xy 76.571848 -293.598124) (xy 76.556264 -293.644805) (xy 76.533393 -293.688382) (xy 76.503828 -293.727726)
			(xy 76.468335 -293.761818) (xy 76.427832 -293.789774) (xy 76.38337 -293.810872) (xy 76.336099 -293.824564)
			(xy 76.287244 -293.830496) (xy 76.238069 -293.828515) (xy 76.18985 -293.818671) (xy 76.143834 -293.801219)
			(xy 76.101213 -293.776612) (xy 76.063092 -293.745487) (xy 76.030457 -293.70865) (xy 76.004154 -293.667054)
			(xy 75.984863 -293.621778) (xy 75.973086 -293.573994) (xy 75.969126 -293.52494) (xy 75.630278 -293.52494)
			(xy 75.629783 -293.549547) (xy 75.621888 -293.598124) (xy 75.606304 -293.644805) (xy 75.583433 -293.688382)
			(xy 75.553868 -293.727726) (xy 75.518375 -293.761818) (xy 75.477872 -293.789774) (xy 75.43341 -293.810872)
			(xy 75.386139 -293.824564) (xy 75.337284 -293.830496) (xy 75.288109 -293.828515) (xy 75.23989 -293.818671)
			(xy 75.193874 -293.801219) (xy 75.151253 -293.776612) (xy 75.113132 -293.745487) (xy 75.080497 -293.70865)
			(xy 75.054194 -293.667054) (xy 75.034903 -293.621778) (xy 75.023126 -293.573994) (xy 75.019166 -293.52494)
			(xy 74.680318 -293.52494) (xy 74.679823 -293.549547) (xy 74.671928 -293.598124) (xy 74.656344 -293.644805)
			(xy 74.633473 -293.688382) (xy 74.603908 -293.727726) (xy 74.568415 -293.761818) (xy 74.527912 -293.789774)
			(xy 74.48345 -293.810872) (xy 74.436179 -293.824564) (xy 74.387324 -293.830496) (xy 74.338149 -293.828515)
			(xy 74.28993 -293.818671) (xy 74.243914 -293.801219) (xy 74.201293 -293.776612) (xy 74.163172 -293.745487)
			(xy 74.130537 -293.70865) (xy 74.104234 -293.667054) (xy 74.084943 -293.621778) (xy 74.073166 -293.573994)
			(xy 74.069206 -293.52494) (xy 73.730104 -293.52494) (xy 73.729609 -293.549547) (xy 73.721714 -293.598124)
			(xy 73.70613 -293.644805) (xy 73.683259 -293.688382) (xy 73.653694 -293.727726) (xy 73.618201 -293.761818)
			(xy 73.577698 -293.789774) (xy 73.533236 -293.810872) (xy 73.485965 -293.824564) (xy 73.43711 -293.830496)
			(xy 73.387935 -293.828515) (xy 73.339716 -293.818671) (xy 73.2937 -293.801219) (xy 73.251079 -293.776612)
			(xy 73.212958 -293.745487) (xy 73.180323 -293.70865) (xy 73.15402 -293.667054) (xy 73.134729 -293.621778)
			(xy 73.122952 -293.573994) (xy 73.118992 -293.52494) (xy 72.780144 -293.52494) (xy 72.779649 -293.549547)
			(xy 72.771754 -293.598124) (xy 72.75617 -293.644805) (xy 72.733299 -293.688382) (xy 72.703734 -293.727726)
			(xy 72.668241 -293.761818) (xy 72.627738 -293.789774) (xy 72.583276 -293.810872) (xy 72.536005 -293.824564)
			(xy 72.48715 -293.830496) (xy 72.437975 -293.828515) (xy 72.389756 -293.818671) (xy 72.34374 -293.801219)
			(xy 72.301119 -293.776612) (xy 72.262998 -293.745487) (xy 72.230363 -293.70865) (xy 72.20406 -293.667054)
			(xy 72.184769 -293.621778) (xy 72.172992 -293.573994) (xy 72.169032 -293.52494) (xy 71.830184 -293.52494)
			(xy 71.829689 -293.549547) (xy 71.821794 -293.598124) (xy 71.80621 -293.644805) (xy 71.783339 -293.688382)
			(xy 71.753774 -293.727726) (xy 71.718281 -293.761818) (xy 71.677778 -293.789774) (xy 71.633316 -293.810872)
			(xy 71.586045 -293.824564) (xy 71.53719 -293.830496) (xy 71.488015 -293.828515) (xy 71.439796 -293.818671)
			(xy 71.39378 -293.801219) (xy 71.351159 -293.776612) (xy 71.313038 -293.745487) (xy 71.280403 -293.70865)
			(xy 71.2541 -293.667054) (xy 71.234809 -293.621778) (xy 71.223032 -293.573994) (xy 71.219072 -293.52494)
			(xy 70.880224 -293.52494) (xy 70.879729 -293.549547) (xy 70.871834 -293.598124) (xy 70.85625 -293.644805)
			(xy 70.833379 -293.688382) (xy 70.803814 -293.727726) (xy 70.768321 -293.761818) (xy 70.727818 -293.789774)
			(xy 70.683356 -293.810872) (xy 70.636085 -293.824564) (xy 70.58723 -293.830496) (xy 70.538055 -293.828515)
			(xy 70.489836 -293.818671) (xy 70.44382 -293.801219) (xy 70.401199 -293.776612) (xy 70.363078 -293.745487)
			(xy 70.330443 -293.70865) (xy 70.30414 -293.667054) (xy 70.284849 -293.621778) (xy 70.273072 -293.573994)
			(xy 70.269112 -293.52494) (xy 69.930264 -293.52494) (xy 69.929769 -293.549547) (xy 69.921874 -293.598124)
			(xy 69.90629 -293.644805) (xy 69.883419 -293.688382) (xy 69.853854 -293.727726) (xy 69.818361 -293.761818)
			(xy 69.777858 -293.789774) (xy 69.733396 -293.810872) (xy 69.686125 -293.824564) (xy 69.63727 -293.830496)
			(xy 69.588095 -293.828515) (xy 69.539876 -293.818671) (xy 69.49386 -293.801219) (xy 69.451239 -293.776612)
			(xy 69.413118 -293.745487) (xy 69.380483 -293.70865) (xy 69.35418 -293.667054) (xy 69.334889 -293.621778)
			(xy 69.323112 -293.573994) (xy 69.319152 -293.52494) (xy 68.98005 -293.52494) (xy 68.979555 -293.549547)
			(xy 68.97166 -293.598124) (xy 68.956076 -293.644805) (xy 68.933205 -293.688382) (xy 68.90364 -293.727726)
			(xy 68.868147 -293.761818) (xy 68.827644 -293.789774) (xy 68.783182 -293.810872) (xy 68.735911 -293.824564)
			(xy 68.687056 -293.830496) (xy 68.637881 -293.828515) (xy 68.589662 -293.818671) (xy 68.543646 -293.801219)
			(xy 68.501025 -293.776612) (xy 68.462904 -293.745487) (xy 68.430269 -293.70865) (xy 68.403966 -293.667054)
			(xy 68.384675 -293.621778) (xy 68.372898 -293.573994) (xy 68.368938 -293.52494) (xy 67.08013 -293.52494)
			(xy 67.079635 -293.549547) (xy 67.07174 -293.598124) (xy 67.056156 -293.644805) (xy 67.033285 -293.688382)
			(xy 67.00372 -293.727726) (xy 66.968227 -293.761818) (xy 66.927724 -293.789774) (xy 66.883262 -293.810872)
			(xy 66.835991 -293.824564) (xy 66.787136 -293.830496) (xy 66.737961 -293.828515) (xy 66.689742 -293.818671)
			(xy 66.643726 -293.801219) (xy 66.601105 -293.776612) (xy 66.562984 -293.745487) (xy 66.530349 -293.70865)
			(xy 66.504046 -293.667054) (xy 66.484755 -293.621778) (xy 66.472978 -293.573994) (xy 66.469018 -293.52494)
			(xy 65.18021 -293.52494) (xy 65.179715 -293.549547) (xy 65.17182 -293.598124) (xy 65.156236 -293.644805)
			(xy 65.133365 -293.688382) (xy 65.1038 -293.727726) (xy 65.068307 -293.761818) (xy 65.027804 -293.789774)
			(xy 64.983342 -293.810872) (xy 64.936071 -293.824564) (xy 64.887216 -293.830496) (xy 64.838041 -293.828515)
			(xy 64.789822 -293.818671) (xy 64.743806 -293.801219) (xy 64.701185 -293.776612) (xy 64.663064 -293.745487)
			(xy 64.630429 -293.70865) (xy 64.604126 -293.667054) (xy 64.584835 -293.621778) (xy 64.573058 -293.573994)
			(xy 64.569098 -293.52494) (xy 63.28029 -293.52494) (xy 63.279795 -293.549547) (xy 63.2719 -293.598124)
			(xy 63.256316 -293.644805) (xy 63.233445 -293.688382) (xy 63.20388 -293.727726) (xy 63.168387 -293.761818)
			(xy 63.127884 -293.789774) (xy 63.083422 -293.810872) (xy 63.036151 -293.824564) (xy 62.987296 -293.830496)
			(xy 62.938121 -293.828515) (xy 62.889902 -293.818671) (xy 62.843886 -293.801219) (xy 62.801265 -293.776612)
			(xy 62.763144 -293.745487) (xy 62.730509 -293.70865) (xy 62.704206 -293.667054) (xy 62.684915 -293.621778)
			(xy 62.673138 -293.573994) (xy 62.669178 -293.52494) (xy 61.380116 -293.52494) (xy 61.379621 -293.549547)
			(xy 61.371726 -293.598124) (xy 61.356142 -293.644805) (xy 61.333271 -293.688382) (xy 61.303706 -293.727726)
			(xy 61.268213 -293.761818) (xy 61.22771 -293.789774) (xy 61.183248 -293.810872) (xy 61.135977 -293.824564)
			(xy 61.087122 -293.830496) (xy 61.037947 -293.828515) (xy 60.989728 -293.818671) (xy 60.943712 -293.801219)
			(xy 60.901091 -293.776612) (xy 60.86297 -293.745487) (xy 60.830335 -293.70865) (xy 60.804032 -293.667054)
			(xy 60.784741 -293.621778) (xy 60.772964 -293.573994) (xy 60.769004 -293.52494) (xy 58.530236 -293.52494)
			(xy 58.529741 -293.549547) (xy 58.521846 -293.598124) (xy 58.506262 -293.644805) (xy 58.483391 -293.688382)
			(xy 58.453826 -293.727726) (xy 58.418333 -293.761818) (xy 58.37783 -293.789774) (xy 58.333368 -293.810872)
			(xy 58.286097 -293.824564) (xy 58.237242 -293.830496) (xy 58.188067 -293.828515) (xy 58.139848 -293.818671)
			(xy 58.093832 -293.801219) (xy 58.051211 -293.776612) (xy 58.01309 -293.745487) (xy 57.980455 -293.70865)
			(xy 57.954152 -293.667054) (xy 57.934861 -293.621778) (xy 57.923084 -293.573994) (xy 57.919124 -293.52494)
			(xy 56.630062 -293.52494) (xy 56.629567 -293.549547) (xy 56.621672 -293.598124) (xy 56.606088 -293.644805)
			(xy 56.583217 -293.688382) (xy 56.553652 -293.727726) (xy 56.518159 -293.761818) (xy 56.477656 -293.789774)
			(xy 56.433194 -293.810872) (xy 56.385923 -293.824564) (xy 56.337068 -293.830496) (xy 56.287893 -293.828515)
			(xy 56.239674 -293.818671) (xy 56.193658 -293.801219) (xy 56.151037 -293.776612) (xy 56.112916 -293.745487)
			(xy 56.080281 -293.70865) (xy 56.053978 -293.667054) (xy 56.034687 -293.621778) (xy 56.02291 -293.573994)
			(xy 56.01895 -293.52494) (xy 54.730142 -293.52494) (xy 54.729647 -293.549547) (xy 54.721752 -293.598124)
			(xy 54.706168 -293.644805) (xy 54.683297 -293.688382) (xy 54.653732 -293.727726) (xy 54.618239 -293.761818)
			(xy 54.577736 -293.789774) (xy 54.533274 -293.810872) (xy 54.486003 -293.824564) (xy 54.437148 -293.830496)
			(xy 54.387973 -293.828515) (xy 54.339754 -293.818671) (xy 54.293738 -293.801219) (xy 54.251117 -293.776612)
			(xy 54.212996 -293.745487) (xy 54.180361 -293.70865) (xy 54.154058 -293.667054) (xy 54.134767 -293.621778)
			(xy 54.12299 -293.573994) (xy 54.11903 -293.52494) (xy 52.830222 -293.52494) (xy 52.829727 -293.549547)
			(xy 52.821832 -293.598124) (xy 52.806248 -293.644805) (xy 52.783377 -293.688382) (xy 52.753812 -293.727726)
			(xy 52.718319 -293.761818) (xy 52.677816 -293.789774) (xy 52.633354 -293.810872) (xy 52.586083 -293.824564)
			(xy 52.537228 -293.830496) (xy 52.488053 -293.828515) (xy 52.439834 -293.818671) (xy 52.393818 -293.801219)
			(xy 52.351197 -293.776612) (xy 52.313076 -293.745487) (xy 52.280441 -293.70865) (xy 52.254138 -293.667054)
			(xy 52.234847 -293.621778) (xy 52.22307 -293.573994) (xy 52.21911 -293.52494) (xy 50.930302 -293.52494)
			(xy 50.929807 -293.549547) (xy 50.921912 -293.598124) (xy 50.906328 -293.644805) (xy 50.883457 -293.688382)
			(xy 50.853892 -293.727726) (xy 50.818399 -293.761818) (xy 50.777896 -293.789774) (xy 50.733434 -293.810872)
			(xy 50.686163 -293.824564) (xy 50.637308 -293.830496) (xy 50.588133 -293.828515) (xy 50.539914 -293.818671)
			(xy 50.493898 -293.801219) (xy 50.451277 -293.776612) (xy 50.413156 -293.745487) (xy 50.380521 -293.70865)
			(xy 50.354218 -293.667054) (xy 50.334927 -293.621778) (xy 50.32315 -293.573994) (xy 50.31919 -293.52494)
			(xy 49.030128 -293.52494) (xy 49.029633 -293.549547) (xy 49.021738 -293.598124) (xy 49.006154 -293.644805)
			(xy 48.983283 -293.688382) (xy 48.953718 -293.727726) (xy 48.918225 -293.761818) (xy 48.877722 -293.789774)
			(xy 48.83326 -293.810872) (xy 48.785989 -293.824564) (xy 48.737134 -293.830496) (xy 48.687959 -293.828515)
			(xy 48.63974 -293.818671) (xy 48.593724 -293.801219) (xy 48.551103 -293.776612) (xy 48.512982 -293.745487)
			(xy 48.480347 -293.70865) (xy 48.454044 -293.667054) (xy 48.434753 -293.621778) (xy 48.422976 -293.573994)
			(xy 48.419016 -293.52494) (xy 48.276764 -293.52494) (xy 48.276764 -293.652956) (xy 48.277032 -293.659842)
			(xy 48.28077 -293.673101) (xy 48.28413 -293.679118) (xy 48.298608 -293.703502) (xy 48.303891 -293.713508)
			(xy 48.306103 -293.736) (xy 48.298525 -293.757291) (xy 48.290988 -293.765732) (xy 48.081438 -293.975028)
			(xy 48.076335 -293.981064) (xy 48.069739 -293.995418) (xy 48.068484 -294.003222) (xy 48.06823 -294.009318)
			(xy 48.06823 -294.38346) (xy 48.070008 -294.396668) (xy 48.07077 -294.399716) (xy 48.075171 -294.4182)
			(xy 48.079889 -294.455902) (xy 48.080168 -294.4749) (xy 49.368976 -294.4749) (xy 49.372936 -294.425846)
			(xy 49.384713 -294.378062) (xy 49.404004 -294.332786) (xy 49.430307 -294.29119) (xy 49.462942 -294.254353)
			(xy 49.501063 -294.223228) (xy 49.543684 -294.198621) (xy 49.5897 -294.181169) (xy 49.637919 -294.171325)
			(xy 49.687094 -294.169344) (xy 49.735949 -294.175276) (xy 49.78322 -294.188968) (xy 49.827682 -294.210066)
			(xy 49.868185 -294.238022) (xy 49.903678 -294.272114) (xy 49.933243 -294.311458) (xy 49.956114 -294.355035)
			(xy 49.971698 -294.401716) (xy 49.979593 -294.450293) (xy 49.980088 -294.4749) (xy 51.26915 -294.4749)
			(xy 51.27311 -294.425846) (xy 51.284887 -294.378062) (xy 51.304178 -294.332786) (xy 51.330481 -294.29119)
			(xy 51.363116 -294.254353) (xy 51.401237 -294.223228) (xy 51.443858 -294.198621) (xy 51.489874 -294.181169)
			(xy 51.538093 -294.171325) (xy 51.587268 -294.169344) (xy 51.636123 -294.175276) (xy 51.683394 -294.188968)
			(xy 51.727856 -294.210066) (xy 51.768359 -294.238022) (xy 51.803852 -294.272114) (xy 51.833417 -294.311458)
			(xy 51.856288 -294.355035) (xy 51.871872 -294.401716) (xy 51.879767 -294.450293) (xy 51.880262 -294.4749)
			(xy 53.16907 -294.4749) (xy 53.17303 -294.425846) (xy 53.184807 -294.378062) (xy 53.204098 -294.332786)
			(xy 53.230401 -294.29119) (xy 53.263036 -294.254353) (xy 53.301157 -294.223228) (xy 53.343778 -294.198621)
			(xy 53.389794 -294.181169) (xy 53.438013 -294.171325) (xy 53.487188 -294.169344) (xy 53.536043 -294.175276)
			(xy 53.583314 -294.188968) (xy 53.627776 -294.210066) (xy 53.668279 -294.238022) (xy 53.703772 -294.272114)
			(xy 53.733337 -294.311458) (xy 53.756208 -294.355035) (xy 53.771792 -294.401716) (xy 53.779687 -294.450293)
			(xy 53.780182 -294.4749) (xy 55.06899 -294.4749) (xy 55.07295 -294.425846) (xy 55.084727 -294.378062)
			(xy 55.104018 -294.332786) (xy 55.130321 -294.29119) (xy 55.162956 -294.254353) (xy 55.201077 -294.223228)
			(xy 55.243698 -294.198621) (xy 55.289714 -294.181169) (xy 55.337933 -294.171325) (xy 55.387108 -294.169344)
			(xy 55.435963 -294.175276) (xy 55.483234 -294.188968) (xy 55.527696 -294.210066) (xy 55.568199 -294.238022)
			(xy 55.603692 -294.272114) (xy 55.633257 -294.311458) (xy 55.656128 -294.355035) (xy 55.671712 -294.401716)
			(xy 55.679607 -294.450293) (xy 55.680102 -294.4749) (xy 56.969164 -294.4749) (xy 56.973124 -294.425846)
			(xy 56.984901 -294.378062) (xy 57.004192 -294.332786) (xy 57.030495 -294.29119) (xy 57.06313 -294.254353)
			(xy 57.101251 -294.223228) (xy 57.143872 -294.198621) (xy 57.189888 -294.181169) (xy 57.238107 -294.171325)
			(xy 57.287282 -294.169344) (xy 57.336137 -294.175276) (xy 57.383408 -294.188968) (xy 57.42787 -294.210066)
			(xy 57.468373 -294.238022) (xy 57.503866 -294.272114) (xy 57.533431 -294.311458) (xy 57.556302 -294.355035)
			(xy 57.571886 -294.401716) (xy 57.579781 -294.450293) (xy 57.580276 -294.4749) (xy 59.819044 -294.4749)
			(xy 59.823004 -294.425846) (xy 59.834781 -294.378062) (xy 59.854072 -294.332786) (xy 59.880375 -294.29119)
			(xy 59.91301 -294.254353) (xy 59.951131 -294.223228) (xy 59.993752 -294.198621) (xy 60.039768 -294.181169)
			(xy 60.087987 -294.171325) (xy 60.137162 -294.169344) (xy 60.186017 -294.175276) (xy 60.233288 -294.188968)
			(xy 60.27775 -294.210066) (xy 60.318253 -294.238022) (xy 60.353746 -294.272114) (xy 60.383311 -294.311458)
			(xy 60.406182 -294.355035) (xy 60.421766 -294.401716) (xy 60.429661 -294.450293) (xy 60.430156 -294.4749)
			(xy 61.718964 -294.4749) (xy 61.722924 -294.425846) (xy 61.734701 -294.378062) (xy 61.753992 -294.332786)
			(xy 61.780295 -294.29119) (xy 61.81293 -294.254353) (xy 61.851051 -294.223228) (xy 61.893672 -294.198621)
			(xy 61.939688 -294.181169) (xy 61.987907 -294.171325) (xy 62.037082 -294.169344) (xy 62.085937 -294.175276)
			(xy 62.133208 -294.188968) (xy 62.17767 -294.210066) (xy 62.218173 -294.238022) (xy 62.253666 -294.272114)
			(xy 62.283231 -294.311458) (xy 62.306102 -294.355035) (xy 62.321686 -294.401716) (xy 62.329581 -294.450293)
			(xy 62.330076 -294.4749) (xy 63.619138 -294.4749) (xy 63.623098 -294.425846) (xy 63.634875 -294.378062)
			(xy 63.654166 -294.332786) (xy 63.680469 -294.29119) (xy 63.713104 -294.254353) (xy 63.751225 -294.223228)
			(xy 63.793846 -294.198621) (xy 63.839862 -294.181169) (xy 63.888081 -294.171325) (xy 63.937256 -294.169344)
			(xy 63.986111 -294.175276) (xy 64.033382 -294.188968) (xy 64.077844 -294.210066) (xy 64.118347 -294.238022)
			(xy 64.15384 -294.272114) (xy 64.183405 -294.311458) (xy 64.206276 -294.355035) (xy 64.22186 -294.401716)
			(xy 64.229755 -294.450293) (xy 64.23025 -294.4749) (xy 65.519058 -294.4749) (xy 65.523018 -294.425846)
			(xy 65.534795 -294.378062) (xy 65.554086 -294.332786) (xy 65.580389 -294.29119) (xy 65.613024 -294.254353)
			(xy 65.651145 -294.223228) (xy 65.693766 -294.198621) (xy 65.739782 -294.181169) (xy 65.788001 -294.171325)
			(xy 65.837176 -294.169344) (xy 65.886031 -294.175276) (xy 65.933302 -294.188968) (xy 65.977764 -294.210066)
			(xy 66.018267 -294.238022) (xy 66.05376 -294.272114) (xy 66.083325 -294.311458) (xy 66.106196 -294.355035)
			(xy 66.12178 -294.401716) (xy 66.129675 -294.450293) (xy 66.13017 -294.4749) (xy 66.469018 -294.4749)
			(xy 66.472978 -294.425846) (xy 66.484755 -294.378062) (xy 66.504046 -294.332786) (xy 66.530349 -294.29119)
			(xy 66.562984 -294.254353) (xy 66.601105 -294.223228) (xy 66.643726 -294.198621) (xy 66.689742 -294.181169)
			(xy 66.737961 -294.171325) (xy 66.787136 -294.169344) (xy 66.835991 -294.175276) (xy 66.883262 -294.188968)
			(xy 66.927724 -294.210066) (xy 66.968227 -294.238022) (xy 67.00372 -294.272114) (xy 67.033285 -294.311458)
			(xy 67.056156 -294.355035) (xy 67.07174 -294.401716) (xy 67.079635 -294.450293) (xy 67.08013 -294.4749)
			(xy 67.418978 -294.4749) (xy 67.422938 -294.425846) (xy 67.434715 -294.378062) (xy 67.454006 -294.332786)
			(xy 67.480309 -294.29119) (xy 67.512944 -294.254353) (xy 67.551065 -294.223228) (xy 67.593686 -294.198621)
			(xy 67.639702 -294.181169) (xy 67.687921 -294.171325) (xy 67.737096 -294.169344) (xy 67.785951 -294.175276)
			(xy 67.833222 -294.188968) (xy 67.877684 -294.210066) (xy 67.918187 -294.238022) (xy 67.95368 -294.272114)
			(xy 67.983245 -294.311458) (xy 68.006116 -294.355035) (xy 68.0217 -294.401716) (xy 68.029595 -294.450293)
			(xy 68.03009 -294.4749) (xy 68.368938 -294.4749) (xy 68.372898 -294.425846) (xy 68.384675 -294.378062)
			(xy 68.403966 -294.332786) (xy 68.430269 -294.29119) (xy 68.462904 -294.254353) (xy 68.501025 -294.223228)
			(xy 68.543646 -294.198621) (xy 68.589662 -294.181169) (xy 68.637881 -294.171325) (xy 68.687056 -294.169344)
			(xy 68.735911 -294.175276) (xy 68.783182 -294.188968) (xy 68.827644 -294.210066) (xy 68.868147 -294.238022)
			(xy 68.90364 -294.272114) (xy 68.933205 -294.311458) (xy 68.956076 -294.355035) (xy 68.97166 -294.401716)
			(xy 68.979555 -294.450293) (xy 68.98005 -294.4749) (xy 69.319152 -294.4749) (xy 69.323112 -294.425846)
			(xy 69.334889 -294.378062) (xy 69.35418 -294.332786) (xy 69.380483 -294.29119) (xy 69.413118 -294.254353)
			(xy 69.451239 -294.223228) (xy 69.49386 -294.198621) (xy 69.539876 -294.181169) (xy 69.588095 -294.171325)
			(xy 69.63727 -294.169344) (xy 69.686125 -294.175276) (xy 69.733396 -294.188968) (xy 69.777858 -294.210066)
			(xy 69.818361 -294.238022) (xy 69.853854 -294.272114) (xy 69.883419 -294.311458) (xy 69.90629 -294.355035)
			(xy 69.921874 -294.401716) (xy 69.929769 -294.450293) (xy 69.930264 -294.4749) (xy 70.269112 -294.4749)
			(xy 70.273072 -294.425846) (xy 70.284849 -294.378062) (xy 70.30414 -294.332786) (xy 70.330443 -294.29119)
			(xy 70.363078 -294.254353) (xy 70.401199 -294.223228) (xy 70.44382 -294.198621) (xy 70.489836 -294.181169)
			(xy 70.538055 -294.171325) (xy 70.58723 -294.169344) (xy 70.636085 -294.175276) (xy 70.683356 -294.188968)
			(xy 70.727818 -294.210066) (xy 70.768321 -294.238022) (xy 70.803814 -294.272114) (xy 70.833379 -294.311458)
			(xy 70.85625 -294.355035) (xy 70.871834 -294.401716) (xy 70.879729 -294.450293) (xy 70.880224 -294.4749)
			(xy 71.219072 -294.4749) (xy 71.223032 -294.425846) (xy 71.234809 -294.378062) (xy 71.2541 -294.332786)
			(xy 71.280403 -294.29119) (xy 71.313038 -294.254353) (xy 71.351159 -294.223228) (xy 71.39378 -294.198621)
			(xy 71.439796 -294.181169) (xy 71.488015 -294.171325) (xy 71.53719 -294.169344) (xy 71.586045 -294.175276)
			(xy 71.633316 -294.188968) (xy 71.677778 -294.210066) (xy 71.718281 -294.238022) (xy 71.753774 -294.272114)
			(xy 71.783339 -294.311458) (xy 71.80621 -294.355035) (xy 71.821794 -294.401716) (xy 71.829689 -294.450293)
			(xy 71.830184 -294.4749) (xy 72.169032 -294.4749) (xy 72.172992 -294.425846) (xy 72.184769 -294.378062)
			(xy 72.20406 -294.332786) (xy 72.230363 -294.29119) (xy 72.262998 -294.254353) (xy 72.301119 -294.223228)
			(xy 72.34374 -294.198621) (xy 72.389756 -294.181169) (xy 72.437975 -294.171325) (xy 72.48715 -294.169344)
			(xy 72.536005 -294.175276) (xy 72.583276 -294.188968) (xy 72.627738 -294.210066) (xy 72.668241 -294.238022)
			(xy 72.703734 -294.272114) (xy 72.733299 -294.311458) (xy 72.75617 -294.355035) (xy 72.771754 -294.401716)
			(xy 72.779649 -294.450293) (xy 72.780144 -294.4749) (xy 73.118992 -294.4749) (xy 73.122952 -294.425846)
			(xy 73.134729 -294.378062) (xy 73.15402 -294.332786) (xy 73.180323 -294.29119) (xy 73.212958 -294.254353)
			(xy 73.251079 -294.223228) (xy 73.2937 -294.198621) (xy 73.339716 -294.181169) (xy 73.387935 -294.171325)
			(xy 73.43711 -294.169344) (xy 73.485965 -294.175276) (xy 73.533236 -294.188968) (xy 73.577698 -294.210066)
			(xy 73.618201 -294.238022) (xy 73.653694 -294.272114) (xy 73.683259 -294.311458) (xy 73.70613 -294.355035)
			(xy 73.721714 -294.401716) (xy 73.729609 -294.450293) (xy 73.730104 -294.4749) (xy 74.068952 -294.4749)
			(xy 74.072912 -294.425846) (xy 74.084689 -294.378062) (xy 74.10398 -294.332786) (xy 74.130283 -294.29119)
			(xy 74.162918 -294.254353) (xy 74.201039 -294.223228) (xy 74.24366 -294.198621) (xy 74.289676 -294.181169)
			(xy 74.337895 -294.171325) (xy 74.38707 -294.169344) (xy 74.435925 -294.175276) (xy 74.483196 -294.188968)
			(xy 74.527658 -294.210066) (xy 74.568161 -294.238022) (xy 74.603654 -294.272114) (xy 74.633219 -294.311458)
			(xy 74.65609 -294.355035) (xy 74.671674 -294.401716) (xy 74.679569 -294.450293) (xy 74.680064 -294.4749)
			(xy 75.019166 -294.4749) (xy 75.023126 -294.425846) (xy 75.034903 -294.378062) (xy 75.054194 -294.332786)
			(xy 75.080497 -294.29119) (xy 75.113132 -294.254353) (xy 75.151253 -294.223228) (xy 75.193874 -294.198621)
			(xy 75.23989 -294.181169) (xy 75.288109 -294.171325) (xy 75.337284 -294.169344) (xy 75.386139 -294.175276)
			(xy 75.43341 -294.188968) (xy 75.477872 -294.210066) (xy 75.518375 -294.238022) (xy 75.553868 -294.272114)
			(xy 75.583433 -294.311458) (xy 75.606304 -294.355035) (xy 75.621888 -294.401716) (xy 75.629783 -294.450293)
			(xy 75.630278 -294.4749) (xy 75.969126 -294.4749) (xy 75.973086 -294.425846) (xy 75.984863 -294.378062)
			(xy 76.004154 -294.332786) (xy 76.030457 -294.29119) (xy 76.063092 -294.254353) (xy 76.101213 -294.223228)
			(xy 76.143834 -294.198621) (xy 76.18985 -294.181169) (xy 76.238069 -294.171325) (xy 76.287244 -294.169344)
			(xy 76.336099 -294.175276) (xy 76.38337 -294.188968) (xy 76.427832 -294.210066) (xy 76.468335 -294.238022)
			(xy 76.503828 -294.272114) (xy 76.533393 -294.311458) (xy 76.556264 -294.355035) (xy 76.571848 -294.401716)
			(xy 76.579743 -294.450293) (xy 76.580238 -294.4749) (xy 76.919086 -294.4749) (xy 76.923046 -294.425846)
			(xy 76.934823 -294.378062) (xy 76.954114 -294.332786) (xy 76.980417 -294.29119) (xy 77.013052 -294.254353)
			(xy 77.051173 -294.223228) (xy 77.093794 -294.198621) (xy 77.13981 -294.181169) (xy 77.188029 -294.171325)
			(xy 77.237204 -294.169344) (xy 77.286059 -294.175276) (xy 77.33333 -294.188968) (xy 77.377792 -294.210066)
			(xy 77.418295 -294.238022) (xy 77.453788 -294.272114) (xy 77.483353 -294.311458) (xy 77.506224 -294.355035)
			(xy 77.521808 -294.401716) (xy 77.529703 -294.450293) (xy 77.530198 -294.4749) (xy 77.869046 -294.4749)
			(xy 77.873006 -294.425846) (xy 77.884783 -294.378062) (xy 77.904074 -294.332786) (xy 77.930377 -294.29119)
			(xy 77.963012 -294.254353) (xy 78.001133 -294.223228) (xy 78.043754 -294.198621) (xy 78.08977 -294.181169)
			(xy 78.137989 -294.171325) (xy 78.187164 -294.169344) (xy 78.236019 -294.175276) (xy 78.28329 -294.188968)
			(xy 78.327752 -294.210066) (xy 78.368255 -294.238022) (xy 78.403748 -294.272114) (xy 78.433313 -294.311458)
			(xy 78.456184 -294.355035) (xy 78.471768 -294.401716) (xy 78.479663 -294.450293) (xy 78.480158 -294.4749)
			(xy 78.819006 -294.4749) (xy 78.822966 -294.425846) (xy 78.834743 -294.378062) (xy 78.854034 -294.332786)
			(xy 78.880337 -294.29119) (xy 78.912972 -294.254353) (xy 78.951093 -294.223228) (xy 78.993714 -294.198621)
			(xy 79.03973 -294.181169) (xy 79.087949 -294.171325) (xy 79.137124 -294.169344) (xy 79.185979 -294.175276)
			(xy 79.23325 -294.188968) (xy 79.277712 -294.210066) (xy 79.318215 -294.238022) (xy 79.353708 -294.272114)
			(xy 79.383273 -294.311458) (xy 79.406144 -294.355035) (xy 79.421728 -294.401716) (xy 79.429623 -294.450293)
			(xy 79.430118 -294.4749) (xy 79.768966 -294.4749) (xy 79.772926 -294.425846) (xy 79.784703 -294.378062)
			(xy 79.803994 -294.332786) (xy 79.830297 -294.29119) (xy 79.862932 -294.254353) (xy 79.901053 -294.223228)
			(xy 79.943674 -294.198621) (xy 79.98969 -294.181169) (xy 80.037909 -294.171325) (xy 80.087084 -294.169344)
			(xy 80.135939 -294.175276) (xy 80.18321 -294.188968) (xy 80.227672 -294.210066) (xy 80.268175 -294.238022)
			(xy 80.303668 -294.272114) (xy 80.333233 -294.311458) (xy 80.356104 -294.355035) (xy 80.371688 -294.401716)
			(xy 80.379583 -294.450293) (xy 80.380078 -294.4749) (xy 80.71918 -294.4749) (xy 80.72314 -294.425846)
			(xy 80.734917 -294.378062) (xy 80.754208 -294.332786) (xy 80.780511 -294.29119) (xy 80.813146 -294.254353)
			(xy 80.851267 -294.223228) (xy 80.893888 -294.198621) (xy 80.939904 -294.181169) (xy 80.988123 -294.171325)
			(xy 81.037298 -294.169344) (xy 81.086153 -294.175276) (xy 81.133424 -294.188968) (xy 81.177886 -294.210066)
			(xy 81.218389 -294.238022) (xy 81.253882 -294.272114) (xy 81.283447 -294.311458) (xy 81.306318 -294.355035)
			(xy 81.321902 -294.401716) (xy 81.329797 -294.450293) (xy 81.330292 -294.4749) (xy 81.66914 -294.4749)
			(xy 81.6731 -294.425846) (xy 81.684877 -294.378062) (xy 81.704168 -294.332786) (xy 81.730471 -294.29119)
			(xy 81.763106 -294.254353) (xy 81.801227 -294.223228) (xy 81.843848 -294.198621) (xy 81.889864 -294.181169)
			(xy 81.938083 -294.171325) (xy 81.987258 -294.169344) (xy 82.036113 -294.175276) (xy 82.083384 -294.188968)
			(xy 82.127846 -294.210066) (xy 82.168349 -294.238022) (xy 82.203842 -294.272114) (xy 82.233407 -294.311458)
			(xy 82.256278 -294.355035) (xy 82.271862 -294.401716) (xy 82.279757 -294.450293) (xy 82.280252 -294.4749)
			(xy 82.6191 -294.4749) (xy 82.62306 -294.425846) (xy 82.634837 -294.378062) (xy 82.654128 -294.332786)
			(xy 82.680431 -294.29119) (xy 82.713066 -294.254353) (xy 82.751187 -294.223228) (xy 82.793808 -294.198621)
			(xy 82.839824 -294.181169) (xy 82.888043 -294.171325) (xy 82.937218 -294.169344) (xy 82.986073 -294.175276)
			(xy 83.033344 -294.188968) (xy 83.077806 -294.210066) (xy 83.118309 -294.238022) (xy 83.153802 -294.272114)
			(xy 83.183367 -294.311458) (xy 83.206238 -294.355035) (xy 83.221822 -294.401716) (xy 83.229717 -294.450293)
			(xy 83.230212 -294.4749) (xy 83.229717 -294.499507) (xy 83.221822 -294.548084) (xy 83.206238 -294.594765)
			(xy 83.183367 -294.638342) (xy 83.153802 -294.677686) (xy 83.120227 -294.709936) (xy 89.163026 -294.709936)
			(xy 89.163028 -294.655424) (xy 89.170789 -294.601467) (xy 89.186151 -294.549165) (xy 89.208799 -294.49958)
			(xy 89.238274 -294.453724) (xy 89.273975 -294.41253) (xy 89.315175 -294.376836) (xy 89.361037 -294.347368)
			(xy 89.410625 -294.324728) (xy 89.46293 -294.309376) (xy 89.516888 -294.301624) (xy 89.544144 -294.301164)
			(xy 89.569544 -294.301926) (xy 89.584276 -294.302414) (xy 89.613006 -294.295872) (xy 89.638673 -294.281399)
			(xy 89.65914 -294.260202) (xy 89.672703 -294.234044) (xy 89.678235 -294.205102) (xy 89.675274 -294.175786)
			(xy 89.670128 -294.161972) (xy 89.660964 -294.13877) (xy 89.648075 -294.090579) (xy 89.641576 -294.041119)
			(xy 89.641172 -294.016176) (xy 89.641704 -293.988927) (xy 89.649463 -293.934983) (xy 89.664821 -293.882693)
			(xy 89.687463 -293.83312) (xy 89.716931 -293.787275) (xy 89.752622 -293.746089) (xy 89.793812 -293.710403)
			(xy 89.839661 -293.680941) (xy 89.889236 -293.658304) (xy 89.941529 -293.642953) (xy 89.995473 -293.635201)
			(xy 90.049972 -293.635204) (xy 90.103916 -293.642963) (xy 90.156206 -293.65832) (xy 90.205779 -293.680963)
			(xy 90.251624 -293.71043) (xy 90.29281 -293.746121) (xy 90.328497 -293.787311) (xy 90.357958 -293.83316)
			(xy 90.380595 -293.882735) (xy 90.395946 -293.935027) (xy 90.402498 -293.980616) (xy 91.28074 -293.980616)
			(xy 91.284811 -293.924994) (xy 91.296937 -293.870557) (xy 91.31686 -293.818466) (xy 91.344156 -293.769831)
			(xy 91.378242 -293.725688) (xy 91.418391 -293.686979) (xy 91.463749 -293.654528) (xy 91.513349 -293.629027)
			(xy 91.566133 -293.61102) (xy 91.620976 -293.60089) (xy 91.67671 -293.598853) (xy 91.732147 -293.604953)
			(xy 91.786104 -293.619059) (xy 91.837433 -293.640871) (xy 91.885039 -293.669925) (xy 91.927907 -293.7056)
			(xy 91.965124 -293.747137) (xy 91.995897 -293.79365) (xy 92.019569 -293.844147) (xy 92.035637 -293.897554)
			(xy 92.043757 -293.95273) (xy 92.044266 -293.980616) (xy 92.043757 -294.008502) (xy 92.035637 -294.063678)
			(xy 92.019569 -294.117085) (xy 91.995897 -294.167582) (xy 91.965124 -294.214095) (xy 91.927907 -294.255632)
			(xy 91.885039 -294.291307) (xy 91.837433 -294.320361) (xy 91.786104 -294.342173) (xy 91.732147 -294.356279)
			(xy 91.67671 -294.362379) (xy 91.620976 -294.360342) (xy 91.566133 -294.350212) (xy 91.513349 -294.332205)
			(xy 91.463749 -294.306704) (xy 91.418391 -294.274253) (xy 91.378242 -294.235544) (xy 91.344156 -294.191401)
			(xy 91.31686 -294.142766) (xy 91.296937 -294.090675) (xy 91.284811 -294.036238) (xy 91.28074 -293.980616)
			(xy 90.402498 -293.980616) (xy 90.403699 -293.988972) (xy 90.403696 -294.043471) (xy 90.395937 -294.097414)
			(xy 90.38058 -294.149705) (xy 90.357938 -294.199278) (xy 90.328471 -294.245123) (xy 90.29278 -294.286309)
			(xy 90.25159 -294.321996) (xy 90.205741 -294.351458) (xy 90.156166 -294.374095) (xy 90.103874 -294.389446)
			(xy 90.049929 -294.397199) (xy 90.02268 -294.397684) (xy 89.99728 -294.396922) (xy 89.982549 -294.396526)
			(xy 89.953832 -294.403059) (xy 89.928174 -294.417517) (xy 89.907712 -294.438698) (xy 89.894147 -294.464839)
			(xy 89.888608 -294.493765) (xy 89.889394 -294.50157) (xy 90.53652 -294.50157) (xy 90.540591 -294.445948)
			(xy 90.552717 -294.391511) (xy 90.57264 -294.33942) (xy 90.599936 -294.290785) (xy 90.634022 -294.246642)
			(xy 90.674171 -294.207933) (xy 90.719529 -294.175482) (xy 90.769129 -294.149981) (xy 90.821913 -294.131974)
			(xy 90.876756 -294.121844) (xy 90.93249 -294.119807) (xy 90.987927 -294.125907) (xy 91.041884 -294.140013)
			(xy 91.093213 -294.161825) (xy 91.140819 -294.190879) (xy 91.183687 -294.226554) (xy 91.220904 -294.268091)
			(xy 91.251677 -294.314604) (xy 91.275349 -294.365101) (xy 91.291417 -294.418508) (xy 91.299537 -294.473684)
			(xy 91.300046 -294.50157) (xy 91.299537 -294.529456) (xy 91.291417 -294.584632) (xy 91.275349 -294.638039)
			(xy 91.251677 -294.688536) (xy 91.220904 -294.735049) (xy 91.183687 -294.776586) (xy 91.140819 -294.812261)
			(xy 91.093213 -294.841315) (xy 91.041884 -294.863127) (xy 90.987927 -294.877233) (xy 90.93249 -294.883333)
			(xy 90.876756 -294.881296) (xy 90.821913 -294.871166) (xy 90.769129 -294.853159) (xy 90.719529 -294.827658)
			(xy 90.674171 -294.795207) (xy 90.634022 -294.756498) (xy 90.599936 -294.712355) (xy 90.57264 -294.66372)
			(xy 90.552717 -294.611629) (xy 90.540591 -294.557192) (xy 90.53652 -294.50157) (xy 89.889394 -294.50157)
			(xy 89.891557 -294.523067) (xy 89.896696 -294.536876) (xy 89.905845 -294.560083) (xy 89.91874 -294.608272)
			(xy 89.925244 -294.65773) (xy 89.925652 -294.682672) (xy 89.925175 -294.709928) (xy 89.917421 -294.763886)
			(xy 89.902066 -294.81619) (xy 89.879424 -294.865778) (xy 89.849955 -294.911637) (xy 89.814259 -294.952836)
			(xy 89.773063 -294.988536) (xy 89.727206 -295.018009) (xy 89.67762 -295.040655) (xy 89.625317 -295.056014)
			(xy 89.57136 -295.063773) (xy 89.516848 -295.063773) (xy 89.462891 -295.056016) (xy 89.410587 -295.040658)
			(xy 89.361001 -295.018012) (xy 89.315143 -294.98854) (xy 89.273947 -294.952842) (xy 89.23825 -294.911644)
			(xy 89.20878 -294.865785) (xy 89.186137 -294.816198) (xy 89.170781 -294.763893) (xy 89.163026 -294.709936)
			(xy 83.120227 -294.709936) (xy 83.118309 -294.711778) (xy 83.077806 -294.739734) (xy 83.033344 -294.760832)
			(xy 82.986073 -294.774524) (xy 82.937218 -294.780456) (xy 82.888043 -294.778475) (xy 82.839824 -294.768631)
			(xy 82.793808 -294.751179) (xy 82.751187 -294.726572) (xy 82.713066 -294.695447) (xy 82.680431 -294.65861)
			(xy 82.654128 -294.617014) (xy 82.634837 -294.571738) (xy 82.62306 -294.523954) (xy 82.6191 -294.4749)
			(xy 82.280252 -294.4749) (xy 82.279757 -294.499507) (xy 82.271862 -294.548084) (xy 82.256278 -294.594765)
			(xy 82.233407 -294.638342) (xy 82.203842 -294.677686) (xy 82.168349 -294.711778) (xy 82.127846 -294.739734)
			(xy 82.083384 -294.760832) (xy 82.036113 -294.774524) (xy 81.987258 -294.780456) (xy 81.938083 -294.778475)
			(xy 81.889864 -294.768631) (xy 81.843848 -294.751179) (xy 81.801227 -294.726572) (xy 81.763106 -294.695447)
			(xy 81.730471 -294.65861) (xy 81.704168 -294.617014) (xy 81.684877 -294.571738) (xy 81.6731 -294.523954)
			(xy 81.66914 -294.4749) (xy 81.330292 -294.4749) (xy 81.329797 -294.499507) (xy 81.321902 -294.548084)
			(xy 81.306318 -294.594765) (xy 81.283447 -294.638342) (xy 81.253882 -294.677686) (xy 81.218389 -294.711778)
			(xy 81.177886 -294.739734) (xy 81.133424 -294.760832) (xy 81.086153 -294.774524) (xy 81.037298 -294.780456)
			(xy 80.988123 -294.778475) (xy 80.939904 -294.768631) (xy 80.893888 -294.751179) (xy 80.851267 -294.726572)
			(xy 80.813146 -294.695447) (xy 80.780511 -294.65861) (xy 80.754208 -294.617014) (xy 80.734917 -294.571738)
			(xy 80.72314 -294.523954) (xy 80.71918 -294.4749) (xy 80.380078 -294.4749) (xy 80.379583 -294.499507)
			(xy 80.371688 -294.548084) (xy 80.356104 -294.594765) (xy 80.333233 -294.638342) (xy 80.303668 -294.677686)
			(xy 80.268175 -294.711778) (xy 80.227672 -294.739734) (xy 80.18321 -294.760832) (xy 80.135939 -294.774524)
			(xy 80.087084 -294.780456) (xy 80.037909 -294.778475) (xy 79.98969 -294.768631) (xy 79.943674 -294.751179)
			(xy 79.901053 -294.726572) (xy 79.862932 -294.695447) (xy 79.830297 -294.65861) (xy 79.803994 -294.617014)
			(xy 79.784703 -294.571738) (xy 79.772926 -294.523954) (xy 79.768966 -294.4749) (xy 79.430118 -294.4749)
			(xy 79.429623 -294.499507) (xy 79.421728 -294.548084) (xy 79.406144 -294.594765) (xy 79.383273 -294.638342)
			(xy 79.353708 -294.677686) (xy 79.318215 -294.711778) (xy 79.277712 -294.739734) (xy 79.23325 -294.760832)
			(xy 79.185979 -294.774524) (xy 79.137124 -294.780456) (xy 79.087949 -294.778475) (xy 79.03973 -294.768631)
			(xy 78.993714 -294.751179) (xy 78.951093 -294.726572) (xy 78.912972 -294.695447) (xy 78.880337 -294.65861)
			(xy 78.854034 -294.617014) (xy 78.834743 -294.571738) (xy 78.822966 -294.523954) (xy 78.819006 -294.4749)
			(xy 78.480158 -294.4749) (xy 78.479663 -294.499507) (xy 78.471768 -294.548084) (xy 78.456184 -294.594765)
			(xy 78.433313 -294.638342) (xy 78.403748 -294.677686) (xy 78.368255 -294.711778) (xy 78.327752 -294.739734)
			(xy 78.28329 -294.760832) (xy 78.236019 -294.774524) (xy 78.187164 -294.780456) (xy 78.137989 -294.778475)
			(xy 78.08977 -294.768631) (xy 78.043754 -294.751179) (xy 78.001133 -294.726572) (xy 77.963012 -294.695447)
			(xy 77.930377 -294.65861) (xy 77.904074 -294.617014) (xy 77.884783 -294.571738) (xy 77.873006 -294.523954)
			(xy 77.869046 -294.4749) (xy 77.530198 -294.4749) (xy 77.529703 -294.499507) (xy 77.521808 -294.548084)
			(xy 77.506224 -294.594765) (xy 77.483353 -294.638342) (xy 77.453788 -294.677686) (xy 77.418295 -294.711778)
			(xy 77.377792 -294.739734) (xy 77.33333 -294.760832) (xy 77.286059 -294.774524) (xy 77.237204 -294.780456)
			(xy 77.188029 -294.778475) (xy 77.13981 -294.768631) (xy 77.093794 -294.751179) (xy 77.051173 -294.726572)
			(xy 77.013052 -294.695447) (xy 76.980417 -294.65861) (xy 76.954114 -294.617014) (xy 76.934823 -294.571738)
			(xy 76.923046 -294.523954) (xy 76.919086 -294.4749) (xy 76.580238 -294.4749) (xy 76.579743 -294.499507)
			(xy 76.571848 -294.548084) (xy 76.556264 -294.594765) (xy 76.533393 -294.638342) (xy 76.503828 -294.677686)
			(xy 76.468335 -294.711778) (xy 76.427832 -294.739734) (xy 76.38337 -294.760832) (xy 76.336099 -294.774524)
			(xy 76.287244 -294.780456) (xy 76.238069 -294.778475) (xy 76.18985 -294.768631) (xy 76.143834 -294.751179)
			(xy 76.101213 -294.726572) (xy 76.063092 -294.695447) (xy 76.030457 -294.65861) (xy 76.004154 -294.617014)
			(xy 75.984863 -294.571738) (xy 75.973086 -294.523954) (xy 75.969126 -294.4749) (xy 75.630278 -294.4749)
			(xy 75.629783 -294.499507) (xy 75.621888 -294.548084) (xy 75.606304 -294.594765) (xy 75.583433 -294.638342)
			(xy 75.553868 -294.677686) (xy 75.518375 -294.711778) (xy 75.477872 -294.739734) (xy 75.43341 -294.760832)
			(xy 75.386139 -294.774524) (xy 75.337284 -294.780456) (xy 75.288109 -294.778475) (xy 75.23989 -294.768631)
			(xy 75.193874 -294.751179) (xy 75.151253 -294.726572) (xy 75.113132 -294.695447) (xy 75.080497 -294.65861)
			(xy 75.054194 -294.617014) (xy 75.034903 -294.571738) (xy 75.023126 -294.523954) (xy 75.019166 -294.4749)
			(xy 74.680064 -294.4749) (xy 74.679569 -294.499507) (xy 74.671674 -294.548084) (xy 74.65609 -294.594765)
			(xy 74.633219 -294.638342) (xy 74.603654 -294.677686) (xy 74.568161 -294.711778) (xy 74.527658 -294.739734)
			(xy 74.483196 -294.760832) (xy 74.435925 -294.774524) (xy 74.38707 -294.780456) (xy 74.337895 -294.778475)
			(xy 74.289676 -294.768631) (xy 74.24366 -294.751179) (xy 74.201039 -294.726572) (xy 74.162918 -294.695447)
			(xy 74.130283 -294.65861) (xy 74.10398 -294.617014) (xy 74.084689 -294.571738) (xy 74.072912 -294.523954)
			(xy 74.068952 -294.4749) (xy 73.730104 -294.4749) (xy 73.729609 -294.499507) (xy 73.721714 -294.548084)
			(xy 73.70613 -294.594765) (xy 73.683259 -294.638342) (xy 73.653694 -294.677686) (xy 73.618201 -294.711778)
			(xy 73.577698 -294.739734) (xy 73.533236 -294.760832) (xy 73.485965 -294.774524) (xy 73.43711 -294.780456)
			(xy 73.387935 -294.778475) (xy 73.339716 -294.768631) (xy 73.2937 -294.751179) (xy 73.251079 -294.726572)
			(xy 73.212958 -294.695447) (xy 73.180323 -294.65861) (xy 73.15402 -294.617014) (xy 73.134729 -294.571738)
			(xy 73.122952 -294.523954) (xy 73.118992 -294.4749) (xy 72.780144 -294.4749) (xy 72.779649 -294.499507)
			(xy 72.771754 -294.548084) (xy 72.75617 -294.594765) (xy 72.733299 -294.638342) (xy 72.703734 -294.677686)
			(xy 72.668241 -294.711778) (xy 72.627738 -294.739734) (xy 72.583276 -294.760832) (xy 72.536005 -294.774524)
			(xy 72.48715 -294.780456) (xy 72.437975 -294.778475) (xy 72.389756 -294.768631) (xy 72.34374 -294.751179)
			(xy 72.301119 -294.726572) (xy 72.262998 -294.695447) (xy 72.230363 -294.65861) (xy 72.20406 -294.617014)
			(xy 72.184769 -294.571738) (xy 72.172992 -294.523954) (xy 72.169032 -294.4749) (xy 71.830184 -294.4749)
			(xy 71.829689 -294.499507) (xy 71.821794 -294.548084) (xy 71.80621 -294.594765) (xy 71.783339 -294.638342)
			(xy 71.753774 -294.677686) (xy 71.718281 -294.711778) (xy 71.677778 -294.739734) (xy 71.633316 -294.760832)
			(xy 71.586045 -294.774524) (xy 71.53719 -294.780456) (xy 71.488015 -294.778475) (xy 71.439796 -294.768631)
			(xy 71.39378 -294.751179) (xy 71.351159 -294.726572) (xy 71.313038 -294.695447) (xy 71.280403 -294.65861)
			(xy 71.2541 -294.617014) (xy 71.234809 -294.571738) (xy 71.223032 -294.523954) (xy 71.219072 -294.4749)
			(xy 70.880224 -294.4749) (xy 70.879729 -294.499507) (xy 70.871834 -294.548084) (xy 70.85625 -294.594765)
			(xy 70.833379 -294.638342) (xy 70.803814 -294.677686) (xy 70.768321 -294.711778) (xy 70.727818 -294.739734)
			(xy 70.683356 -294.760832) (xy 70.636085 -294.774524) (xy 70.58723 -294.780456) (xy 70.538055 -294.778475)
			(xy 70.489836 -294.768631) (xy 70.44382 -294.751179) (xy 70.401199 -294.726572) (xy 70.363078 -294.695447)
			(xy 70.330443 -294.65861) (xy 70.30414 -294.617014) (xy 70.284849 -294.571738) (xy 70.273072 -294.523954)
			(xy 70.269112 -294.4749) (xy 69.930264 -294.4749) (xy 69.929769 -294.499507) (xy 69.921874 -294.548084)
			(xy 69.90629 -294.594765) (xy 69.883419 -294.638342) (xy 69.853854 -294.677686) (xy 69.818361 -294.711778)
			(xy 69.777858 -294.739734) (xy 69.733396 -294.760832) (xy 69.686125 -294.774524) (xy 69.63727 -294.780456)
			(xy 69.588095 -294.778475) (xy 69.539876 -294.768631) (xy 69.49386 -294.751179) (xy 69.451239 -294.726572)
			(xy 69.413118 -294.695447) (xy 69.380483 -294.65861) (xy 69.35418 -294.617014) (xy 69.334889 -294.571738)
			(xy 69.323112 -294.523954) (xy 69.319152 -294.4749) (xy 68.98005 -294.4749) (xy 68.979555 -294.499507)
			(xy 68.97166 -294.548084) (xy 68.956076 -294.594765) (xy 68.933205 -294.638342) (xy 68.90364 -294.677686)
			(xy 68.868147 -294.711778) (xy 68.827644 -294.739734) (xy 68.783182 -294.760832) (xy 68.735911 -294.774524)
			(xy 68.687056 -294.780456) (xy 68.637881 -294.778475) (xy 68.589662 -294.768631) (xy 68.543646 -294.751179)
			(xy 68.501025 -294.726572) (xy 68.462904 -294.695447) (xy 68.430269 -294.65861) (xy 68.403966 -294.617014)
			(xy 68.384675 -294.571738) (xy 68.372898 -294.523954) (xy 68.368938 -294.4749) (xy 68.03009 -294.4749)
			(xy 68.029595 -294.499507) (xy 68.0217 -294.548084) (xy 68.006116 -294.594765) (xy 67.983245 -294.638342)
			(xy 67.95368 -294.677686) (xy 67.918187 -294.711778) (xy 67.877684 -294.739734) (xy 67.833222 -294.760832)
			(xy 67.785951 -294.774524) (xy 67.737096 -294.780456) (xy 67.687921 -294.778475) (xy 67.639702 -294.768631)
			(xy 67.593686 -294.751179) (xy 67.551065 -294.726572) (xy 67.512944 -294.695447) (xy 67.480309 -294.65861)
			(xy 67.454006 -294.617014) (xy 67.434715 -294.571738) (xy 67.422938 -294.523954) (xy 67.418978 -294.4749)
			(xy 67.08013 -294.4749) (xy 67.079635 -294.499507) (xy 67.07174 -294.548084) (xy 67.056156 -294.594765)
			(xy 67.033285 -294.638342) (xy 67.00372 -294.677686) (xy 66.968227 -294.711778) (xy 66.927724 -294.739734)
			(xy 66.883262 -294.760832) (xy 66.835991 -294.774524) (xy 66.787136 -294.780456) (xy 66.737961 -294.778475)
			(xy 66.689742 -294.768631) (xy 66.643726 -294.751179) (xy 66.601105 -294.726572) (xy 66.562984 -294.695447)
			(xy 66.530349 -294.65861) (xy 66.504046 -294.617014) (xy 66.484755 -294.571738) (xy 66.472978 -294.523954)
			(xy 66.469018 -294.4749) (xy 66.13017 -294.4749) (xy 66.129675 -294.499507) (xy 66.12178 -294.548084)
			(xy 66.106196 -294.594765) (xy 66.083325 -294.638342) (xy 66.05376 -294.677686) (xy 66.018267 -294.711778)
			(xy 65.977764 -294.739734) (xy 65.933302 -294.760832) (xy 65.886031 -294.774524) (xy 65.837176 -294.780456)
			(xy 65.788001 -294.778475) (xy 65.739782 -294.768631) (xy 65.693766 -294.751179) (xy 65.651145 -294.726572)
			(xy 65.613024 -294.695447) (xy 65.580389 -294.65861) (xy 65.554086 -294.617014) (xy 65.534795 -294.571738)
			(xy 65.523018 -294.523954) (xy 65.519058 -294.4749) (xy 64.23025 -294.4749) (xy 64.229755 -294.499507)
			(xy 64.22186 -294.548084) (xy 64.206276 -294.594765) (xy 64.183405 -294.638342) (xy 64.15384 -294.677686)
			(xy 64.118347 -294.711778) (xy 64.077844 -294.739734) (xy 64.033382 -294.760832) (xy 63.986111 -294.774524)
			(xy 63.937256 -294.780456) (xy 63.888081 -294.778475) (xy 63.839862 -294.768631) (xy 63.793846 -294.751179)
			(xy 63.751225 -294.726572) (xy 63.713104 -294.695447) (xy 63.680469 -294.65861) (xy 63.654166 -294.617014)
			(xy 63.634875 -294.571738) (xy 63.623098 -294.523954) (xy 63.619138 -294.4749) (xy 62.330076 -294.4749)
			(xy 62.329581 -294.499507) (xy 62.321686 -294.548084) (xy 62.306102 -294.594765) (xy 62.283231 -294.638342)
			(xy 62.253666 -294.677686) (xy 62.218173 -294.711778) (xy 62.17767 -294.739734) (xy 62.133208 -294.760832)
			(xy 62.085937 -294.774524) (xy 62.037082 -294.780456) (xy 61.987907 -294.778475) (xy 61.939688 -294.768631)
			(xy 61.893672 -294.751179) (xy 61.851051 -294.726572) (xy 61.81293 -294.695447) (xy 61.780295 -294.65861)
			(xy 61.753992 -294.617014) (xy 61.734701 -294.571738) (xy 61.722924 -294.523954) (xy 61.718964 -294.4749)
			(xy 60.430156 -294.4749) (xy 60.429661 -294.499507) (xy 60.421766 -294.548084) (xy 60.406182 -294.594765)
			(xy 60.383311 -294.638342) (xy 60.353746 -294.677686) (xy 60.318253 -294.711778) (xy 60.27775 -294.739734)
			(xy 60.233288 -294.760832) (xy 60.186017 -294.774524) (xy 60.137162 -294.780456) (xy 60.087987 -294.778475)
			(xy 60.039768 -294.768631) (xy 59.993752 -294.751179) (xy 59.951131 -294.726572) (xy 59.91301 -294.695447)
			(xy 59.880375 -294.65861) (xy 59.854072 -294.617014) (xy 59.834781 -294.571738) (xy 59.823004 -294.523954)
			(xy 59.819044 -294.4749) (xy 57.580276 -294.4749) (xy 57.579781 -294.499507) (xy 57.571886 -294.548084)
			(xy 57.556302 -294.594765) (xy 57.533431 -294.638342) (xy 57.503866 -294.677686) (xy 57.468373 -294.711778)
			(xy 57.42787 -294.739734) (xy 57.383408 -294.760832) (xy 57.336137 -294.774524) (xy 57.287282 -294.780456)
			(xy 57.238107 -294.778475) (xy 57.189888 -294.768631) (xy 57.143872 -294.751179) (xy 57.101251 -294.726572)
			(xy 57.06313 -294.695447) (xy 57.030495 -294.65861) (xy 57.004192 -294.617014) (xy 56.984901 -294.571738)
			(xy 56.973124 -294.523954) (xy 56.969164 -294.4749) (xy 55.680102 -294.4749) (xy 55.679607 -294.499507)
			(xy 55.671712 -294.548084) (xy 55.656128 -294.594765) (xy 55.633257 -294.638342) (xy 55.603692 -294.677686)
			(xy 55.568199 -294.711778) (xy 55.527696 -294.739734) (xy 55.483234 -294.760832) (xy 55.435963 -294.774524)
			(xy 55.387108 -294.780456) (xy 55.337933 -294.778475) (xy 55.289714 -294.768631) (xy 55.243698 -294.751179)
			(xy 55.201077 -294.726572) (xy 55.162956 -294.695447) (xy 55.130321 -294.65861) (xy 55.104018 -294.617014)
			(xy 55.084727 -294.571738) (xy 55.07295 -294.523954) (xy 55.06899 -294.4749) (xy 53.780182 -294.4749)
			(xy 53.779687 -294.499507) (xy 53.771792 -294.548084) (xy 53.756208 -294.594765) (xy 53.733337 -294.638342)
			(xy 53.703772 -294.677686) (xy 53.668279 -294.711778) (xy 53.627776 -294.739734) (xy 53.583314 -294.760832)
			(xy 53.536043 -294.774524) (xy 53.487188 -294.780456) (xy 53.438013 -294.778475) (xy 53.389794 -294.768631)
			(xy 53.343778 -294.751179) (xy 53.301157 -294.726572) (xy 53.263036 -294.695447) (xy 53.230401 -294.65861)
			(xy 53.204098 -294.617014) (xy 53.184807 -294.571738) (xy 53.17303 -294.523954) (xy 53.16907 -294.4749)
			(xy 51.880262 -294.4749) (xy 51.879767 -294.499507) (xy 51.871872 -294.548084) (xy 51.856288 -294.594765)
			(xy 51.833417 -294.638342) (xy 51.803852 -294.677686) (xy 51.768359 -294.711778) (xy 51.727856 -294.739734)
			(xy 51.683394 -294.760832) (xy 51.636123 -294.774524) (xy 51.587268 -294.780456) (xy 51.538093 -294.778475)
			(xy 51.489874 -294.768631) (xy 51.443858 -294.751179) (xy 51.401237 -294.726572) (xy 51.363116 -294.695447)
			(xy 51.330481 -294.65861) (xy 51.304178 -294.617014) (xy 51.284887 -294.571738) (xy 51.27311 -294.523954)
			(xy 51.26915 -294.4749) (xy 49.980088 -294.4749) (xy 49.979593 -294.499507) (xy 49.971698 -294.548084)
			(xy 49.956114 -294.594765) (xy 49.933243 -294.638342) (xy 49.903678 -294.677686) (xy 49.868185 -294.711778)
			(xy 49.827682 -294.739734) (xy 49.78322 -294.760832) (xy 49.735949 -294.774524) (xy 49.687094 -294.780456)
			(xy 49.637919 -294.778475) (xy 49.5897 -294.768631) (xy 49.543684 -294.751179) (xy 49.501063 -294.726572)
			(xy 49.462942 -294.695447) (xy 49.430307 -294.65861) (xy 49.404004 -294.617014) (xy 49.384713 -294.571738)
			(xy 49.372936 -294.523954) (xy 49.368976 -294.4749) (xy 48.080168 -294.4749) (xy 48.080168 -294.49522)
			(xy 48.080627 -294.505098) (xy 48.088068 -294.523399) (xy 48.094646 -294.53078) (xy 48.0949 -294.531034)
			(xy 48.158654 -294.594788) (xy 48.159924 -294.595804) (xy 48.163226 -294.599106) (xy 48.258984 -294.694864)
			(xy 48.265659 -294.70169) (xy 48.278242 -294.716051) (xy 48.28413 -294.723566) (xy 48.292725 -294.734988)
			(xy 48.30799 -294.759157) (xy 48.31461 -294.771826) (xy 48.325032 -294.793268) (xy 48.33982 -294.838589)
			(xy 48.347369 -294.885659) (xy 48.347884 -294.909494) (xy 48.347884 -295.355518) (xy 92.615764 -295.355518)
			(xy 92.619835 -295.299896) (xy 92.631961 -295.245459) (xy 92.651884 -295.193368) (xy 92.67918 -295.144733)
			(xy 92.713266 -295.10059) (xy 92.753415 -295.061881) (xy 92.798773 -295.02943) (xy 92.848373 -295.003929)
			(xy 92.901157 -294.985922) (xy 92.956 -294.975792) (xy 93.011734 -294.973755) (xy 93.067171 -294.979855)
			(xy 93.121128 -294.993961) (xy 93.172457 -295.015773) (xy 93.220063 -295.044827) (xy 93.262931 -295.080502)
			(xy 93.300148 -295.122039) (xy 93.330921 -295.168552) (xy 93.354593 -295.219049) (xy 93.370661 -295.272456)
			(xy 93.378781 -295.327632) (xy 93.37929 -295.355518) (xy 93.378781 -295.383404) (xy 93.370661 -295.43858)
			(xy 93.354593 -295.491987) (xy 93.330921 -295.542484) (xy 93.300148 -295.588997) (xy 93.262931 -295.630534)
			(xy 93.220063 -295.666209) (xy 93.172457 -295.695263) (xy 93.121128 -295.717075) (xy 93.067171 -295.731181)
			(xy 93.011734 -295.737281) (xy 92.956 -295.735244) (xy 92.901157 -295.725114) (xy 92.848373 -295.707107)
			(xy 92.798773 -295.681606) (xy 92.753415 -295.649155) (xy 92.713266 -295.610446) (xy 92.67918 -295.566303)
			(xy 92.651884 -295.517668) (xy 92.631961 -295.465577) (xy 92.619835 -295.41114) (xy 92.615764 -295.355518)
			(xy 48.347884 -295.355518) (xy 48.347884 -296.074846) (xy 48.347884 -296.075354) (xy 48.348688 -296.087999)
			(xy 48.360959 -296.110128) (xy 48.371252 -296.117518) (xy 48.378364 -296.121328) (xy 48.436022 -296.146728)
			(xy 48.43653 -296.146728) (xy 48.457866 -296.15638) (xy 48.467339 -296.160275) (xy 48.487792 -296.160943)
			(xy 48.49749 -296.15765) (xy 48.509682 -296.152824) (xy 48.513664 -296.151219) (xy 48.521073 -296.146883)
			(xy 48.524414 -296.144188) (xy 48.529494 -296.13987) (xy 48.537876 -296.133266) (xy 48.558068 -296.118305)
			(xy 48.60232 -296.094497) (xy 48.649872 -296.078252) (xy 48.699441 -296.070007) (xy 48.724566 -296.069512)
			(xy 48.732948 -296.069512) (xy 48.756536 -296.0706) (xy 48.802974 -296.079148) (xy 48.825404 -296.08653)
			(xy 48.84753 -296.094709) (xy 48.889152 -296.116904) (xy 48.926864 -296.145236) (xy 48.959771 -296.179033)
			(xy 48.987087 -296.217488) (xy 49.008163 -296.259687) (xy 49.022498 -296.304626) (xy 49.02975 -296.351235)
			(xy 49.030128 -296.37482) (xy 50.31919 -296.37482) (xy 50.32315 -296.325766) (xy 50.334927 -296.277982)
			(xy 50.354218 -296.232706) (xy 50.380521 -296.19111) (xy 50.413156 -296.154273) (xy 50.451277 -296.123148)
			(xy 50.493898 -296.098541) (xy 50.539914 -296.081089) (xy 50.588133 -296.071245) (xy 50.637308 -296.069264)
			(xy 50.686163 -296.075196) (xy 50.733434 -296.088888) (xy 50.777896 -296.109986) (xy 50.818399 -296.137942)
			(xy 50.853892 -296.172034) (xy 50.883457 -296.211378) (xy 50.906328 -296.254955) (xy 50.921912 -296.301636)
			(xy 50.929807 -296.350213) (xy 50.930302 -296.37482) (xy 52.21911 -296.37482) (xy 52.22307 -296.325766)
			(xy 52.234847 -296.277982) (xy 52.254138 -296.232706) (xy 52.280441 -296.19111) (xy 52.313076 -296.154273)
			(xy 52.351197 -296.123148) (xy 52.393818 -296.098541) (xy 52.439834 -296.081089) (xy 52.488053 -296.071245)
			(xy 52.537228 -296.069264) (xy 52.586083 -296.075196) (xy 52.633354 -296.088888) (xy 52.677816 -296.109986)
			(xy 52.718319 -296.137942) (xy 52.753812 -296.172034) (xy 52.783377 -296.211378) (xy 52.806248 -296.254955)
			(xy 52.821832 -296.301636) (xy 52.829727 -296.350213) (xy 52.830222 -296.37482) (xy 54.11903 -296.37482)
			(xy 54.12299 -296.325766) (xy 54.134767 -296.277982) (xy 54.154058 -296.232706) (xy 54.180361 -296.19111)
			(xy 54.212996 -296.154273) (xy 54.251117 -296.123148) (xy 54.293738 -296.098541) (xy 54.339754 -296.081089)
			(xy 54.387973 -296.071245) (xy 54.437148 -296.069264) (xy 54.486003 -296.075196) (xy 54.533274 -296.088888)
			(xy 54.577736 -296.109986) (xy 54.618239 -296.137942) (xy 54.653732 -296.172034) (xy 54.683297 -296.211378)
			(xy 54.706168 -296.254955) (xy 54.721752 -296.301636) (xy 54.729647 -296.350213) (xy 54.730142 -296.37482)
			(xy 56.019204 -296.37482) (xy 56.023164 -296.325766) (xy 56.034941 -296.277982) (xy 56.054232 -296.232706)
			(xy 56.080535 -296.19111) (xy 56.11317 -296.154273) (xy 56.151291 -296.123148) (xy 56.193912 -296.098541)
			(xy 56.239928 -296.081089) (xy 56.288147 -296.071245) (xy 56.337322 -296.069264) (xy 56.386177 -296.075196)
			(xy 56.433448 -296.088888) (xy 56.47791 -296.109986) (xy 56.518413 -296.137942) (xy 56.553906 -296.172034)
			(xy 56.583471 -296.211378) (xy 56.606342 -296.254955) (xy 56.621926 -296.301636) (xy 56.629821 -296.350213)
			(xy 56.630316 -296.37482) (xy 57.919124 -296.37482) (xy 57.923084 -296.325766) (xy 57.934861 -296.277982)
			(xy 57.954152 -296.232706) (xy 57.980455 -296.19111) (xy 58.01309 -296.154273) (xy 58.051211 -296.123148)
			(xy 58.093832 -296.098541) (xy 58.139848 -296.081089) (xy 58.188067 -296.071245) (xy 58.237242 -296.069264)
			(xy 58.286097 -296.075196) (xy 58.333368 -296.088888) (xy 58.37783 -296.109986) (xy 58.418333 -296.137942)
			(xy 58.453826 -296.172034) (xy 58.483391 -296.211378) (xy 58.506262 -296.254955) (xy 58.521846 -296.301636)
			(xy 58.529741 -296.350213) (xy 58.530236 -296.37482) (xy 60.769004 -296.37482) (xy 60.772964 -296.325766)
			(xy 60.784741 -296.277982) (xy 60.804032 -296.232706) (xy 60.830335 -296.19111) (xy 60.86297 -296.154273)
			(xy 60.901091 -296.123148) (xy 60.943712 -296.098541) (xy 60.989728 -296.081089) (xy 61.037947 -296.071245)
			(xy 61.087122 -296.069264) (xy 61.135977 -296.075196) (xy 61.183248 -296.088888) (xy 61.22771 -296.109986)
			(xy 61.268213 -296.137942) (xy 61.303706 -296.172034) (xy 61.333271 -296.211378) (xy 61.356142 -296.254955)
			(xy 61.371726 -296.301636) (xy 61.379621 -296.350213) (xy 61.380116 -296.37482) (xy 62.669178 -296.37482)
			(xy 62.673138 -296.325766) (xy 62.684915 -296.277982) (xy 62.704206 -296.232706) (xy 62.730509 -296.19111)
			(xy 62.763144 -296.154273) (xy 62.801265 -296.123148) (xy 62.843886 -296.098541) (xy 62.889902 -296.081089)
			(xy 62.938121 -296.071245) (xy 62.987296 -296.069264) (xy 63.036151 -296.075196) (xy 63.083422 -296.088888)
			(xy 63.127884 -296.109986) (xy 63.168387 -296.137942) (xy 63.20388 -296.172034) (xy 63.233445 -296.211378)
			(xy 63.256316 -296.254955) (xy 63.2719 -296.301636) (xy 63.279795 -296.350213) (xy 63.28029 -296.37482)
			(xy 64.569098 -296.37482) (xy 64.573058 -296.325766) (xy 64.584835 -296.277982) (xy 64.604126 -296.232706)
			(xy 64.630429 -296.19111) (xy 64.663064 -296.154273) (xy 64.701185 -296.123148) (xy 64.743806 -296.098541)
			(xy 64.789822 -296.081089) (xy 64.838041 -296.071245) (xy 64.887216 -296.069264) (xy 64.936071 -296.075196)
			(xy 64.983342 -296.088888) (xy 65.027804 -296.109986) (xy 65.068307 -296.137942) (xy 65.1038 -296.172034)
			(xy 65.133365 -296.211378) (xy 65.156236 -296.254955) (xy 65.17182 -296.301636) (xy 65.179715 -296.350213)
			(xy 65.18021 -296.37482) (xy 66.469018 -296.37482) (xy 66.472978 -296.325766) (xy 66.484755 -296.277982)
			(xy 66.504046 -296.232706) (xy 66.530349 -296.19111) (xy 66.562984 -296.154273) (xy 66.601105 -296.123148)
			(xy 66.643726 -296.098541) (xy 66.689742 -296.081089) (xy 66.737961 -296.071245) (xy 66.787136 -296.069264)
			(xy 66.835991 -296.075196) (xy 66.883262 -296.088888) (xy 66.927724 -296.109986) (xy 66.968227 -296.137942)
			(xy 67.00372 -296.172034) (xy 67.033285 -296.211378) (xy 67.056156 -296.254955) (xy 67.07174 -296.301636)
			(xy 67.079635 -296.350213) (xy 67.08013 -296.37482) (xy 67.418978 -296.37482) (xy 67.422938 -296.325766)
			(xy 67.434715 -296.277982) (xy 67.454006 -296.232706) (xy 67.480309 -296.19111) (xy 67.512944 -296.154273)
			(xy 67.551065 -296.123148) (xy 67.593686 -296.098541) (xy 67.639702 -296.081089) (xy 67.687921 -296.071245)
			(xy 67.737096 -296.069264) (xy 67.785951 -296.075196) (xy 67.833222 -296.088888) (xy 67.877684 -296.109986)
			(xy 67.918187 -296.137942) (xy 67.95368 -296.172034) (xy 67.983245 -296.211378) (xy 68.006116 -296.254955)
			(xy 68.0217 -296.301636) (xy 68.029595 -296.350213) (xy 68.03009 -296.37482) (xy 68.368938 -296.37482)
			(xy 68.372898 -296.325766) (xy 68.384675 -296.277982) (xy 68.403966 -296.232706) (xy 68.430269 -296.19111)
			(xy 68.462904 -296.154273) (xy 68.501025 -296.123148) (xy 68.543646 -296.098541) (xy 68.589662 -296.081089)
			(xy 68.637881 -296.071245) (xy 68.687056 -296.069264) (xy 68.735911 -296.075196) (xy 68.783182 -296.088888)
			(xy 68.827644 -296.109986) (xy 68.868147 -296.137942) (xy 68.90364 -296.172034) (xy 68.933205 -296.211378)
			(xy 68.956076 -296.254955) (xy 68.97166 -296.301636) (xy 68.979555 -296.350213) (xy 68.98005 -296.37482)
			(xy 69.319152 -296.37482) (xy 69.323112 -296.325766) (xy 69.334889 -296.277982) (xy 69.35418 -296.232706)
			(xy 69.380483 -296.19111) (xy 69.413118 -296.154273) (xy 69.451239 -296.123148) (xy 69.49386 -296.098541)
			(xy 69.539876 -296.081089) (xy 69.588095 -296.071245) (xy 69.63727 -296.069264) (xy 69.686125 -296.075196)
			(xy 69.733396 -296.088888) (xy 69.777858 -296.109986) (xy 69.818361 -296.137942) (xy 69.853854 -296.172034)
			(xy 69.883419 -296.211378) (xy 69.90629 -296.254955) (xy 69.921874 -296.301636) (xy 69.929769 -296.350213)
			(xy 69.930264 -296.37482) (xy 70.269112 -296.37482) (xy 70.273072 -296.325766) (xy 70.284849 -296.277982)
			(xy 70.30414 -296.232706) (xy 70.330443 -296.19111) (xy 70.363078 -296.154273) (xy 70.401199 -296.123148)
			(xy 70.44382 -296.098541) (xy 70.489836 -296.081089) (xy 70.538055 -296.071245) (xy 70.58723 -296.069264)
			(xy 70.636085 -296.075196) (xy 70.683356 -296.088888) (xy 70.727818 -296.109986) (xy 70.768321 -296.137942)
			(xy 70.803814 -296.172034) (xy 70.833379 -296.211378) (xy 70.85625 -296.254955) (xy 70.871834 -296.301636)
			(xy 70.879729 -296.350213) (xy 70.880224 -296.37482) (xy 71.219072 -296.37482) (xy 71.223032 -296.325766)
			(xy 71.234809 -296.277982) (xy 71.2541 -296.232706) (xy 71.280403 -296.19111) (xy 71.313038 -296.154273)
			(xy 71.351159 -296.123148) (xy 71.39378 -296.098541) (xy 71.439796 -296.081089) (xy 71.488015 -296.071245)
			(xy 71.53719 -296.069264) (xy 71.586045 -296.075196) (xy 71.633316 -296.088888) (xy 71.677778 -296.109986)
			(xy 71.718281 -296.137942) (xy 71.753774 -296.172034) (xy 71.783339 -296.211378) (xy 71.80621 -296.254955)
			(xy 71.821794 -296.301636) (xy 71.829689 -296.350213) (xy 71.830184 -296.37482) (xy 72.169032 -296.37482)
			(xy 72.172992 -296.325766) (xy 72.184769 -296.277982) (xy 72.20406 -296.232706) (xy 72.230363 -296.19111)
			(xy 72.262998 -296.154273) (xy 72.301119 -296.123148) (xy 72.34374 -296.098541) (xy 72.389756 -296.081089)
			(xy 72.437975 -296.071245) (xy 72.48715 -296.069264) (xy 72.536005 -296.075196) (xy 72.583276 -296.088888)
			(xy 72.627738 -296.109986) (xy 72.668241 -296.137942) (xy 72.703734 -296.172034) (xy 72.733299 -296.211378)
			(xy 72.75617 -296.254955) (xy 72.771754 -296.301636) (xy 72.779649 -296.350213) (xy 72.780144 -296.37482)
			(xy 73.118992 -296.37482) (xy 73.122952 -296.325766) (xy 73.134729 -296.277982) (xy 73.15402 -296.232706)
			(xy 73.180323 -296.19111) (xy 73.212958 -296.154273) (xy 73.251079 -296.123148) (xy 73.2937 -296.098541)
			(xy 73.339716 -296.081089) (xy 73.387935 -296.071245) (xy 73.43711 -296.069264) (xy 73.485965 -296.075196)
			(xy 73.533236 -296.088888) (xy 73.577698 -296.109986) (xy 73.618201 -296.137942) (xy 73.653694 -296.172034)
			(xy 73.683259 -296.211378) (xy 73.70613 -296.254955) (xy 73.721714 -296.301636) (xy 73.729609 -296.350213)
			(xy 73.730104 -296.37482) (xy 74.068952 -296.37482) (xy 74.072912 -296.325766) (xy 74.084689 -296.277982)
			(xy 74.10398 -296.232706) (xy 74.130283 -296.19111) (xy 74.162918 -296.154273) (xy 74.201039 -296.123148)
			(xy 74.24366 -296.098541) (xy 74.289676 -296.081089) (xy 74.337895 -296.071245) (xy 74.38707 -296.069264)
			(xy 74.435925 -296.075196) (xy 74.483196 -296.088888) (xy 74.527658 -296.109986) (xy 74.568161 -296.137942)
			(xy 74.603654 -296.172034) (xy 74.633219 -296.211378) (xy 74.65609 -296.254955) (xy 74.671674 -296.301636)
			(xy 74.679569 -296.350213) (xy 74.680064 -296.37482) (xy 75.019166 -296.37482) (xy 75.023126 -296.325766)
			(xy 75.034903 -296.277982) (xy 75.054194 -296.232706) (xy 75.080497 -296.19111) (xy 75.113132 -296.154273)
			(xy 75.151253 -296.123148) (xy 75.193874 -296.098541) (xy 75.23989 -296.081089) (xy 75.288109 -296.071245)
			(xy 75.337284 -296.069264) (xy 75.386139 -296.075196) (xy 75.43341 -296.088888) (xy 75.477872 -296.109986)
			(xy 75.518375 -296.137942) (xy 75.553868 -296.172034) (xy 75.583433 -296.211378) (xy 75.606304 -296.254955)
			(xy 75.621888 -296.301636) (xy 75.629783 -296.350213) (xy 75.630278 -296.37482) (xy 75.969126 -296.37482)
			(xy 75.973086 -296.325766) (xy 75.984863 -296.277982) (xy 76.004154 -296.232706) (xy 76.030457 -296.19111)
			(xy 76.063092 -296.154273) (xy 76.101213 -296.123148) (xy 76.143834 -296.098541) (xy 76.18985 -296.081089)
			(xy 76.238069 -296.071245) (xy 76.287244 -296.069264) (xy 76.336099 -296.075196) (xy 76.38337 -296.088888)
			(xy 76.427832 -296.109986) (xy 76.468335 -296.137942) (xy 76.503828 -296.172034) (xy 76.533393 -296.211378)
			(xy 76.556264 -296.254955) (xy 76.571848 -296.301636) (xy 76.579743 -296.350213) (xy 76.580238 -296.37482)
			(xy 76.919086 -296.37482) (xy 76.923046 -296.325766) (xy 76.934823 -296.277982) (xy 76.954114 -296.232706)
			(xy 76.980417 -296.19111) (xy 77.013052 -296.154273) (xy 77.051173 -296.123148) (xy 77.093794 -296.098541)
			(xy 77.13981 -296.081089) (xy 77.188029 -296.071245) (xy 77.237204 -296.069264) (xy 77.286059 -296.075196)
			(xy 77.33333 -296.088888) (xy 77.377792 -296.109986) (xy 77.418295 -296.137942) (xy 77.453788 -296.172034)
			(xy 77.483353 -296.211378) (xy 77.506224 -296.254955) (xy 77.521808 -296.301636) (xy 77.529703 -296.350213)
			(xy 77.530198 -296.37482) (xy 77.869046 -296.37482) (xy 77.873006 -296.325766) (xy 77.884783 -296.277982)
			(xy 77.904074 -296.232706) (xy 77.930377 -296.19111) (xy 77.963012 -296.154273) (xy 78.001133 -296.123148)
			(xy 78.043754 -296.098541) (xy 78.08977 -296.081089) (xy 78.137989 -296.071245) (xy 78.187164 -296.069264)
			(xy 78.236019 -296.075196) (xy 78.28329 -296.088888) (xy 78.327752 -296.109986) (xy 78.368255 -296.137942)
			(xy 78.403748 -296.172034) (xy 78.433313 -296.211378) (xy 78.456184 -296.254955) (xy 78.471768 -296.301636)
			(xy 78.479663 -296.350213) (xy 78.480158 -296.37482) (xy 78.819006 -296.37482) (xy 78.822966 -296.325766)
			(xy 78.834743 -296.277982) (xy 78.854034 -296.232706) (xy 78.880337 -296.19111) (xy 78.912972 -296.154273)
			(xy 78.951093 -296.123148) (xy 78.993714 -296.098541) (xy 79.03973 -296.081089) (xy 79.087949 -296.071245)
			(xy 79.137124 -296.069264) (xy 79.185979 -296.075196) (xy 79.23325 -296.088888) (xy 79.277712 -296.109986)
			(xy 79.318215 -296.137942) (xy 79.353708 -296.172034) (xy 79.383273 -296.211378) (xy 79.406144 -296.254955)
			(xy 79.421728 -296.301636) (xy 79.429623 -296.350213) (xy 79.430118 -296.37482) (xy 79.768966 -296.37482)
			(xy 79.772926 -296.325766) (xy 79.784703 -296.277982) (xy 79.803994 -296.232706) (xy 79.830297 -296.19111)
			(xy 79.862932 -296.154273) (xy 79.901053 -296.123148) (xy 79.943674 -296.098541) (xy 79.98969 -296.081089)
			(xy 80.037909 -296.071245) (xy 80.087084 -296.069264) (xy 80.135939 -296.075196) (xy 80.18321 -296.088888)
			(xy 80.227672 -296.109986) (xy 80.268175 -296.137942) (xy 80.303668 -296.172034) (xy 80.333233 -296.211378)
			(xy 80.356104 -296.254955) (xy 80.371688 -296.301636) (xy 80.379583 -296.350213) (xy 80.380078 -296.37482)
			(xy 80.71918 -296.37482) (xy 80.72314 -296.325766) (xy 80.734917 -296.277982) (xy 80.754208 -296.232706)
			(xy 80.780511 -296.19111) (xy 80.813146 -296.154273) (xy 80.851267 -296.123148) (xy 80.893888 -296.098541)
			(xy 80.939904 -296.081089) (xy 80.988123 -296.071245) (xy 81.037298 -296.069264) (xy 81.086153 -296.075196)
			(xy 81.133424 -296.088888) (xy 81.177886 -296.109986) (xy 81.218389 -296.137942) (xy 81.253882 -296.172034)
			(xy 81.283447 -296.211378) (xy 81.306318 -296.254955) (xy 81.321902 -296.301636) (xy 81.329797 -296.350213)
			(xy 81.330292 -296.37482) (xy 81.66914 -296.37482) (xy 81.6731 -296.325766) (xy 81.684877 -296.277982)
			(xy 81.704168 -296.232706) (xy 81.730471 -296.19111) (xy 81.763106 -296.154273) (xy 81.801227 -296.123148)
			(xy 81.843848 -296.098541) (xy 81.889864 -296.081089) (xy 81.938083 -296.071245) (xy 81.987258 -296.069264)
			(xy 82.036113 -296.075196) (xy 82.083384 -296.088888) (xy 82.127846 -296.109986) (xy 82.168349 -296.137942)
			(xy 82.203842 -296.172034) (xy 82.233407 -296.211378) (xy 82.256278 -296.254955) (xy 82.271862 -296.301636)
			(xy 82.279757 -296.350213) (xy 82.280252 -296.37482) (xy 82.6191 -296.37482) (xy 82.62306 -296.325766)
			(xy 82.634837 -296.277982) (xy 82.654128 -296.232706) (xy 82.680431 -296.19111) (xy 82.713066 -296.154273)
			(xy 82.751187 -296.123148) (xy 82.793808 -296.098541) (xy 82.839824 -296.081089) (xy 82.888043 -296.071245)
			(xy 82.937218 -296.069264) (xy 82.986073 -296.075196) (xy 83.033344 -296.088888) (xy 83.077806 -296.109986)
			(xy 83.118309 -296.137942) (xy 83.153802 -296.172034) (xy 83.183367 -296.211378) (xy 83.206238 -296.254955)
			(xy 83.221822 -296.301636) (xy 83.229717 -296.350213) (xy 83.230212 -296.37482) (xy 83.229717 -296.399427)
			(xy 83.221822 -296.448004) (xy 83.206238 -296.494685) (xy 83.183367 -296.538262) (xy 83.153802 -296.577606)
			(xy 83.118309 -296.611698) (xy 83.116318 -296.613072) (xy 89.262456 -296.613072) (xy 89.266527 -296.55745)
			(xy 89.278653 -296.503013) (xy 89.298576 -296.450922) (xy 89.325872 -296.402287) (xy 89.359958 -296.358144)
			(xy 89.400107 -296.319435) (xy 89.445465 -296.286984) (xy 89.495065 -296.261483) (xy 89.547849 -296.243476)
			(xy 89.602692 -296.233346) (xy 89.658426 -296.231309) (xy 89.713863 -296.237409) (xy 89.76782 -296.251515)
			(xy 89.819149 -296.273327) (xy 89.866755 -296.302381) (xy 89.909623 -296.338056) (xy 89.94684 -296.379593)
			(xy 89.977613 -296.426106) (xy 90.001285 -296.476603) (xy 90.017353 -296.53001) (xy 90.025473 -296.585186)
			(xy 90.025982 -296.613072) (xy 90.537282 -296.613072) (xy 90.541353 -296.55745) (xy 90.553479 -296.503013)
			(xy 90.573402 -296.450922) (xy 90.600698 -296.402287) (xy 90.634784 -296.358144) (xy 90.674933 -296.319435)
			(xy 90.720291 -296.286984) (xy 90.769891 -296.261483) (xy 90.822675 -296.243476) (xy 90.877518 -296.233346)
			(xy 90.933252 -296.231309) (xy 90.988689 -296.237409) (xy 91.042646 -296.251515) (xy 91.093975 -296.273327)
			(xy 91.141581 -296.302381) (xy 91.184449 -296.338056) (xy 91.221666 -296.379593) (xy 91.252439 -296.426106)
			(xy 91.276111 -296.476603) (xy 91.292179 -296.53001) (xy 91.300299 -296.585186) (xy 91.300808 -296.613072)
			(xy 91.300299 -296.640958) (xy 91.292179 -296.696134) (xy 91.276111 -296.749541) (xy 91.252439 -296.800038)
			(xy 91.221666 -296.846551) (xy 91.184449 -296.888088) (xy 91.141581 -296.923763) (xy 91.093975 -296.952817)
			(xy 91.042646 -296.974629) (xy 90.988689 -296.988735) (xy 90.933252 -296.994835) (xy 90.877518 -296.992798)
			(xy 90.822675 -296.982668) (xy 90.769891 -296.964661) (xy 90.720291 -296.93916) (xy 90.674933 -296.906709)
			(xy 90.634784 -296.868) (xy 90.600698 -296.823857) (xy 90.573402 -296.775222) (xy 90.553479 -296.723131)
			(xy 90.541353 -296.668694) (xy 90.537282 -296.613072) (xy 90.025982 -296.613072) (xy 90.025473 -296.640958)
			(xy 90.017353 -296.696134) (xy 90.001285 -296.749541) (xy 89.977613 -296.800038) (xy 89.94684 -296.846551)
			(xy 89.909623 -296.888088) (xy 89.866755 -296.923763) (xy 89.819149 -296.952817) (xy 89.76782 -296.974629)
			(xy 89.713863 -296.988735) (xy 89.658426 -296.994835) (xy 89.602692 -296.992798) (xy 89.547849 -296.982668)
			(xy 89.495065 -296.964661) (xy 89.445465 -296.93916) (xy 89.400107 -296.906709) (xy 89.359958 -296.868)
			(xy 89.325872 -296.823857) (xy 89.298576 -296.775222) (xy 89.278653 -296.723131) (xy 89.266527 -296.668694)
			(xy 89.262456 -296.613072) (xy 83.116318 -296.613072) (xy 83.077806 -296.639654) (xy 83.033344 -296.660752)
			(xy 82.986073 -296.674444) (xy 82.937218 -296.680376) (xy 82.888043 -296.678395) (xy 82.839824 -296.668551)
			(xy 82.793808 -296.651099) (xy 82.751187 -296.626492) (xy 82.713066 -296.595367) (xy 82.680431 -296.55853)
			(xy 82.654128 -296.516934) (xy 82.634837 -296.471658) (xy 82.62306 -296.423874) (xy 82.6191 -296.37482)
			(xy 82.280252 -296.37482) (xy 82.279757 -296.399427) (xy 82.271862 -296.448004) (xy 82.256278 -296.494685)
			(xy 82.233407 -296.538262) (xy 82.203842 -296.577606) (xy 82.168349 -296.611698) (xy 82.127846 -296.639654)
			(xy 82.083384 -296.660752) (xy 82.036113 -296.674444) (xy 81.987258 -296.680376) (xy 81.938083 -296.678395)
			(xy 81.889864 -296.668551) (xy 81.843848 -296.651099) (xy 81.801227 -296.626492) (xy 81.763106 -296.595367)
			(xy 81.730471 -296.55853) (xy 81.704168 -296.516934) (xy 81.684877 -296.471658) (xy 81.6731 -296.423874)
			(xy 81.66914 -296.37482) (xy 81.330292 -296.37482) (xy 81.329797 -296.399427) (xy 81.321902 -296.448004)
			(xy 81.306318 -296.494685) (xy 81.283447 -296.538262) (xy 81.253882 -296.577606) (xy 81.218389 -296.611698)
			(xy 81.177886 -296.639654) (xy 81.133424 -296.660752) (xy 81.086153 -296.674444) (xy 81.037298 -296.680376)
			(xy 80.988123 -296.678395) (xy 80.939904 -296.668551) (xy 80.893888 -296.651099) (xy 80.851267 -296.626492)
			(xy 80.813146 -296.595367) (xy 80.780511 -296.55853) (xy 80.754208 -296.516934) (xy 80.734917 -296.471658)
			(xy 80.72314 -296.423874) (xy 80.71918 -296.37482) (xy 80.380078 -296.37482) (xy 80.379583 -296.399427)
			(xy 80.371688 -296.448004) (xy 80.356104 -296.494685) (xy 80.333233 -296.538262) (xy 80.303668 -296.577606)
			(xy 80.268175 -296.611698) (xy 80.227672 -296.639654) (xy 80.18321 -296.660752) (xy 80.135939 -296.674444)
			(xy 80.087084 -296.680376) (xy 80.037909 -296.678395) (xy 79.98969 -296.668551) (xy 79.943674 -296.651099)
			(xy 79.901053 -296.626492) (xy 79.862932 -296.595367) (xy 79.830297 -296.55853) (xy 79.803994 -296.516934)
			(xy 79.784703 -296.471658) (xy 79.772926 -296.423874) (xy 79.768966 -296.37482) (xy 79.430118 -296.37482)
			(xy 79.429623 -296.399427) (xy 79.421728 -296.448004) (xy 79.406144 -296.494685) (xy 79.383273 -296.538262)
			(xy 79.353708 -296.577606) (xy 79.318215 -296.611698) (xy 79.277712 -296.639654) (xy 79.23325 -296.660752)
			(xy 79.185979 -296.674444) (xy 79.137124 -296.680376) (xy 79.087949 -296.678395) (xy 79.03973 -296.668551)
			(xy 78.993714 -296.651099) (xy 78.951093 -296.626492) (xy 78.912972 -296.595367) (xy 78.880337 -296.55853)
			(xy 78.854034 -296.516934) (xy 78.834743 -296.471658) (xy 78.822966 -296.423874) (xy 78.819006 -296.37482)
			(xy 78.480158 -296.37482) (xy 78.479663 -296.399427) (xy 78.471768 -296.448004) (xy 78.456184 -296.494685)
			(xy 78.433313 -296.538262) (xy 78.403748 -296.577606) (xy 78.368255 -296.611698) (xy 78.327752 -296.639654)
			(xy 78.28329 -296.660752) (xy 78.236019 -296.674444) (xy 78.187164 -296.680376) (xy 78.137989 -296.678395)
			(xy 78.08977 -296.668551) (xy 78.043754 -296.651099) (xy 78.001133 -296.626492) (xy 77.963012 -296.595367)
			(xy 77.930377 -296.55853) (xy 77.904074 -296.516934) (xy 77.884783 -296.471658) (xy 77.873006 -296.423874)
			(xy 77.869046 -296.37482) (xy 77.530198 -296.37482) (xy 77.529703 -296.399427) (xy 77.521808 -296.448004)
			(xy 77.506224 -296.494685) (xy 77.483353 -296.538262) (xy 77.453788 -296.577606) (xy 77.418295 -296.611698)
			(xy 77.377792 -296.639654) (xy 77.33333 -296.660752) (xy 77.286059 -296.674444) (xy 77.237204 -296.680376)
			(xy 77.188029 -296.678395) (xy 77.13981 -296.668551) (xy 77.093794 -296.651099) (xy 77.051173 -296.626492)
			(xy 77.013052 -296.595367) (xy 76.980417 -296.55853) (xy 76.954114 -296.516934) (xy 76.934823 -296.471658)
			(xy 76.923046 -296.423874) (xy 76.919086 -296.37482) (xy 76.580238 -296.37482) (xy 76.579743 -296.399427)
			(xy 76.571848 -296.448004) (xy 76.556264 -296.494685) (xy 76.533393 -296.538262) (xy 76.503828 -296.577606)
			(xy 76.468335 -296.611698) (xy 76.427832 -296.639654) (xy 76.38337 -296.660752) (xy 76.336099 -296.674444)
			(xy 76.287244 -296.680376) (xy 76.238069 -296.678395) (xy 76.18985 -296.668551) (xy 76.143834 -296.651099)
			(xy 76.101213 -296.626492) (xy 76.063092 -296.595367) (xy 76.030457 -296.55853) (xy 76.004154 -296.516934)
			(xy 75.984863 -296.471658) (xy 75.973086 -296.423874) (xy 75.969126 -296.37482) (xy 75.630278 -296.37482)
			(xy 75.629783 -296.399427) (xy 75.621888 -296.448004) (xy 75.606304 -296.494685) (xy 75.583433 -296.538262)
			(xy 75.553868 -296.577606) (xy 75.518375 -296.611698) (xy 75.477872 -296.639654) (xy 75.43341 -296.660752)
			(xy 75.386139 -296.674444) (xy 75.337284 -296.680376) (xy 75.288109 -296.678395) (xy 75.23989 -296.668551)
			(xy 75.193874 -296.651099) (xy 75.151253 -296.626492) (xy 75.113132 -296.595367) (xy 75.080497 -296.55853)
			(xy 75.054194 -296.516934) (xy 75.034903 -296.471658) (xy 75.023126 -296.423874) (xy 75.019166 -296.37482)
			(xy 74.680064 -296.37482) (xy 74.679569 -296.399427) (xy 74.671674 -296.448004) (xy 74.65609 -296.494685)
			(xy 74.633219 -296.538262) (xy 74.603654 -296.577606) (xy 74.568161 -296.611698) (xy 74.527658 -296.639654)
			(xy 74.483196 -296.660752) (xy 74.435925 -296.674444) (xy 74.38707 -296.680376) (xy 74.337895 -296.678395)
			(xy 74.289676 -296.668551) (xy 74.24366 -296.651099) (xy 74.201039 -296.626492) (xy 74.162918 -296.595367)
			(xy 74.130283 -296.55853) (xy 74.10398 -296.516934) (xy 74.084689 -296.471658) (xy 74.072912 -296.423874)
			(xy 74.068952 -296.37482) (xy 73.730104 -296.37482) (xy 73.729609 -296.399427) (xy 73.721714 -296.448004)
			(xy 73.70613 -296.494685) (xy 73.683259 -296.538262) (xy 73.653694 -296.577606) (xy 73.618201 -296.611698)
			(xy 73.577698 -296.639654) (xy 73.533236 -296.660752) (xy 73.485965 -296.674444) (xy 73.43711 -296.680376)
			(xy 73.387935 -296.678395) (xy 73.339716 -296.668551) (xy 73.2937 -296.651099) (xy 73.251079 -296.626492)
			(xy 73.212958 -296.595367) (xy 73.180323 -296.55853) (xy 73.15402 -296.516934) (xy 73.134729 -296.471658)
			(xy 73.122952 -296.423874) (xy 73.118992 -296.37482) (xy 72.780144 -296.37482) (xy 72.779649 -296.399427)
			(xy 72.771754 -296.448004) (xy 72.75617 -296.494685) (xy 72.733299 -296.538262) (xy 72.703734 -296.577606)
			(xy 72.668241 -296.611698) (xy 72.627738 -296.639654) (xy 72.583276 -296.660752) (xy 72.536005 -296.674444)
			(xy 72.48715 -296.680376) (xy 72.437975 -296.678395) (xy 72.389756 -296.668551) (xy 72.34374 -296.651099)
			(xy 72.301119 -296.626492) (xy 72.262998 -296.595367) (xy 72.230363 -296.55853) (xy 72.20406 -296.516934)
			(xy 72.184769 -296.471658) (xy 72.172992 -296.423874) (xy 72.169032 -296.37482) (xy 71.830184 -296.37482)
			(xy 71.829689 -296.399427) (xy 71.821794 -296.448004) (xy 71.80621 -296.494685) (xy 71.783339 -296.538262)
			(xy 71.753774 -296.577606) (xy 71.718281 -296.611698) (xy 71.677778 -296.639654) (xy 71.633316 -296.660752)
			(xy 71.586045 -296.674444) (xy 71.53719 -296.680376) (xy 71.488015 -296.678395) (xy 71.439796 -296.668551)
			(xy 71.39378 -296.651099) (xy 71.351159 -296.626492) (xy 71.313038 -296.595367) (xy 71.280403 -296.55853)
			(xy 71.2541 -296.516934) (xy 71.234809 -296.471658) (xy 71.223032 -296.423874) (xy 71.219072 -296.37482)
			(xy 70.880224 -296.37482) (xy 70.879729 -296.399427) (xy 70.871834 -296.448004) (xy 70.85625 -296.494685)
			(xy 70.833379 -296.538262) (xy 70.803814 -296.577606) (xy 70.768321 -296.611698) (xy 70.727818 -296.639654)
			(xy 70.683356 -296.660752) (xy 70.636085 -296.674444) (xy 70.58723 -296.680376) (xy 70.538055 -296.678395)
			(xy 70.489836 -296.668551) (xy 70.44382 -296.651099) (xy 70.401199 -296.626492) (xy 70.363078 -296.595367)
			(xy 70.330443 -296.55853) (xy 70.30414 -296.516934) (xy 70.284849 -296.471658) (xy 70.273072 -296.423874)
			(xy 70.269112 -296.37482) (xy 69.930264 -296.37482) (xy 69.929769 -296.399427) (xy 69.921874 -296.448004)
			(xy 69.90629 -296.494685) (xy 69.883419 -296.538262) (xy 69.853854 -296.577606) (xy 69.818361 -296.611698)
			(xy 69.777858 -296.639654) (xy 69.733396 -296.660752) (xy 69.686125 -296.674444) (xy 69.63727 -296.680376)
			(xy 69.588095 -296.678395) (xy 69.539876 -296.668551) (xy 69.49386 -296.651099) (xy 69.451239 -296.626492)
			(xy 69.413118 -296.595367) (xy 69.380483 -296.55853) (xy 69.35418 -296.516934) (xy 69.334889 -296.471658)
			(xy 69.323112 -296.423874) (xy 69.319152 -296.37482) (xy 68.98005 -296.37482) (xy 68.979555 -296.399427)
			(xy 68.97166 -296.448004) (xy 68.956076 -296.494685) (xy 68.933205 -296.538262) (xy 68.90364 -296.577606)
			(xy 68.868147 -296.611698) (xy 68.827644 -296.639654) (xy 68.783182 -296.660752) (xy 68.735911 -296.674444)
			(xy 68.687056 -296.680376) (xy 68.637881 -296.678395) (xy 68.589662 -296.668551) (xy 68.543646 -296.651099)
			(xy 68.501025 -296.626492) (xy 68.462904 -296.595367) (xy 68.430269 -296.55853) (xy 68.403966 -296.516934)
			(xy 68.384675 -296.471658) (xy 68.372898 -296.423874) (xy 68.368938 -296.37482) (xy 68.03009 -296.37482)
			(xy 68.029595 -296.399427) (xy 68.0217 -296.448004) (xy 68.006116 -296.494685) (xy 67.983245 -296.538262)
			(xy 67.95368 -296.577606) (xy 67.918187 -296.611698) (xy 67.877684 -296.639654) (xy 67.833222 -296.660752)
			(xy 67.785951 -296.674444) (xy 67.737096 -296.680376) (xy 67.687921 -296.678395) (xy 67.639702 -296.668551)
			(xy 67.593686 -296.651099) (xy 67.551065 -296.626492) (xy 67.512944 -296.595367) (xy 67.480309 -296.55853)
			(xy 67.454006 -296.516934) (xy 67.434715 -296.471658) (xy 67.422938 -296.423874) (xy 67.418978 -296.37482)
			(xy 67.08013 -296.37482) (xy 67.079635 -296.399427) (xy 67.07174 -296.448004) (xy 67.056156 -296.494685)
			(xy 67.033285 -296.538262) (xy 67.00372 -296.577606) (xy 66.968227 -296.611698) (xy 66.927724 -296.639654)
			(xy 66.883262 -296.660752) (xy 66.835991 -296.674444) (xy 66.787136 -296.680376) (xy 66.737961 -296.678395)
			(xy 66.689742 -296.668551) (xy 66.643726 -296.651099) (xy 66.601105 -296.626492) (xy 66.562984 -296.595367)
			(xy 66.530349 -296.55853) (xy 66.504046 -296.516934) (xy 66.484755 -296.471658) (xy 66.472978 -296.423874)
			(xy 66.469018 -296.37482) (xy 65.18021 -296.37482) (xy 65.179715 -296.399427) (xy 65.17182 -296.448004)
			(xy 65.156236 -296.494685) (xy 65.133365 -296.538262) (xy 65.1038 -296.577606) (xy 65.068307 -296.611698)
			(xy 65.027804 -296.639654) (xy 64.983342 -296.660752) (xy 64.936071 -296.674444) (xy 64.887216 -296.680376)
			(xy 64.838041 -296.678395) (xy 64.789822 -296.668551) (xy 64.743806 -296.651099) (xy 64.701185 -296.626492)
			(xy 64.663064 -296.595367) (xy 64.630429 -296.55853) (xy 64.604126 -296.516934) (xy 64.584835 -296.471658)
			(xy 64.573058 -296.423874) (xy 64.569098 -296.37482) (xy 63.28029 -296.37482) (xy 63.279795 -296.399427)
			(xy 63.2719 -296.448004) (xy 63.256316 -296.494685) (xy 63.233445 -296.538262) (xy 63.20388 -296.577606)
			(xy 63.168387 -296.611698) (xy 63.127884 -296.639654) (xy 63.083422 -296.660752) (xy 63.036151 -296.674444)
			(xy 62.987296 -296.680376) (xy 62.938121 -296.678395) (xy 62.889902 -296.668551) (xy 62.843886 -296.651099)
			(xy 62.801265 -296.626492) (xy 62.763144 -296.595367) (xy 62.730509 -296.55853) (xy 62.704206 -296.516934)
			(xy 62.684915 -296.471658) (xy 62.673138 -296.423874) (xy 62.669178 -296.37482) (xy 61.380116 -296.37482)
			(xy 61.379621 -296.399427) (xy 61.371726 -296.448004) (xy 61.356142 -296.494685) (xy 61.333271 -296.538262)
			(xy 61.303706 -296.577606) (xy 61.268213 -296.611698) (xy 61.22771 -296.639654) (xy 61.183248 -296.660752)
			(xy 61.135977 -296.674444) (xy 61.087122 -296.680376) (xy 61.037947 -296.678395) (xy 60.989728 -296.668551)
			(xy 60.943712 -296.651099) (xy 60.901091 -296.626492) (xy 60.86297 -296.595367) (xy 60.830335 -296.55853)
			(xy 60.804032 -296.516934) (xy 60.784741 -296.471658) (xy 60.772964 -296.423874) (xy 60.769004 -296.37482)
			(xy 58.530236 -296.37482) (xy 58.529741 -296.399427) (xy 58.521846 -296.448004) (xy 58.506262 -296.494685)
			(xy 58.483391 -296.538262) (xy 58.453826 -296.577606) (xy 58.418333 -296.611698) (xy 58.37783 -296.639654)
			(xy 58.333368 -296.660752) (xy 58.286097 -296.674444) (xy 58.237242 -296.680376) (xy 58.188067 -296.678395)
			(xy 58.139848 -296.668551) (xy 58.093832 -296.651099) (xy 58.051211 -296.626492) (xy 58.01309 -296.595367)
			(xy 57.980455 -296.55853) (xy 57.954152 -296.516934) (xy 57.934861 -296.471658) (xy 57.923084 -296.423874)
			(xy 57.919124 -296.37482) (xy 56.630316 -296.37482) (xy 56.629821 -296.399427) (xy 56.621926 -296.448004)
			(xy 56.606342 -296.494685) (xy 56.583471 -296.538262) (xy 56.553906 -296.577606) (xy 56.518413 -296.611698)
			(xy 56.47791 -296.639654) (xy 56.433448 -296.660752) (xy 56.386177 -296.674444) (xy 56.337322 -296.680376)
			(xy 56.288147 -296.678395) (xy 56.239928 -296.668551) (xy 56.193912 -296.651099) (xy 56.151291 -296.626492)
			(xy 56.11317 -296.595367) (xy 56.080535 -296.55853) (xy 56.054232 -296.516934) (xy 56.034941 -296.471658)
			(xy 56.023164 -296.423874) (xy 56.019204 -296.37482) (xy 54.730142 -296.37482) (xy 54.729647 -296.399427)
			(xy 54.721752 -296.448004) (xy 54.706168 -296.494685) (xy 54.683297 -296.538262) (xy 54.653732 -296.577606)
			(xy 54.618239 -296.611698) (xy 54.577736 -296.639654) (xy 54.533274 -296.660752) (xy 54.486003 -296.674444)
			(xy 54.437148 -296.680376) (xy 54.387973 -296.678395) (xy 54.339754 -296.668551) (xy 54.293738 -296.651099)
			(xy 54.251117 -296.626492) (xy 54.212996 -296.595367) (xy 54.180361 -296.55853) (xy 54.154058 -296.516934)
			(xy 54.134767 -296.471658) (xy 54.12299 -296.423874) (xy 54.11903 -296.37482) (xy 52.830222 -296.37482)
			(xy 52.829727 -296.399427) (xy 52.821832 -296.448004) (xy 52.806248 -296.494685) (xy 52.783377 -296.538262)
			(xy 52.753812 -296.577606) (xy 52.718319 -296.611698) (xy 52.677816 -296.639654) (xy 52.633354 -296.660752)
			(xy 52.586083 -296.674444) (xy 52.537228 -296.680376) (xy 52.488053 -296.678395) (xy 52.439834 -296.668551)
			(xy 52.393818 -296.651099) (xy 52.351197 -296.626492) (xy 52.313076 -296.595367) (xy 52.280441 -296.55853)
			(xy 52.254138 -296.516934) (xy 52.234847 -296.471658) (xy 52.22307 -296.423874) (xy 52.21911 -296.37482)
			(xy 50.930302 -296.37482) (xy 50.929807 -296.399427) (xy 50.921912 -296.448004) (xy 50.906328 -296.494685)
			(xy 50.883457 -296.538262) (xy 50.853892 -296.577606) (xy 50.818399 -296.611698) (xy 50.777896 -296.639654)
			(xy 50.733434 -296.660752) (xy 50.686163 -296.674444) (xy 50.637308 -296.680376) (xy 50.588133 -296.678395)
			(xy 50.539914 -296.668551) (xy 50.493898 -296.651099) (xy 50.451277 -296.626492) (xy 50.413156 -296.595367)
			(xy 50.380521 -296.55853) (xy 50.354218 -296.516934) (xy 50.334927 -296.471658) (xy 50.32315 -296.423874)
			(xy 50.31919 -296.37482) (xy 49.030128 -296.37482) (xy 49.029656 -296.398811) (xy 49.022147 -296.446201)
			(xy 49.007319 -296.491834) (xy 48.985534 -296.534585) (xy 48.957331 -296.573403) (xy 48.923403 -296.607331)
			(xy 48.884585 -296.635534) (xy 48.841834 -296.657319) (xy 48.796201 -296.672147) (xy 48.748811 -296.679656)
			(xy 48.72482 -296.680128) (xy 48.724566 -296.680128) (xy 48.70013 -296.679645) (xy 48.651882 -296.67186)
			(xy 48.605489 -296.656493) (xy 48.562133 -296.633937) (xy 48.522921 -296.604767) (xy 48.488853 -296.569727)
			(xy 48.460797 -296.529711) (xy 48.449738 -296.507916) (xy 48.44415 -296.496232) (xy 48.423068 -296.481246)
			(xy 48.334168 -296.470578) (xy 48.333152 -296.470578) (xy 48.32624 -296.470058) (xy 48.312581 -296.472379)
			(xy 48.306228 -296.47515) (xy 48.289464 -296.483278) (xy 48.285543 -296.485185) (xy 48.278383 -296.490161)
			(xy 48.27524 -296.493184) (xy 48.270414 -296.49801) (xy 48.268636 -296.500296) (xy 48.263302 -296.506392)
			(xy 48.261524 -296.50817) (xy 48.26127 -296.508424) (xy 48.257714 -296.51198) (xy 48.25746 -296.512234)
			(xy 48.125126 -296.644822) (xy 48.080676 -296.689272) (xy 48.075036 -296.696341) (xy 48.068676 -296.713258)
			(xy 48.06823 -296.722292) (xy 48.06823 -297.23334) (xy 48.070008 -297.246548) (xy 48.07077 -297.249596)
			(xy 48.075166 -297.26808) (xy 48.079875 -297.305782) (xy 48.080168 -297.32478) (xy 49.368976 -297.32478)
			(xy 49.372936 -297.275726) (xy 49.384713 -297.227942) (xy 49.404004 -297.182666) (xy 49.430307 -297.14107)
			(xy 49.462942 -297.104233) (xy 49.501063 -297.073108) (xy 49.543684 -297.048501) (xy 49.5897 -297.031049)
			(xy 49.637919 -297.021205) (xy 49.687094 -297.019224) (xy 49.735949 -297.025156) (xy 49.78322 -297.038848)
			(xy 49.827682 -297.059946) (xy 49.868185 -297.087902) (xy 49.903678 -297.121994) (xy 49.933243 -297.161338)
			(xy 49.956114 -297.204915) (xy 49.971698 -297.251596) (xy 49.979593 -297.300173) (xy 49.980088 -297.32478)
			(xy 51.26915 -297.32478) (xy 51.27311 -297.275726) (xy 51.284887 -297.227942) (xy 51.304178 -297.182666)
			(xy 51.330481 -297.14107) (xy 51.363116 -297.104233) (xy 51.401237 -297.073108) (xy 51.443858 -297.048501)
			(xy 51.489874 -297.031049) (xy 51.538093 -297.021205) (xy 51.587268 -297.019224) (xy 51.636123 -297.025156)
			(xy 51.683394 -297.038848) (xy 51.727856 -297.059946) (xy 51.768359 -297.087902) (xy 51.803852 -297.121994)
			(xy 51.833417 -297.161338) (xy 51.856288 -297.204915) (xy 51.871872 -297.251596) (xy 51.879767 -297.300173)
			(xy 51.880262 -297.32478) (xy 53.16907 -297.32478) (xy 53.17303 -297.275726) (xy 53.184807 -297.227942)
			(xy 53.204098 -297.182666) (xy 53.230401 -297.14107) (xy 53.263036 -297.104233) (xy 53.301157 -297.073108)
			(xy 53.343778 -297.048501) (xy 53.389794 -297.031049) (xy 53.438013 -297.021205) (xy 53.487188 -297.019224)
			(xy 53.536043 -297.025156) (xy 53.583314 -297.038848) (xy 53.627776 -297.059946) (xy 53.668279 -297.087902)
			(xy 53.703772 -297.121994) (xy 53.733337 -297.161338) (xy 53.756208 -297.204915) (xy 53.771792 -297.251596)
			(xy 53.779687 -297.300173) (xy 53.780182 -297.32478) (xy 55.06899 -297.32478) (xy 55.07295 -297.275726)
			(xy 55.084727 -297.227942) (xy 55.104018 -297.182666) (xy 55.130321 -297.14107) (xy 55.162956 -297.104233)
			(xy 55.201077 -297.073108) (xy 55.243698 -297.048501) (xy 55.289714 -297.031049) (xy 55.337933 -297.021205)
			(xy 55.387108 -297.019224) (xy 55.435963 -297.025156) (xy 55.483234 -297.038848) (xy 55.527696 -297.059946)
			(xy 55.568199 -297.087902) (xy 55.603692 -297.121994) (xy 55.633257 -297.161338) (xy 55.656128 -297.204915)
			(xy 55.671712 -297.251596) (xy 55.679607 -297.300173) (xy 55.680102 -297.32478) (xy 56.969164 -297.32478)
			(xy 56.973124 -297.275726) (xy 56.984901 -297.227942) (xy 57.004192 -297.182666) (xy 57.030495 -297.14107)
			(xy 57.06313 -297.104233) (xy 57.101251 -297.073108) (xy 57.143872 -297.048501) (xy 57.189888 -297.031049)
			(xy 57.238107 -297.021205) (xy 57.287282 -297.019224) (xy 57.336137 -297.025156) (xy 57.383408 -297.038848)
			(xy 57.42787 -297.059946) (xy 57.468373 -297.087902) (xy 57.503866 -297.121994) (xy 57.533431 -297.161338)
			(xy 57.556302 -297.204915) (xy 57.571886 -297.251596) (xy 57.579781 -297.300173) (xy 57.580276 -297.32478)
			(xy 59.819044 -297.32478) (xy 59.823004 -297.275726) (xy 59.834781 -297.227942) (xy 59.854072 -297.182666)
			(xy 59.880375 -297.14107) (xy 59.91301 -297.104233) (xy 59.951131 -297.073108) (xy 59.993752 -297.048501)
			(xy 60.039768 -297.031049) (xy 60.087987 -297.021205) (xy 60.137162 -297.019224) (xy 60.186017 -297.025156)
			(xy 60.233288 -297.038848) (xy 60.27775 -297.059946) (xy 60.318253 -297.087902) (xy 60.353746 -297.121994)
			(xy 60.383311 -297.161338) (xy 60.406182 -297.204915) (xy 60.421766 -297.251596) (xy 60.429661 -297.300173)
			(xy 60.430156 -297.32478) (xy 61.718964 -297.32478) (xy 61.722924 -297.275726) (xy 61.734701 -297.227942)
			(xy 61.753992 -297.182666) (xy 61.780295 -297.14107) (xy 61.81293 -297.104233) (xy 61.851051 -297.073108)
			(xy 61.893672 -297.048501) (xy 61.939688 -297.031049) (xy 61.987907 -297.021205) (xy 62.037082 -297.019224)
			(xy 62.085937 -297.025156) (xy 62.133208 -297.038848) (xy 62.17767 -297.059946) (xy 62.218173 -297.087902)
			(xy 62.253666 -297.121994) (xy 62.283231 -297.161338) (xy 62.306102 -297.204915) (xy 62.321686 -297.251596)
			(xy 62.329581 -297.300173) (xy 62.330076 -297.32478) (xy 63.619138 -297.32478) (xy 63.623098 -297.275726)
			(xy 63.634875 -297.227942) (xy 63.654166 -297.182666) (xy 63.680469 -297.14107) (xy 63.713104 -297.104233)
			(xy 63.751225 -297.073108) (xy 63.793846 -297.048501) (xy 63.839862 -297.031049) (xy 63.888081 -297.021205)
			(xy 63.937256 -297.019224) (xy 63.986111 -297.025156) (xy 64.033382 -297.038848) (xy 64.077844 -297.059946)
			(xy 64.118347 -297.087902) (xy 64.15384 -297.121994) (xy 64.183405 -297.161338) (xy 64.206276 -297.204915)
			(xy 64.22186 -297.251596) (xy 64.229755 -297.300173) (xy 64.23025 -297.32478) (xy 65.519058 -297.32478)
			(xy 65.523018 -297.275726) (xy 65.534795 -297.227942) (xy 65.554086 -297.182666) (xy 65.580389 -297.14107)
			(xy 65.613024 -297.104233) (xy 65.651145 -297.073108) (xy 65.693766 -297.048501) (xy 65.739782 -297.031049)
			(xy 65.788001 -297.021205) (xy 65.837176 -297.019224) (xy 65.886031 -297.025156) (xy 65.933302 -297.038848)
			(xy 65.977764 -297.059946) (xy 66.018267 -297.087902) (xy 66.05376 -297.121994) (xy 66.083325 -297.161338)
			(xy 66.106196 -297.204915) (xy 66.12178 -297.251596) (xy 66.129675 -297.300173) (xy 66.13017 -297.32478)
			(xy 66.469018 -297.32478) (xy 66.472978 -297.275726) (xy 66.484755 -297.227942) (xy 66.504046 -297.182666)
			(xy 66.530349 -297.14107) (xy 66.562984 -297.104233) (xy 66.601105 -297.073108) (xy 66.643726 -297.048501)
			(xy 66.689742 -297.031049) (xy 66.737961 -297.021205) (xy 66.787136 -297.019224) (xy 66.835991 -297.025156)
			(xy 66.883262 -297.038848) (xy 66.927724 -297.059946) (xy 66.968227 -297.087902) (xy 67.00372 -297.121994)
			(xy 67.033285 -297.161338) (xy 67.056156 -297.204915) (xy 67.07174 -297.251596) (xy 67.079635 -297.300173)
			(xy 67.08013 -297.32478) (xy 67.418978 -297.32478) (xy 67.422938 -297.275726) (xy 67.434715 -297.227942)
			(xy 67.454006 -297.182666) (xy 67.480309 -297.14107) (xy 67.512944 -297.104233) (xy 67.551065 -297.073108)
			(xy 67.593686 -297.048501) (xy 67.639702 -297.031049) (xy 67.687921 -297.021205) (xy 67.737096 -297.019224)
			(xy 67.785951 -297.025156) (xy 67.833222 -297.038848) (xy 67.877684 -297.059946) (xy 67.918187 -297.087902)
			(xy 67.95368 -297.121994) (xy 67.983245 -297.161338) (xy 68.006116 -297.204915) (xy 68.0217 -297.251596)
			(xy 68.029595 -297.300173) (xy 68.03009 -297.32478) (xy 68.368938 -297.32478) (xy 68.372898 -297.275726)
			(xy 68.384675 -297.227942) (xy 68.403966 -297.182666) (xy 68.430269 -297.14107) (xy 68.462904 -297.104233)
			(xy 68.501025 -297.073108) (xy 68.543646 -297.048501) (xy 68.589662 -297.031049) (xy 68.637881 -297.021205)
			(xy 68.687056 -297.019224) (xy 68.735911 -297.025156) (xy 68.783182 -297.038848) (xy 68.827644 -297.059946)
			(xy 68.868147 -297.087902) (xy 68.90364 -297.121994) (xy 68.933205 -297.161338) (xy 68.956076 -297.204915)
			(xy 68.97166 -297.251596) (xy 68.979555 -297.300173) (xy 68.98005 -297.32478) (xy 69.319152 -297.32478)
			(xy 69.323112 -297.275726) (xy 69.334889 -297.227942) (xy 69.35418 -297.182666) (xy 69.380483 -297.14107)
			(xy 69.413118 -297.104233) (xy 69.451239 -297.073108) (xy 69.49386 -297.048501) (xy 69.539876 -297.031049)
			(xy 69.588095 -297.021205) (xy 69.63727 -297.019224) (xy 69.686125 -297.025156) (xy 69.733396 -297.038848)
			(xy 69.777858 -297.059946) (xy 69.818361 -297.087902) (xy 69.853854 -297.121994) (xy 69.883419 -297.161338)
			(xy 69.90629 -297.204915) (xy 69.921874 -297.251596) (xy 69.929769 -297.300173) (xy 69.930264 -297.32478)
			(xy 70.269112 -297.32478) (xy 70.273072 -297.275726) (xy 70.284849 -297.227942) (xy 70.30414 -297.182666)
			(xy 70.330443 -297.14107) (xy 70.363078 -297.104233) (xy 70.401199 -297.073108) (xy 70.44382 -297.048501)
			(xy 70.489836 -297.031049) (xy 70.538055 -297.021205) (xy 70.58723 -297.019224) (xy 70.636085 -297.025156)
			(xy 70.683356 -297.038848) (xy 70.727818 -297.059946) (xy 70.768321 -297.087902) (xy 70.803814 -297.121994)
			(xy 70.833379 -297.161338) (xy 70.85625 -297.204915) (xy 70.871834 -297.251596) (xy 70.879729 -297.300173)
			(xy 70.880224 -297.32478) (xy 71.219072 -297.32478) (xy 71.223032 -297.275726) (xy 71.234809 -297.227942)
			(xy 71.2541 -297.182666) (xy 71.280403 -297.14107) (xy 71.313038 -297.104233) (xy 71.351159 -297.073108)
			(xy 71.39378 -297.048501) (xy 71.439796 -297.031049) (xy 71.488015 -297.021205) (xy 71.53719 -297.019224)
			(xy 71.586045 -297.025156) (xy 71.633316 -297.038848) (xy 71.677778 -297.059946) (xy 71.718281 -297.087902)
			(xy 71.753774 -297.121994) (xy 71.783339 -297.161338) (xy 71.80621 -297.204915) (xy 71.821794 -297.251596)
			(xy 71.829689 -297.300173) (xy 71.830184 -297.32478) (xy 72.169032 -297.32478) (xy 72.172992 -297.275726)
			(xy 72.184769 -297.227942) (xy 72.20406 -297.182666) (xy 72.230363 -297.14107) (xy 72.262998 -297.104233)
			(xy 72.301119 -297.073108) (xy 72.34374 -297.048501) (xy 72.389756 -297.031049) (xy 72.437975 -297.021205)
			(xy 72.48715 -297.019224) (xy 72.536005 -297.025156) (xy 72.583276 -297.038848) (xy 72.627738 -297.059946)
			(xy 72.668241 -297.087902) (xy 72.703734 -297.121994) (xy 72.733299 -297.161338) (xy 72.75617 -297.204915)
			(xy 72.771754 -297.251596) (xy 72.779649 -297.300173) (xy 72.780144 -297.32478) (xy 73.118992 -297.32478)
			(xy 73.122952 -297.275726) (xy 73.134729 -297.227942) (xy 73.15402 -297.182666) (xy 73.180323 -297.14107)
			(xy 73.212958 -297.104233) (xy 73.251079 -297.073108) (xy 73.2937 -297.048501) (xy 73.339716 -297.031049)
			(xy 73.387935 -297.021205) (xy 73.43711 -297.019224) (xy 73.485965 -297.025156) (xy 73.533236 -297.038848)
			(xy 73.577698 -297.059946) (xy 73.618201 -297.087902) (xy 73.653694 -297.121994) (xy 73.683259 -297.161338)
			(xy 73.70613 -297.204915) (xy 73.721714 -297.251596) (xy 73.729609 -297.300173) (xy 73.730104 -297.32478)
			(xy 74.069206 -297.32478) (xy 74.073166 -297.275726) (xy 74.084943 -297.227942) (xy 74.104234 -297.182666)
			(xy 74.130537 -297.14107) (xy 74.163172 -297.104233) (xy 74.201293 -297.073108) (xy 74.243914 -297.048501)
			(xy 74.28993 -297.031049) (xy 74.338149 -297.021205) (xy 74.387324 -297.019224) (xy 74.436179 -297.025156)
			(xy 74.48345 -297.038848) (xy 74.527912 -297.059946) (xy 74.568415 -297.087902) (xy 74.603908 -297.121994)
			(xy 74.633473 -297.161338) (xy 74.656344 -297.204915) (xy 74.671928 -297.251596) (xy 74.679823 -297.300173)
			(xy 74.680318 -297.32478) (xy 75.019166 -297.32478) (xy 75.023126 -297.275726) (xy 75.034903 -297.227942)
			(xy 75.054194 -297.182666) (xy 75.080497 -297.14107) (xy 75.113132 -297.104233) (xy 75.151253 -297.073108)
			(xy 75.193874 -297.048501) (xy 75.23989 -297.031049) (xy 75.288109 -297.021205) (xy 75.337284 -297.019224)
			(xy 75.386139 -297.025156) (xy 75.43341 -297.038848) (xy 75.477872 -297.059946) (xy 75.518375 -297.087902)
			(xy 75.553868 -297.121994) (xy 75.583433 -297.161338) (xy 75.606304 -297.204915) (xy 75.621888 -297.251596)
			(xy 75.629783 -297.300173) (xy 75.630278 -297.32478) (xy 75.969126 -297.32478) (xy 75.973086 -297.275726)
			(xy 75.984863 -297.227942) (xy 76.004154 -297.182666) (xy 76.030457 -297.14107) (xy 76.063092 -297.104233)
			(xy 76.101213 -297.073108) (xy 76.143834 -297.048501) (xy 76.18985 -297.031049) (xy 76.238069 -297.021205)
			(xy 76.287244 -297.019224) (xy 76.336099 -297.025156) (xy 76.38337 -297.038848) (xy 76.427832 -297.059946)
			(xy 76.468335 -297.087902) (xy 76.503828 -297.121994) (xy 76.533393 -297.161338) (xy 76.556264 -297.204915)
			(xy 76.571848 -297.251596) (xy 76.579743 -297.300173) (xy 76.580238 -297.32478) (xy 76.919086 -297.32478)
			(xy 76.923046 -297.275726) (xy 76.934823 -297.227942) (xy 76.954114 -297.182666) (xy 76.980417 -297.14107)
			(xy 77.013052 -297.104233) (xy 77.051173 -297.073108) (xy 77.093794 -297.048501) (xy 77.13981 -297.031049)
			(xy 77.188029 -297.021205) (xy 77.237204 -297.019224) (xy 77.286059 -297.025156) (xy 77.33333 -297.038848)
			(xy 77.377792 -297.059946) (xy 77.418295 -297.087902) (xy 77.453788 -297.121994) (xy 77.483353 -297.161338)
			(xy 77.506224 -297.204915) (xy 77.521808 -297.251596) (xy 77.529703 -297.300173) (xy 77.530198 -297.32478)
			(xy 77.869046 -297.32478) (xy 77.873006 -297.275726) (xy 77.884783 -297.227942) (xy 77.904074 -297.182666)
			(xy 77.930377 -297.14107) (xy 77.963012 -297.104233) (xy 78.001133 -297.073108) (xy 78.043754 -297.048501)
			(xy 78.08977 -297.031049) (xy 78.137989 -297.021205) (xy 78.187164 -297.019224) (xy 78.236019 -297.025156)
			(xy 78.28329 -297.038848) (xy 78.327752 -297.059946) (xy 78.368255 -297.087902) (xy 78.403748 -297.121994)
			(xy 78.433313 -297.161338) (xy 78.456184 -297.204915) (xy 78.471768 -297.251596) (xy 78.479663 -297.300173)
			(xy 78.480158 -297.32478) (xy 78.819006 -297.32478) (xy 78.822966 -297.275726) (xy 78.834743 -297.227942)
			(xy 78.854034 -297.182666) (xy 78.880337 -297.14107) (xy 78.912972 -297.104233) (xy 78.951093 -297.073108)
			(xy 78.993714 -297.048501) (xy 79.03973 -297.031049) (xy 79.087949 -297.021205) (xy 79.137124 -297.019224)
			(xy 79.185979 -297.025156) (xy 79.23325 -297.038848) (xy 79.277712 -297.059946) (xy 79.318215 -297.087902)
			(xy 79.353708 -297.121994) (xy 79.383273 -297.161338) (xy 79.406144 -297.204915) (xy 79.421728 -297.251596)
			(xy 79.429623 -297.300173) (xy 79.430118 -297.32478) (xy 79.768966 -297.32478) (xy 79.772926 -297.275726)
			(xy 79.784703 -297.227942) (xy 79.803994 -297.182666) (xy 79.830297 -297.14107) (xy 79.862932 -297.104233)
			(xy 79.901053 -297.073108) (xy 79.943674 -297.048501) (xy 79.98969 -297.031049) (xy 80.037909 -297.021205)
			(xy 80.087084 -297.019224) (xy 80.135939 -297.025156) (xy 80.18321 -297.038848) (xy 80.227672 -297.059946)
			(xy 80.268175 -297.087902) (xy 80.303668 -297.121994) (xy 80.333233 -297.161338) (xy 80.356104 -297.204915)
			(xy 80.371688 -297.251596) (xy 80.379583 -297.300173) (xy 80.380078 -297.32478) (xy 80.71918 -297.32478)
			(xy 80.72314 -297.275726) (xy 80.734917 -297.227942) (xy 80.754208 -297.182666) (xy 80.780511 -297.14107)
			(xy 80.813146 -297.104233) (xy 80.851267 -297.073108) (xy 80.893888 -297.048501) (xy 80.939904 -297.031049)
			(xy 80.988123 -297.021205) (xy 81.037298 -297.019224) (xy 81.086153 -297.025156) (xy 81.133424 -297.038848)
			(xy 81.177886 -297.059946) (xy 81.218389 -297.087902) (xy 81.253882 -297.121994) (xy 81.283447 -297.161338)
			(xy 81.306318 -297.204915) (xy 81.321902 -297.251596) (xy 81.329797 -297.300173) (xy 81.330292 -297.32478)
			(xy 81.66914 -297.32478) (xy 81.6731 -297.275726) (xy 81.684877 -297.227942) (xy 81.704168 -297.182666)
			(xy 81.730471 -297.14107) (xy 81.763106 -297.104233) (xy 81.801227 -297.073108) (xy 81.843848 -297.048501)
			(xy 81.889864 -297.031049) (xy 81.938083 -297.021205) (xy 81.987258 -297.019224) (xy 82.036113 -297.025156)
			(xy 82.083384 -297.038848) (xy 82.127846 -297.059946) (xy 82.168349 -297.087902) (xy 82.203842 -297.121994)
			(xy 82.233407 -297.161338) (xy 82.256278 -297.204915) (xy 82.271862 -297.251596) (xy 82.279757 -297.300173)
			(xy 82.280252 -297.32478) (xy 82.6191 -297.32478) (xy 82.62306 -297.275726) (xy 82.634837 -297.227942)
			(xy 82.654128 -297.182666) (xy 82.680431 -297.14107) (xy 82.713066 -297.104233) (xy 82.751187 -297.073108)
			(xy 82.793808 -297.048501) (xy 82.839824 -297.031049) (xy 82.888043 -297.021205) (xy 82.937218 -297.019224)
			(xy 82.986073 -297.025156) (xy 83.033344 -297.038848) (xy 83.077806 -297.059946) (xy 83.118309 -297.087902)
			(xy 83.153802 -297.121994) (xy 83.183367 -297.161338) (xy 83.206238 -297.204915) (xy 83.221822 -297.251596)
			(xy 83.229717 -297.300173) (xy 83.230212 -297.32478) (xy 83.229717 -297.349387) (xy 83.221822 -297.397964)
			(xy 83.206238 -297.444645) (xy 83.183367 -297.488222) (xy 83.153802 -297.527566) (xy 83.118309 -297.561658)
			(xy 83.077806 -297.589614) (xy 83.033344 -297.610712) (xy 82.986073 -297.624404) (xy 82.937218 -297.630336)
			(xy 82.888043 -297.628355) (xy 82.839824 -297.618511) (xy 82.793808 -297.601059) (xy 82.751187 -297.576452)
			(xy 82.713066 -297.545327) (xy 82.680431 -297.50849) (xy 82.654128 -297.466894) (xy 82.634837 -297.421618)
			(xy 82.62306 -297.373834) (xy 82.6191 -297.32478) (xy 82.280252 -297.32478) (xy 82.279757 -297.349387)
			(xy 82.271862 -297.397964) (xy 82.256278 -297.444645) (xy 82.233407 -297.488222) (xy 82.203842 -297.527566)
			(xy 82.168349 -297.561658) (xy 82.127846 -297.589614) (xy 82.083384 -297.610712) (xy 82.036113 -297.624404)
			(xy 81.987258 -297.630336) (xy 81.938083 -297.628355) (xy 81.889864 -297.618511) (xy 81.843848 -297.601059)
			(xy 81.801227 -297.576452) (xy 81.763106 -297.545327) (xy 81.730471 -297.50849) (xy 81.704168 -297.466894)
			(xy 81.684877 -297.421618) (xy 81.6731 -297.373834) (xy 81.66914 -297.32478) (xy 81.330292 -297.32478)
			(xy 81.329797 -297.349387) (xy 81.321902 -297.397964) (xy 81.306318 -297.444645) (xy 81.283447 -297.488222)
			(xy 81.253882 -297.527566) (xy 81.218389 -297.561658) (xy 81.177886 -297.589614) (xy 81.133424 -297.610712)
			(xy 81.086153 -297.624404) (xy 81.037298 -297.630336) (xy 80.988123 -297.628355) (xy 80.939904 -297.618511)
			(xy 80.893888 -297.601059) (xy 80.851267 -297.576452) (xy 80.813146 -297.545327) (xy 80.780511 -297.50849)
			(xy 80.754208 -297.466894) (xy 80.734917 -297.421618) (xy 80.72314 -297.373834) (xy 80.71918 -297.32478)
			(xy 80.380078 -297.32478) (xy 80.379583 -297.349387) (xy 80.371688 -297.397964) (xy 80.356104 -297.444645)
			(xy 80.333233 -297.488222) (xy 80.303668 -297.527566) (xy 80.268175 -297.561658) (xy 80.227672 -297.589614)
			(xy 80.18321 -297.610712) (xy 80.135939 -297.624404) (xy 80.087084 -297.630336) (xy 80.037909 -297.628355)
			(xy 79.98969 -297.618511) (xy 79.943674 -297.601059) (xy 79.901053 -297.576452) (xy 79.862932 -297.545327)
			(xy 79.830297 -297.50849) (xy 79.803994 -297.466894) (xy 79.784703 -297.421618) (xy 79.772926 -297.373834)
			(xy 79.768966 -297.32478) (xy 79.430118 -297.32478) (xy 79.429623 -297.349387) (xy 79.421728 -297.397964)
			(xy 79.406144 -297.444645) (xy 79.383273 -297.488222) (xy 79.353708 -297.527566) (xy 79.318215 -297.561658)
			(xy 79.277712 -297.589614) (xy 79.23325 -297.610712) (xy 79.185979 -297.624404) (xy 79.137124 -297.630336)
			(xy 79.087949 -297.628355) (xy 79.03973 -297.618511) (xy 78.993714 -297.601059) (xy 78.951093 -297.576452)
			(xy 78.912972 -297.545327) (xy 78.880337 -297.50849) (xy 78.854034 -297.466894) (xy 78.834743 -297.421618)
			(xy 78.822966 -297.373834) (xy 78.819006 -297.32478) (xy 78.480158 -297.32478) (xy 78.479663 -297.349387)
			(xy 78.471768 -297.397964) (xy 78.456184 -297.444645) (xy 78.433313 -297.488222) (xy 78.403748 -297.527566)
			(xy 78.368255 -297.561658) (xy 78.327752 -297.589614) (xy 78.28329 -297.610712) (xy 78.236019 -297.624404)
			(xy 78.187164 -297.630336) (xy 78.137989 -297.628355) (xy 78.08977 -297.618511) (xy 78.043754 -297.601059)
			(xy 78.001133 -297.576452) (xy 77.963012 -297.545327) (xy 77.930377 -297.50849) (xy 77.904074 -297.466894)
			(xy 77.884783 -297.421618) (xy 77.873006 -297.373834) (xy 77.869046 -297.32478) (xy 77.530198 -297.32478)
			(xy 77.529703 -297.349387) (xy 77.521808 -297.397964) (xy 77.506224 -297.444645) (xy 77.483353 -297.488222)
			(xy 77.453788 -297.527566) (xy 77.418295 -297.561658) (xy 77.377792 -297.589614) (xy 77.33333 -297.610712)
			(xy 77.286059 -297.624404) (xy 77.237204 -297.630336) (xy 77.188029 -297.628355) (xy 77.13981 -297.618511)
			(xy 77.093794 -297.601059) (xy 77.051173 -297.576452) (xy 77.013052 -297.545327) (xy 76.980417 -297.50849)
			(xy 76.954114 -297.466894) (xy 76.934823 -297.421618) (xy 76.923046 -297.373834) (xy 76.919086 -297.32478)
			(xy 76.580238 -297.32478) (xy 76.579743 -297.349387) (xy 76.571848 -297.397964) (xy 76.556264 -297.444645)
			(xy 76.533393 -297.488222) (xy 76.503828 -297.527566) (xy 76.468335 -297.561658) (xy 76.427832 -297.589614)
			(xy 76.38337 -297.610712) (xy 76.336099 -297.624404) (xy 76.287244 -297.630336) (xy 76.238069 -297.628355)
			(xy 76.18985 -297.618511) (xy 76.143834 -297.601059) (xy 76.101213 -297.576452) (xy 76.063092 -297.545327)
			(xy 76.030457 -297.50849) (xy 76.004154 -297.466894) (xy 75.984863 -297.421618) (xy 75.973086 -297.373834)
			(xy 75.969126 -297.32478) (xy 75.630278 -297.32478) (xy 75.629783 -297.349387) (xy 75.621888 -297.397964)
			(xy 75.606304 -297.444645) (xy 75.583433 -297.488222) (xy 75.553868 -297.527566) (xy 75.518375 -297.561658)
			(xy 75.477872 -297.589614) (xy 75.43341 -297.610712) (xy 75.386139 -297.624404) (xy 75.337284 -297.630336)
			(xy 75.288109 -297.628355) (xy 75.23989 -297.618511) (xy 75.193874 -297.601059) (xy 75.151253 -297.576452)
			(xy 75.113132 -297.545327) (xy 75.080497 -297.50849) (xy 75.054194 -297.466894) (xy 75.034903 -297.421618)
			(xy 75.023126 -297.373834) (xy 75.019166 -297.32478) (xy 74.680318 -297.32478) (xy 74.679823 -297.349387)
			(xy 74.671928 -297.397964) (xy 74.656344 -297.444645) (xy 74.633473 -297.488222) (xy 74.603908 -297.527566)
			(xy 74.568415 -297.561658) (xy 74.527912 -297.589614) (xy 74.48345 -297.610712) (xy 74.436179 -297.624404)
			(xy 74.387324 -297.630336) (xy 74.338149 -297.628355) (xy 74.28993 -297.618511) (xy 74.243914 -297.601059)
			(xy 74.201293 -297.576452) (xy 74.163172 -297.545327) (xy 74.130537 -297.50849) (xy 74.104234 -297.466894)
			(xy 74.084943 -297.421618) (xy 74.073166 -297.373834) (xy 74.069206 -297.32478) (xy 73.730104 -297.32478)
			(xy 73.729609 -297.349387) (xy 73.721714 -297.397964) (xy 73.70613 -297.444645) (xy 73.683259 -297.488222)
			(xy 73.653694 -297.527566) (xy 73.618201 -297.561658) (xy 73.577698 -297.589614) (xy 73.533236 -297.610712)
			(xy 73.485965 -297.624404) (xy 73.43711 -297.630336) (xy 73.387935 -297.628355) (xy 73.339716 -297.618511)
			(xy 73.2937 -297.601059) (xy 73.251079 -297.576452) (xy 73.212958 -297.545327) (xy 73.180323 -297.50849)
			(xy 73.15402 -297.466894) (xy 73.134729 -297.421618) (xy 73.122952 -297.373834) (xy 73.118992 -297.32478)
			(xy 72.780144 -297.32478) (xy 72.779649 -297.349387) (xy 72.771754 -297.397964) (xy 72.75617 -297.444645)
			(xy 72.733299 -297.488222) (xy 72.703734 -297.527566) (xy 72.668241 -297.561658) (xy 72.627738 -297.589614)
			(xy 72.583276 -297.610712) (xy 72.536005 -297.624404) (xy 72.48715 -297.630336) (xy 72.437975 -297.628355)
			(xy 72.389756 -297.618511) (xy 72.34374 -297.601059) (xy 72.301119 -297.576452) (xy 72.262998 -297.545327)
			(xy 72.230363 -297.50849) (xy 72.20406 -297.466894) (xy 72.184769 -297.421618) (xy 72.172992 -297.373834)
			(xy 72.169032 -297.32478) (xy 71.830184 -297.32478) (xy 71.829689 -297.349387) (xy 71.821794 -297.397964)
			(xy 71.80621 -297.444645) (xy 71.783339 -297.488222) (xy 71.753774 -297.527566) (xy 71.718281 -297.561658)
			(xy 71.677778 -297.589614) (xy 71.633316 -297.610712) (xy 71.586045 -297.624404) (xy 71.53719 -297.630336)
			(xy 71.488015 -297.628355) (xy 71.439796 -297.618511) (xy 71.39378 -297.601059) (xy 71.351159 -297.576452)
			(xy 71.313038 -297.545327) (xy 71.280403 -297.50849) (xy 71.2541 -297.466894) (xy 71.234809 -297.421618)
			(xy 71.223032 -297.373834) (xy 71.219072 -297.32478) (xy 70.880224 -297.32478) (xy 70.879729 -297.349387)
			(xy 70.871834 -297.397964) (xy 70.85625 -297.444645) (xy 70.833379 -297.488222) (xy 70.803814 -297.527566)
			(xy 70.768321 -297.561658) (xy 70.727818 -297.589614) (xy 70.683356 -297.610712) (xy 70.636085 -297.624404)
			(xy 70.58723 -297.630336) (xy 70.538055 -297.628355) (xy 70.489836 -297.618511) (xy 70.44382 -297.601059)
			(xy 70.401199 -297.576452) (xy 70.363078 -297.545327) (xy 70.330443 -297.50849) (xy 70.30414 -297.466894)
			(xy 70.284849 -297.421618) (xy 70.273072 -297.373834) (xy 70.269112 -297.32478) (xy 69.930264 -297.32478)
			(xy 69.929769 -297.349387) (xy 69.921874 -297.397964) (xy 69.90629 -297.444645) (xy 69.883419 -297.488222)
			(xy 69.853854 -297.527566) (xy 69.818361 -297.561658) (xy 69.777858 -297.589614) (xy 69.733396 -297.610712)
			(xy 69.686125 -297.624404) (xy 69.63727 -297.630336) (xy 69.588095 -297.628355) (xy 69.539876 -297.618511)
			(xy 69.49386 -297.601059) (xy 69.451239 -297.576452) (xy 69.413118 -297.545327) (xy 69.380483 -297.50849)
			(xy 69.35418 -297.466894) (xy 69.334889 -297.421618) (xy 69.323112 -297.373834) (xy 69.319152 -297.32478)
			(xy 68.98005 -297.32478) (xy 68.979555 -297.349387) (xy 68.97166 -297.397964) (xy 68.956076 -297.444645)
			(xy 68.933205 -297.488222) (xy 68.90364 -297.527566) (xy 68.868147 -297.561658) (xy 68.827644 -297.589614)
			(xy 68.783182 -297.610712) (xy 68.735911 -297.624404) (xy 68.687056 -297.630336) (xy 68.637881 -297.628355)
			(xy 68.589662 -297.618511) (xy 68.543646 -297.601059) (xy 68.501025 -297.576452) (xy 68.462904 -297.545327)
			(xy 68.430269 -297.50849) (xy 68.403966 -297.466894) (xy 68.384675 -297.421618) (xy 68.372898 -297.373834)
			(xy 68.368938 -297.32478) (xy 68.03009 -297.32478) (xy 68.029595 -297.349387) (xy 68.0217 -297.397964)
			(xy 68.006116 -297.444645) (xy 67.983245 -297.488222) (xy 67.95368 -297.527566) (xy 67.918187 -297.561658)
			(xy 67.877684 -297.589614) (xy 67.833222 -297.610712) (xy 67.785951 -297.624404) (xy 67.737096 -297.630336)
			(xy 67.687921 -297.628355) (xy 67.639702 -297.618511) (xy 67.593686 -297.601059) (xy 67.551065 -297.576452)
			(xy 67.512944 -297.545327) (xy 67.480309 -297.50849) (xy 67.454006 -297.466894) (xy 67.434715 -297.421618)
			(xy 67.422938 -297.373834) (xy 67.418978 -297.32478) (xy 67.08013 -297.32478) (xy 67.079635 -297.349387)
			(xy 67.07174 -297.397964) (xy 67.056156 -297.444645) (xy 67.033285 -297.488222) (xy 67.00372 -297.527566)
			(xy 66.968227 -297.561658) (xy 66.927724 -297.589614) (xy 66.883262 -297.610712) (xy 66.835991 -297.624404)
			(xy 66.787136 -297.630336) (xy 66.737961 -297.628355) (xy 66.689742 -297.618511) (xy 66.643726 -297.601059)
			(xy 66.601105 -297.576452) (xy 66.562984 -297.545327) (xy 66.530349 -297.50849) (xy 66.504046 -297.466894)
			(xy 66.484755 -297.421618) (xy 66.472978 -297.373834) (xy 66.469018 -297.32478) (xy 66.13017 -297.32478)
			(xy 66.129675 -297.349387) (xy 66.12178 -297.397964) (xy 66.106196 -297.444645) (xy 66.083325 -297.488222)
			(xy 66.05376 -297.527566) (xy 66.018267 -297.561658) (xy 65.977764 -297.589614) (xy 65.933302 -297.610712)
			(xy 65.886031 -297.624404) (xy 65.837176 -297.630336) (xy 65.788001 -297.628355) (xy 65.739782 -297.618511)
			(xy 65.693766 -297.601059) (xy 65.651145 -297.576452) (xy 65.613024 -297.545327) (xy 65.580389 -297.50849)
			(xy 65.554086 -297.466894) (xy 65.534795 -297.421618) (xy 65.523018 -297.373834) (xy 65.519058 -297.32478)
			(xy 64.23025 -297.32478) (xy 64.229755 -297.349387) (xy 64.22186 -297.397964) (xy 64.206276 -297.444645)
			(xy 64.183405 -297.488222) (xy 64.15384 -297.527566) (xy 64.118347 -297.561658) (xy 64.077844 -297.589614)
			(xy 64.033382 -297.610712) (xy 63.986111 -297.624404) (xy 63.937256 -297.630336) (xy 63.888081 -297.628355)
			(xy 63.839862 -297.618511) (xy 63.793846 -297.601059) (xy 63.751225 -297.576452) (xy 63.713104 -297.545327)
			(xy 63.680469 -297.50849) (xy 63.654166 -297.466894) (xy 63.634875 -297.421618) (xy 63.623098 -297.373834)
			(xy 63.619138 -297.32478) (xy 62.330076 -297.32478) (xy 62.329581 -297.349387) (xy 62.321686 -297.397964)
			(xy 62.306102 -297.444645) (xy 62.283231 -297.488222) (xy 62.253666 -297.527566) (xy 62.218173 -297.561658)
			(xy 62.17767 -297.589614) (xy 62.133208 -297.610712) (xy 62.085937 -297.624404) (xy 62.037082 -297.630336)
			(xy 61.987907 -297.628355) (xy 61.939688 -297.618511) (xy 61.893672 -297.601059) (xy 61.851051 -297.576452)
			(xy 61.81293 -297.545327) (xy 61.780295 -297.50849) (xy 61.753992 -297.466894) (xy 61.734701 -297.421618)
			(xy 61.722924 -297.373834) (xy 61.718964 -297.32478) (xy 60.430156 -297.32478) (xy 60.429661 -297.349387)
			(xy 60.421766 -297.397964) (xy 60.406182 -297.444645) (xy 60.383311 -297.488222) (xy 60.353746 -297.527566)
			(xy 60.318253 -297.561658) (xy 60.27775 -297.589614) (xy 60.233288 -297.610712) (xy 60.186017 -297.624404)
			(xy 60.137162 -297.630336) (xy 60.087987 -297.628355) (xy 60.039768 -297.618511) (xy 59.993752 -297.601059)
			(xy 59.951131 -297.576452) (xy 59.91301 -297.545327) (xy 59.880375 -297.50849) (xy 59.854072 -297.466894)
			(xy 59.834781 -297.421618) (xy 59.823004 -297.373834) (xy 59.819044 -297.32478) (xy 57.580276 -297.32478)
			(xy 57.579781 -297.349387) (xy 57.571886 -297.397964) (xy 57.556302 -297.444645) (xy 57.533431 -297.488222)
			(xy 57.503866 -297.527566) (xy 57.468373 -297.561658) (xy 57.42787 -297.589614) (xy 57.383408 -297.610712)
			(xy 57.336137 -297.624404) (xy 57.287282 -297.630336) (xy 57.238107 -297.628355) (xy 57.189888 -297.618511)
			(xy 57.143872 -297.601059) (xy 57.101251 -297.576452) (xy 57.06313 -297.545327) (xy 57.030495 -297.50849)
			(xy 57.004192 -297.466894) (xy 56.984901 -297.421618) (xy 56.973124 -297.373834) (xy 56.969164 -297.32478)
			(xy 55.680102 -297.32478) (xy 55.679607 -297.349387) (xy 55.671712 -297.397964) (xy 55.656128 -297.444645)
			(xy 55.633257 -297.488222) (xy 55.603692 -297.527566) (xy 55.568199 -297.561658) (xy 55.527696 -297.589614)
			(xy 55.483234 -297.610712) (xy 55.435963 -297.624404) (xy 55.387108 -297.630336) (xy 55.337933 -297.628355)
			(xy 55.289714 -297.618511) (xy 55.243698 -297.601059) (xy 55.201077 -297.576452) (xy 55.162956 -297.545327)
			(xy 55.130321 -297.50849) (xy 55.104018 -297.466894) (xy 55.084727 -297.421618) (xy 55.07295 -297.373834)
			(xy 55.06899 -297.32478) (xy 53.780182 -297.32478) (xy 53.779687 -297.349387) (xy 53.771792 -297.397964)
			(xy 53.756208 -297.444645) (xy 53.733337 -297.488222) (xy 53.703772 -297.527566) (xy 53.668279 -297.561658)
			(xy 53.627776 -297.589614) (xy 53.583314 -297.610712) (xy 53.536043 -297.624404) (xy 53.487188 -297.630336)
			(xy 53.438013 -297.628355) (xy 53.389794 -297.618511) (xy 53.343778 -297.601059) (xy 53.301157 -297.576452)
			(xy 53.263036 -297.545327) (xy 53.230401 -297.50849) (xy 53.204098 -297.466894) (xy 53.184807 -297.421618)
			(xy 53.17303 -297.373834) (xy 53.16907 -297.32478) (xy 51.880262 -297.32478) (xy 51.879767 -297.349387)
			(xy 51.871872 -297.397964) (xy 51.856288 -297.444645) (xy 51.833417 -297.488222) (xy 51.803852 -297.527566)
			(xy 51.768359 -297.561658) (xy 51.727856 -297.589614) (xy 51.683394 -297.610712) (xy 51.636123 -297.624404)
			(xy 51.587268 -297.630336) (xy 51.538093 -297.628355) (xy 51.489874 -297.618511) (xy 51.443858 -297.601059)
			(xy 51.401237 -297.576452) (xy 51.363116 -297.545327) (xy 51.330481 -297.50849) (xy 51.304178 -297.466894)
			(xy 51.284887 -297.421618) (xy 51.27311 -297.373834) (xy 51.26915 -297.32478) (xy 49.980088 -297.32478)
			(xy 49.979593 -297.349387) (xy 49.971698 -297.397964) (xy 49.956114 -297.444645) (xy 49.933243 -297.488222)
			(xy 49.903678 -297.527566) (xy 49.868185 -297.561658) (xy 49.827682 -297.589614) (xy 49.78322 -297.610712)
			(xy 49.735949 -297.624404) (xy 49.687094 -297.630336) (xy 49.637919 -297.628355) (xy 49.5897 -297.618511)
			(xy 49.543684 -297.601059) (xy 49.501063 -297.576452) (xy 49.462942 -297.545327) (xy 49.430307 -297.50849)
			(xy 49.404004 -297.466894) (xy 49.384713 -297.421618) (xy 49.372936 -297.373834) (xy 49.368976 -297.32478)
			(xy 48.080168 -297.32478) (xy 48.079914 -297.335194) (xy 48.079914 -297.341544) (xy 48.07966 -297.346116)
			(xy 48.07966 -297.346878) (xy 48.078434 -297.361278) (xy 48.073595 -297.389774) (xy 48.070008 -297.403774)
			(xy 48.06823 -297.410378) (xy 48.06823 -297.426888) (xy 48.068771 -297.438424) (xy 48.078815 -297.459194)
			(xy 48.087534 -297.466766) (xy 48.090582 -297.469052) (xy 48.10506 -297.479974) (xy 48.12792 -297.497246)
			(xy 48.146404 -297.511752) (xy 48.179108 -297.545485) (xy 48.206254 -297.583834) (xy 48.227201 -297.62589)
			(xy 48.241454 -297.67066) (xy 48.248675 -297.717086) (xy 48.249078 -297.740578) (xy 48.249078 -297.95851)
			(xy 84.756242 -297.95851) (xy 84.760313 -297.902888) (xy 84.772439 -297.848451) (xy 84.792362 -297.79636)
			(xy 84.819658 -297.747725) (xy 84.853744 -297.703582) (xy 84.893893 -297.664873) (xy 84.939251 -297.632422)
			(xy 84.988851 -297.606921) (xy 85.041635 -297.588914) (xy 85.096478 -297.578784) (xy 85.152212 -297.576747)
			(xy 85.207649 -297.582847) (xy 85.261606 -297.596953) (xy 85.312935 -297.618765) (xy 85.360541 -297.647819)
			(xy 85.395394 -297.676824) (xy 86.299546 -297.676824) (xy 86.303617 -297.621202) (xy 86.315743 -297.566765)
			(xy 86.335666 -297.514674) (xy 86.362962 -297.466039) (xy 86.397048 -297.421896) (xy 86.437197 -297.383187)
			(xy 86.482555 -297.350736) (xy 86.532155 -297.325235) (xy 86.584939 -297.307228) (xy 86.639782 -297.297098)
			(xy 86.695516 -297.295061) (xy 86.750953 -297.301161) (xy 86.80491 -297.315267) (xy 86.856239 -297.337079)
			(xy 86.903845 -297.366133) (xy 86.914281 -297.374818) (xy 92.615764 -297.374818) (xy 92.619835 -297.319196)
			(xy 92.631961 -297.264759) (xy 92.651884 -297.212668) (xy 92.67918 -297.164033) (xy 92.713266 -297.11989)
			(xy 92.753415 -297.081181) (xy 92.798773 -297.04873) (xy 92.848373 -297.023229) (xy 92.901157 -297.005222)
			(xy 92.956 -296.995092) (xy 93.011734 -296.993055) (xy 93.067171 -296.999155) (xy 93.121128 -297.013261)
			(xy 93.172457 -297.035073) (xy 93.220063 -297.064127) (xy 93.262931 -297.099802) (xy 93.300148 -297.141339)
			(xy 93.330921 -297.187852) (xy 93.354593 -297.238349) (xy 93.370661 -297.291756) (xy 93.378781 -297.346932)
			(xy 93.37929 -297.374818) (xy 93.378781 -297.402704) (xy 93.370661 -297.45788) (xy 93.354593 -297.511287)
			(xy 93.330921 -297.561784) (xy 93.300148 -297.608297) (xy 93.262931 -297.649834) (xy 93.220063 -297.685509)
			(xy 93.172457 -297.714563) (xy 93.121128 -297.736375) (xy 93.067171 -297.750481) (xy 93.011734 -297.756581)
			(xy 92.956 -297.754544) (xy 92.901157 -297.744414) (xy 92.848373 -297.726407) (xy 92.798773 -297.700906)
			(xy 92.753415 -297.668455) (xy 92.713266 -297.629746) (xy 92.67918 -297.585603) (xy 92.651884 -297.536968)
			(xy 92.631961 -297.484877) (xy 92.619835 -297.43044) (xy 92.615764 -297.374818) (xy 86.914281 -297.374818)
			(xy 86.946713 -297.401808) (xy 86.98393 -297.443345) (xy 87.014703 -297.489858) (xy 87.038375 -297.540355)
			(xy 87.054443 -297.593762) (xy 87.062563 -297.648938) (xy 87.063072 -297.676824) (xy 87.062563 -297.70471)
			(xy 87.054443 -297.759886) (xy 87.038375 -297.813293) (xy 87.014703 -297.86379) (xy 86.98393 -297.910303)
			(xy 86.946713 -297.95184) (xy 86.903845 -297.987515) (xy 86.856239 -298.016569) (xy 86.80491 -298.038381)
			(xy 86.750953 -298.052487) (xy 86.695516 -298.058587) (xy 86.639782 -298.05655) (xy 86.584939 -298.04642)
			(xy 86.532155 -298.028413) (xy 86.482555 -298.002912) (xy 86.437197 -297.970461) (xy 86.397048 -297.931752)
			(xy 86.362962 -297.887609) (xy 86.335666 -297.838974) (xy 86.315743 -297.786883) (xy 86.303617 -297.732446)
			(xy 86.299546 -297.676824) (xy 85.395394 -297.676824) (xy 85.403409 -297.683494) (xy 85.440626 -297.725031)
			(xy 85.471399 -297.771544) (xy 85.495071 -297.822041) (xy 85.511139 -297.875448) (xy 85.519259 -297.930624)
			(xy 85.519768 -297.95851) (xy 85.519259 -297.986396) (xy 85.511139 -298.041572) (xy 85.495071 -298.094979)
			(xy 85.471399 -298.145476) (xy 85.440626 -298.191989) (xy 85.403409 -298.233526) (xy 85.360541 -298.269201)
			(xy 85.312935 -298.298255) (xy 85.261606 -298.320067) (xy 85.207649 -298.334173) (xy 85.152212 -298.340273)
			(xy 85.096478 -298.338236) (xy 85.041635 -298.328106) (xy 84.988851 -298.310099) (xy 84.939251 -298.284598)
			(xy 84.893893 -298.252147) (xy 84.853744 -298.213438) (xy 84.819658 -298.169295) (xy 84.792362 -298.12066)
			(xy 84.772439 -298.068569) (xy 84.760313 -298.014132) (xy 84.756242 -297.95851) (xy 48.249078 -297.95851)
			(xy 48.249078 -298.27474) (xy 48.419016 -298.27474) (xy 48.422976 -298.225686) (xy 48.434753 -298.177902)
			(xy 48.454044 -298.132626) (xy 48.480347 -298.09103) (xy 48.512982 -298.054193) (xy 48.551103 -298.023068)
			(xy 48.593724 -297.998461) (xy 48.63974 -297.981009) (xy 48.687959 -297.971165) (xy 48.737134 -297.969184)
			(xy 48.785989 -297.975116) (xy 48.83326 -297.988808) (xy 48.877722 -298.009906) (xy 48.918225 -298.037862)
			(xy 48.953718 -298.071954) (xy 48.983283 -298.111298) (xy 49.006154 -298.154875) (xy 49.021738 -298.201556)
			(xy 49.029633 -298.250133) (xy 49.030128 -298.27474) (xy 50.31919 -298.27474) (xy 50.32315 -298.225686)
			(xy 50.334927 -298.177902) (xy 50.354218 -298.132626) (xy 50.380521 -298.09103) (xy 50.413156 -298.054193)
			(xy 50.451277 -298.023068) (xy 50.493898 -297.998461) (xy 50.539914 -297.981009) (xy 50.588133 -297.971165)
			(xy 50.637308 -297.969184) (xy 50.686163 -297.975116) (xy 50.733434 -297.988808) (xy 50.777896 -298.009906)
			(xy 50.818399 -298.037862) (xy 50.853892 -298.071954) (xy 50.883457 -298.111298) (xy 50.906328 -298.154875)
			(xy 50.921912 -298.201556) (xy 50.929807 -298.250133) (xy 50.930302 -298.27474) (xy 52.21911 -298.27474)
			(xy 52.22307 -298.225686) (xy 52.234847 -298.177902) (xy 52.254138 -298.132626) (xy 52.280441 -298.09103)
			(xy 52.313076 -298.054193) (xy 52.351197 -298.023068) (xy 52.393818 -297.998461) (xy 52.439834 -297.981009)
			(xy 52.488053 -297.971165) (xy 52.537228 -297.969184) (xy 52.586083 -297.975116) (xy 52.633354 -297.988808)
			(xy 52.677816 -298.009906) (xy 52.718319 -298.037862) (xy 52.753812 -298.071954) (xy 52.783377 -298.111298)
			(xy 52.806248 -298.154875) (xy 52.821832 -298.201556) (xy 52.829727 -298.250133) (xy 52.830222 -298.27474)
			(xy 54.11903 -298.27474) (xy 54.12299 -298.225686) (xy 54.134767 -298.177902) (xy 54.154058 -298.132626)
			(xy 54.180361 -298.09103) (xy 54.212996 -298.054193) (xy 54.251117 -298.023068) (xy 54.293738 -297.998461)
			(xy 54.339754 -297.981009) (xy 54.387973 -297.971165) (xy 54.437148 -297.969184) (xy 54.486003 -297.975116)
			(xy 54.533274 -297.988808) (xy 54.577736 -298.009906) (xy 54.618239 -298.037862) (xy 54.653732 -298.071954)
			(xy 54.683297 -298.111298) (xy 54.706168 -298.154875) (xy 54.721752 -298.201556) (xy 54.729647 -298.250133)
			(xy 54.730142 -298.27474) (xy 56.01895 -298.27474) (xy 56.02291 -298.225686) (xy 56.034687 -298.177902)
			(xy 56.053978 -298.132626) (xy 56.080281 -298.09103) (xy 56.112916 -298.054193) (xy 56.151037 -298.023068)
			(xy 56.193658 -297.998461) (xy 56.239674 -297.981009) (xy 56.287893 -297.971165) (xy 56.337068 -297.969184)
			(xy 56.385923 -297.975116) (xy 56.433194 -297.988808) (xy 56.477656 -298.009906) (xy 56.518159 -298.037862)
			(xy 56.553652 -298.071954) (xy 56.583217 -298.111298) (xy 56.606088 -298.154875) (xy 56.621672 -298.201556)
			(xy 56.629567 -298.250133) (xy 56.630062 -298.27474) (xy 57.919124 -298.27474) (xy 57.923084 -298.225686)
			(xy 57.934861 -298.177902) (xy 57.954152 -298.132626) (xy 57.980455 -298.09103) (xy 58.01309 -298.054193)
			(xy 58.051211 -298.023068) (xy 58.093832 -297.998461) (xy 58.139848 -297.981009) (xy 58.188067 -297.971165)
			(xy 58.237242 -297.969184) (xy 58.286097 -297.975116) (xy 58.333368 -297.988808) (xy 58.37783 -298.009906)
			(xy 58.418333 -298.037862) (xy 58.453826 -298.071954) (xy 58.483391 -298.111298) (xy 58.506262 -298.154875)
			(xy 58.521846 -298.201556) (xy 58.529741 -298.250133) (xy 58.530236 -298.27474) (xy 60.769004 -298.27474)
			(xy 60.772964 -298.225686) (xy 60.784741 -298.177902) (xy 60.804032 -298.132626) (xy 60.830335 -298.09103)
			(xy 60.86297 -298.054193) (xy 60.901091 -298.023068) (xy 60.943712 -297.998461) (xy 60.989728 -297.981009)
			(xy 61.037947 -297.971165) (xy 61.087122 -297.969184) (xy 61.135977 -297.975116) (xy 61.183248 -297.988808)
			(xy 61.22771 -298.009906) (xy 61.268213 -298.037862) (xy 61.303706 -298.071954) (xy 61.333271 -298.111298)
			(xy 61.356142 -298.154875) (xy 61.371726 -298.201556) (xy 61.379621 -298.250133) (xy 61.380116 -298.27474)
			(xy 62.669178 -298.27474) (xy 62.673138 -298.225686) (xy 62.684915 -298.177902) (xy 62.704206 -298.132626)
			(xy 62.730509 -298.09103) (xy 62.763144 -298.054193) (xy 62.801265 -298.023068) (xy 62.843886 -297.998461)
			(xy 62.889902 -297.981009) (xy 62.938121 -297.971165) (xy 62.987296 -297.969184) (xy 63.036151 -297.975116)
			(xy 63.083422 -297.988808) (xy 63.127884 -298.009906) (xy 63.168387 -298.037862) (xy 63.20388 -298.071954)
			(xy 63.233445 -298.111298) (xy 63.256316 -298.154875) (xy 63.2719 -298.201556) (xy 63.279795 -298.250133)
			(xy 63.28029 -298.27474) (xy 64.569098 -298.27474) (xy 64.573058 -298.225686) (xy 64.584835 -298.177902)
			(xy 64.604126 -298.132626) (xy 64.630429 -298.09103) (xy 64.663064 -298.054193) (xy 64.701185 -298.023068)
			(xy 64.743806 -297.998461) (xy 64.789822 -297.981009) (xy 64.838041 -297.971165) (xy 64.887216 -297.969184)
			(xy 64.936071 -297.975116) (xy 64.983342 -297.988808) (xy 65.027804 -298.009906) (xy 65.068307 -298.037862)
			(xy 65.1038 -298.071954) (xy 65.133365 -298.111298) (xy 65.156236 -298.154875) (xy 65.17182 -298.201556)
			(xy 65.179715 -298.250133) (xy 65.18021 -298.27474) (xy 66.469018 -298.27474) (xy 66.472978 -298.225686)
			(xy 66.484755 -298.177902) (xy 66.504046 -298.132626) (xy 66.530349 -298.09103) (xy 66.562984 -298.054193)
			(xy 66.601105 -298.023068) (xy 66.643726 -297.998461) (xy 66.689742 -297.981009) (xy 66.737961 -297.971165)
			(xy 66.787136 -297.969184) (xy 66.835991 -297.975116) (xy 66.883262 -297.988808) (xy 66.927724 -298.009906)
			(xy 66.968227 -298.037862) (xy 67.00372 -298.071954) (xy 67.033285 -298.111298) (xy 67.056156 -298.154875)
			(xy 67.07174 -298.201556) (xy 67.079635 -298.250133) (xy 67.08013 -298.27474) (xy 68.368938 -298.27474)
			(xy 68.372898 -298.225686) (xy 68.384675 -298.177902) (xy 68.403966 -298.132626) (xy 68.430269 -298.09103)
			(xy 68.462904 -298.054193) (xy 68.501025 -298.023068) (xy 68.543646 -297.998461) (xy 68.589662 -297.981009)
			(xy 68.637881 -297.971165) (xy 68.687056 -297.969184) (xy 68.735911 -297.975116) (xy 68.783182 -297.988808)
			(xy 68.827644 -298.009906) (xy 68.868147 -298.037862) (xy 68.90364 -298.071954) (xy 68.933205 -298.111298)
			(xy 68.956076 -298.154875) (xy 68.97166 -298.201556) (xy 68.979555 -298.250133) (xy 68.98005 -298.27474)
			(xy 69.319152 -298.27474) (xy 69.323112 -298.225686) (xy 69.334889 -298.177902) (xy 69.35418 -298.132626)
			(xy 69.380483 -298.09103) (xy 69.413118 -298.054193) (xy 69.451239 -298.023068) (xy 69.49386 -297.998461)
			(xy 69.539876 -297.981009) (xy 69.588095 -297.971165) (xy 69.63727 -297.969184) (xy 69.686125 -297.975116)
			(xy 69.733396 -297.988808) (xy 69.777858 -298.009906) (xy 69.818361 -298.037862) (xy 69.853854 -298.071954)
			(xy 69.883419 -298.111298) (xy 69.90629 -298.154875) (xy 69.921874 -298.201556) (xy 69.929769 -298.250133)
			(xy 69.930264 -298.27474) (xy 70.269112 -298.27474) (xy 70.273072 -298.225686) (xy 70.284849 -298.177902)
			(xy 70.30414 -298.132626) (xy 70.330443 -298.09103) (xy 70.363078 -298.054193) (xy 70.401199 -298.023068)
			(xy 70.44382 -297.998461) (xy 70.489836 -297.981009) (xy 70.538055 -297.971165) (xy 70.58723 -297.969184)
			(xy 70.636085 -297.975116) (xy 70.683356 -297.988808) (xy 70.727818 -298.009906) (xy 70.768321 -298.037862)
			(xy 70.803814 -298.071954) (xy 70.833379 -298.111298) (xy 70.85625 -298.154875) (xy 70.871834 -298.201556)
			(xy 70.879729 -298.250133) (xy 70.880224 -298.27474) (xy 71.219072 -298.27474) (xy 71.223032 -298.225686)
			(xy 71.234809 -298.177902) (xy 71.2541 -298.132626) (xy 71.280403 -298.09103) (xy 71.313038 -298.054193)
			(xy 71.351159 -298.023068) (xy 71.39378 -297.998461) (xy 71.439796 -297.981009) (xy 71.488015 -297.971165)
			(xy 71.53719 -297.969184) (xy 71.586045 -297.975116) (xy 71.633316 -297.988808) (xy 71.677778 -298.009906)
			(xy 71.718281 -298.037862) (xy 71.753774 -298.071954) (xy 71.783339 -298.111298) (xy 71.80621 -298.154875)
			(xy 71.821794 -298.201556) (xy 71.829689 -298.250133) (xy 71.830184 -298.27474) (xy 72.169032 -298.27474)
			(xy 72.172992 -298.225686) (xy 72.184769 -298.177902) (xy 72.20406 -298.132626) (xy 72.230363 -298.09103)
			(xy 72.262998 -298.054193) (xy 72.301119 -298.023068) (xy 72.34374 -297.998461) (xy 72.389756 -297.981009)
			(xy 72.437975 -297.971165) (xy 72.48715 -297.969184) (xy 72.536005 -297.975116) (xy 72.583276 -297.988808)
			(xy 72.627738 -298.009906) (xy 72.668241 -298.037862) (xy 72.703734 -298.071954) (xy 72.733299 -298.111298)
			(xy 72.75617 -298.154875) (xy 72.771754 -298.201556) (xy 72.779649 -298.250133) (xy 72.780144 -298.27474)
			(xy 73.118992 -298.27474) (xy 73.122952 -298.225686) (xy 73.134729 -298.177902) (xy 73.15402 -298.132626)
			(xy 73.180323 -298.09103) (xy 73.212958 -298.054193) (xy 73.251079 -298.023068) (xy 73.2937 -297.998461)
			(xy 73.339716 -297.981009) (xy 73.387935 -297.971165) (xy 73.43711 -297.969184) (xy 73.485965 -297.975116)
			(xy 73.533236 -297.988808) (xy 73.577698 -298.009906) (xy 73.618201 -298.037862) (xy 73.653694 -298.071954)
			(xy 73.683259 -298.111298) (xy 73.70613 -298.154875) (xy 73.721714 -298.201556) (xy 73.729609 -298.250133)
			(xy 73.730104 -298.27474) (xy 74.068952 -298.27474) (xy 74.072912 -298.225686) (xy 74.084689 -298.177902)
			(xy 74.10398 -298.132626) (xy 74.130283 -298.09103) (xy 74.162918 -298.054193) (xy 74.201039 -298.023068)
			(xy 74.24366 -297.998461) (xy 74.289676 -297.981009) (xy 74.337895 -297.971165) (xy 74.38707 -297.969184)
			(xy 74.435925 -297.975116) (xy 74.483196 -297.988808) (xy 74.527658 -298.009906) (xy 74.568161 -298.037862)
			(xy 74.603654 -298.071954) (xy 74.633219 -298.111298) (xy 74.65609 -298.154875) (xy 74.671674 -298.201556)
			(xy 74.679569 -298.250133) (xy 74.680064 -298.27474) (xy 75.019166 -298.27474) (xy 75.023126 -298.225686)
			(xy 75.034903 -298.177902) (xy 75.054194 -298.132626) (xy 75.080497 -298.09103) (xy 75.113132 -298.054193)
			(xy 75.151253 -298.023068) (xy 75.193874 -297.998461) (xy 75.23989 -297.981009) (xy 75.288109 -297.971165)
			(xy 75.337284 -297.969184) (xy 75.386139 -297.975116) (xy 75.43341 -297.988808) (xy 75.477872 -298.009906)
			(xy 75.518375 -298.037862) (xy 75.553868 -298.071954) (xy 75.583433 -298.111298) (xy 75.606304 -298.154875)
			(xy 75.621888 -298.201556) (xy 75.629783 -298.250133) (xy 75.630278 -298.27474) (xy 75.969126 -298.27474)
			(xy 75.973086 -298.225686) (xy 75.984863 -298.177902) (xy 76.004154 -298.132626) (xy 76.030457 -298.09103)
			(xy 76.063092 -298.054193) (xy 76.101213 -298.023068) (xy 76.143834 -297.998461) (xy 76.18985 -297.981009)
			(xy 76.238069 -297.971165) (xy 76.287244 -297.969184) (xy 76.336099 -297.975116) (xy 76.38337 -297.988808)
			(xy 76.427832 -298.009906) (xy 76.468335 -298.037862) (xy 76.503828 -298.071954) (xy 76.533393 -298.111298)
			(xy 76.556264 -298.154875) (xy 76.571848 -298.201556) (xy 76.579743 -298.250133) (xy 76.580238 -298.27474)
			(xy 76.919086 -298.27474) (xy 76.923046 -298.225686) (xy 76.934823 -298.177902) (xy 76.954114 -298.132626)
			(xy 76.980417 -298.09103) (xy 77.013052 -298.054193) (xy 77.051173 -298.023068) (xy 77.093794 -297.998461)
			(xy 77.13981 -297.981009) (xy 77.188029 -297.971165) (xy 77.237204 -297.969184) (xy 77.286059 -297.975116)
			(xy 77.33333 -297.988808) (xy 77.377792 -298.009906) (xy 77.418295 -298.037862) (xy 77.453788 -298.071954)
			(xy 77.483353 -298.111298) (xy 77.506224 -298.154875) (xy 77.521808 -298.201556) (xy 77.529703 -298.250133)
			(xy 77.530198 -298.27474) (xy 77.869046 -298.27474) (xy 77.873006 -298.225686) (xy 77.884783 -298.177902)
			(xy 77.904074 -298.132626) (xy 77.930377 -298.09103) (xy 77.963012 -298.054193) (xy 78.001133 -298.023068)
			(xy 78.043754 -297.998461) (xy 78.08977 -297.981009) (xy 78.137989 -297.971165) (xy 78.187164 -297.969184)
			(xy 78.236019 -297.975116) (xy 78.28329 -297.988808) (xy 78.327752 -298.009906) (xy 78.368255 -298.037862)
			(xy 78.403748 -298.071954) (xy 78.433313 -298.111298) (xy 78.456184 -298.154875) (xy 78.471768 -298.201556)
			(xy 78.479663 -298.250133) (xy 78.480158 -298.27474) (xy 78.819006 -298.27474) (xy 78.822966 -298.225686)
			(xy 78.834743 -298.177902) (xy 78.854034 -298.132626) (xy 78.880337 -298.09103) (xy 78.912972 -298.054193)
			(xy 78.951093 -298.023068) (xy 78.993714 -297.998461) (xy 79.03973 -297.981009) (xy 79.087949 -297.971165)
			(xy 79.137124 -297.969184) (xy 79.185979 -297.975116) (xy 79.23325 -297.988808) (xy 79.277712 -298.009906)
			(xy 79.318215 -298.037862) (xy 79.353708 -298.071954) (xy 79.383273 -298.111298) (xy 79.406144 -298.154875)
			(xy 79.421728 -298.201556) (xy 79.429623 -298.250133) (xy 79.430118 -298.27474) (xy 79.768966 -298.27474)
			(xy 79.772926 -298.225686) (xy 79.784703 -298.177902) (xy 79.803994 -298.132626) (xy 79.830297 -298.09103)
			(xy 79.862932 -298.054193) (xy 79.901053 -298.023068) (xy 79.943674 -297.998461) (xy 79.98969 -297.981009)
			(xy 80.037909 -297.971165) (xy 80.087084 -297.969184) (xy 80.135939 -297.975116) (xy 80.18321 -297.988808)
			(xy 80.227672 -298.009906) (xy 80.268175 -298.037862) (xy 80.303668 -298.071954) (xy 80.333233 -298.111298)
			(xy 80.356104 -298.154875) (xy 80.371688 -298.201556) (xy 80.379583 -298.250133) (xy 80.380078 -298.27474)
			(xy 80.71918 -298.27474) (xy 80.72314 -298.225686) (xy 80.734917 -298.177902) (xy 80.754208 -298.132626)
			(xy 80.780511 -298.09103) (xy 80.813146 -298.054193) (xy 80.851267 -298.023068) (xy 80.893888 -297.998461)
			(xy 80.939904 -297.981009) (xy 80.988123 -297.971165) (xy 81.037298 -297.969184) (xy 81.086153 -297.975116)
			(xy 81.133424 -297.988808) (xy 81.177886 -298.009906) (xy 81.218389 -298.037862) (xy 81.253882 -298.071954)
			(xy 81.283447 -298.111298) (xy 81.306318 -298.154875) (xy 81.321902 -298.201556) (xy 81.329797 -298.250133)
			(xy 81.330292 -298.27474) (xy 81.66914 -298.27474) (xy 81.6731 -298.225686) (xy 81.684877 -298.177902)
			(xy 81.704168 -298.132626) (xy 81.730471 -298.09103) (xy 81.763106 -298.054193) (xy 81.801227 -298.023068)
			(xy 81.843848 -297.998461) (xy 81.889864 -297.981009) (xy 81.938083 -297.971165) (xy 81.987258 -297.969184)
			(xy 82.036113 -297.975116) (xy 82.083384 -297.988808) (xy 82.127846 -298.009906) (xy 82.168349 -298.037862)
			(xy 82.203842 -298.071954) (xy 82.233407 -298.111298) (xy 82.256278 -298.154875) (xy 82.271862 -298.201556)
			(xy 82.279757 -298.250133) (xy 82.280252 -298.27474) (xy 82.6191 -298.27474) (xy 82.62306 -298.225686)
			(xy 82.634837 -298.177902) (xy 82.654128 -298.132626) (xy 82.680431 -298.09103) (xy 82.713066 -298.054193)
			(xy 82.751187 -298.023068) (xy 82.793808 -297.998461) (xy 82.839824 -297.981009) (xy 82.888043 -297.971165)
			(xy 82.937218 -297.969184) (xy 82.986073 -297.975116) (xy 83.033344 -297.988808) (xy 83.077806 -298.009906)
			(xy 83.118309 -298.037862) (xy 83.153802 -298.071954) (xy 83.183367 -298.111298) (xy 83.206238 -298.154875)
			(xy 83.221822 -298.201556) (xy 83.229717 -298.250133) (xy 83.230212 -298.27474) (xy 83.229717 -298.299347)
			(xy 83.221822 -298.347924) (xy 83.221246 -298.349649) (xy 83.66759 -298.349649) (xy 83.66759 -298.296351)
			(xy 83.675533 -298.243647) (xy 83.691243 -298.192717) (xy 83.714369 -298.144696) (xy 83.744393 -298.100659)
			(xy 83.780645 -298.061588) (xy 83.822316 -298.028357) (xy 83.868474 -298.001708) (xy 83.918088 -297.982236)
			(xy 83.97005 -297.970376) (xy 84.0232 -297.966393) (xy 84.07635 -297.970376) (xy 84.128312 -297.982236)
			(xy 84.177926 -298.001708) (xy 84.224084 -298.028357) (xy 84.265755 -298.061588) (xy 84.302007 -298.100659)
			(xy 84.332031 -298.144696) (xy 84.355157 -298.192717) (xy 84.370867 -298.243647) (xy 84.37881 -298.296351)
			(xy 84.379308 -298.323) (xy 84.37881 -298.349649) (xy 84.370867 -298.402353) (xy 84.355157 -298.453283)
			(xy 84.332031 -298.501304) (xy 84.302007 -298.545341) (xy 84.265755 -298.584412) (xy 84.224084 -298.617643)
			(xy 84.177926 -298.644292) (xy 84.128312 -298.663764) (xy 84.07635 -298.675624) (xy 84.0232 -298.679608)
			(xy 83.97005 -298.675624) (xy 83.918088 -298.663764) (xy 83.868474 -298.644292) (xy 83.822316 -298.617643)
			(xy 83.780645 -298.584412) (xy 83.744393 -298.545341) (xy 83.714369 -298.501304) (xy 83.691243 -298.453283)
			(xy 83.675533 -298.402353) (xy 83.66759 -298.349649) (xy 83.221246 -298.349649) (xy 83.206238 -298.394605)
			(xy 83.183367 -298.438182) (xy 83.153802 -298.477526) (xy 83.118309 -298.511618) (xy 83.077806 -298.539574)
			(xy 83.033344 -298.560672) (xy 82.986073 -298.574364) (xy 82.937218 -298.580296) (xy 82.888043 -298.578315)
			(xy 82.839824 -298.568471) (xy 82.793808 -298.551019) (xy 82.751187 -298.526412) (xy 82.713066 -298.495287)
			(xy 82.680431 -298.45845) (xy 82.654128 -298.416854) (xy 82.634837 -298.371578) (xy 82.62306 -298.323794)
			(xy 82.6191 -298.27474) (xy 82.280252 -298.27474) (xy 82.279757 -298.299347) (xy 82.271862 -298.347924)
			(xy 82.256278 -298.394605) (xy 82.233407 -298.438182) (xy 82.203842 -298.477526) (xy 82.168349 -298.511618)
			(xy 82.127846 -298.539574) (xy 82.083384 -298.560672) (xy 82.036113 -298.574364) (xy 81.987258 -298.580296)
			(xy 81.938083 -298.578315) (xy 81.889864 -298.568471) (xy 81.843848 -298.551019) (xy 81.801227 -298.526412)
			(xy 81.763106 -298.495287) (xy 81.730471 -298.45845) (xy 81.704168 -298.416854) (xy 81.684877 -298.371578)
			(xy 81.6731 -298.323794) (xy 81.66914 -298.27474) (xy 81.330292 -298.27474) (xy 81.329797 -298.299347)
			(xy 81.321902 -298.347924) (xy 81.306318 -298.394605) (xy 81.283447 -298.438182) (xy 81.253882 -298.477526)
			(xy 81.218389 -298.511618) (xy 81.177886 -298.539574) (xy 81.133424 -298.560672) (xy 81.086153 -298.574364)
			(xy 81.037298 -298.580296) (xy 80.988123 -298.578315) (xy 80.939904 -298.568471) (xy 80.893888 -298.551019)
			(xy 80.851267 -298.526412) (xy 80.813146 -298.495287) (xy 80.780511 -298.45845) (xy 80.754208 -298.416854)
			(xy 80.734917 -298.371578) (xy 80.72314 -298.323794) (xy 80.71918 -298.27474) (xy 80.380078 -298.27474)
			(xy 80.379583 -298.299347) (xy 80.371688 -298.347924) (xy 80.356104 -298.394605) (xy 80.333233 -298.438182)
			(xy 80.303668 -298.477526) (xy 80.268175 -298.511618) (xy 80.227672 -298.539574) (xy 80.18321 -298.560672)
			(xy 80.135939 -298.574364) (xy 80.087084 -298.580296) (xy 80.037909 -298.578315) (xy 79.98969 -298.568471)
			(xy 79.943674 -298.551019) (xy 79.901053 -298.526412) (xy 79.862932 -298.495287) (xy 79.830297 -298.45845)
			(xy 79.803994 -298.416854) (xy 79.784703 -298.371578) (xy 79.772926 -298.323794) (xy 79.768966 -298.27474)
			(xy 79.430118 -298.27474) (xy 79.429623 -298.299347) (xy 79.421728 -298.347924) (xy 79.406144 -298.394605)
			(xy 79.383273 -298.438182) (xy 79.353708 -298.477526) (xy 79.318215 -298.511618) (xy 79.277712 -298.539574)
			(xy 79.23325 -298.560672) (xy 79.185979 -298.574364) (xy 79.137124 -298.580296) (xy 79.087949 -298.578315)
			(xy 79.03973 -298.568471) (xy 78.993714 -298.551019) (xy 78.951093 -298.526412) (xy 78.912972 -298.495287)
			(xy 78.880337 -298.45845) (xy 78.854034 -298.416854) (xy 78.834743 -298.371578) (xy 78.822966 -298.323794)
			(xy 78.819006 -298.27474) (xy 78.480158 -298.27474) (xy 78.479663 -298.299347) (xy 78.471768 -298.347924)
			(xy 78.456184 -298.394605) (xy 78.433313 -298.438182) (xy 78.403748 -298.477526) (xy 78.368255 -298.511618)
			(xy 78.327752 -298.539574) (xy 78.28329 -298.560672) (xy 78.236019 -298.574364) (xy 78.187164 -298.580296)
			(xy 78.137989 -298.578315) (xy 78.08977 -298.568471) (xy 78.043754 -298.551019) (xy 78.001133 -298.526412)
			(xy 77.963012 -298.495287) (xy 77.930377 -298.45845) (xy 77.904074 -298.416854) (xy 77.884783 -298.371578)
			(xy 77.873006 -298.323794) (xy 77.869046 -298.27474) (xy 77.530198 -298.27474) (xy 77.529703 -298.299347)
			(xy 77.521808 -298.347924) (xy 77.506224 -298.394605) (xy 77.483353 -298.438182) (xy 77.453788 -298.477526)
			(xy 77.418295 -298.511618) (xy 77.377792 -298.539574) (xy 77.33333 -298.560672) (xy 77.286059 -298.574364)
			(xy 77.237204 -298.580296) (xy 77.188029 -298.578315) (xy 77.13981 -298.568471) (xy 77.093794 -298.551019)
			(xy 77.051173 -298.526412) (xy 77.013052 -298.495287) (xy 76.980417 -298.45845) (xy 76.954114 -298.416854)
			(xy 76.934823 -298.371578) (xy 76.923046 -298.323794) (xy 76.919086 -298.27474) (xy 76.580238 -298.27474)
			(xy 76.579743 -298.299347) (xy 76.571848 -298.347924) (xy 76.556264 -298.394605) (xy 76.533393 -298.438182)
			(xy 76.503828 -298.477526) (xy 76.468335 -298.511618) (xy 76.427832 -298.539574) (xy 76.38337 -298.560672)
			(xy 76.336099 -298.574364) (xy 76.287244 -298.580296) (xy 76.238069 -298.578315) (xy 76.18985 -298.568471)
			(xy 76.143834 -298.551019) (xy 76.101213 -298.526412) (xy 76.063092 -298.495287) (xy 76.030457 -298.45845)
			(xy 76.004154 -298.416854) (xy 75.984863 -298.371578) (xy 75.973086 -298.323794) (xy 75.969126 -298.27474)
			(xy 75.630278 -298.27474) (xy 75.629783 -298.299347) (xy 75.621888 -298.347924) (xy 75.606304 -298.394605)
			(xy 75.583433 -298.438182) (xy 75.553868 -298.477526) (xy 75.518375 -298.511618) (xy 75.477872 -298.539574)
			(xy 75.43341 -298.560672) (xy 75.386139 -298.574364) (xy 75.337284 -298.580296) (xy 75.288109 -298.578315)
			(xy 75.23989 -298.568471) (xy 75.193874 -298.551019) (xy 75.151253 -298.526412) (xy 75.113132 -298.495287)
			(xy 75.080497 -298.45845) (xy 75.054194 -298.416854) (xy 75.034903 -298.371578) (xy 75.023126 -298.323794)
			(xy 75.019166 -298.27474) (xy 74.680064 -298.27474) (xy 74.679569 -298.299347) (xy 74.671674 -298.347924)
			(xy 74.65609 -298.394605) (xy 74.633219 -298.438182) (xy 74.603654 -298.477526) (xy 74.568161 -298.511618)
			(xy 74.527658 -298.539574) (xy 74.483196 -298.560672) (xy 74.435925 -298.574364) (xy 74.38707 -298.580296)
			(xy 74.337895 -298.578315) (xy 74.289676 -298.568471) (xy 74.24366 -298.551019) (xy 74.201039 -298.526412)
			(xy 74.162918 -298.495287) (xy 74.130283 -298.45845) (xy 74.10398 -298.416854) (xy 74.084689 -298.371578)
			(xy 74.072912 -298.323794) (xy 74.068952 -298.27474) (xy 73.730104 -298.27474) (xy 73.729609 -298.299347)
			(xy 73.721714 -298.347924) (xy 73.70613 -298.394605) (xy 73.683259 -298.438182) (xy 73.653694 -298.477526)
			(xy 73.618201 -298.511618) (xy 73.577698 -298.539574) (xy 73.533236 -298.560672) (xy 73.485965 -298.574364)
			(xy 73.43711 -298.580296) (xy 73.387935 -298.578315) (xy 73.339716 -298.568471) (xy 73.2937 -298.551019)
			(xy 73.251079 -298.526412) (xy 73.212958 -298.495287) (xy 73.180323 -298.45845) (xy 73.15402 -298.416854)
			(xy 73.134729 -298.371578) (xy 73.122952 -298.323794) (xy 73.118992 -298.27474) (xy 72.780144 -298.27474)
			(xy 72.779649 -298.299347) (xy 72.771754 -298.347924) (xy 72.75617 -298.394605) (xy 72.733299 -298.438182)
			(xy 72.703734 -298.477526) (xy 72.668241 -298.511618) (xy 72.627738 -298.539574) (xy 72.583276 -298.560672)
			(xy 72.536005 -298.574364) (xy 72.48715 -298.580296) (xy 72.437975 -298.578315) (xy 72.389756 -298.568471)
			(xy 72.34374 -298.551019) (xy 72.301119 -298.526412) (xy 72.262998 -298.495287) (xy 72.230363 -298.45845)
			(xy 72.20406 -298.416854) (xy 72.184769 -298.371578) (xy 72.172992 -298.323794) (xy 72.169032 -298.27474)
			(xy 71.830184 -298.27474) (xy 71.829689 -298.299347) (xy 71.821794 -298.347924) (xy 71.80621 -298.394605)
			(xy 71.783339 -298.438182) (xy 71.753774 -298.477526) (xy 71.718281 -298.511618) (xy 71.677778 -298.539574)
			(xy 71.633316 -298.560672) (xy 71.586045 -298.574364) (xy 71.53719 -298.580296) (xy 71.488015 -298.578315)
			(xy 71.439796 -298.568471) (xy 71.39378 -298.551019) (xy 71.351159 -298.526412) (xy 71.313038 -298.495287)
			(xy 71.280403 -298.45845) (xy 71.2541 -298.416854) (xy 71.234809 -298.371578) (xy 71.223032 -298.323794)
			(xy 71.219072 -298.27474) (xy 70.880224 -298.27474) (xy 70.879729 -298.299347) (xy 70.871834 -298.347924)
			(xy 70.85625 -298.394605) (xy 70.833379 -298.438182) (xy 70.803814 -298.477526) (xy 70.768321 -298.511618)
			(xy 70.727818 -298.539574) (xy 70.683356 -298.560672) (xy 70.636085 -298.574364) (xy 70.58723 -298.580296)
			(xy 70.538055 -298.578315) (xy 70.489836 -298.568471) (xy 70.44382 -298.551019) (xy 70.401199 -298.526412)
			(xy 70.363078 -298.495287) (xy 70.330443 -298.45845) (xy 70.30414 -298.416854) (xy 70.284849 -298.371578)
			(xy 70.273072 -298.323794) (xy 70.269112 -298.27474) (xy 69.930264 -298.27474) (xy 69.929769 -298.299347)
			(xy 69.921874 -298.347924) (xy 69.90629 -298.394605) (xy 69.883419 -298.438182) (xy 69.853854 -298.477526)
			(xy 69.818361 -298.511618) (xy 69.777858 -298.539574) (xy 69.733396 -298.560672) (xy 69.686125 -298.574364)
			(xy 69.63727 -298.580296) (xy 69.588095 -298.578315) (xy 69.539876 -298.568471) (xy 69.49386 -298.551019)
			(xy 69.451239 -298.526412) (xy 69.413118 -298.495287) (xy 69.380483 -298.45845) (xy 69.35418 -298.416854)
			(xy 69.334889 -298.371578) (xy 69.323112 -298.323794) (xy 69.319152 -298.27474) (xy 68.98005 -298.27474)
			(xy 68.979555 -298.299347) (xy 68.97166 -298.347924) (xy 68.956076 -298.394605) (xy 68.933205 -298.438182)
			(xy 68.90364 -298.477526) (xy 68.868147 -298.511618) (xy 68.827644 -298.539574) (xy 68.783182 -298.560672)
			(xy 68.735911 -298.574364) (xy 68.687056 -298.580296) (xy 68.637881 -298.578315) (xy 68.589662 -298.568471)
			(xy 68.543646 -298.551019) (xy 68.501025 -298.526412) (xy 68.462904 -298.495287) (xy 68.430269 -298.45845)
			(xy 68.403966 -298.416854) (xy 68.384675 -298.371578) (xy 68.372898 -298.323794) (xy 68.368938 -298.27474)
			(xy 67.08013 -298.27474) (xy 67.079635 -298.299347) (xy 67.07174 -298.347924) (xy 67.056156 -298.394605)
			(xy 67.033285 -298.438182) (xy 67.00372 -298.477526) (xy 66.968227 -298.511618) (xy 66.927724 -298.539574)
			(xy 66.883262 -298.560672) (xy 66.835991 -298.574364) (xy 66.787136 -298.580296) (xy 66.737961 -298.578315)
			(xy 66.689742 -298.568471) (xy 66.643726 -298.551019) (xy 66.601105 -298.526412) (xy 66.562984 -298.495287)
			(xy 66.530349 -298.45845) (xy 66.504046 -298.416854) (xy 66.484755 -298.371578) (xy 66.472978 -298.323794)
			(xy 66.469018 -298.27474) (xy 65.18021 -298.27474) (xy 65.179715 -298.299347) (xy 65.17182 -298.347924)
			(xy 65.156236 -298.394605) (xy 65.133365 -298.438182) (xy 65.1038 -298.477526) (xy 65.068307 -298.511618)
			(xy 65.027804 -298.539574) (xy 64.983342 -298.560672) (xy 64.936071 -298.574364) (xy 64.887216 -298.580296)
			(xy 64.838041 -298.578315) (xy 64.789822 -298.568471) (xy 64.743806 -298.551019) (xy 64.701185 -298.526412)
			(xy 64.663064 -298.495287) (xy 64.630429 -298.45845) (xy 64.604126 -298.416854) (xy 64.584835 -298.371578)
			(xy 64.573058 -298.323794) (xy 64.569098 -298.27474) (xy 63.28029 -298.27474) (xy 63.279795 -298.299347)
			(xy 63.2719 -298.347924) (xy 63.256316 -298.394605) (xy 63.233445 -298.438182) (xy 63.20388 -298.477526)
			(xy 63.168387 -298.511618) (xy 63.127884 -298.539574) (xy 63.083422 -298.560672) (xy 63.036151 -298.574364)
			(xy 62.987296 -298.580296) (xy 62.938121 -298.578315) (xy 62.889902 -298.568471) (xy 62.843886 -298.551019)
			(xy 62.801265 -298.526412) (xy 62.763144 -298.495287) (xy 62.730509 -298.45845) (xy 62.704206 -298.416854)
			(xy 62.684915 -298.371578) (xy 62.673138 -298.323794) (xy 62.669178 -298.27474) (xy 61.380116 -298.27474)
			(xy 61.379621 -298.299347) (xy 61.371726 -298.347924) (xy 61.356142 -298.394605) (xy 61.333271 -298.438182)
			(xy 61.303706 -298.477526) (xy 61.268213 -298.511618) (xy 61.22771 -298.539574) (xy 61.183248 -298.560672)
			(xy 61.135977 -298.574364) (xy 61.087122 -298.580296) (xy 61.037947 -298.578315) (xy 60.989728 -298.568471)
			(xy 60.943712 -298.551019) (xy 60.901091 -298.526412) (xy 60.86297 -298.495287) (xy 60.830335 -298.45845)
			(xy 60.804032 -298.416854) (xy 60.784741 -298.371578) (xy 60.772964 -298.323794) (xy 60.769004 -298.27474)
			(xy 58.530236 -298.27474) (xy 58.529741 -298.299347) (xy 58.521846 -298.347924) (xy 58.506262 -298.394605)
			(xy 58.483391 -298.438182) (xy 58.453826 -298.477526) (xy 58.418333 -298.511618) (xy 58.37783 -298.539574)
			(xy 58.333368 -298.560672) (xy 58.286097 -298.574364) (xy 58.237242 -298.580296) (xy 58.188067 -298.578315)
			(xy 58.139848 -298.568471) (xy 58.093832 -298.551019) (xy 58.051211 -298.526412) (xy 58.01309 -298.495287)
			(xy 57.980455 -298.45845) (xy 57.954152 -298.416854) (xy 57.934861 -298.371578) (xy 57.923084 -298.323794)
			(xy 57.919124 -298.27474) (xy 56.630062 -298.27474) (xy 56.629567 -298.299347) (xy 56.621672 -298.347924)
			(xy 56.606088 -298.394605) (xy 56.583217 -298.438182) (xy 56.553652 -298.477526) (xy 56.518159 -298.511618)
			(xy 56.477656 -298.539574) (xy 56.433194 -298.560672) (xy 56.385923 -298.574364) (xy 56.337068 -298.580296)
			(xy 56.287893 -298.578315) (xy 56.239674 -298.568471) (xy 56.193658 -298.551019) (xy 56.151037 -298.526412)
			(xy 56.112916 -298.495287) (xy 56.080281 -298.45845) (xy 56.053978 -298.416854) (xy 56.034687 -298.371578)
			(xy 56.02291 -298.323794) (xy 56.01895 -298.27474) (xy 54.730142 -298.27474) (xy 54.729647 -298.299347)
			(xy 54.721752 -298.347924) (xy 54.706168 -298.394605) (xy 54.683297 -298.438182) (xy 54.653732 -298.477526)
			(xy 54.618239 -298.511618) (xy 54.577736 -298.539574) (xy 54.533274 -298.560672) (xy 54.486003 -298.574364)
			(xy 54.437148 -298.580296) (xy 54.387973 -298.578315) (xy 54.339754 -298.568471) (xy 54.293738 -298.551019)
			(xy 54.251117 -298.526412) (xy 54.212996 -298.495287) (xy 54.180361 -298.45845) (xy 54.154058 -298.416854)
			(xy 54.134767 -298.371578) (xy 54.12299 -298.323794) (xy 54.11903 -298.27474) (xy 52.830222 -298.27474)
			(xy 52.829727 -298.299347) (xy 52.821832 -298.347924) (xy 52.806248 -298.394605) (xy 52.783377 -298.438182)
			(xy 52.753812 -298.477526) (xy 52.718319 -298.511618) (xy 52.677816 -298.539574) (xy 52.633354 -298.560672)
			(xy 52.586083 -298.574364) (xy 52.537228 -298.580296) (xy 52.488053 -298.578315) (xy 52.439834 -298.568471)
			(xy 52.393818 -298.551019) (xy 52.351197 -298.526412) (xy 52.313076 -298.495287) (xy 52.280441 -298.45845)
			(xy 52.254138 -298.416854) (xy 52.234847 -298.371578) (xy 52.22307 -298.323794) (xy 52.21911 -298.27474)
			(xy 50.930302 -298.27474) (xy 50.929807 -298.299347) (xy 50.921912 -298.347924) (xy 50.906328 -298.394605)
			(xy 50.883457 -298.438182) (xy 50.853892 -298.477526) (xy 50.818399 -298.511618) (xy 50.777896 -298.539574)
			(xy 50.733434 -298.560672) (xy 50.686163 -298.574364) (xy 50.637308 -298.580296) (xy 50.588133 -298.578315)
			(xy 50.539914 -298.568471) (xy 50.493898 -298.551019) (xy 50.451277 -298.526412) (xy 50.413156 -298.495287)
			(xy 50.380521 -298.45845) (xy 50.354218 -298.416854) (xy 50.334927 -298.371578) (xy 50.32315 -298.323794)
			(xy 50.31919 -298.27474) (xy 49.030128 -298.27474) (xy 49.029633 -298.299347) (xy 49.021738 -298.347924)
			(xy 49.006154 -298.394605) (xy 48.983283 -298.438182) (xy 48.953718 -298.477526) (xy 48.918225 -298.511618)
			(xy 48.877722 -298.539574) (xy 48.83326 -298.560672) (xy 48.785989 -298.574364) (xy 48.737134 -298.580296)
			(xy 48.687959 -298.578315) (xy 48.63974 -298.568471) (xy 48.593724 -298.551019) (xy 48.551103 -298.526412)
			(xy 48.512982 -298.495287) (xy 48.480347 -298.45845) (xy 48.454044 -298.416854) (xy 48.434753 -298.371578)
			(xy 48.422976 -298.323794) (xy 48.419016 -298.27474) (xy 48.249078 -298.27474) (xy 48.249078 -298.7294)
			(xy 86.488268 -298.7294) (xy 86.492339 -298.673778) (xy 86.504465 -298.619341) (xy 86.524388 -298.56725)
			(xy 86.551684 -298.518615) (xy 86.58577 -298.474472) (xy 86.625919 -298.435763) (xy 86.671277 -298.403312)
			(xy 86.720877 -298.377811) (xy 86.773661 -298.359804) (xy 86.828504 -298.349674) (xy 86.884238 -298.347637)
			(xy 86.939675 -298.353737) (xy 86.993632 -298.367843) (xy 87.044961 -298.389655) (xy 87.092567 -298.418709)
			(xy 87.135435 -298.454384) (xy 87.172652 -298.495921) (xy 87.203425 -298.542434) (xy 87.227097 -298.592931)
			(xy 87.243165 -298.646338) (xy 87.251285 -298.701514) (xy 87.251794 -298.7294) (xy 87.251285 -298.757286)
			(xy 87.243165 -298.812462) (xy 87.227097 -298.865869) (xy 87.203425 -298.916366) (xy 87.172652 -298.962879)
			(xy 87.135435 -299.004416) (xy 87.092567 -299.040091) (xy 87.044961 -299.069145) (xy 86.993632 -299.090957)
			(xy 86.939675 -299.105063) (xy 86.884238 -299.111163) (xy 86.828504 -299.109126) (xy 86.773661 -299.098996)
			(xy 86.720877 -299.080989) (xy 86.671277 -299.055488) (xy 86.625919 -299.023037) (xy 86.58577 -298.984328)
			(xy 86.551684 -298.940185) (xy 86.524388 -298.89155) (xy 86.504465 -298.839459) (xy 86.492339 -298.785022)
			(xy 86.488268 -298.7294) (xy 48.249078 -298.7294) (xy 48.249078 -298.809156) (xy 48.248621 -298.832642)
			(xy 48.241378 -298.879054) (xy 48.227119 -298.923811) (xy 48.206178 -298.965858) (xy 48.17905 -299.004206)
			(xy 48.146372 -299.03795) (xy 48.12792 -299.052488) (xy 48.11268 -299.063918) (xy 48.112172 -299.06468)
			(xy 48.092614 -299.078904) (xy 48.086518 -299.083984) (xy 48.083216 -299.087286) (xy 48.076381 -299.094688)
			(xy 48.068676 -299.113287) (xy 48.06823 -299.123354) (xy 48.06823 -299.133514) (xy 48.070008 -299.146722)
			(xy 48.07077 -299.14977) (xy 48.075168 -299.168254) (xy 48.079879 -299.205956) (xy 48.080168 -299.224954)
			(xy 49.368976 -299.224954) (xy 49.372936 -299.1759) (xy 49.384713 -299.128116) (xy 49.404004 -299.08284)
			(xy 49.430307 -299.041244) (xy 49.462942 -299.004407) (xy 49.501063 -298.973282) (xy 49.543684 -298.948675)
			(xy 49.5897 -298.931223) (xy 49.637919 -298.921379) (xy 49.687094 -298.919398) (xy 49.735949 -298.92533)
			(xy 49.78322 -298.939022) (xy 49.827682 -298.96012) (xy 49.868185 -298.988076) (xy 49.903678 -299.022168)
			(xy 49.933243 -299.061512) (xy 49.956114 -299.105089) (xy 49.971698 -299.15177) (xy 49.979593 -299.200347)
			(xy 49.980088 -299.224954) (xy 50.31919 -299.224954) (xy 50.32315 -299.1759) (xy 50.334927 -299.128116)
			(xy 50.354218 -299.08284) (xy 50.380521 -299.041244) (xy 50.413156 -299.004407) (xy 50.451277 -298.973282)
			(xy 50.493898 -298.948675) (xy 50.539914 -298.931223) (xy 50.588133 -298.921379) (xy 50.637308 -298.919398)
			(xy 50.686163 -298.92533) (xy 50.733434 -298.939022) (xy 50.777896 -298.96012) (xy 50.818399 -298.988076)
			(xy 50.853892 -299.022168) (xy 50.883457 -299.061512) (xy 50.906328 -299.105089) (xy 50.921912 -299.15177)
			(xy 50.929807 -299.200347) (xy 50.930302 -299.224954) (xy 51.26915 -299.224954) (xy 51.27311 -299.1759)
			(xy 51.284887 -299.128116) (xy 51.304178 -299.08284) (xy 51.330481 -299.041244) (xy 51.363116 -299.004407)
			(xy 51.401237 -298.973282) (xy 51.443858 -298.948675) (xy 51.489874 -298.931223) (xy 51.538093 -298.921379)
			(xy 51.587268 -298.919398) (xy 51.636123 -298.92533) (xy 51.683394 -298.939022) (xy 51.727856 -298.96012)
			(xy 51.768359 -298.988076) (xy 51.803852 -299.022168) (xy 51.833417 -299.061512) (xy 51.856288 -299.105089)
			(xy 51.871872 -299.15177) (xy 51.879767 -299.200347) (xy 51.880262 -299.224954) (xy 52.21911 -299.224954)
			(xy 52.22307 -299.1759) (xy 52.234847 -299.128116) (xy 52.254138 -299.08284) (xy 52.280441 -299.041244)
			(xy 52.313076 -299.004407) (xy 52.351197 -298.973282) (xy 52.393818 -298.948675) (xy 52.439834 -298.931223)
			(xy 52.488053 -298.921379) (xy 52.537228 -298.919398) (xy 52.586083 -298.92533) (xy 52.633354 -298.939022)
			(xy 52.677816 -298.96012) (xy 52.718319 -298.988076) (xy 52.753812 -299.022168) (xy 52.783377 -299.061512)
			(xy 52.806248 -299.105089) (xy 52.821832 -299.15177) (xy 52.829727 -299.200347) (xy 52.830222 -299.224954)
			(xy 53.16907 -299.224954) (xy 53.17303 -299.1759) (xy 53.184807 -299.128116) (xy 53.204098 -299.08284)
			(xy 53.230401 -299.041244) (xy 53.263036 -299.004407) (xy 53.301157 -298.973282) (xy 53.343778 -298.948675)
			(xy 53.389794 -298.931223) (xy 53.438013 -298.921379) (xy 53.487188 -298.919398) (xy 53.536043 -298.92533)
			(xy 53.583314 -298.939022) (xy 53.627776 -298.96012) (xy 53.668279 -298.988076) (xy 53.703772 -299.022168)
			(xy 53.733337 -299.061512) (xy 53.756208 -299.105089) (xy 53.771792 -299.15177) (xy 53.779687 -299.200347)
			(xy 53.780182 -299.224954) (xy 54.11903 -299.224954) (xy 54.12299 -299.1759) (xy 54.134767 -299.128116)
			(xy 54.154058 -299.08284) (xy 54.180361 -299.041244) (xy 54.212996 -299.004407) (xy 54.251117 -298.973282)
			(xy 54.293738 -298.948675) (xy 54.339754 -298.931223) (xy 54.387973 -298.921379) (xy 54.437148 -298.919398)
			(xy 54.486003 -298.92533) (xy 54.533274 -298.939022) (xy 54.577736 -298.96012) (xy 54.618239 -298.988076)
			(xy 54.653732 -299.022168) (xy 54.683297 -299.061512) (xy 54.706168 -299.105089) (xy 54.721752 -299.15177)
			(xy 54.729647 -299.200347) (xy 54.730142 -299.224954) (xy 55.06899 -299.224954) (xy 55.07295 -299.1759)
			(xy 55.084727 -299.128116) (xy 55.104018 -299.08284) (xy 55.130321 -299.041244) (xy 55.162956 -299.004407)
			(xy 55.201077 -298.973282) (xy 55.243698 -298.948675) (xy 55.289714 -298.931223) (xy 55.337933 -298.921379)
			(xy 55.387108 -298.919398) (xy 55.435963 -298.92533) (xy 55.483234 -298.939022) (xy 55.527696 -298.96012)
			(xy 55.568199 -298.988076) (xy 55.603692 -299.022168) (xy 55.633257 -299.061512) (xy 55.656128 -299.105089)
			(xy 55.671712 -299.15177) (xy 55.679607 -299.200347) (xy 55.680102 -299.224954) (xy 56.01895 -299.224954)
			(xy 56.02291 -299.1759) (xy 56.034687 -299.128116) (xy 56.053978 -299.08284) (xy 56.080281 -299.041244)
			(xy 56.112916 -299.004407) (xy 56.151037 -298.973282) (xy 56.193658 -298.948675) (xy 56.239674 -298.931223)
			(xy 56.287893 -298.921379) (xy 56.337068 -298.919398) (xy 56.385923 -298.92533) (xy 56.433194 -298.939022)
			(xy 56.477656 -298.96012) (xy 56.518159 -298.988076) (xy 56.553652 -299.022168) (xy 56.583217 -299.061512)
			(xy 56.606088 -299.105089) (xy 56.621672 -299.15177) (xy 56.629567 -299.200347) (xy 56.630062 -299.224954)
			(xy 56.969164 -299.224954) (xy 56.973124 -299.1759) (xy 56.984901 -299.128116) (xy 57.004192 -299.08284)
			(xy 57.030495 -299.041244) (xy 57.06313 -299.004407) (xy 57.101251 -298.973282) (xy 57.143872 -298.948675)
			(xy 57.189888 -298.931223) (xy 57.238107 -298.921379) (xy 57.287282 -298.919398) (xy 57.336137 -298.92533)
			(xy 57.383408 -298.939022) (xy 57.42787 -298.96012) (xy 57.468373 -298.988076) (xy 57.503866 -299.022168)
			(xy 57.533431 -299.061512) (xy 57.556302 -299.105089) (xy 57.571886 -299.15177) (xy 57.579781 -299.200347)
			(xy 57.580276 -299.224954) (xy 57.919124 -299.224954) (xy 57.923084 -299.1759) (xy 57.934861 -299.128116)
			(xy 57.954152 -299.08284) (xy 57.980455 -299.041244) (xy 58.01309 -299.004407) (xy 58.051211 -298.973282)
			(xy 58.093832 -298.948675) (xy 58.139848 -298.931223) (xy 58.188067 -298.921379) (xy 58.237242 -298.919398)
			(xy 58.286097 -298.92533) (xy 58.333368 -298.939022) (xy 58.37783 -298.96012) (xy 58.418333 -298.988076)
			(xy 58.453826 -299.022168) (xy 58.483391 -299.061512) (xy 58.506262 -299.105089) (xy 58.521846 -299.15177)
			(xy 58.529741 -299.200347) (xy 58.530236 -299.224954) (xy 59.819044 -299.224954) (xy 59.823004 -299.1759)
			(xy 59.834781 -299.128116) (xy 59.854072 -299.08284) (xy 59.880375 -299.041244) (xy 59.91301 -299.004407)
			(xy 59.951131 -298.973282) (xy 59.993752 -298.948675) (xy 60.039768 -298.931223) (xy 60.087987 -298.921379)
			(xy 60.137162 -298.919398) (xy 60.186017 -298.92533) (xy 60.233288 -298.939022) (xy 60.27775 -298.96012)
			(xy 60.318253 -298.988076) (xy 60.353746 -299.022168) (xy 60.383311 -299.061512) (xy 60.406182 -299.105089)
			(xy 60.421766 -299.15177) (xy 60.429661 -299.200347) (xy 60.430156 -299.224954) (xy 60.769004 -299.224954)
			(xy 60.772964 -299.1759) (xy 60.784741 -299.128116) (xy 60.804032 -299.08284) (xy 60.830335 -299.041244)
			(xy 60.86297 -299.004407) (xy 60.901091 -298.973282) (xy 60.943712 -298.948675) (xy 60.989728 -298.931223)
			(xy 61.037947 -298.921379) (xy 61.087122 -298.919398) (xy 61.135977 -298.92533) (xy 61.183248 -298.939022)
			(xy 61.22771 -298.96012) (xy 61.268213 -298.988076) (xy 61.303706 -299.022168) (xy 61.333271 -299.061512)
			(xy 61.356142 -299.105089) (xy 61.371726 -299.15177) (xy 61.379621 -299.200347) (xy 61.380116 -299.224954)
			(xy 61.718964 -299.224954) (xy 61.722924 -299.1759) (xy 61.734701 -299.128116) (xy 61.753992 -299.08284)
			(xy 61.780295 -299.041244) (xy 61.81293 -299.004407) (xy 61.851051 -298.973282) (xy 61.893672 -298.948675)
			(xy 61.939688 -298.931223) (xy 61.987907 -298.921379) (xy 62.037082 -298.919398) (xy 62.085937 -298.92533)
			(xy 62.133208 -298.939022) (xy 62.17767 -298.96012) (xy 62.218173 -298.988076) (xy 62.253666 -299.022168)
			(xy 62.283231 -299.061512) (xy 62.306102 -299.105089) (xy 62.321686 -299.15177) (xy 62.329581 -299.200347)
			(xy 62.330076 -299.224954) (xy 62.669178 -299.224954) (xy 62.673138 -299.1759) (xy 62.684915 -299.128116)
			(xy 62.704206 -299.08284) (xy 62.730509 -299.041244) (xy 62.763144 -299.004407) (xy 62.801265 -298.973282)
			(xy 62.843886 -298.948675) (xy 62.889902 -298.931223) (xy 62.938121 -298.921379) (xy 62.987296 -298.919398)
			(xy 63.036151 -298.92533) (xy 63.083422 -298.939022) (xy 63.127884 -298.96012) (xy 63.168387 -298.988076)
			(xy 63.20388 -299.022168) (xy 63.233445 -299.061512) (xy 63.256316 -299.105089) (xy 63.2719 -299.15177)
			(xy 63.279795 -299.200347) (xy 63.28029 -299.224954) (xy 63.619138 -299.224954) (xy 63.623098 -299.1759)
			(xy 63.634875 -299.128116) (xy 63.654166 -299.08284) (xy 63.680469 -299.041244) (xy 63.713104 -299.004407)
			(xy 63.751225 -298.973282) (xy 63.793846 -298.948675) (xy 63.839862 -298.931223) (xy 63.888081 -298.921379)
			(xy 63.937256 -298.919398) (xy 63.986111 -298.92533) (xy 64.033382 -298.939022) (xy 64.077844 -298.96012)
			(xy 64.118347 -298.988076) (xy 64.15384 -299.022168) (xy 64.183405 -299.061512) (xy 64.206276 -299.105089)
			(xy 64.22186 -299.15177) (xy 64.229755 -299.200347) (xy 64.23025 -299.224954) (xy 64.569098 -299.224954)
			(xy 64.573058 -299.1759) (xy 64.584835 -299.128116) (xy 64.604126 -299.08284) (xy 64.630429 -299.041244)
			(xy 64.663064 -299.004407) (xy 64.701185 -298.973282) (xy 64.743806 -298.948675) (xy 64.789822 -298.931223)
			(xy 64.838041 -298.921379) (xy 64.887216 -298.919398) (xy 64.936071 -298.92533) (xy 64.983342 -298.939022)
			(xy 65.027804 -298.96012) (xy 65.068307 -298.988076) (xy 65.1038 -299.022168) (xy 65.133365 -299.061512)
			(xy 65.156236 -299.105089) (xy 65.17182 -299.15177) (xy 65.179715 -299.200347) (xy 65.18021 -299.224954)
			(xy 65.519058 -299.224954) (xy 65.523018 -299.1759) (xy 65.534795 -299.128116) (xy 65.554086 -299.08284)
			(xy 65.580389 -299.041244) (xy 65.613024 -299.004407) (xy 65.651145 -298.973282) (xy 65.693766 -298.948675)
			(xy 65.739782 -298.931223) (xy 65.788001 -298.921379) (xy 65.837176 -298.919398) (xy 65.886031 -298.92533)
			(xy 65.933302 -298.939022) (xy 65.977764 -298.96012) (xy 66.018267 -298.988076) (xy 66.05376 -299.022168)
			(xy 66.083325 -299.061512) (xy 66.106196 -299.105089) (xy 66.12178 -299.15177) (xy 66.129675 -299.200347)
			(xy 66.13017 -299.224954) (xy 66.469018 -299.224954) (xy 66.472978 -299.1759) (xy 66.484755 -299.128116)
			(xy 66.504046 -299.08284) (xy 66.530349 -299.041244) (xy 66.562984 -299.004407) (xy 66.601105 -298.973282)
			(xy 66.643726 -298.948675) (xy 66.689742 -298.931223) (xy 66.737961 -298.921379) (xy 66.787136 -298.919398)
			(xy 66.835991 -298.92533) (xy 66.883262 -298.939022) (xy 66.927724 -298.96012) (xy 66.968227 -298.988076)
			(xy 67.00372 -299.022168) (xy 67.033285 -299.061512) (xy 67.056156 -299.105089) (xy 67.07174 -299.15177)
			(xy 67.079635 -299.200347) (xy 67.08013 -299.224954) (xy 67.418978 -299.224954) (xy 67.422938 -299.1759)
			(xy 67.434715 -299.128116) (xy 67.454006 -299.08284) (xy 67.480309 -299.041244) (xy 67.512944 -299.004407)
			(xy 67.551065 -298.973282) (xy 67.593686 -298.948675) (xy 67.639702 -298.931223) (xy 67.687921 -298.921379)
			(xy 67.737096 -298.919398) (xy 67.785951 -298.92533) (xy 67.833222 -298.939022) (xy 67.877684 -298.96012)
			(xy 67.918187 -298.988076) (xy 67.95368 -299.022168) (xy 67.983245 -299.061512) (xy 68.006116 -299.105089)
			(xy 68.0217 -299.15177) (xy 68.029595 -299.200347) (xy 68.03009 -299.224954) (xy 68.368938 -299.224954)
			(xy 68.372898 -299.1759) (xy 68.384675 -299.128116) (xy 68.403966 -299.08284) (xy 68.430269 -299.041244)
			(xy 68.462904 -299.004407) (xy 68.501025 -298.973282) (xy 68.543646 -298.948675) (xy 68.589662 -298.931223)
			(xy 68.637881 -298.921379) (xy 68.687056 -298.919398) (xy 68.735911 -298.92533) (xy 68.783182 -298.939022)
			(xy 68.827644 -298.96012) (xy 68.868147 -298.988076) (xy 68.90364 -299.022168) (xy 68.933205 -299.061512)
			(xy 68.956076 -299.105089) (xy 68.97166 -299.15177) (xy 68.979555 -299.200347) (xy 68.98005 -299.224954)
			(xy 69.319152 -299.224954) (xy 69.323112 -299.1759) (xy 69.334889 -299.128116) (xy 69.35418 -299.08284)
			(xy 69.380483 -299.041244) (xy 69.413118 -299.004407) (xy 69.451239 -298.973282) (xy 69.49386 -298.948675)
			(xy 69.539876 -298.931223) (xy 69.588095 -298.921379) (xy 69.63727 -298.919398) (xy 69.686125 -298.92533)
			(xy 69.733396 -298.939022) (xy 69.777858 -298.96012) (xy 69.818361 -298.988076) (xy 69.853854 -299.022168)
			(xy 69.883419 -299.061512) (xy 69.90629 -299.105089) (xy 69.921874 -299.15177) (xy 69.929769 -299.200347)
			(xy 69.930264 -299.224954) (xy 70.269112 -299.224954) (xy 70.273072 -299.1759) (xy 70.284849 -299.128116)
			(xy 70.30414 -299.08284) (xy 70.330443 -299.041244) (xy 70.363078 -299.004407) (xy 70.401199 -298.973282)
			(xy 70.44382 -298.948675) (xy 70.489836 -298.931223) (xy 70.538055 -298.921379) (xy 70.58723 -298.919398)
			(xy 70.636085 -298.92533) (xy 70.683356 -298.939022) (xy 70.727818 -298.96012) (xy 70.768321 -298.988076)
			(xy 70.803814 -299.022168) (xy 70.833379 -299.061512) (xy 70.85625 -299.105089) (xy 70.871834 -299.15177)
			(xy 70.879729 -299.200347) (xy 70.880224 -299.224954) (xy 71.219072 -299.224954) (xy 71.223032 -299.1759)
			(xy 71.234809 -299.128116) (xy 71.2541 -299.08284) (xy 71.280403 -299.041244) (xy 71.313038 -299.004407)
			(xy 71.351159 -298.973282) (xy 71.39378 -298.948675) (xy 71.439796 -298.931223) (xy 71.488015 -298.921379)
			(xy 71.53719 -298.919398) (xy 71.586045 -298.92533) (xy 71.633316 -298.939022) (xy 71.677778 -298.96012)
			(xy 71.718281 -298.988076) (xy 71.753774 -299.022168) (xy 71.783339 -299.061512) (xy 71.80621 -299.105089)
			(xy 71.821794 -299.15177) (xy 71.829689 -299.200347) (xy 71.830184 -299.224954) (xy 72.169032 -299.224954)
			(xy 72.172992 -299.1759) (xy 72.184769 -299.128116) (xy 72.20406 -299.08284) (xy 72.230363 -299.041244)
			(xy 72.262998 -299.004407) (xy 72.301119 -298.973282) (xy 72.34374 -298.948675) (xy 72.389756 -298.931223)
			(xy 72.437975 -298.921379) (xy 72.48715 -298.919398) (xy 72.536005 -298.92533) (xy 72.583276 -298.939022)
			(xy 72.627738 -298.96012) (xy 72.668241 -298.988076) (xy 72.703734 -299.022168) (xy 72.733299 -299.061512)
			(xy 72.75617 -299.105089) (xy 72.771754 -299.15177) (xy 72.779649 -299.200347) (xy 72.780144 -299.224954)
			(xy 73.118992 -299.224954) (xy 73.122952 -299.1759) (xy 73.134729 -299.128116) (xy 73.15402 -299.08284)
			(xy 73.180323 -299.041244) (xy 73.212958 -299.004407) (xy 73.251079 -298.973282) (xy 73.2937 -298.948675)
			(xy 73.339716 -298.931223) (xy 73.387935 -298.921379) (xy 73.43711 -298.919398) (xy 73.485965 -298.92533)
			(xy 73.533236 -298.939022) (xy 73.577698 -298.96012) (xy 73.618201 -298.988076) (xy 73.653694 -299.022168)
			(xy 73.683259 -299.061512) (xy 73.70613 -299.105089) (xy 73.721714 -299.15177) (xy 73.729609 -299.200347)
			(xy 73.730104 -299.224954) (xy 75.969126 -299.224954) (xy 75.973086 -299.1759) (xy 75.984863 -299.128116)
			(xy 76.004154 -299.08284) (xy 76.030457 -299.041244) (xy 76.063092 -299.004407) (xy 76.101213 -298.973282)
			(xy 76.143834 -298.948675) (xy 76.18985 -298.931223) (xy 76.238069 -298.921379) (xy 76.287244 -298.919398)
			(xy 76.336099 -298.92533) (xy 76.38337 -298.939022) (xy 76.427832 -298.96012) (xy 76.468335 -298.988076)
			(xy 76.503828 -299.022168) (xy 76.533393 -299.061512) (xy 76.556264 -299.105089) (xy 76.571848 -299.15177)
			(xy 76.579743 -299.200347) (xy 76.580238 -299.224954) (xy 76.919086 -299.224954) (xy 76.923046 -299.1759)
			(xy 76.934823 -299.128116) (xy 76.954114 -299.08284) (xy 76.980417 -299.041244) (xy 77.013052 -299.004407)
			(xy 77.051173 -298.973282) (xy 77.093794 -298.948675) (xy 77.13981 -298.931223) (xy 77.188029 -298.921379)
			(xy 77.237204 -298.919398) (xy 77.286059 -298.92533) (xy 77.33333 -298.939022) (xy 77.377792 -298.96012)
			(xy 77.418295 -298.988076) (xy 77.453788 -299.022168) (xy 77.483353 -299.061512) (xy 77.506224 -299.105089)
			(xy 77.521808 -299.15177) (xy 77.529703 -299.200347) (xy 77.530198 -299.224954) (xy 77.869046 -299.224954)
			(xy 77.873006 -299.1759) (xy 77.884783 -299.128116) (xy 77.904074 -299.08284) (xy 77.930377 -299.041244)
			(xy 77.963012 -299.004407) (xy 78.001133 -298.973282) (xy 78.043754 -298.948675) (xy 78.08977 -298.931223)
			(xy 78.137989 -298.921379) (xy 78.187164 -298.919398) (xy 78.236019 -298.92533) (xy 78.28329 -298.939022)
			(xy 78.327752 -298.96012) (xy 78.368255 -298.988076) (xy 78.403748 -299.022168) (xy 78.433313 -299.061512)
			(xy 78.456184 -299.105089) (xy 78.471768 -299.15177) (xy 78.479663 -299.200347) (xy 78.480158 -299.224954)
			(xy 78.819006 -299.224954) (xy 78.822966 -299.1759) (xy 78.834743 -299.128116) (xy 78.854034 -299.08284)
			(xy 78.880337 -299.041244) (xy 78.912972 -299.004407) (xy 78.951093 -298.973282) (xy 78.993714 -298.948675)
			(xy 79.03973 -298.931223) (xy 79.087949 -298.921379) (xy 79.137124 -298.919398) (xy 79.185979 -298.92533)
			(xy 79.23325 -298.939022) (xy 79.277712 -298.96012) (xy 79.318215 -298.988076) (xy 79.353708 -299.022168)
			(xy 79.383273 -299.061512) (xy 79.406144 -299.105089) (xy 79.421728 -299.15177) (xy 79.429623 -299.200347)
			(xy 79.430118 -299.224954) (xy 79.768966 -299.224954) (xy 79.772926 -299.1759) (xy 79.784703 -299.128116)
			(xy 79.803994 -299.08284) (xy 79.830297 -299.041244) (xy 79.862932 -299.004407) (xy 79.901053 -298.973282)
			(xy 79.943674 -298.948675) (xy 79.98969 -298.931223) (xy 80.037909 -298.921379) (xy 80.087084 -298.919398)
			(xy 80.135939 -298.92533) (xy 80.18321 -298.939022) (xy 80.227672 -298.96012) (xy 80.268175 -298.988076)
			(xy 80.303668 -299.022168) (xy 80.333233 -299.061512) (xy 80.356104 -299.105089) (xy 80.371688 -299.15177)
			(xy 80.379583 -299.200347) (xy 80.380078 -299.224954) (xy 80.71918 -299.224954) (xy 80.72314 -299.1759)
			(xy 80.734917 -299.128116) (xy 80.754208 -299.08284) (xy 80.780511 -299.041244) (xy 80.813146 -299.004407)
			(xy 80.851267 -298.973282) (xy 80.893888 -298.948675) (xy 80.939904 -298.931223) (xy 80.988123 -298.921379)
			(xy 81.037298 -298.919398) (xy 81.086153 -298.92533) (xy 81.133424 -298.939022) (xy 81.177886 -298.96012)
			(xy 81.218389 -298.988076) (xy 81.253882 -299.022168) (xy 81.283447 -299.061512) (xy 81.306318 -299.105089)
			(xy 81.321902 -299.15177) (xy 81.329797 -299.200347) (xy 81.330292 -299.224954) (xy 81.66914 -299.224954)
			(xy 81.6731 -299.1759) (xy 81.684877 -299.128116) (xy 81.704168 -299.08284) (xy 81.730471 -299.041244)
			(xy 81.763106 -299.004407) (xy 81.801227 -298.973282) (xy 81.843848 -298.948675) (xy 81.889864 -298.931223)
			(xy 81.938083 -298.921379) (xy 81.987258 -298.919398) (xy 82.036113 -298.92533) (xy 82.083384 -298.939022)
			(xy 82.127846 -298.96012) (xy 82.168349 -298.988076) (xy 82.203842 -299.022168) (xy 82.233407 -299.061512)
			(xy 82.256278 -299.105089) (xy 82.271862 -299.15177) (xy 82.279757 -299.200347) (xy 82.280252 -299.224954)
			(xy 82.6191 -299.224954) (xy 82.62306 -299.1759) (xy 82.634837 -299.128116) (xy 82.654128 -299.08284)
			(xy 82.680431 -299.041244) (xy 82.713066 -299.004407) (xy 82.751187 -298.973282) (xy 82.793808 -298.948675)
			(xy 82.839824 -298.931223) (xy 82.888043 -298.921379) (xy 82.937218 -298.919398) (xy 82.986073 -298.92533)
			(xy 83.033344 -298.939022) (xy 83.077806 -298.96012) (xy 83.118309 -298.988076) (xy 83.153802 -299.022168)
			(xy 83.183367 -299.061512) (xy 83.206238 -299.105089) (xy 83.221822 -299.15177) (xy 83.229717 -299.200347)
			(xy 83.230212 -299.224954) (xy 83.229717 -299.249561) (xy 83.221822 -299.298138) (xy 83.206238 -299.344819)
			(xy 83.183367 -299.388396) (xy 83.153802 -299.42774) (xy 83.118309 -299.461832) (xy 83.077806 -299.489788)
			(xy 83.033344 -299.510886) (xy 82.986073 -299.524578) (xy 82.937218 -299.53051) (xy 82.888043 -299.528529)
			(xy 82.839824 -299.518685) (xy 82.793808 -299.501233) (xy 82.751187 -299.476626) (xy 82.713066 -299.445501)
			(xy 82.680431 -299.408664) (xy 82.654128 -299.367068) (xy 82.634837 -299.321792) (xy 82.62306 -299.274008)
			(xy 82.6191 -299.224954) (xy 82.280252 -299.224954) (xy 82.279757 -299.249561) (xy 82.271862 -299.298138)
			(xy 82.256278 -299.344819) (xy 82.233407 -299.388396) (xy 82.203842 -299.42774) (xy 82.168349 -299.461832)
			(xy 82.127846 -299.489788) (xy 82.083384 -299.510886) (xy 82.036113 -299.524578) (xy 81.987258 -299.53051)
			(xy 81.938083 -299.528529) (xy 81.889864 -299.518685) (xy 81.843848 -299.501233) (xy 81.801227 -299.476626)
			(xy 81.763106 -299.445501) (xy 81.730471 -299.408664) (xy 81.704168 -299.367068) (xy 81.684877 -299.321792)
			(xy 81.6731 -299.274008) (xy 81.66914 -299.224954) (xy 81.330292 -299.224954) (xy 81.329797 -299.249561)
			(xy 81.321902 -299.298138) (xy 81.306318 -299.344819) (xy 81.283447 -299.388396) (xy 81.253882 -299.42774)
			(xy 81.218389 -299.461832) (xy 81.177886 -299.489788) (xy 81.133424 -299.510886) (xy 81.086153 -299.524578)
			(xy 81.037298 -299.53051) (xy 80.988123 -299.528529) (xy 80.939904 -299.518685) (xy 80.893888 -299.501233)
			(xy 80.851267 -299.476626) (xy 80.813146 -299.445501) (xy 80.780511 -299.408664) (xy 80.754208 -299.367068)
			(xy 80.734917 -299.321792) (xy 80.72314 -299.274008) (xy 80.71918 -299.224954) (xy 80.380078 -299.224954)
			(xy 80.379583 -299.249561) (xy 80.371688 -299.298138) (xy 80.356104 -299.344819) (xy 80.333233 -299.388396)
			(xy 80.303668 -299.42774) (xy 80.268175 -299.461832) (xy 80.227672 -299.489788) (xy 80.18321 -299.510886)
			(xy 80.135939 -299.524578) (xy 80.087084 -299.53051) (xy 80.037909 -299.528529) (xy 79.98969 -299.518685)
			(xy 79.943674 -299.501233) (xy 79.901053 -299.476626) (xy 79.862932 -299.445501) (xy 79.830297 -299.408664)
			(xy 79.803994 -299.367068) (xy 79.784703 -299.321792) (xy 79.772926 -299.274008) (xy 79.768966 -299.224954)
			(xy 79.430118 -299.224954) (xy 79.429623 -299.249561) (xy 79.421728 -299.298138) (xy 79.406144 -299.344819)
			(xy 79.383273 -299.388396) (xy 79.353708 -299.42774) (xy 79.318215 -299.461832) (xy 79.277712 -299.489788)
			(xy 79.23325 -299.510886) (xy 79.185979 -299.524578) (xy 79.137124 -299.53051) (xy 79.087949 -299.528529)
			(xy 79.03973 -299.518685) (xy 78.993714 -299.501233) (xy 78.951093 -299.476626) (xy 78.912972 -299.445501)
			(xy 78.880337 -299.408664) (xy 78.854034 -299.367068) (xy 78.834743 -299.321792) (xy 78.822966 -299.274008)
			(xy 78.819006 -299.224954) (xy 78.480158 -299.224954) (xy 78.479663 -299.249561) (xy 78.471768 -299.298138)
			(xy 78.456184 -299.344819) (xy 78.433313 -299.388396) (xy 78.403748 -299.42774) (xy 78.368255 -299.461832)
			(xy 78.327752 -299.489788) (xy 78.28329 -299.510886) (xy 78.236019 -299.524578) (xy 78.187164 -299.53051)
			(xy 78.137989 -299.528529) (xy 78.08977 -299.518685) (xy 78.043754 -299.501233) (xy 78.001133 -299.476626)
			(xy 77.963012 -299.445501) (xy 77.930377 -299.408664) (xy 77.904074 -299.367068) (xy 77.884783 -299.321792)
			(xy 77.873006 -299.274008) (xy 77.869046 -299.224954) (xy 77.530198 -299.224954) (xy 77.529703 -299.249561)
			(xy 77.521808 -299.298138) (xy 77.506224 -299.344819) (xy 77.483353 -299.388396) (xy 77.453788 -299.42774)
			(xy 77.418295 -299.461832) (xy 77.377792 -299.489788) (xy 77.33333 -299.510886) (xy 77.286059 -299.524578)
			(xy 77.237204 -299.53051) (xy 77.188029 -299.528529) (xy 77.13981 -299.518685) (xy 77.093794 -299.501233)
			(xy 77.051173 -299.476626) (xy 77.013052 -299.445501) (xy 76.980417 -299.408664) (xy 76.954114 -299.367068)
			(xy 76.934823 -299.321792) (xy 76.923046 -299.274008) (xy 76.919086 -299.224954) (xy 76.580238 -299.224954)
			(xy 76.579743 -299.249561) (xy 76.571848 -299.298138) (xy 76.556264 -299.344819) (xy 76.533393 -299.388396)
			(xy 76.503828 -299.42774) (xy 76.468335 -299.461832) (xy 76.427832 -299.489788) (xy 76.38337 -299.510886)
			(xy 76.336099 -299.524578) (xy 76.287244 -299.53051) (xy 76.238069 -299.528529) (xy 76.18985 -299.518685)
			(xy 76.143834 -299.501233) (xy 76.101213 -299.476626) (xy 76.063092 -299.445501) (xy 76.030457 -299.408664)
			(xy 76.004154 -299.367068) (xy 75.984863 -299.321792) (xy 75.973086 -299.274008) (xy 75.969126 -299.224954)
			(xy 73.730104 -299.224954) (xy 73.729609 -299.249561) (xy 73.721714 -299.298138) (xy 73.70613 -299.344819)
			(xy 73.683259 -299.388396) (xy 73.653694 -299.42774) (xy 73.618201 -299.461832) (xy 73.577698 -299.489788)
			(xy 73.533236 -299.510886) (xy 73.485965 -299.524578) (xy 73.43711 -299.53051) (xy 73.387935 -299.528529)
			(xy 73.339716 -299.518685) (xy 73.2937 -299.501233) (xy 73.251079 -299.476626) (xy 73.212958 -299.445501)
			(xy 73.180323 -299.408664) (xy 73.15402 -299.367068) (xy 73.134729 -299.321792) (xy 73.122952 -299.274008)
			(xy 73.118992 -299.224954) (xy 72.780144 -299.224954) (xy 72.779649 -299.249561) (xy 72.771754 -299.298138)
			(xy 72.75617 -299.344819) (xy 72.733299 -299.388396) (xy 72.703734 -299.42774) (xy 72.668241 -299.461832)
			(xy 72.627738 -299.489788) (xy 72.583276 -299.510886) (xy 72.536005 -299.524578) (xy 72.48715 -299.53051)
			(xy 72.437975 -299.528529) (xy 72.389756 -299.518685) (xy 72.34374 -299.501233) (xy 72.301119 -299.476626)
			(xy 72.262998 -299.445501) (xy 72.230363 -299.408664) (xy 72.20406 -299.367068) (xy 72.184769 -299.321792)
			(xy 72.172992 -299.274008) (xy 72.169032 -299.224954) (xy 71.830184 -299.224954) (xy 71.829689 -299.249561)
			(xy 71.821794 -299.298138) (xy 71.80621 -299.344819) (xy 71.783339 -299.388396) (xy 71.753774 -299.42774)
			(xy 71.718281 -299.461832) (xy 71.677778 -299.489788) (xy 71.633316 -299.510886) (xy 71.586045 -299.524578)
			(xy 71.53719 -299.53051) (xy 71.488015 -299.528529) (xy 71.439796 -299.518685) (xy 71.39378 -299.501233)
			(xy 71.351159 -299.476626) (xy 71.313038 -299.445501) (xy 71.280403 -299.408664) (xy 71.2541 -299.367068)
			(xy 71.234809 -299.321792) (xy 71.223032 -299.274008) (xy 71.219072 -299.224954) (xy 70.880224 -299.224954)
			(xy 70.879729 -299.249561) (xy 70.871834 -299.298138) (xy 70.85625 -299.344819) (xy 70.833379 -299.388396)
			(xy 70.803814 -299.42774) (xy 70.768321 -299.461832) (xy 70.727818 -299.489788) (xy 70.683356 -299.510886)
			(xy 70.636085 -299.524578) (xy 70.58723 -299.53051) (xy 70.538055 -299.528529) (xy 70.489836 -299.518685)
			(xy 70.44382 -299.501233) (xy 70.401199 -299.476626) (xy 70.363078 -299.445501) (xy 70.330443 -299.408664)
			(xy 70.30414 -299.367068) (xy 70.284849 -299.321792) (xy 70.273072 -299.274008) (xy 70.269112 -299.224954)
			(xy 69.930264 -299.224954) (xy 69.929769 -299.249561) (xy 69.921874 -299.298138) (xy 69.90629 -299.344819)
			(xy 69.883419 -299.388396) (xy 69.853854 -299.42774) (xy 69.818361 -299.461832) (xy 69.777858 -299.489788)
			(xy 69.733396 -299.510886) (xy 69.686125 -299.524578) (xy 69.63727 -299.53051) (xy 69.588095 -299.528529)
			(xy 69.539876 -299.518685) (xy 69.49386 -299.501233) (xy 69.451239 -299.476626) (xy 69.413118 -299.445501)
			(xy 69.380483 -299.408664) (xy 69.35418 -299.367068) (xy 69.334889 -299.321792) (xy 69.323112 -299.274008)
			(xy 69.319152 -299.224954) (xy 68.98005 -299.224954) (xy 68.979555 -299.249561) (xy 68.97166 -299.298138)
			(xy 68.956076 -299.344819) (xy 68.933205 -299.388396) (xy 68.90364 -299.42774) (xy 68.868147 -299.461832)
			(xy 68.827644 -299.489788) (xy 68.783182 -299.510886) (xy 68.735911 -299.524578) (xy 68.687056 -299.53051)
			(xy 68.637881 -299.528529) (xy 68.589662 -299.518685) (xy 68.543646 -299.501233) (xy 68.501025 -299.476626)
			(xy 68.462904 -299.445501) (xy 68.430269 -299.408664) (xy 68.403966 -299.367068) (xy 68.384675 -299.321792)
			(xy 68.372898 -299.274008) (xy 68.368938 -299.224954) (xy 68.03009 -299.224954) (xy 68.029595 -299.249561)
			(xy 68.0217 -299.298138) (xy 68.006116 -299.344819) (xy 67.983245 -299.388396) (xy 67.95368 -299.42774)
			(xy 67.918187 -299.461832) (xy 67.877684 -299.489788) (xy 67.833222 -299.510886) (xy 67.785951 -299.524578)
			(xy 67.737096 -299.53051) (xy 67.687921 -299.528529) (xy 67.639702 -299.518685) (xy 67.593686 -299.501233)
			(xy 67.551065 -299.476626) (xy 67.512944 -299.445501) (xy 67.480309 -299.408664) (xy 67.454006 -299.367068)
			(xy 67.434715 -299.321792) (xy 67.422938 -299.274008) (xy 67.418978 -299.224954) (xy 67.08013 -299.224954)
			(xy 67.079635 -299.249561) (xy 67.07174 -299.298138) (xy 67.056156 -299.344819) (xy 67.033285 -299.388396)
			(xy 67.00372 -299.42774) (xy 66.968227 -299.461832) (xy 66.927724 -299.489788) (xy 66.883262 -299.510886)
			(xy 66.835991 -299.524578) (xy 66.787136 -299.53051) (xy 66.737961 -299.528529) (xy 66.689742 -299.518685)
			(xy 66.643726 -299.501233) (xy 66.601105 -299.476626) (xy 66.562984 -299.445501) (xy 66.530349 -299.408664)
			(xy 66.504046 -299.367068) (xy 66.484755 -299.321792) (xy 66.472978 -299.274008) (xy 66.469018 -299.224954)
			(xy 66.13017 -299.224954) (xy 66.129675 -299.249561) (xy 66.12178 -299.298138) (xy 66.106196 -299.344819)
			(xy 66.083325 -299.388396) (xy 66.05376 -299.42774) (xy 66.018267 -299.461832) (xy 65.977764 -299.489788)
			(xy 65.933302 -299.510886) (xy 65.886031 -299.524578) (xy 65.837176 -299.53051) (xy 65.788001 -299.528529)
			(xy 65.739782 -299.518685) (xy 65.693766 -299.501233) (xy 65.651145 -299.476626) (xy 65.613024 -299.445501)
			(xy 65.580389 -299.408664) (xy 65.554086 -299.367068) (xy 65.534795 -299.321792) (xy 65.523018 -299.274008)
			(xy 65.519058 -299.224954) (xy 65.18021 -299.224954) (xy 65.179715 -299.249561) (xy 65.17182 -299.298138)
			(xy 65.156236 -299.344819) (xy 65.133365 -299.388396) (xy 65.1038 -299.42774) (xy 65.068307 -299.461832)
			(xy 65.027804 -299.489788) (xy 64.983342 -299.510886) (xy 64.936071 -299.524578) (xy 64.887216 -299.53051)
			(xy 64.838041 -299.528529) (xy 64.789822 -299.518685) (xy 64.743806 -299.501233) (xy 64.701185 -299.476626)
			(xy 64.663064 -299.445501) (xy 64.630429 -299.408664) (xy 64.604126 -299.367068) (xy 64.584835 -299.321792)
			(xy 64.573058 -299.274008) (xy 64.569098 -299.224954) (xy 64.23025 -299.224954) (xy 64.229755 -299.249561)
			(xy 64.22186 -299.298138) (xy 64.206276 -299.344819) (xy 64.183405 -299.388396) (xy 64.15384 -299.42774)
			(xy 64.118347 -299.461832) (xy 64.077844 -299.489788) (xy 64.033382 -299.510886) (xy 63.986111 -299.524578)
			(xy 63.937256 -299.53051) (xy 63.888081 -299.528529) (xy 63.839862 -299.518685) (xy 63.793846 -299.501233)
			(xy 63.751225 -299.476626) (xy 63.713104 -299.445501) (xy 63.680469 -299.408664) (xy 63.654166 -299.367068)
			(xy 63.634875 -299.321792) (xy 63.623098 -299.274008) (xy 63.619138 -299.224954) (xy 63.28029 -299.224954)
			(xy 63.279795 -299.249561) (xy 63.2719 -299.298138) (xy 63.256316 -299.344819) (xy 63.233445 -299.388396)
			(xy 63.20388 -299.42774) (xy 63.168387 -299.461832) (xy 63.127884 -299.489788) (xy 63.083422 -299.510886)
			(xy 63.036151 -299.524578) (xy 62.987296 -299.53051) (xy 62.938121 -299.528529) (xy 62.889902 -299.518685)
			(xy 62.843886 -299.501233) (xy 62.801265 -299.476626) (xy 62.763144 -299.445501) (xy 62.730509 -299.408664)
			(xy 62.704206 -299.367068) (xy 62.684915 -299.321792) (xy 62.673138 -299.274008) (xy 62.669178 -299.224954)
			(xy 62.330076 -299.224954) (xy 62.329581 -299.249561) (xy 62.321686 -299.298138) (xy 62.306102 -299.344819)
			(xy 62.283231 -299.388396) (xy 62.253666 -299.42774) (xy 62.218173 -299.461832) (xy 62.17767 -299.489788)
			(xy 62.133208 -299.510886) (xy 62.085937 -299.524578) (xy 62.037082 -299.53051) (xy 61.987907 -299.528529)
			(xy 61.939688 -299.518685) (xy 61.893672 -299.501233) (xy 61.851051 -299.476626) (xy 61.81293 -299.445501)
			(xy 61.780295 -299.408664) (xy 61.753992 -299.367068) (xy 61.734701 -299.321792) (xy 61.722924 -299.274008)
			(xy 61.718964 -299.224954) (xy 61.380116 -299.224954) (xy 61.379621 -299.249561) (xy 61.371726 -299.298138)
			(xy 61.356142 -299.344819) (xy 61.333271 -299.388396) (xy 61.303706 -299.42774) (xy 61.268213 -299.461832)
			(xy 61.22771 -299.489788) (xy 61.183248 -299.510886) (xy 61.135977 -299.524578) (xy 61.087122 -299.53051)
			(xy 61.037947 -299.528529) (xy 60.989728 -299.518685) (xy 60.943712 -299.501233) (xy 60.901091 -299.476626)
			(xy 60.86297 -299.445501) (xy 60.830335 -299.408664) (xy 60.804032 -299.367068) (xy 60.784741 -299.321792)
			(xy 60.772964 -299.274008) (xy 60.769004 -299.224954) (xy 60.430156 -299.224954) (xy 60.429661 -299.249561)
			(xy 60.421766 -299.298138) (xy 60.406182 -299.344819) (xy 60.383311 -299.388396) (xy 60.353746 -299.42774)
			(xy 60.318253 -299.461832) (xy 60.27775 -299.489788) (xy 60.233288 -299.510886) (xy 60.186017 -299.524578)
			(xy 60.137162 -299.53051) (xy 60.087987 -299.528529) (xy 60.039768 -299.518685) (xy 59.993752 -299.501233)
			(xy 59.951131 -299.476626) (xy 59.91301 -299.445501) (xy 59.880375 -299.408664) (xy 59.854072 -299.367068)
			(xy 59.834781 -299.321792) (xy 59.823004 -299.274008) (xy 59.819044 -299.224954) (xy 58.530236 -299.224954)
			(xy 58.529741 -299.249561) (xy 58.521846 -299.298138) (xy 58.506262 -299.344819) (xy 58.483391 -299.388396)
			(xy 58.453826 -299.42774) (xy 58.418333 -299.461832) (xy 58.37783 -299.489788) (xy 58.333368 -299.510886)
			(xy 58.286097 -299.524578) (xy 58.237242 -299.53051) (xy 58.188067 -299.528529) (xy 58.139848 -299.518685)
			(xy 58.093832 -299.501233) (xy 58.051211 -299.476626) (xy 58.01309 -299.445501) (xy 57.980455 -299.408664)
			(xy 57.954152 -299.367068) (xy 57.934861 -299.321792) (xy 57.923084 -299.274008) (xy 57.919124 -299.224954)
			(xy 57.580276 -299.224954) (xy 57.579781 -299.249561) (xy 57.571886 -299.298138) (xy 57.556302 -299.344819)
			(xy 57.533431 -299.388396) (xy 57.503866 -299.42774) (xy 57.468373 -299.461832) (xy 57.42787 -299.489788)
			(xy 57.383408 -299.510886) (xy 57.336137 -299.524578) (xy 57.287282 -299.53051) (xy 57.238107 -299.528529)
			(xy 57.189888 -299.518685) (xy 57.143872 -299.501233) (xy 57.101251 -299.476626) (xy 57.06313 -299.445501)
			(xy 57.030495 -299.408664) (xy 57.004192 -299.367068) (xy 56.984901 -299.321792) (xy 56.973124 -299.274008)
			(xy 56.969164 -299.224954) (xy 56.630062 -299.224954) (xy 56.629567 -299.249561) (xy 56.621672 -299.298138)
			(xy 56.606088 -299.344819) (xy 56.583217 -299.388396) (xy 56.553652 -299.42774) (xy 56.518159 -299.461832)
			(xy 56.477656 -299.489788) (xy 56.433194 -299.510886) (xy 56.385923 -299.524578) (xy 56.337068 -299.53051)
			(xy 56.287893 -299.528529) (xy 56.239674 -299.518685) (xy 56.193658 -299.501233) (xy 56.151037 -299.476626)
			(xy 56.112916 -299.445501) (xy 56.080281 -299.408664) (xy 56.053978 -299.367068) (xy 56.034687 -299.321792)
			(xy 56.02291 -299.274008) (xy 56.01895 -299.224954) (xy 55.680102 -299.224954) (xy 55.679607 -299.249561)
			(xy 55.671712 -299.298138) (xy 55.656128 -299.344819) (xy 55.633257 -299.388396) (xy 55.603692 -299.42774)
			(xy 55.568199 -299.461832) (xy 55.527696 -299.489788) (xy 55.483234 -299.510886) (xy 55.435963 -299.524578)
			(xy 55.387108 -299.53051) (xy 55.337933 -299.528529) (xy 55.289714 -299.518685) (xy 55.243698 -299.501233)
			(xy 55.201077 -299.476626) (xy 55.162956 -299.445501) (xy 55.130321 -299.408664) (xy 55.104018 -299.367068)
			(xy 55.084727 -299.321792) (xy 55.07295 -299.274008) (xy 55.06899 -299.224954) (xy 54.730142 -299.224954)
			(xy 54.729647 -299.249561) (xy 54.721752 -299.298138) (xy 54.706168 -299.344819) (xy 54.683297 -299.388396)
			(xy 54.653732 -299.42774) (xy 54.618239 -299.461832) (xy 54.577736 -299.489788) (xy 54.533274 -299.510886)
			(xy 54.486003 -299.524578) (xy 54.437148 -299.53051) (xy 54.387973 -299.528529) (xy 54.339754 -299.518685)
			(xy 54.293738 -299.501233) (xy 54.251117 -299.476626) (xy 54.212996 -299.445501) (xy 54.180361 -299.408664)
			(xy 54.154058 -299.367068) (xy 54.134767 -299.321792) (xy 54.12299 -299.274008) (xy 54.11903 -299.224954)
			(xy 53.780182 -299.224954) (xy 53.779687 -299.249561) (xy 53.771792 -299.298138) (xy 53.756208 -299.344819)
			(xy 53.733337 -299.388396) (xy 53.703772 -299.42774) (xy 53.668279 -299.461832) (xy 53.627776 -299.489788)
			(xy 53.583314 -299.510886) (xy 53.536043 -299.524578) (xy 53.487188 -299.53051) (xy 53.438013 -299.528529)
			(xy 53.389794 -299.518685) (xy 53.343778 -299.501233) (xy 53.301157 -299.476626) (xy 53.263036 -299.445501)
			(xy 53.230401 -299.408664) (xy 53.204098 -299.367068) (xy 53.184807 -299.321792) (xy 53.17303 -299.274008)
			(xy 53.16907 -299.224954) (xy 52.830222 -299.224954) (xy 52.829727 -299.249561) (xy 52.821832 -299.298138)
			(xy 52.806248 -299.344819) (xy 52.783377 -299.388396) (xy 52.753812 -299.42774) (xy 52.718319 -299.461832)
			(xy 52.677816 -299.489788) (xy 52.633354 -299.510886) (xy 52.586083 -299.524578) (xy 52.537228 -299.53051)
			(xy 52.488053 -299.528529) (xy 52.439834 -299.518685) (xy 52.393818 -299.501233) (xy 52.351197 -299.476626)
			(xy 52.313076 -299.445501) (xy 52.280441 -299.408664) (xy 52.254138 -299.367068) (xy 52.234847 -299.321792)
			(xy 52.22307 -299.274008) (xy 52.21911 -299.224954) (xy 51.880262 -299.224954) (xy 51.879767 -299.249561)
			(xy 51.871872 -299.298138) (xy 51.856288 -299.344819) (xy 51.833417 -299.388396) (xy 51.803852 -299.42774)
			(xy 51.768359 -299.461832) (xy 51.727856 -299.489788) (xy 51.683394 -299.510886) (xy 51.636123 -299.524578)
			(xy 51.587268 -299.53051) (xy 51.538093 -299.528529) (xy 51.489874 -299.518685) (xy 51.443858 -299.501233)
			(xy 51.401237 -299.476626) (xy 51.363116 -299.445501) (xy 51.330481 -299.408664) (xy 51.304178 -299.367068)
			(xy 51.284887 -299.321792) (xy 51.27311 -299.274008) (xy 51.26915 -299.224954) (xy 50.930302 -299.224954)
			(xy 50.929807 -299.249561) (xy 50.921912 -299.298138) (xy 50.906328 -299.344819) (xy 50.883457 -299.388396)
			(xy 50.853892 -299.42774) (xy 50.818399 -299.461832) (xy 50.777896 -299.489788) (xy 50.733434 -299.510886)
			(xy 50.686163 -299.524578) (xy 50.637308 -299.53051) (xy 50.588133 -299.528529) (xy 50.539914 -299.518685)
			(xy 50.493898 -299.501233) (xy 50.451277 -299.476626) (xy 50.413156 -299.445501) (xy 50.380521 -299.408664)
			(xy 50.354218 -299.367068) (xy 50.334927 -299.321792) (xy 50.32315 -299.274008) (xy 50.31919 -299.224954)
			(xy 49.980088 -299.224954) (xy 49.979593 -299.249561) (xy 49.971698 -299.298138) (xy 49.956114 -299.344819)
			(xy 49.933243 -299.388396) (xy 49.903678 -299.42774) (xy 49.868185 -299.461832) (xy 49.827682 -299.489788)
			(xy 49.78322 -299.510886) (xy 49.735949 -299.524578) (xy 49.687094 -299.53051) (xy 49.637919 -299.528529)
			(xy 49.5897 -299.518685) (xy 49.543684 -299.501233) (xy 49.501063 -299.476626) (xy 49.462942 -299.445501)
			(xy 49.430307 -299.408664) (xy 49.404004 -299.367068) (xy 49.384713 -299.321792) (xy 49.372936 -299.274008)
			(xy 49.368976 -299.224954) (xy 48.080168 -299.224954) (xy 48.079914 -299.235368) (xy 48.079914 -299.241718)
			(xy 48.07966 -299.24629) (xy 48.07966 -299.247052) (xy 48.078435 -299.261453) (xy 48.073598 -299.289948)
			(xy 48.070008 -299.303948) (xy 48.06823 -299.310552) (xy 48.06823 -299.76445) (xy 88.041732 -299.76445)
			(xy 88.045803 -299.708828) (xy 88.057929 -299.654391) (xy 88.077852 -299.6023) (xy 88.105148 -299.553665)
			(xy 88.139234 -299.509522) (xy 88.179383 -299.470813) (xy 88.224741 -299.438362) (xy 88.274341 -299.412861)
			(xy 88.327125 -299.394854) (xy 88.381968 -299.384724) (xy 88.437702 -299.382687) (xy 88.493139 -299.388787)
			(xy 88.547096 -299.402893) (xy 88.598425 -299.424705) (xy 88.646031 -299.453759) (xy 88.688899 -299.489434)
			(xy 88.726116 -299.530971) (xy 88.756889 -299.577484) (xy 88.769164 -299.603668) (xy 90.31046 -299.603668)
			(xy 90.314531 -299.548046) (xy 90.326657 -299.493609) (xy 90.34658 -299.441518) (xy 90.373876 -299.392883)
			(xy 90.407962 -299.34874) (xy 90.448111 -299.310031) (xy 90.493469 -299.27758) (xy 90.543069 -299.252079)
			(xy 90.595853 -299.234072) (xy 90.650696 -299.223942) (xy 90.70643 -299.221905) (xy 90.761867 -299.228005)
			(xy 90.815824 -299.242111) (xy 90.867153 -299.263923) (xy 90.914759 -299.292977) (xy 90.957627 -299.328652)
			(xy 90.994844 -299.370189) (xy 91.025617 -299.416702) (xy 91.049289 -299.467199) (xy 91.065357 -299.520606)
			(xy 91.073477 -299.575782) (xy 91.073986 -299.603668) (xy 91.073477 -299.631554) (xy 91.065357 -299.68673)
			(xy 91.049289 -299.740137) (xy 91.030747 -299.77969) (xy 92.63837 -299.77969) (xy 92.642441 -299.724068)
			(xy 92.654567 -299.669631) (xy 92.67449 -299.61754) (xy 92.701786 -299.568905) (xy 92.735872 -299.524762)
			(xy 92.776021 -299.486053) (xy 92.821379 -299.453602) (xy 92.870979 -299.428101) (xy 92.923763 -299.410094)
			(xy 92.978606 -299.399964) (xy 93.03434 -299.397927) (xy 93.089777 -299.404027) (xy 93.143734 -299.418133)
			(xy 93.195063 -299.439945) (xy 93.242669 -299.468999) (xy 93.285537 -299.504674) (xy 93.322754 -299.546211)
			(xy 93.353527 -299.592724) (xy 93.377199 -299.643221) (xy 93.393267 -299.696628) (xy 93.401387 -299.751804)
			(xy 93.401896 -299.77969) (xy 93.401387 -299.807576) (xy 93.393267 -299.862752) (xy 93.377199 -299.916159)
			(xy 93.353527 -299.966656) (xy 93.322754 -300.013169) (xy 93.285537 -300.054706) (xy 93.242669 -300.090381)
			(xy 93.195063 -300.119435) (xy 93.143734 -300.141247) (xy 93.089777 -300.155353) (xy 93.03434 -300.161453)
			(xy 92.978606 -300.159416) (xy 92.923763 -300.149286) (xy 92.870979 -300.131279) (xy 92.821379 -300.105778)
			(xy 92.776021 -300.073327) (xy 92.735872 -300.034618) (xy 92.701786 -299.990475) (xy 92.67449 -299.94184)
			(xy 92.654567 -299.889749) (xy 92.642441 -299.835312) (xy 92.63837 -299.77969) (xy 91.030747 -299.77969)
			(xy 91.025617 -299.790634) (xy 90.994844 -299.837147) (xy 90.957627 -299.878684) (xy 90.914759 -299.914359)
			(xy 90.867153 -299.943413) (xy 90.815824 -299.965225) (xy 90.761867 -299.979331) (xy 90.70643 -299.985431)
			(xy 90.650696 -299.983394) (xy 90.595853 -299.973264) (xy 90.543069 -299.955257) (xy 90.493469 -299.929756)
			(xy 90.448111 -299.897305) (xy 90.407962 -299.858596) (xy 90.373876 -299.814453) (xy 90.34658 -299.765818)
			(xy 90.326657 -299.713727) (xy 90.314531 -299.65929) (xy 90.31046 -299.603668) (xy 88.769164 -299.603668)
			(xy 88.780561 -299.627981) (xy 88.796629 -299.681388) (xy 88.804749 -299.736564) (xy 88.805258 -299.76445)
			(xy 88.804749 -299.792336) (xy 88.796629 -299.847512) (xy 88.780561 -299.900919) (xy 88.756889 -299.951416)
			(xy 88.726116 -299.997929) (xy 88.688899 -300.039466) (xy 88.646031 -300.075141) (xy 88.598425 -300.104195)
			(xy 88.547096 -300.126007) (xy 88.493139 -300.140113) (xy 88.437702 -300.146213) (xy 88.381968 -300.144176)
			(xy 88.327125 -300.134046) (xy 88.274341 -300.116039) (xy 88.224741 -300.090538) (xy 88.179383 -300.058087)
			(xy 88.139234 -300.019378) (xy 88.105148 -299.975235) (xy 88.077852 -299.9266) (xy 88.057929 -299.874509)
			(xy 88.045803 -299.820072) (xy 88.041732 -299.76445) (xy 48.06823 -299.76445) (xy 48.06823 -300.083474)
			(xy 48.070008 -300.096682) (xy 48.07077 -300.09973) (xy 48.07517 -300.118214) (xy 48.079887 -300.155916)
			(xy 48.080168 -300.174914) (xy 48.419016 -300.174914) (xy 48.422976 -300.12586) (xy 48.434753 -300.078076)
			(xy 48.454044 -300.0328) (xy 48.480347 -299.991204) (xy 48.512982 -299.954367) (xy 48.551103 -299.923242)
			(xy 48.593724 -299.898635) (xy 48.63974 -299.881183) (xy 48.687959 -299.871339) (xy 48.737134 -299.869358)
			(xy 48.785989 -299.87529) (xy 48.83326 -299.888982) (xy 48.877722 -299.91008) (xy 48.918225 -299.938036)
			(xy 48.953718 -299.972128) (xy 48.983283 -300.011472) (xy 49.006154 -300.055049) (xy 49.021738 -300.10173)
			(xy 49.029633 -300.150307) (xy 49.030128 -300.174914) (xy 50.31919 -300.174914) (xy 50.32315 -300.12586)
			(xy 50.334927 -300.078076) (xy 50.354218 -300.0328) (xy 50.380521 -299.991204) (xy 50.413156 -299.954367)
			(xy 50.451277 -299.923242) (xy 50.493898 -299.898635) (xy 50.539914 -299.881183) (xy 50.588133 -299.871339)
			(xy 50.637308 -299.869358) (xy 50.686163 -299.87529) (xy 50.733434 -299.888982) (xy 50.777896 -299.91008)
			(xy 50.818399 -299.938036) (xy 50.853892 -299.972128) (xy 50.883457 -300.011472) (xy 50.906328 -300.055049)
			(xy 50.921912 -300.10173) (xy 50.929807 -300.150307) (xy 50.930302 -300.174914) (xy 51.26915 -300.174914)
			(xy 51.27311 -300.12586) (xy 51.284887 -300.078076) (xy 51.304178 -300.0328) (xy 51.330481 -299.991204)
			(xy 51.363116 -299.954367) (xy 51.401237 -299.923242) (xy 51.443858 -299.898635) (xy 51.489874 -299.881183)
			(xy 51.538093 -299.871339) (xy 51.587268 -299.869358) (xy 51.636123 -299.87529) (xy 51.683394 -299.888982)
			(xy 51.727856 -299.91008) (xy 51.768359 -299.938036) (xy 51.803852 -299.972128) (xy 51.833417 -300.011472)
			(xy 51.856288 -300.055049) (xy 51.871872 -300.10173) (xy 51.879767 -300.150307) (xy 51.880262 -300.174914)
			(xy 52.21911 -300.174914) (xy 52.22307 -300.12586) (xy 52.234847 -300.078076) (xy 52.254138 -300.0328)
			(xy 52.280441 -299.991204) (xy 52.313076 -299.954367) (xy 52.351197 -299.923242) (xy 52.393818 -299.898635)
			(xy 52.439834 -299.881183) (xy 52.488053 -299.871339) (xy 52.537228 -299.869358) (xy 52.586083 -299.87529)
			(xy 52.633354 -299.888982) (xy 52.677816 -299.91008) (xy 52.718319 -299.938036) (xy 52.753812 -299.972128)
			(xy 52.783377 -300.011472) (xy 52.806248 -300.055049) (xy 52.821832 -300.10173) (xy 52.829727 -300.150307)
			(xy 52.830222 -300.174914) (xy 53.16907 -300.174914) (xy 53.17303 -300.12586) (xy 53.184807 -300.078076)
			(xy 53.204098 -300.0328) (xy 53.230401 -299.991204) (xy 53.263036 -299.954367) (xy 53.301157 -299.923242)
			(xy 53.343778 -299.898635) (xy 53.389794 -299.881183) (xy 53.438013 -299.871339) (xy 53.487188 -299.869358)
			(xy 53.536043 -299.87529) (xy 53.583314 -299.888982) (xy 53.627776 -299.91008) (xy 53.668279 -299.938036)
			(xy 53.703772 -299.972128) (xy 53.733337 -300.011472) (xy 53.756208 -300.055049) (xy 53.771792 -300.10173)
			(xy 53.779687 -300.150307) (xy 53.780182 -300.174914) (xy 54.11903 -300.174914) (xy 54.12299 -300.12586)
			(xy 54.134767 -300.078076) (xy 54.154058 -300.0328) (xy 54.180361 -299.991204) (xy 54.212996 -299.954367)
			(xy 54.251117 -299.923242) (xy 54.293738 -299.898635) (xy 54.339754 -299.881183) (xy 54.387973 -299.871339)
			(xy 54.437148 -299.869358) (xy 54.486003 -299.87529) (xy 54.533274 -299.888982) (xy 54.577736 -299.91008)
			(xy 54.618239 -299.938036) (xy 54.653732 -299.972128) (xy 54.683297 -300.011472) (xy 54.706168 -300.055049)
			(xy 54.721752 -300.10173) (xy 54.729647 -300.150307) (xy 54.730142 -300.174914) (xy 55.06899 -300.174914)
			(xy 55.07295 -300.12586) (xy 55.084727 -300.078076) (xy 55.104018 -300.0328) (xy 55.130321 -299.991204)
			(xy 55.162956 -299.954367) (xy 55.201077 -299.923242) (xy 55.243698 -299.898635) (xy 55.289714 -299.881183)
			(xy 55.337933 -299.871339) (xy 55.387108 -299.869358) (xy 55.435963 -299.87529) (xy 55.483234 -299.888982)
			(xy 55.527696 -299.91008) (xy 55.568199 -299.938036) (xy 55.603692 -299.972128) (xy 55.633257 -300.011472)
			(xy 55.656128 -300.055049) (xy 55.671712 -300.10173) (xy 55.679607 -300.150307) (xy 55.680102 -300.174914)
			(xy 56.01895 -300.174914) (xy 56.02291 -300.12586) (xy 56.034687 -300.078076) (xy 56.053978 -300.0328)
			(xy 56.080281 -299.991204) (xy 56.112916 -299.954367) (xy 56.151037 -299.923242) (xy 56.193658 -299.898635)
			(xy 56.239674 -299.881183) (xy 56.287893 -299.871339) (xy 56.337068 -299.869358) (xy 56.385923 -299.87529)
			(xy 56.433194 -299.888982) (xy 56.477656 -299.91008) (xy 56.518159 -299.938036) (xy 56.553652 -299.972128)
			(xy 56.583217 -300.011472) (xy 56.606088 -300.055049) (xy 56.621672 -300.10173) (xy 56.629567 -300.150307)
			(xy 56.630062 -300.174914) (xy 56.969164 -300.174914) (xy 56.973124 -300.12586) (xy 56.984901 -300.078076)
			(xy 57.004192 -300.0328) (xy 57.030495 -299.991204) (xy 57.06313 -299.954367) (xy 57.101251 -299.923242)
			(xy 57.143872 -299.898635) (xy 57.189888 -299.881183) (xy 57.238107 -299.871339) (xy 57.287282 -299.869358)
			(xy 57.336137 -299.87529) (xy 57.383408 -299.888982) (xy 57.42787 -299.91008) (xy 57.468373 -299.938036)
			(xy 57.503866 -299.972128) (xy 57.533431 -300.011472) (xy 57.556302 -300.055049) (xy 57.571886 -300.10173)
			(xy 57.579781 -300.150307) (xy 57.580276 -300.174914) (xy 57.919124 -300.174914) (xy 57.923084 -300.12586)
			(xy 57.934861 -300.078076) (xy 57.954152 -300.0328) (xy 57.980455 -299.991204) (xy 58.01309 -299.954367)
			(xy 58.051211 -299.923242) (xy 58.093832 -299.898635) (xy 58.139848 -299.881183) (xy 58.188067 -299.871339)
			(xy 58.237242 -299.869358) (xy 58.286097 -299.87529) (xy 58.333368 -299.888982) (xy 58.37783 -299.91008)
			(xy 58.418333 -299.938036) (xy 58.453826 -299.972128) (xy 58.483391 -300.011472) (xy 58.506262 -300.055049)
			(xy 58.521846 -300.10173) (xy 58.529741 -300.150307) (xy 58.530236 -300.174914) (xy 59.819044 -300.174914)
			(xy 59.823004 -300.12586) (xy 59.834781 -300.078076) (xy 59.854072 -300.0328) (xy 59.880375 -299.991204)
			(xy 59.91301 -299.954367) (xy 59.951131 -299.923242) (xy 59.993752 -299.898635) (xy 60.039768 -299.881183)
			(xy 60.087987 -299.871339) (xy 60.137162 -299.869358) (xy 60.186017 -299.87529) (xy 60.233288 -299.888982)
			(xy 60.27775 -299.91008) (xy 60.318253 -299.938036) (xy 60.353746 -299.972128) (xy 60.383311 -300.011472)
			(xy 60.406182 -300.055049) (xy 60.421766 -300.10173) (xy 60.429661 -300.150307) (xy 60.430156 -300.174914)
			(xy 60.769004 -300.174914) (xy 60.772964 -300.12586) (xy 60.784741 -300.078076) (xy 60.804032 -300.0328)
			(xy 60.830335 -299.991204) (xy 60.86297 -299.954367) (xy 60.901091 -299.923242) (xy 60.943712 -299.898635)
			(xy 60.989728 -299.881183) (xy 61.037947 -299.871339) (xy 61.087122 -299.869358) (xy 61.135977 -299.87529)
			(xy 61.183248 -299.888982) (xy 61.22771 -299.91008) (xy 61.268213 -299.938036) (xy 61.303706 -299.972128)
			(xy 61.333271 -300.011472) (xy 61.356142 -300.055049) (xy 61.371726 -300.10173) (xy 61.379621 -300.150307)
			(xy 61.380116 -300.174914) (xy 61.718964 -300.174914) (xy 61.722924 -300.12586) (xy 61.734701 -300.078076)
			(xy 61.753992 -300.0328) (xy 61.780295 -299.991204) (xy 61.81293 -299.954367) (xy 61.851051 -299.923242)
			(xy 61.893672 -299.898635) (xy 61.939688 -299.881183) (xy 61.987907 -299.871339) (xy 62.037082 -299.869358)
			(xy 62.085937 -299.87529) (xy 62.133208 -299.888982) (xy 62.17767 -299.91008) (xy 62.218173 -299.938036)
			(xy 62.253666 -299.972128) (xy 62.283231 -300.011472) (xy 62.306102 -300.055049) (xy 62.321686 -300.10173)
			(xy 62.329581 -300.150307) (xy 62.330076 -300.174914) (xy 62.669178 -300.174914) (xy 62.673138 -300.12586)
			(xy 62.684915 -300.078076) (xy 62.704206 -300.0328) (xy 62.730509 -299.991204) (xy 62.763144 -299.954367)
			(xy 62.801265 -299.923242) (xy 62.843886 -299.898635) (xy 62.889902 -299.881183) (xy 62.938121 -299.871339)
			(xy 62.987296 -299.869358) (xy 63.036151 -299.87529) (xy 63.083422 -299.888982) (xy 63.127884 -299.91008)
			(xy 63.168387 -299.938036) (xy 63.20388 -299.972128) (xy 63.233445 -300.011472) (xy 63.256316 -300.055049)
			(xy 63.2719 -300.10173) (xy 63.279795 -300.150307) (xy 63.28029 -300.174914) (xy 63.619138 -300.174914)
			(xy 63.623098 -300.12586) (xy 63.634875 -300.078076) (xy 63.654166 -300.0328) (xy 63.680469 -299.991204)
			(xy 63.713104 -299.954367) (xy 63.751225 -299.923242) (xy 63.793846 -299.898635) (xy 63.839862 -299.881183)
			(xy 63.888081 -299.871339) (xy 63.937256 -299.869358) (xy 63.986111 -299.87529) (xy 64.033382 -299.888982)
			(xy 64.077844 -299.91008) (xy 64.118347 -299.938036) (xy 64.15384 -299.972128) (xy 64.183405 -300.011472)
			(xy 64.206276 -300.055049) (xy 64.22186 -300.10173) (xy 64.229755 -300.150307) (xy 64.23025 -300.174914)
			(xy 64.569098 -300.174914) (xy 64.573058 -300.12586) (xy 64.584835 -300.078076) (xy 64.604126 -300.0328)
			(xy 64.630429 -299.991204) (xy 64.663064 -299.954367) (xy 64.701185 -299.923242) (xy 64.743806 -299.898635)
			(xy 64.789822 -299.881183) (xy 64.838041 -299.871339) (xy 64.887216 -299.869358) (xy 64.936071 -299.87529)
			(xy 64.983342 -299.888982) (xy 65.027804 -299.91008) (xy 65.068307 -299.938036) (xy 65.1038 -299.972128)
			(xy 65.133365 -300.011472) (xy 65.156236 -300.055049) (xy 65.17182 -300.10173) (xy 65.179715 -300.150307)
			(xy 65.18021 -300.174914) (xy 65.519058 -300.174914) (xy 65.523018 -300.12586) (xy 65.534795 -300.078076)
			(xy 65.554086 -300.0328) (xy 65.580389 -299.991204) (xy 65.613024 -299.954367) (xy 65.651145 -299.923242)
			(xy 65.693766 -299.898635) (xy 65.739782 -299.881183) (xy 65.788001 -299.871339) (xy 65.837176 -299.869358)
			(xy 65.886031 -299.87529) (xy 65.933302 -299.888982) (xy 65.977764 -299.91008) (xy 66.018267 -299.938036)
			(xy 66.05376 -299.972128) (xy 66.083325 -300.011472) (xy 66.106196 -300.055049) (xy 66.12178 -300.10173)
			(xy 66.129675 -300.150307) (xy 66.13017 -300.174914) (xy 66.469018 -300.174914) (xy 66.472978 -300.12586)
			(xy 66.484755 -300.078076) (xy 66.504046 -300.0328) (xy 66.530349 -299.991204) (xy 66.562984 -299.954367)
			(xy 66.601105 -299.923242) (xy 66.643726 -299.898635) (xy 66.689742 -299.881183) (xy 66.737961 -299.871339)
			(xy 66.787136 -299.869358) (xy 66.835991 -299.87529) (xy 66.883262 -299.888982) (xy 66.927724 -299.91008)
			(xy 66.968227 -299.938036) (xy 67.00372 -299.972128) (xy 67.033285 -300.011472) (xy 67.056156 -300.055049)
			(xy 67.07174 -300.10173) (xy 67.079635 -300.150307) (xy 67.08013 -300.174914) (xy 67.418978 -300.174914)
			(xy 67.422938 -300.12586) (xy 67.434715 -300.078076) (xy 67.454006 -300.0328) (xy 67.480309 -299.991204)
			(xy 67.512944 -299.954367) (xy 67.551065 -299.923242) (xy 67.593686 -299.898635) (xy 67.639702 -299.881183)
			(xy 67.687921 -299.871339) (xy 67.737096 -299.869358) (xy 67.785951 -299.87529) (xy 67.833222 -299.888982)
			(xy 67.877684 -299.91008) (xy 67.918187 -299.938036) (xy 67.95368 -299.972128) (xy 67.983245 -300.011472)
			(xy 68.006116 -300.055049) (xy 68.0217 -300.10173) (xy 68.029595 -300.150307) (xy 68.03009 -300.174914)
			(xy 68.368938 -300.174914) (xy 68.372898 -300.12586) (xy 68.384675 -300.078076) (xy 68.403966 -300.0328)
			(xy 68.430269 -299.991204) (xy 68.462904 -299.954367) (xy 68.501025 -299.923242) (xy 68.543646 -299.898635)
			(xy 68.589662 -299.881183) (xy 68.637881 -299.871339) (xy 68.687056 -299.869358) (xy 68.735911 -299.87529)
			(xy 68.783182 -299.888982) (xy 68.827644 -299.91008) (xy 68.868147 -299.938036) (xy 68.90364 -299.972128)
			(xy 68.933205 -300.011472) (xy 68.956076 -300.055049) (xy 68.97166 -300.10173) (xy 68.979555 -300.150307)
			(xy 68.98005 -300.174914) (xy 69.319152 -300.174914) (xy 69.323112 -300.12586) (xy 69.334889 -300.078076)
			(xy 69.35418 -300.0328) (xy 69.380483 -299.991204) (xy 69.413118 -299.954367) (xy 69.451239 -299.923242)
			(xy 69.49386 -299.898635) (xy 69.539876 -299.881183) (xy 69.588095 -299.871339) (xy 69.63727 -299.869358)
			(xy 69.686125 -299.87529) (xy 69.733396 -299.888982) (xy 69.777858 -299.91008) (xy 69.818361 -299.938036)
			(xy 69.853854 -299.972128) (xy 69.883419 -300.011472) (xy 69.90629 -300.055049) (xy 69.921874 -300.10173)
			(xy 69.929769 -300.150307) (xy 69.930264 -300.174914) (xy 70.269112 -300.174914) (xy 70.273072 -300.12586)
			(xy 70.284849 -300.078076) (xy 70.30414 -300.0328) (xy 70.330443 -299.991204) (xy 70.363078 -299.954367)
			(xy 70.401199 -299.923242) (xy 70.44382 -299.898635) (xy 70.489836 -299.881183) (xy 70.538055 -299.871339)
			(xy 70.58723 -299.869358) (xy 70.636085 -299.87529) (xy 70.683356 -299.888982) (xy 70.727818 -299.91008)
			(xy 70.768321 -299.938036) (xy 70.803814 -299.972128) (xy 70.833379 -300.011472) (xy 70.85625 -300.055049)
			(xy 70.871834 -300.10173) (xy 70.879729 -300.150307) (xy 70.880224 -300.174914) (xy 71.219072 -300.174914)
			(xy 71.223032 -300.12586) (xy 71.234809 -300.078076) (xy 71.2541 -300.0328) (xy 71.280403 -299.991204)
			(xy 71.313038 -299.954367) (xy 71.351159 -299.923242) (xy 71.39378 -299.898635) (xy 71.439796 -299.881183)
			(xy 71.488015 -299.871339) (xy 71.53719 -299.869358) (xy 71.586045 -299.87529) (xy 71.633316 -299.888982)
			(xy 71.677778 -299.91008) (xy 71.718281 -299.938036) (xy 71.753774 -299.972128) (xy 71.783339 -300.011472)
			(xy 71.80621 -300.055049) (xy 71.821794 -300.10173) (xy 71.829689 -300.150307) (xy 71.830184 -300.174914)
			(xy 72.169032 -300.174914) (xy 72.172992 -300.12586) (xy 72.184769 -300.078076) (xy 72.20406 -300.0328)
			(xy 72.230363 -299.991204) (xy 72.262998 -299.954367) (xy 72.301119 -299.923242) (xy 72.34374 -299.898635)
			(xy 72.389756 -299.881183) (xy 72.437975 -299.871339) (xy 72.48715 -299.869358) (xy 72.536005 -299.87529)
			(xy 72.583276 -299.888982) (xy 72.627738 -299.91008) (xy 72.668241 -299.938036) (xy 72.703734 -299.972128)
			(xy 72.733299 -300.011472) (xy 72.75617 -300.055049) (xy 72.771754 -300.10173) (xy 72.779649 -300.150307)
			(xy 72.780144 -300.174914) (xy 73.118992 -300.174914) (xy 73.122952 -300.12586) (xy 73.134729 -300.078076)
			(xy 73.15402 -300.0328) (xy 73.180323 -299.991204) (xy 73.212958 -299.954367) (xy 73.251079 -299.923242)
			(xy 73.2937 -299.898635) (xy 73.339716 -299.881183) (xy 73.387935 -299.871339) (xy 73.43711 -299.869358)
			(xy 73.485965 -299.87529) (xy 73.533236 -299.888982) (xy 73.577698 -299.91008) (xy 73.618201 -299.938036)
			(xy 73.653694 -299.972128) (xy 73.683259 -300.011472) (xy 73.70613 -300.055049) (xy 73.721714 -300.10173)
			(xy 73.729609 -300.150307) (xy 73.730104 -300.174914) (xy 74.068952 -300.174914) (xy 74.072912 -300.12586)
			(xy 74.084689 -300.078076) (xy 74.10398 -300.0328) (xy 74.130283 -299.991204) (xy 74.162918 -299.954367)
			(xy 74.201039 -299.923242) (xy 74.24366 -299.898635) (xy 74.289676 -299.881183) (xy 74.337895 -299.871339)
			(xy 74.38707 -299.869358) (xy 74.435925 -299.87529) (xy 74.483196 -299.888982) (xy 74.527658 -299.91008)
			(xy 74.568161 -299.938036) (xy 74.603654 -299.972128) (xy 74.633219 -300.011472) (xy 74.65609 -300.055049)
			(xy 74.671674 -300.10173) (xy 74.679569 -300.150307) (xy 74.680064 -300.174914) (xy 75.969126 -300.174914)
			(xy 75.973086 -300.12586) (xy 75.984863 -300.078076) (xy 76.004154 -300.0328) (xy 76.030457 -299.991204)
			(xy 76.063092 -299.954367) (xy 76.101213 -299.923242) (xy 76.143834 -299.898635) (xy 76.18985 -299.881183)
			(xy 76.238069 -299.871339) (xy 76.287244 -299.869358) (xy 76.336099 -299.87529) (xy 76.38337 -299.888982)
			(xy 76.427832 -299.91008) (xy 76.468335 -299.938036) (xy 76.503828 -299.972128) (xy 76.533393 -300.011472)
			(xy 76.556264 -300.055049) (xy 76.571848 -300.10173) (xy 76.579743 -300.150307) (xy 76.580238 -300.174914)
			(xy 76.919086 -300.174914) (xy 76.923046 -300.12586) (xy 76.934823 -300.078076) (xy 76.954114 -300.0328)
			(xy 76.980417 -299.991204) (xy 77.013052 -299.954367) (xy 77.051173 -299.923242) (xy 77.093794 -299.898635)
			(xy 77.13981 -299.881183) (xy 77.188029 -299.871339) (xy 77.237204 -299.869358) (xy 77.286059 -299.87529)
			(xy 77.33333 -299.888982) (xy 77.377792 -299.91008) (xy 77.418295 -299.938036) (xy 77.453788 -299.972128)
			(xy 77.483353 -300.011472) (xy 77.506224 -300.055049) (xy 77.521808 -300.10173) (xy 77.529703 -300.150307)
			(xy 77.530198 -300.174914) (xy 77.869046 -300.174914) (xy 77.873006 -300.12586) (xy 77.884783 -300.078076)
			(xy 77.904074 -300.0328) (xy 77.930377 -299.991204) (xy 77.963012 -299.954367) (xy 78.001133 -299.923242)
			(xy 78.043754 -299.898635) (xy 78.08977 -299.881183) (xy 78.137989 -299.871339) (xy 78.187164 -299.869358)
			(xy 78.236019 -299.87529) (xy 78.28329 -299.888982) (xy 78.327752 -299.91008) (xy 78.368255 -299.938036)
			(xy 78.403748 -299.972128) (xy 78.433313 -300.011472) (xy 78.456184 -300.055049) (xy 78.471768 -300.10173)
			(xy 78.479663 -300.150307) (xy 78.480158 -300.174914) (xy 78.819006 -300.174914) (xy 78.822966 -300.12586)
			(xy 78.834743 -300.078076) (xy 78.854034 -300.0328) (xy 78.880337 -299.991204) (xy 78.912972 -299.954367)
			(xy 78.951093 -299.923242) (xy 78.993714 -299.898635) (xy 79.03973 -299.881183) (xy 79.087949 -299.871339)
			(xy 79.137124 -299.869358) (xy 79.185979 -299.87529) (xy 79.23325 -299.888982) (xy 79.277712 -299.91008)
			(xy 79.318215 -299.938036) (xy 79.353708 -299.972128) (xy 79.383273 -300.011472) (xy 79.406144 -300.055049)
			(xy 79.421728 -300.10173) (xy 79.429623 -300.150307) (xy 79.430118 -300.174914) (xy 79.768966 -300.174914)
			(xy 79.772926 -300.12586) (xy 79.784703 -300.078076) (xy 79.803994 -300.0328) (xy 79.830297 -299.991204)
			(xy 79.862932 -299.954367) (xy 79.901053 -299.923242) (xy 79.943674 -299.898635) (xy 79.98969 -299.881183)
			(xy 80.037909 -299.871339) (xy 80.087084 -299.869358) (xy 80.135939 -299.87529) (xy 80.18321 -299.888982)
			(xy 80.227672 -299.91008) (xy 80.268175 -299.938036) (xy 80.303668 -299.972128) (xy 80.333233 -300.011472)
			(xy 80.356104 -300.055049) (xy 80.371688 -300.10173) (xy 80.379583 -300.150307) (xy 80.380078 -300.174914)
			(xy 80.71918 -300.174914) (xy 80.72314 -300.12586) (xy 80.734917 -300.078076) (xy 80.754208 -300.0328)
			(xy 80.780511 -299.991204) (xy 80.813146 -299.954367) (xy 80.851267 -299.923242) (xy 80.893888 -299.898635)
			(xy 80.939904 -299.881183) (xy 80.988123 -299.871339) (xy 81.037298 -299.869358) (xy 81.086153 -299.87529)
			(xy 81.133424 -299.888982) (xy 81.177886 -299.91008) (xy 81.218389 -299.938036) (xy 81.253882 -299.972128)
			(xy 81.283447 -300.011472) (xy 81.306318 -300.055049) (xy 81.321902 -300.10173) (xy 81.329797 -300.150307)
			(xy 81.330292 -300.174914) (xy 81.66914 -300.174914) (xy 81.6731 -300.12586) (xy 81.684877 -300.078076)
			(xy 81.704168 -300.0328) (xy 81.730471 -299.991204) (xy 81.763106 -299.954367) (xy 81.801227 -299.923242)
			(xy 81.843848 -299.898635) (xy 81.889864 -299.881183) (xy 81.938083 -299.871339) (xy 81.987258 -299.869358)
			(xy 82.036113 -299.87529) (xy 82.083384 -299.888982) (xy 82.127846 -299.91008) (xy 82.168349 -299.938036)
			(xy 82.203842 -299.972128) (xy 82.233407 -300.011472) (xy 82.256278 -300.055049) (xy 82.271862 -300.10173)
			(xy 82.279757 -300.150307) (xy 82.280252 -300.174914) (xy 82.6191 -300.174914) (xy 82.62306 -300.12586)
			(xy 82.634837 -300.078076) (xy 82.654128 -300.0328) (xy 82.680431 -299.991204) (xy 82.713066 -299.954367)
			(xy 82.751187 -299.923242) (xy 82.793808 -299.898635) (xy 82.839824 -299.881183) (xy 82.888043 -299.871339)
			(xy 82.937218 -299.869358) (xy 82.986073 -299.87529) (xy 83.033344 -299.888982) (xy 83.077806 -299.91008)
			(xy 83.118309 -299.938036) (xy 83.153802 -299.972128) (xy 83.183367 -300.011472) (xy 83.206238 -300.055049)
			(xy 83.221822 -300.10173) (xy 83.229717 -300.150307) (xy 83.230212 -300.174914) (xy 83.229717 -300.199521)
			(xy 83.221822 -300.248098) (xy 83.206238 -300.294779) (xy 83.183367 -300.338356) (xy 83.153802 -300.3777)
			(xy 83.138034 -300.392846) (xy 93.257876 -300.392846) (xy 93.261947 -300.337224) (xy 93.274073 -300.282787)
			(xy 93.293996 -300.230696) (xy 93.321292 -300.182061) (xy 93.355378 -300.137918) (xy 93.395527 -300.099209)
			(xy 93.440885 -300.066758) (xy 93.490485 -300.041257) (xy 93.543269 -300.02325) (xy 93.598112 -300.01312)
			(xy 93.653846 -300.011083) (xy 93.709283 -300.017183) (xy 93.76324 -300.031289) (xy 93.814569 -300.053101)
			(xy 93.862175 -300.082155) (xy 93.905043 -300.11783) (xy 93.94226 -300.159367) (xy 93.973033 -300.20588)
			(xy 93.996705 -300.256377) (xy 94.012773 -300.309784) (xy 94.020893 -300.36496) (xy 94.021402 -300.392846)
			(xy 94.020893 -300.420732) (xy 94.012773 -300.475908) (xy 93.996705 -300.529315) (xy 93.973033 -300.579812)
			(xy 93.94226 -300.626325) (xy 93.905043 -300.667862) (xy 93.862175 -300.703537) (xy 93.814569 -300.732591)
			(xy 93.76324 -300.754403) (xy 93.709283 -300.768509) (xy 93.653846 -300.774609) (xy 93.598112 -300.772572)
			(xy 93.543269 -300.762442) (xy 93.490485 -300.744435) (xy 93.440885 -300.718934) (xy 93.395527 -300.686483)
			(xy 93.355378 -300.647774) (xy 93.321292 -300.603631) (xy 93.293996 -300.554996) (xy 93.274073 -300.502905)
			(xy 93.261947 -300.448468) (xy 93.257876 -300.392846) (xy 83.138034 -300.392846) (xy 83.118309 -300.411792)
			(xy 83.077806 -300.439748) (xy 83.033344 -300.460846) (xy 82.986073 -300.474538) (xy 82.937218 -300.48047)
			(xy 82.888043 -300.478489) (xy 82.839824 -300.468645) (xy 82.793808 -300.451193) (xy 82.751187 -300.426586)
			(xy 82.713066 -300.395461) (xy 82.680431 -300.358624) (xy 82.654128 -300.317028) (xy 82.634837 -300.271752)
			(xy 82.62306 -300.223968) (xy 82.6191 -300.174914) (xy 82.280252 -300.174914) (xy 82.279757 -300.199521)
			(xy 82.271862 -300.248098) (xy 82.256278 -300.294779) (xy 82.233407 -300.338356) (xy 82.203842 -300.3777)
			(xy 82.168349 -300.411792) (xy 82.127846 -300.439748) (xy 82.083384 -300.460846) (xy 82.036113 -300.474538)
			(xy 81.987258 -300.48047) (xy 81.938083 -300.478489) (xy 81.889864 -300.468645) (xy 81.843848 -300.451193)
			(xy 81.801227 -300.426586) (xy 81.763106 -300.395461) (xy 81.730471 -300.358624) (xy 81.704168 -300.317028)
			(xy 81.684877 -300.271752) (xy 81.6731 -300.223968) (xy 81.66914 -300.174914) (xy 81.330292 -300.174914)
			(xy 81.329797 -300.199521) (xy 81.321902 -300.248098) (xy 81.306318 -300.294779) (xy 81.283447 -300.338356)
			(xy 81.253882 -300.3777) (xy 81.218389 -300.411792) (xy 81.177886 -300.439748) (xy 81.133424 -300.460846)
			(xy 81.086153 -300.474538) (xy 81.037298 -300.48047) (xy 80.988123 -300.478489) (xy 80.939904 -300.468645)
			(xy 80.893888 -300.451193) (xy 80.851267 -300.426586) (xy 80.813146 -300.395461) (xy 80.780511 -300.358624)
			(xy 80.754208 -300.317028) (xy 80.734917 -300.271752) (xy 80.72314 -300.223968) (xy 80.71918 -300.174914)
			(xy 80.380078 -300.174914) (xy 80.379583 -300.199521) (xy 80.371688 -300.248098) (xy 80.356104 -300.294779)
			(xy 80.333233 -300.338356) (xy 80.303668 -300.3777) (xy 80.268175 -300.411792) (xy 80.227672 -300.439748)
			(xy 80.18321 -300.460846) (xy 80.135939 -300.474538) (xy 80.087084 -300.48047) (xy 80.037909 -300.478489)
			(xy 79.98969 -300.468645) (xy 79.943674 -300.451193) (xy 79.901053 -300.426586) (xy 79.862932 -300.395461)
			(xy 79.830297 -300.358624) (xy 79.803994 -300.317028) (xy 79.784703 -300.271752) (xy 79.772926 -300.223968)
			(xy 79.768966 -300.174914) (xy 79.430118 -300.174914) (xy 79.429623 -300.199521) (xy 79.421728 -300.248098)
			(xy 79.406144 -300.294779) (xy 79.383273 -300.338356) (xy 79.353708 -300.3777) (xy 79.318215 -300.411792)
			(xy 79.277712 -300.439748) (xy 79.23325 -300.460846) (xy 79.185979 -300.474538) (xy 79.137124 -300.48047)
			(xy 79.087949 -300.478489) (xy 79.03973 -300.468645) (xy 78.993714 -300.451193) (xy 78.951093 -300.426586)
			(xy 78.912972 -300.395461) (xy 78.880337 -300.358624) (xy 78.854034 -300.317028) (xy 78.834743 -300.271752)
			(xy 78.822966 -300.223968) (xy 78.819006 -300.174914) (xy 78.480158 -300.174914) (xy 78.479663 -300.199521)
			(xy 78.471768 -300.248098) (xy 78.456184 -300.294779) (xy 78.433313 -300.338356) (xy 78.403748 -300.3777)
			(xy 78.368255 -300.411792) (xy 78.327752 -300.439748) (xy 78.28329 -300.460846) (xy 78.236019 -300.474538)
			(xy 78.187164 -300.48047) (xy 78.137989 -300.478489) (xy 78.08977 -300.468645) (xy 78.043754 -300.451193)
			(xy 78.001133 -300.426586) (xy 77.963012 -300.395461) (xy 77.930377 -300.358624) (xy 77.904074 -300.317028)
			(xy 77.884783 -300.271752) (xy 77.873006 -300.223968) (xy 77.869046 -300.174914) (xy 77.530198 -300.174914)
			(xy 77.529703 -300.199521) (xy 77.521808 -300.248098) (xy 77.506224 -300.294779) (xy 77.483353 -300.338356)
			(xy 77.453788 -300.3777) (xy 77.418295 -300.411792) (xy 77.377792 -300.439748) (xy 77.33333 -300.460846)
			(xy 77.286059 -300.474538) (xy 77.237204 -300.48047) (xy 77.188029 -300.478489) (xy 77.13981 -300.468645)
			(xy 77.093794 -300.451193) (xy 77.051173 -300.426586) (xy 77.013052 -300.395461) (xy 76.980417 -300.358624)
			(xy 76.954114 -300.317028) (xy 76.934823 -300.271752) (xy 76.923046 -300.223968) (xy 76.919086 -300.174914)
			(xy 76.580238 -300.174914) (xy 76.579743 -300.199521) (xy 76.571848 -300.248098) (xy 76.556264 -300.294779)
			(xy 76.533393 -300.338356) (xy 76.503828 -300.3777) (xy 76.468335 -300.411792) (xy 76.427832 -300.439748)
			(xy 76.38337 -300.460846) (xy 76.336099 -300.474538) (xy 76.287244 -300.48047) (xy 76.238069 -300.478489)
			(xy 76.18985 -300.468645) (xy 76.143834 -300.451193) (xy 76.101213 -300.426586) (xy 76.063092 -300.395461)
			(xy 76.030457 -300.358624) (xy 76.004154 -300.317028) (xy 75.984863 -300.271752) (xy 75.973086 -300.223968)
			(xy 75.969126 -300.174914) (xy 74.680064 -300.174914) (xy 74.679569 -300.199521) (xy 74.671674 -300.248098)
			(xy 74.65609 -300.294779) (xy 74.633219 -300.338356) (xy 74.603654 -300.3777) (xy 74.568161 -300.411792)
			(xy 74.527658 -300.439748) (xy 74.483196 -300.460846) (xy 74.435925 -300.474538) (xy 74.38707 -300.48047)
			(xy 74.337895 -300.478489) (xy 74.289676 -300.468645) (xy 74.24366 -300.451193) (xy 74.201039 -300.426586)
			(xy 74.162918 -300.395461) (xy 74.130283 -300.358624) (xy 74.10398 -300.317028) (xy 74.084689 -300.271752)
			(xy 74.072912 -300.223968) (xy 74.068952 -300.174914) (xy 73.730104 -300.174914) (xy 73.729609 -300.199521)
			(xy 73.721714 -300.248098) (xy 73.70613 -300.294779) (xy 73.683259 -300.338356) (xy 73.653694 -300.3777)
			(xy 73.618201 -300.411792) (xy 73.577698 -300.439748) (xy 73.533236 -300.460846) (xy 73.485965 -300.474538)
			(xy 73.43711 -300.48047) (xy 73.387935 -300.478489) (xy 73.339716 -300.468645) (xy 73.2937 -300.451193)
			(xy 73.251079 -300.426586) (xy 73.212958 -300.395461) (xy 73.180323 -300.358624) (xy 73.15402 -300.317028)
			(xy 73.134729 -300.271752) (xy 73.122952 -300.223968) (xy 73.118992 -300.174914) (xy 72.780144 -300.174914)
			(xy 72.779649 -300.199521) (xy 72.771754 -300.248098) (xy 72.75617 -300.294779) (xy 72.733299 -300.338356)
			(xy 72.703734 -300.3777) (xy 72.668241 -300.411792) (xy 72.627738 -300.439748) (xy 72.583276 -300.460846)
			(xy 72.536005 -300.474538) (xy 72.48715 -300.48047) (xy 72.437975 -300.478489) (xy 72.389756 -300.468645)
			(xy 72.34374 -300.451193) (xy 72.301119 -300.426586) (xy 72.262998 -300.395461) (xy 72.230363 -300.358624)
			(xy 72.20406 -300.317028) (xy 72.184769 -300.271752) (xy 72.172992 -300.223968) (xy 72.169032 -300.174914)
			(xy 71.830184 -300.174914) (xy 71.829689 -300.199521) (xy 71.821794 -300.248098) (xy 71.80621 -300.294779)
			(xy 71.783339 -300.338356) (xy 71.753774 -300.3777) (xy 71.718281 -300.411792) (xy 71.677778 -300.439748)
			(xy 71.633316 -300.460846) (xy 71.586045 -300.474538) (xy 71.53719 -300.48047) (xy 71.488015 -300.478489)
			(xy 71.439796 -300.468645) (xy 71.39378 -300.451193) (xy 71.351159 -300.426586) (xy 71.313038 -300.395461)
			(xy 71.280403 -300.358624) (xy 71.2541 -300.317028) (xy 71.234809 -300.271752) (xy 71.223032 -300.223968)
			(xy 71.219072 -300.174914) (xy 70.880224 -300.174914) (xy 70.879729 -300.199521) (xy 70.871834 -300.248098)
			(xy 70.85625 -300.294779) (xy 70.833379 -300.338356) (xy 70.803814 -300.3777) (xy 70.768321 -300.411792)
			(xy 70.727818 -300.439748) (xy 70.683356 -300.460846) (xy 70.636085 -300.474538) (xy 70.58723 -300.48047)
			(xy 70.538055 -300.478489) (xy 70.489836 -300.468645) (xy 70.44382 -300.451193) (xy 70.401199 -300.426586)
			(xy 70.363078 -300.395461) (xy 70.330443 -300.358624) (xy 70.30414 -300.317028) (xy 70.284849 -300.271752)
			(xy 70.273072 -300.223968) (xy 70.269112 -300.174914) (xy 69.930264 -300.174914) (xy 69.929769 -300.199521)
			(xy 69.921874 -300.248098) (xy 69.90629 -300.294779) (xy 69.883419 -300.338356) (xy 69.853854 -300.3777)
			(xy 69.818361 -300.411792) (xy 69.777858 -300.439748) (xy 69.733396 -300.460846) (xy 69.686125 -300.474538)
			(xy 69.63727 -300.48047) (xy 69.588095 -300.478489) (xy 69.539876 -300.468645) (xy 69.49386 -300.451193)
			(xy 69.451239 -300.426586) (xy 69.413118 -300.395461) (xy 69.380483 -300.358624) (xy 69.35418 -300.317028)
			(xy 69.334889 -300.271752) (xy 69.323112 -300.223968) (xy 69.319152 -300.174914) (xy 68.98005 -300.174914)
			(xy 68.979555 -300.199521) (xy 68.97166 -300.248098) (xy 68.956076 -300.294779) (xy 68.933205 -300.338356)
			(xy 68.90364 -300.3777) (xy 68.868147 -300.411792) (xy 68.827644 -300.439748) (xy 68.783182 -300.460846)
			(xy 68.735911 -300.474538) (xy 68.687056 -300.48047) (xy 68.637881 -300.478489) (xy 68.589662 -300.468645)
			(xy 68.543646 -300.451193) (xy 68.501025 -300.426586) (xy 68.462904 -300.395461) (xy 68.430269 -300.358624)
			(xy 68.403966 -300.317028) (xy 68.384675 -300.271752) (xy 68.372898 -300.223968) (xy 68.368938 -300.174914)
			(xy 68.03009 -300.174914) (xy 68.029595 -300.199521) (xy 68.0217 -300.248098) (xy 68.006116 -300.294779)
			(xy 67.983245 -300.338356) (xy 67.95368 -300.3777) (xy 67.918187 -300.411792) (xy 67.877684 -300.439748)
			(xy 67.833222 -300.460846) (xy 67.785951 -300.474538) (xy 67.737096 -300.48047) (xy 67.687921 -300.478489)
			(xy 67.639702 -300.468645) (xy 67.593686 -300.451193) (xy 67.551065 -300.426586) (xy 67.512944 -300.395461)
			(xy 67.480309 -300.358624) (xy 67.454006 -300.317028) (xy 67.434715 -300.271752) (xy 67.422938 -300.223968)
			(xy 67.418978 -300.174914) (xy 67.08013 -300.174914) (xy 67.079635 -300.199521) (xy 67.07174 -300.248098)
			(xy 67.056156 -300.294779) (xy 67.033285 -300.338356) (xy 67.00372 -300.3777) (xy 66.968227 -300.411792)
			(xy 66.927724 -300.439748) (xy 66.883262 -300.460846) (xy 66.835991 -300.474538) (xy 66.787136 -300.48047)
			(xy 66.737961 -300.478489) (xy 66.689742 -300.468645) (xy 66.643726 -300.451193) (xy 66.601105 -300.426586)
			(xy 66.562984 -300.395461) (xy 66.530349 -300.358624) (xy 66.504046 -300.317028) (xy 66.484755 -300.271752)
			(xy 66.472978 -300.223968) (xy 66.469018 -300.174914) (xy 66.13017 -300.174914) (xy 66.129675 -300.199521)
			(xy 66.12178 -300.248098) (xy 66.106196 -300.294779) (xy 66.083325 -300.338356) (xy 66.05376 -300.3777)
			(xy 66.018267 -300.411792) (xy 65.977764 -300.439748) (xy 65.933302 -300.460846) (xy 65.886031 -300.474538)
			(xy 65.837176 -300.48047) (xy 65.788001 -300.478489) (xy 65.739782 -300.468645) (xy 65.693766 -300.451193)
			(xy 65.651145 -300.426586) (xy 65.613024 -300.395461) (xy 65.580389 -300.358624) (xy 65.554086 -300.317028)
			(xy 65.534795 -300.271752) (xy 65.523018 -300.223968) (xy 65.519058 -300.174914) (xy 65.18021 -300.174914)
			(xy 65.179715 -300.199521) (xy 65.17182 -300.248098) (xy 65.156236 -300.294779) (xy 65.133365 -300.338356)
			(xy 65.1038 -300.3777) (xy 65.068307 -300.411792) (xy 65.027804 -300.439748) (xy 64.983342 -300.460846)
			(xy 64.936071 -300.474538) (xy 64.887216 -300.48047) (xy 64.838041 -300.478489) (xy 64.789822 -300.468645)
			(xy 64.743806 -300.451193) (xy 64.701185 -300.426586) (xy 64.663064 -300.395461) (xy 64.630429 -300.358624)
			(xy 64.604126 -300.317028) (xy 64.584835 -300.271752) (xy 64.573058 -300.223968) (xy 64.569098 -300.174914)
			(xy 64.23025 -300.174914) (xy 64.229755 -300.199521) (xy 64.22186 -300.248098) (xy 64.206276 -300.294779)
			(xy 64.183405 -300.338356) (xy 64.15384 -300.3777) (xy 64.118347 -300.411792) (xy 64.077844 -300.439748)
			(xy 64.033382 -300.460846) (xy 63.986111 -300.474538) (xy 63.937256 -300.48047) (xy 63.888081 -300.478489)
			(xy 63.839862 -300.468645) (xy 63.793846 -300.451193) (xy 63.751225 -300.426586) (xy 63.713104 -300.395461)
			(xy 63.680469 -300.358624) (xy 63.654166 -300.317028) (xy 63.634875 -300.271752) (xy 63.623098 -300.223968)
			(xy 63.619138 -300.174914) (xy 63.28029 -300.174914) (xy 63.279795 -300.199521) (xy 63.2719 -300.248098)
			(xy 63.256316 -300.294779) (xy 63.233445 -300.338356) (xy 63.20388 -300.3777) (xy 63.168387 -300.411792)
			(xy 63.127884 -300.439748) (xy 63.083422 -300.460846) (xy 63.036151 -300.474538) (xy 62.987296 -300.48047)
			(xy 62.938121 -300.478489) (xy 62.889902 -300.468645) (xy 62.843886 -300.451193) (xy 62.801265 -300.426586)
			(xy 62.763144 -300.395461) (xy 62.730509 -300.358624) (xy 62.704206 -300.317028) (xy 62.684915 -300.271752)
			(xy 62.673138 -300.223968) (xy 62.669178 -300.174914) (xy 62.330076 -300.174914) (xy 62.329581 -300.199521)
			(xy 62.321686 -300.248098) (xy 62.306102 -300.294779) (xy 62.283231 -300.338356) (xy 62.253666 -300.3777)
			(xy 62.218173 -300.411792) (xy 62.17767 -300.439748) (xy 62.133208 -300.460846) (xy 62.085937 -300.474538)
			(xy 62.037082 -300.48047) (xy 61.987907 -300.478489) (xy 61.939688 -300.468645) (xy 61.893672 -300.451193)
			(xy 61.851051 -300.426586) (xy 61.81293 -300.395461) (xy 61.780295 -300.358624) (xy 61.753992 -300.317028)
			(xy 61.734701 -300.271752) (xy 61.722924 -300.223968) (xy 61.718964 -300.174914) (xy 61.380116 -300.174914)
			(xy 61.379621 -300.199521) (xy 61.371726 -300.248098) (xy 61.356142 -300.294779) (xy 61.333271 -300.338356)
			(xy 61.303706 -300.3777) (xy 61.268213 -300.411792) (xy 61.22771 -300.439748) (xy 61.183248 -300.460846)
			(xy 61.135977 -300.474538) (xy 61.087122 -300.48047) (xy 61.037947 -300.478489) (xy 60.989728 -300.468645)
			(xy 60.943712 -300.451193) (xy 60.901091 -300.426586) (xy 60.86297 -300.395461) (xy 60.830335 -300.358624)
			(xy 60.804032 -300.317028) (xy 60.784741 -300.271752) (xy 60.772964 -300.223968) (xy 60.769004 -300.174914)
			(xy 60.430156 -300.174914) (xy 60.429661 -300.199521) (xy 60.421766 -300.248098) (xy 60.406182 -300.294779)
			(xy 60.383311 -300.338356) (xy 60.353746 -300.3777) (xy 60.318253 -300.411792) (xy 60.27775 -300.439748)
			(xy 60.233288 -300.460846) (xy 60.186017 -300.474538) (xy 60.137162 -300.48047) (xy 60.087987 -300.478489)
			(xy 60.039768 -300.468645) (xy 59.993752 -300.451193) (xy 59.951131 -300.426586) (xy 59.91301 -300.395461)
			(xy 59.880375 -300.358624) (xy 59.854072 -300.317028) (xy 59.834781 -300.271752) (xy 59.823004 -300.223968)
			(xy 59.819044 -300.174914) (xy 58.530236 -300.174914) (xy 58.529741 -300.199521) (xy 58.521846 -300.248098)
			(xy 58.506262 -300.294779) (xy 58.483391 -300.338356) (xy 58.453826 -300.3777) (xy 58.418333 -300.411792)
			(xy 58.37783 -300.439748) (xy 58.333368 -300.460846) (xy 58.286097 -300.474538) (xy 58.237242 -300.48047)
			(xy 58.188067 -300.478489) (xy 58.139848 -300.468645) (xy 58.093832 -300.451193) (xy 58.051211 -300.426586)
			(xy 58.01309 -300.395461) (xy 57.980455 -300.358624) (xy 57.954152 -300.317028) (xy 57.934861 -300.271752)
			(xy 57.923084 -300.223968) (xy 57.919124 -300.174914) (xy 57.580276 -300.174914) (xy 57.579781 -300.199521)
			(xy 57.571886 -300.248098) (xy 57.556302 -300.294779) (xy 57.533431 -300.338356) (xy 57.503866 -300.3777)
			(xy 57.468373 -300.411792) (xy 57.42787 -300.439748) (xy 57.383408 -300.460846) (xy 57.336137 -300.474538)
			(xy 57.287282 -300.48047) (xy 57.238107 -300.478489) (xy 57.189888 -300.468645) (xy 57.143872 -300.451193)
			(xy 57.101251 -300.426586) (xy 57.06313 -300.395461) (xy 57.030495 -300.358624) (xy 57.004192 -300.317028)
			(xy 56.984901 -300.271752) (xy 56.973124 -300.223968) (xy 56.969164 -300.174914) (xy 56.630062 -300.174914)
			(xy 56.629567 -300.199521) (xy 56.621672 -300.248098) (xy 56.606088 -300.294779) (xy 56.583217 -300.338356)
			(xy 56.553652 -300.3777) (xy 56.518159 -300.411792) (xy 56.477656 -300.439748) (xy 56.433194 -300.460846)
			(xy 56.385923 -300.474538) (xy 56.337068 -300.48047) (xy 56.287893 -300.478489) (xy 56.239674 -300.468645)
			(xy 56.193658 -300.451193) (xy 56.151037 -300.426586) (xy 56.112916 -300.395461) (xy 56.080281 -300.358624)
			(xy 56.053978 -300.317028) (xy 56.034687 -300.271752) (xy 56.02291 -300.223968) (xy 56.01895 -300.174914)
			(xy 55.680102 -300.174914) (xy 55.679607 -300.199521) (xy 55.671712 -300.248098) (xy 55.656128 -300.294779)
			(xy 55.633257 -300.338356) (xy 55.603692 -300.3777) (xy 55.568199 -300.411792) (xy 55.527696 -300.439748)
			(xy 55.483234 -300.460846) (xy 55.435963 -300.474538) (xy 55.387108 -300.48047) (xy 55.337933 -300.478489)
			(xy 55.289714 -300.468645) (xy 55.243698 -300.451193) (xy 55.201077 -300.426586) (xy 55.162956 -300.395461)
			(xy 55.130321 -300.358624) (xy 55.104018 -300.317028) (xy 55.084727 -300.271752) (xy 55.07295 -300.223968)
			(xy 55.06899 -300.174914) (xy 54.730142 -300.174914) (xy 54.729647 -300.199521) (xy 54.721752 -300.248098)
			(xy 54.706168 -300.294779) (xy 54.683297 -300.338356) (xy 54.653732 -300.3777) (xy 54.618239 -300.411792)
			(xy 54.577736 -300.439748) (xy 54.533274 -300.460846) (xy 54.486003 -300.474538) (xy 54.437148 -300.48047)
			(xy 54.387973 -300.478489) (xy 54.339754 -300.468645) (xy 54.293738 -300.451193) (xy 54.251117 -300.426586)
			(xy 54.212996 -300.395461) (xy 54.180361 -300.358624) (xy 54.154058 -300.317028) (xy 54.134767 -300.271752)
			(xy 54.12299 -300.223968) (xy 54.11903 -300.174914) (xy 53.780182 -300.174914) (xy 53.779687 -300.199521)
			(xy 53.771792 -300.248098) (xy 53.756208 -300.294779) (xy 53.733337 -300.338356) (xy 53.703772 -300.3777)
			(xy 53.668279 -300.411792) (xy 53.627776 -300.439748) (xy 53.583314 -300.460846) (xy 53.536043 -300.474538)
			(xy 53.487188 -300.48047) (xy 53.438013 -300.478489) (xy 53.389794 -300.468645) (xy 53.343778 -300.451193)
			(xy 53.301157 -300.426586) (xy 53.263036 -300.395461) (xy 53.230401 -300.358624) (xy 53.204098 -300.317028)
			(xy 53.184807 -300.271752) (xy 53.17303 -300.223968) (xy 53.16907 -300.174914) (xy 52.830222 -300.174914)
			(xy 52.829727 -300.199521) (xy 52.821832 -300.248098) (xy 52.806248 -300.294779) (xy 52.783377 -300.338356)
			(xy 52.753812 -300.3777) (xy 52.718319 -300.411792) (xy 52.677816 -300.439748) (xy 52.633354 -300.460846)
			(xy 52.586083 -300.474538) (xy 52.537228 -300.48047) (xy 52.488053 -300.478489) (xy 52.439834 -300.468645)
			(xy 52.393818 -300.451193) (xy 52.351197 -300.426586) (xy 52.313076 -300.395461) (xy 52.280441 -300.358624)
			(xy 52.254138 -300.317028) (xy 52.234847 -300.271752) (xy 52.22307 -300.223968) (xy 52.21911 -300.174914)
			(xy 51.880262 -300.174914) (xy 51.879767 -300.199521) (xy 51.871872 -300.248098) (xy 51.856288 -300.294779)
			(xy 51.833417 -300.338356) (xy 51.803852 -300.3777) (xy 51.768359 -300.411792) (xy 51.727856 -300.439748)
			(xy 51.683394 -300.460846) (xy 51.636123 -300.474538) (xy 51.587268 -300.48047) (xy 51.538093 -300.478489)
			(xy 51.489874 -300.468645) (xy 51.443858 -300.451193) (xy 51.401237 -300.426586) (xy 51.363116 -300.395461)
			(xy 51.330481 -300.358624) (xy 51.304178 -300.317028) (xy 51.284887 -300.271752) (xy 51.27311 -300.223968)
			(xy 51.26915 -300.174914) (xy 50.930302 -300.174914) (xy 50.929807 -300.199521) (xy 50.921912 -300.248098)
			(xy 50.906328 -300.294779) (xy 50.883457 -300.338356) (xy 50.853892 -300.3777) (xy 50.818399 -300.411792)
			(xy 50.777896 -300.439748) (xy 50.733434 -300.460846) (xy 50.686163 -300.474538) (xy 50.637308 -300.48047)
			(xy 50.588133 -300.478489) (xy 50.539914 -300.468645) (xy 50.493898 -300.451193) (xy 50.451277 -300.426586)
			(xy 50.413156 -300.395461) (xy 50.380521 -300.358624) (xy 50.354218 -300.317028) (xy 50.334927 -300.271752)
			(xy 50.32315 -300.223968) (xy 50.31919 -300.174914) (xy 49.030128 -300.174914) (xy 49.029633 -300.199521)
			(xy 49.021738 -300.248098) (xy 49.006154 -300.294779) (xy 48.983283 -300.338356) (xy 48.953718 -300.3777)
			(xy 48.918225 -300.411792) (xy 48.877722 -300.439748) (xy 48.83326 -300.460846) (xy 48.785989 -300.474538)
			(xy 48.737134 -300.48047) (xy 48.687959 -300.478489) (xy 48.63974 -300.468645) (xy 48.593724 -300.451193)
			(xy 48.551103 -300.426586) (xy 48.512982 -300.395461) (xy 48.480347 -300.358624) (xy 48.454044 -300.317028)
			(xy 48.434753 -300.271752) (xy 48.422976 -300.223968) (xy 48.419016 -300.174914) (xy 48.080168 -300.174914)
			(xy 48.079914 -300.185328) (xy 48.079914 -300.191678) (xy 48.07966 -300.19625) (xy 48.07966 -300.197012)
			(xy 48.078437 -300.211413) (xy 48.073604 -300.23991) (xy 48.070008 -300.253908) (xy 48.06823 -300.260512)
			(xy 48.06823 -301.033434) (xy 48.070008 -301.046642) (xy 48.07077 -301.04969) (xy 48.075166 -301.068174)
			(xy 48.079876 -301.105876) (xy 48.080168 -301.124874) (xy 49.368976 -301.124874) (xy 49.372936 -301.07582)
			(xy 49.384713 -301.028036) (xy 49.404004 -300.98276) (xy 49.430307 -300.941164) (xy 49.462942 -300.904327)
			(xy 49.501063 -300.873202) (xy 49.543684 -300.848595) (xy 49.5897 -300.831143) (xy 49.637919 -300.821299)
			(xy 49.687094 -300.819318) (xy 49.735949 -300.82525) (xy 49.78322 -300.838942) (xy 49.827682 -300.86004)
			(xy 49.868185 -300.887996) (xy 49.903678 -300.922088) (xy 49.933243 -300.961432) (xy 49.956114 -301.005009)
			(xy 49.971698 -301.05169) (xy 49.979593 -301.100267) (xy 49.980088 -301.124874) (xy 50.31919 -301.124874)
			(xy 50.32315 -301.07582) (xy 50.334927 -301.028036) (xy 50.354218 -300.98276) (xy 50.380521 -300.941164)
			(xy 50.413156 -300.904327) (xy 50.451277 -300.873202) (xy 50.493898 -300.848595) (xy 50.539914 -300.831143)
			(xy 50.588133 -300.821299) (xy 50.637308 -300.819318) (xy 50.686163 -300.82525) (xy 50.733434 -300.838942)
			(xy 50.777896 -300.86004) (xy 50.818399 -300.887996) (xy 50.853892 -300.922088) (xy 50.883457 -300.961432)
			(xy 50.906328 -301.005009) (xy 50.921912 -301.05169) (xy 50.929807 -301.100267) (xy 50.930302 -301.124874)
			(xy 51.26915 -301.124874) (xy 51.27311 -301.07582) (xy 51.284887 -301.028036) (xy 51.304178 -300.98276)
			(xy 51.330481 -300.941164) (xy 51.363116 -300.904327) (xy 51.401237 -300.873202) (xy 51.443858 -300.848595)
			(xy 51.489874 -300.831143) (xy 51.538093 -300.821299) (xy 51.587268 -300.819318) (xy 51.636123 -300.82525)
			(xy 51.683394 -300.838942) (xy 51.727856 -300.86004) (xy 51.768359 -300.887996) (xy 51.803852 -300.922088)
			(xy 51.833417 -300.961432) (xy 51.856288 -301.005009) (xy 51.871872 -301.05169) (xy 51.879767 -301.100267)
			(xy 51.880262 -301.124874) (xy 52.21911 -301.124874) (xy 52.22307 -301.07582) (xy 52.234847 -301.028036)
			(xy 52.254138 -300.98276) (xy 52.280441 -300.941164) (xy 52.313076 -300.904327) (xy 52.351197 -300.873202)
			(xy 52.393818 -300.848595) (xy 52.439834 -300.831143) (xy 52.488053 -300.821299) (xy 52.537228 -300.819318)
			(xy 52.586083 -300.82525) (xy 52.633354 -300.838942) (xy 52.677816 -300.86004) (xy 52.718319 -300.887996)
			(xy 52.753812 -300.922088) (xy 52.783377 -300.961432) (xy 52.806248 -301.005009) (xy 52.821832 -301.05169)
			(xy 52.829727 -301.100267) (xy 52.830222 -301.124874) (xy 53.16907 -301.124874) (xy 53.17303 -301.07582)
			(xy 53.184807 -301.028036) (xy 53.204098 -300.98276) (xy 53.230401 -300.941164) (xy 53.263036 -300.904327)
			(xy 53.301157 -300.873202) (xy 53.343778 -300.848595) (xy 53.389794 -300.831143) (xy 53.438013 -300.821299)
			(xy 53.487188 -300.819318) (xy 53.536043 -300.82525) (xy 53.583314 -300.838942) (xy 53.627776 -300.86004)
			(xy 53.668279 -300.887996) (xy 53.703772 -300.922088) (xy 53.733337 -300.961432) (xy 53.756208 -301.005009)
			(xy 53.771792 -301.05169) (xy 53.779687 -301.100267) (xy 53.780182 -301.124874) (xy 54.11903 -301.124874)
			(xy 54.12299 -301.07582) (xy 54.134767 -301.028036) (xy 54.154058 -300.98276) (xy 54.180361 -300.941164)
			(xy 54.212996 -300.904327) (xy 54.251117 -300.873202) (xy 54.293738 -300.848595) (xy 54.339754 -300.831143)
			(xy 54.387973 -300.821299) (xy 54.437148 -300.819318) (xy 54.486003 -300.82525) (xy 54.533274 -300.838942)
			(xy 54.577736 -300.86004) (xy 54.618239 -300.887996) (xy 54.653732 -300.922088) (xy 54.683297 -300.961432)
			(xy 54.706168 -301.005009) (xy 54.721752 -301.05169) (xy 54.729647 -301.100267) (xy 54.730142 -301.124874)
			(xy 55.06899 -301.124874) (xy 55.07295 -301.07582) (xy 55.084727 -301.028036) (xy 55.104018 -300.98276)
			(xy 55.130321 -300.941164) (xy 55.162956 -300.904327) (xy 55.201077 -300.873202) (xy 55.243698 -300.848595)
			(xy 55.289714 -300.831143) (xy 55.337933 -300.821299) (xy 55.387108 -300.819318) (xy 55.435963 -300.82525)
			(xy 55.483234 -300.838942) (xy 55.527696 -300.86004) (xy 55.568199 -300.887996) (xy 55.603692 -300.922088)
			(xy 55.633257 -300.961432) (xy 55.656128 -301.005009) (xy 55.671712 -301.05169) (xy 55.679607 -301.100267)
			(xy 55.680102 -301.124874) (xy 56.01895 -301.124874) (xy 56.02291 -301.07582) (xy 56.034687 -301.028036)
			(xy 56.053978 -300.98276) (xy 56.080281 -300.941164) (xy 56.112916 -300.904327) (xy 56.151037 -300.873202)
			(xy 56.193658 -300.848595) (xy 56.239674 -300.831143) (xy 56.287893 -300.821299) (xy 56.337068 -300.819318)
			(xy 56.385923 -300.82525) (xy 56.433194 -300.838942) (xy 56.477656 -300.86004) (xy 56.518159 -300.887996)
			(xy 56.553652 -300.922088) (xy 56.583217 -300.961432) (xy 56.606088 -301.005009) (xy 56.621672 -301.05169)
			(xy 56.629567 -301.100267) (xy 56.630062 -301.124874) (xy 56.969164 -301.124874) (xy 56.973124 -301.07582)
			(xy 56.984901 -301.028036) (xy 57.004192 -300.98276) (xy 57.030495 -300.941164) (xy 57.06313 -300.904327)
			(xy 57.101251 -300.873202) (xy 57.143872 -300.848595) (xy 57.189888 -300.831143) (xy 57.238107 -300.821299)
			(xy 57.287282 -300.819318) (xy 57.336137 -300.82525) (xy 57.383408 -300.838942) (xy 57.42787 -300.86004)
			(xy 57.468373 -300.887996) (xy 57.503866 -300.922088) (xy 57.533431 -300.961432) (xy 57.556302 -301.005009)
			(xy 57.571886 -301.05169) (xy 57.579781 -301.100267) (xy 57.580276 -301.124874) (xy 57.919124 -301.124874)
			(xy 57.923084 -301.07582) (xy 57.934861 -301.028036) (xy 57.954152 -300.98276) (xy 57.980455 -300.941164)
			(xy 58.01309 -300.904327) (xy 58.051211 -300.873202) (xy 58.093832 -300.848595) (xy 58.139848 -300.831143)
			(xy 58.188067 -300.821299) (xy 58.237242 -300.819318) (xy 58.286097 -300.82525) (xy 58.333368 -300.838942)
			(xy 58.37783 -300.86004) (xy 58.418333 -300.887996) (xy 58.453826 -300.922088) (xy 58.483391 -300.961432)
			(xy 58.506262 -301.005009) (xy 58.521846 -301.05169) (xy 58.529741 -301.100267) (xy 58.530236 -301.124874)
			(xy 59.819044 -301.124874) (xy 59.823004 -301.07582) (xy 59.834781 -301.028036) (xy 59.854072 -300.98276)
			(xy 59.880375 -300.941164) (xy 59.91301 -300.904327) (xy 59.951131 -300.873202) (xy 59.993752 -300.848595)
			(xy 60.039768 -300.831143) (xy 60.087987 -300.821299) (xy 60.137162 -300.819318) (xy 60.186017 -300.82525)
			(xy 60.233288 -300.838942) (xy 60.27775 -300.86004) (xy 60.318253 -300.887996) (xy 60.353746 -300.922088)
			(xy 60.383311 -300.961432) (xy 60.406182 -301.005009) (xy 60.421766 -301.05169) (xy 60.429661 -301.100267)
			(xy 60.430156 -301.124874) (xy 60.769004 -301.124874) (xy 60.772964 -301.07582) (xy 60.784741 -301.028036)
			(xy 60.804032 -300.98276) (xy 60.830335 -300.941164) (xy 60.86297 -300.904327) (xy 60.901091 -300.873202)
			(xy 60.943712 -300.848595) (xy 60.989728 -300.831143) (xy 61.037947 -300.821299) (xy 61.087122 -300.819318)
			(xy 61.135977 -300.82525) (xy 61.183248 -300.838942) (xy 61.22771 -300.86004) (xy 61.268213 -300.887996)
			(xy 61.303706 -300.922088) (xy 61.333271 -300.961432) (xy 61.356142 -301.005009) (xy 61.371726 -301.05169)
			(xy 61.379621 -301.100267) (xy 61.380116 -301.124874) (xy 61.718964 -301.124874) (xy 61.722924 -301.07582)
			(xy 61.734701 -301.028036) (xy 61.753992 -300.98276) (xy 61.780295 -300.941164) (xy 61.81293 -300.904327)
			(xy 61.851051 -300.873202) (xy 61.893672 -300.848595) (xy 61.939688 -300.831143) (xy 61.987907 -300.821299)
			(xy 62.037082 -300.819318) (xy 62.085937 -300.82525) (xy 62.133208 -300.838942) (xy 62.17767 -300.86004)
			(xy 62.218173 -300.887996) (xy 62.253666 -300.922088) (xy 62.283231 -300.961432) (xy 62.306102 -301.005009)
			(xy 62.321686 -301.05169) (xy 62.329581 -301.100267) (xy 62.330076 -301.124874) (xy 62.669178 -301.124874)
			(xy 62.673138 -301.07582) (xy 62.684915 -301.028036) (xy 62.704206 -300.98276) (xy 62.730509 -300.941164)
			(xy 62.763144 -300.904327) (xy 62.801265 -300.873202) (xy 62.843886 -300.848595) (xy 62.889902 -300.831143)
			(xy 62.938121 -300.821299) (xy 62.987296 -300.819318) (xy 63.036151 -300.82525) (xy 63.083422 -300.838942)
			(xy 63.127884 -300.86004) (xy 63.168387 -300.887996) (xy 63.20388 -300.922088) (xy 63.233445 -300.961432)
			(xy 63.256316 -301.005009) (xy 63.2719 -301.05169) (xy 63.279795 -301.100267) (xy 63.28029 -301.124874)
			(xy 63.619138 -301.124874) (xy 63.623098 -301.07582) (xy 63.634875 -301.028036) (xy 63.654166 -300.98276)
			(xy 63.680469 -300.941164) (xy 63.713104 -300.904327) (xy 63.751225 -300.873202) (xy 63.793846 -300.848595)
			(xy 63.839862 -300.831143) (xy 63.888081 -300.821299) (xy 63.937256 -300.819318) (xy 63.986111 -300.82525)
			(xy 64.033382 -300.838942) (xy 64.077844 -300.86004) (xy 64.118347 -300.887996) (xy 64.15384 -300.922088)
			(xy 64.183405 -300.961432) (xy 64.206276 -301.005009) (xy 64.22186 -301.05169) (xy 64.229755 -301.100267)
			(xy 64.23025 -301.124874) (xy 64.569098 -301.124874) (xy 64.573058 -301.07582) (xy 64.584835 -301.028036)
			(xy 64.604126 -300.98276) (xy 64.630429 -300.941164) (xy 64.663064 -300.904327) (xy 64.701185 -300.873202)
			(xy 64.743806 -300.848595) (xy 64.789822 -300.831143) (xy 64.838041 -300.821299) (xy 64.887216 -300.819318)
			(xy 64.936071 -300.82525) (xy 64.983342 -300.838942) (xy 65.027804 -300.86004) (xy 65.068307 -300.887996)
			(xy 65.1038 -300.922088) (xy 65.133365 -300.961432) (xy 65.156236 -301.005009) (xy 65.17182 -301.05169)
			(xy 65.179715 -301.100267) (xy 65.18021 -301.124874) (xy 65.519058 -301.124874) (xy 65.523018 -301.07582)
			(xy 65.534795 -301.028036) (xy 65.554086 -300.98276) (xy 65.580389 -300.941164) (xy 65.613024 -300.904327)
			(xy 65.651145 -300.873202) (xy 65.693766 -300.848595) (xy 65.739782 -300.831143) (xy 65.788001 -300.821299)
			(xy 65.837176 -300.819318) (xy 65.886031 -300.82525) (xy 65.933302 -300.838942) (xy 65.977764 -300.86004)
			(xy 66.018267 -300.887996) (xy 66.05376 -300.922088) (xy 66.083325 -300.961432) (xy 66.106196 -301.005009)
			(xy 66.12178 -301.05169) (xy 66.129675 -301.100267) (xy 66.13017 -301.124874) (xy 66.469018 -301.124874)
			(xy 66.472978 -301.07582) (xy 66.484755 -301.028036) (xy 66.504046 -300.98276) (xy 66.530349 -300.941164)
			(xy 66.562984 -300.904327) (xy 66.601105 -300.873202) (xy 66.643726 -300.848595) (xy 66.689742 -300.831143)
			(xy 66.737961 -300.821299) (xy 66.787136 -300.819318) (xy 66.835991 -300.82525) (xy 66.883262 -300.838942)
			(xy 66.927724 -300.86004) (xy 66.968227 -300.887996) (xy 67.00372 -300.922088) (xy 67.033285 -300.961432)
			(xy 67.056156 -301.005009) (xy 67.07174 -301.05169) (xy 67.079635 -301.100267) (xy 67.08013 -301.124874)
			(xy 67.418978 -301.124874) (xy 67.422938 -301.07582) (xy 67.434715 -301.028036) (xy 67.454006 -300.98276)
			(xy 67.480309 -300.941164) (xy 67.512944 -300.904327) (xy 67.551065 -300.873202) (xy 67.593686 -300.848595)
			(xy 67.639702 -300.831143) (xy 67.687921 -300.821299) (xy 67.737096 -300.819318) (xy 67.785951 -300.82525)
			(xy 67.833222 -300.838942) (xy 67.877684 -300.86004) (xy 67.918187 -300.887996) (xy 67.95368 -300.922088)
			(xy 67.983245 -300.961432) (xy 68.006116 -301.005009) (xy 68.0217 -301.05169) (xy 68.029595 -301.100267)
			(xy 68.03009 -301.124874) (xy 68.368938 -301.124874) (xy 68.372898 -301.07582) (xy 68.384675 -301.028036)
			(xy 68.403966 -300.98276) (xy 68.430269 -300.941164) (xy 68.462904 -300.904327) (xy 68.501025 -300.873202)
			(xy 68.543646 -300.848595) (xy 68.589662 -300.831143) (xy 68.637881 -300.821299) (xy 68.687056 -300.819318)
			(xy 68.735911 -300.82525) (xy 68.783182 -300.838942) (xy 68.827644 -300.86004) (xy 68.868147 -300.887996)
			(xy 68.90364 -300.922088) (xy 68.933205 -300.961432) (xy 68.956076 -301.005009) (xy 68.97166 -301.05169)
			(xy 68.979555 -301.100267) (xy 68.98005 -301.124874) (xy 69.319152 -301.124874) (xy 69.323112 -301.07582)
			(xy 69.334889 -301.028036) (xy 69.35418 -300.98276) (xy 69.380483 -300.941164) (xy 69.413118 -300.904327)
			(xy 69.451239 -300.873202) (xy 69.49386 -300.848595) (xy 69.539876 -300.831143) (xy 69.588095 -300.821299)
			(xy 69.63727 -300.819318) (xy 69.686125 -300.82525) (xy 69.733396 -300.838942) (xy 69.777858 -300.86004)
			(xy 69.818361 -300.887996) (xy 69.853854 -300.922088) (xy 69.883419 -300.961432) (xy 69.90629 -301.005009)
			(xy 69.921874 -301.05169) (xy 69.929769 -301.100267) (xy 69.930264 -301.124874) (xy 70.269112 -301.124874)
			(xy 70.273072 -301.07582) (xy 70.284849 -301.028036) (xy 70.30414 -300.98276) (xy 70.330443 -300.941164)
			(xy 70.363078 -300.904327) (xy 70.401199 -300.873202) (xy 70.44382 -300.848595) (xy 70.489836 -300.831143)
			(xy 70.538055 -300.821299) (xy 70.58723 -300.819318) (xy 70.636085 -300.82525) (xy 70.683356 -300.838942)
			(xy 70.727818 -300.86004) (xy 70.768321 -300.887996) (xy 70.803814 -300.922088) (xy 70.833379 -300.961432)
			(xy 70.85625 -301.005009) (xy 70.871834 -301.05169) (xy 70.879729 -301.100267) (xy 70.880224 -301.124874)
			(xy 71.219072 -301.124874) (xy 71.223032 -301.07582) (xy 71.234809 -301.028036) (xy 71.2541 -300.98276)
			(xy 71.280403 -300.941164) (xy 71.313038 -300.904327) (xy 71.351159 -300.873202) (xy 71.39378 -300.848595)
			(xy 71.439796 -300.831143) (xy 71.488015 -300.821299) (xy 71.53719 -300.819318) (xy 71.586045 -300.82525)
			(xy 71.633316 -300.838942) (xy 71.677778 -300.86004) (xy 71.718281 -300.887996) (xy 71.753774 -300.922088)
			(xy 71.783339 -300.961432) (xy 71.80621 -301.005009) (xy 71.821794 -301.05169) (xy 71.829689 -301.100267)
			(xy 71.830184 -301.124874) (xy 72.169032 -301.124874) (xy 72.172992 -301.07582) (xy 72.184769 -301.028036)
			(xy 72.20406 -300.98276) (xy 72.230363 -300.941164) (xy 72.262998 -300.904327) (xy 72.301119 -300.873202)
			(xy 72.34374 -300.848595) (xy 72.389756 -300.831143) (xy 72.437975 -300.821299) (xy 72.48715 -300.819318)
			(xy 72.536005 -300.82525) (xy 72.583276 -300.838942) (xy 72.627738 -300.86004) (xy 72.668241 -300.887996)
			(xy 72.703734 -300.922088) (xy 72.733299 -300.961432) (xy 72.75617 -301.005009) (xy 72.771754 -301.05169)
			(xy 72.779649 -301.100267) (xy 72.780144 -301.124874) (xy 73.118992 -301.124874) (xy 73.122952 -301.07582)
			(xy 73.134729 -301.028036) (xy 73.15402 -300.98276) (xy 73.180323 -300.941164) (xy 73.212958 -300.904327)
			(xy 73.251079 -300.873202) (xy 73.2937 -300.848595) (xy 73.339716 -300.831143) (xy 73.387935 -300.821299)
			(xy 73.43711 -300.819318) (xy 73.485965 -300.82525) (xy 73.533236 -300.838942) (xy 73.577698 -300.86004)
			(xy 73.618201 -300.887996) (xy 73.653694 -300.922088) (xy 73.683259 -300.961432) (xy 73.70613 -301.005009)
			(xy 73.721714 -301.05169) (xy 73.729609 -301.100267) (xy 73.730104 -301.124874) (xy 73.729609 -301.149481)
			(xy 73.721714 -301.198058) (xy 73.70613 -301.244739) (xy 73.683259 -301.288316) (xy 73.653694 -301.32766)
			(xy 73.618201 -301.361752) (xy 73.577698 -301.389708) (xy 73.533236 -301.410806) (xy 73.485965 -301.424498)
			(xy 73.43711 -301.43043) (xy 73.387935 -301.428449) (xy 73.339716 -301.418605) (xy 73.2937 -301.401153)
			(xy 73.251079 -301.376546) (xy 73.212958 -301.345421) (xy 73.180323 -301.308584) (xy 73.15402 -301.266988)
			(xy 73.134729 -301.221712) (xy 73.122952 -301.173928) (xy 73.118992 -301.124874) (xy 72.780144 -301.124874)
			(xy 72.779649 -301.149481) (xy 72.771754 -301.198058) (xy 72.75617 -301.244739) (xy 72.733299 -301.288316)
			(xy 72.703734 -301.32766) (xy 72.668241 -301.361752) (xy 72.627738 -301.389708) (xy 72.583276 -301.410806)
			(xy 72.536005 -301.424498) (xy 72.48715 -301.43043) (xy 72.437975 -301.428449) (xy 72.389756 -301.418605)
			(xy 72.34374 -301.401153) (xy 72.301119 -301.376546) (xy 72.262998 -301.345421) (xy 72.230363 -301.308584)
			(xy 72.20406 -301.266988) (xy 72.184769 -301.221712) (xy 72.172992 -301.173928) (xy 72.169032 -301.124874)
			(xy 71.830184 -301.124874) (xy 71.829689 -301.149481) (xy 71.821794 -301.198058) (xy 71.80621 -301.244739)
			(xy 71.783339 -301.288316) (xy 71.753774 -301.32766) (xy 71.718281 -301.361752) (xy 71.677778 -301.389708)
			(xy 71.633316 -301.410806) (xy 71.586045 -301.424498) (xy 71.53719 -301.43043) (xy 71.488015 -301.428449)
			(xy 71.439796 -301.418605) (xy 71.39378 -301.401153) (xy 71.351159 -301.376546) (xy 71.313038 -301.345421)
			(xy 71.280403 -301.308584) (xy 71.2541 -301.266988) (xy 71.234809 -301.221712) (xy 71.223032 -301.173928)
			(xy 71.219072 -301.124874) (xy 70.880224 -301.124874) (xy 70.879729 -301.149481) (xy 70.871834 -301.198058)
			(xy 70.85625 -301.244739) (xy 70.833379 -301.288316) (xy 70.803814 -301.32766) (xy 70.768321 -301.361752)
			(xy 70.727818 -301.389708) (xy 70.683356 -301.410806) (xy 70.636085 -301.424498) (xy 70.58723 -301.43043)
			(xy 70.538055 -301.428449) (xy 70.489836 -301.418605) (xy 70.44382 -301.401153) (xy 70.401199 -301.376546)
			(xy 70.363078 -301.345421) (xy 70.330443 -301.308584) (xy 70.30414 -301.266988) (xy 70.284849 -301.221712)
			(xy 70.273072 -301.173928) (xy 70.269112 -301.124874) (xy 69.930264 -301.124874) (xy 69.929769 -301.149481)
			(xy 69.921874 -301.198058) (xy 69.90629 -301.244739) (xy 69.883419 -301.288316) (xy 69.853854 -301.32766)
			(xy 69.818361 -301.361752) (xy 69.777858 -301.389708) (xy 69.733396 -301.410806) (xy 69.686125 -301.424498)
			(xy 69.63727 -301.43043) (xy 69.588095 -301.428449) (xy 69.539876 -301.418605) (xy 69.49386 -301.401153)
			(xy 69.451239 -301.376546) (xy 69.413118 -301.345421) (xy 69.380483 -301.308584) (xy 69.35418 -301.266988)
			(xy 69.334889 -301.221712) (xy 69.323112 -301.173928) (xy 69.319152 -301.124874) (xy 68.98005 -301.124874)
			(xy 68.979555 -301.149481) (xy 68.97166 -301.198058) (xy 68.956076 -301.244739) (xy 68.933205 -301.288316)
			(xy 68.90364 -301.32766) (xy 68.868147 -301.361752) (xy 68.827644 -301.389708) (xy 68.783182 -301.410806)
			(xy 68.735911 -301.424498) (xy 68.687056 -301.43043) (xy 68.637881 -301.428449) (xy 68.589662 -301.418605)
			(xy 68.543646 -301.401153) (xy 68.501025 -301.376546) (xy 68.462904 -301.345421) (xy 68.430269 -301.308584)
			(xy 68.403966 -301.266988) (xy 68.384675 -301.221712) (xy 68.372898 -301.173928) (xy 68.368938 -301.124874)
			(xy 68.03009 -301.124874) (xy 68.029595 -301.149481) (xy 68.0217 -301.198058) (xy 68.006116 -301.244739)
			(xy 67.983245 -301.288316) (xy 67.95368 -301.32766) (xy 67.918187 -301.361752) (xy 67.877684 -301.389708)
			(xy 67.833222 -301.410806) (xy 67.785951 -301.424498) (xy 67.737096 -301.43043) (xy 67.687921 -301.428449)
			(xy 67.639702 -301.418605) (xy 67.593686 -301.401153) (xy 67.551065 -301.376546) (xy 67.512944 -301.345421)
			(xy 67.480309 -301.308584) (xy 67.454006 -301.266988) (xy 67.434715 -301.221712) (xy 67.422938 -301.173928)
			(xy 67.418978 -301.124874) (xy 67.08013 -301.124874) (xy 67.079635 -301.149481) (xy 67.07174 -301.198058)
			(xy 67.056156 -301.244739) (xy 67.033285 -301.288316) (xy 67.00372 -301.32766) (xy 66.968227 -301.361752)
			(xy 66.927724 -301.389708) (xy 66.883262 -301.410806) (xy 66.835991 -301.424498) (xy 66.787136 -301.43043)
			(xy 66.737961 -301.428449) (xy 66.689742 -301.418605) (xy 66.643726 -301.401153) (xy 66.601105 -301.376546)
			(xy 66.562984 -301.345421) (xy 66.530349 -301.308584) (xy 66.504046 -301.266988) (xy 66.484755 -301.221712)
			(xy 66.472978 -301.173928) (xy 66.469018 -301.124874) (xy 66.13017 -301.124874) (xy 66.129675 -301.149481)
			(xy 66.12178 -301.198058) (xy 66.106196 -301.244739) (xy 66.083325 -301.288316) (xy 66.05376 -301.32766)
			(xy 66.018267 -301.361752) (xy 65.977764 -301.389708) (xy 65.933302 -301.410806) (xy 65.886031 -301.424498)
			(xy 65.837176 -301.43043) (xy 65.788001 -301.428449) (xy 65.739782 -301.418605) (xy 65.693766 -301.401153)
			(xy 65.651145 -301.376546) (xy 65.613024 -301.345421) (xy 65.580389 -301.308584) (xy 65.554086 -301.266988)
			(xy 65.534795 -301.221712) (xy 65.523018 -301.173928) (xy 65.519058 -301.124874) (xy 65.18021 -301.124874)
			(xy 65.179715 -301.149481) (xy 65.17182 -301.198058) (xy 65.156236 -301.244739) (xy 65.133365 -301.288316)
			(xy 65.1038 -301.32766) (xy 65.068307 -301.361752) (xy 65.027804 -301.389708) (xy 64.983342 -301.410806)
			(xy 64.936071 -301.424498) (xy 64.887216 -301.43043) (xy 64.838041 -301.428449) (xy 64.789822 -301.418605)
			(xy 64.743806 -301.401153) (xy 64.701185 -301.376546) (xy 64.663064 -301.345421) (xy 64.630429 -301.308584)
			(xy 64.604126 -301.266988) (xy 64.584835 -301.221712) (xy 64.573058 -301.173928) (xy 64.569098 -301.124874)
			(xy 64.23025 -301.124874) (xy 64.229755 -301.149481) (xy 64.22186 -301.198058) (xy 64.206276 -301.244739)
			(xy 64.183405 -301.288316) (xy 64.15384 -301.32766) (xy 64.118347 -301.361752) (xy 64.077844 -301.389708)
			(xy 64.033382 -301.410806) (xy 63.986111 -301.424498) (xy 63.937256 -301.43043) (xy 63.888081 -301.428449)
			(xy 63.839862 -301.418605) (xy 63.793846 -301.401153) (xy 63.751225 -301.376546) (xy 63.713104 -301.345421)
			(xy 63.680469 -301.308584) (xy 63.654166 -301.266988) (xy 63.634875 -301.221712) (xy 63.623098 -301.173928)
			(xy 63.619138 -301.124874) (xy 63.28029 -301.124874) (xy 63.279795 -301.149481) (xy 63.2719 -301.198058)
			(xy 63.256316 -301.244739) (xy 63.233445 -301.288316) (xy 63.20388 -301.32766) (xy 63.168387 -301.361752)
			(xy 63.127884 -301.389708) (xy 63.083422 -301.410806) (xy 63.036151 -301.424498) (xy 62.987296 -301.43043)
			(xy 62.938121 -301.428449) (xy 62.889902 -301.418605) (xy 62.843886 -301.401153) (xy 62.801265 -301.376546)
			(xy 62.763144 -301.345421) (xy 62.730509 -301.308584) (xy 62.704206 -301.266988) (xy 62.684915 -301.221712)
			(xy 62.673138 -301.173928) (xy 62.669178 -301.124874) (xy 62.330076 -301.124874) (xy 62.329581 -301.149481)
			(xy 62.321686 -301.198058) (xy 62.306102 -301.244739) (xy 62.283231 -301.288316) (xy 62.253666 -301.32766)
			(xy 62.218173 -301.361752) (xy 62.17767 -301.389708) (xy 62.133208 -301.410806) (xy 62.085937 -301.424498)
			(xy 62.037082 -301.43043) (xy 61.987907 -301.428449) (xy 61.939688 -301.418605) (xy 61.893672 -301.401153)
			(xy 61.851051 -301.376546) (xy 61.81293 -301.345421) (xy 61.780295 -301.308584) (xy 61.753992 -301.266988)
			(xy 61.734701 -301.221712) (xy 61.722924 -301.173928) (xy 61.718964 -301.124874) (xy 61.380116 -301.124874)
			(xy 61.379621 -301.149481) (xy 61.371726 -301.198058) (xy 61.356142 -301.244739) (xy 61.333271 -301.288316)
			(xy 61.303706 -301.32766) (xy 61.268213 -301.361752) (xy 61.22771 -301.389708) (xy 61.183248 -301.410806)
			(xy 61.135977 -301.424498) (xy 61.087122 -301.43043) (xy 61.037947 -301.428449) (xy 60.989728 -301.418605)
			(xy 60.943712 -301.401153) (xy 60.901091 -301.376546) (xy 60.86297 -301.345421) (xy 60.830335 -301.308584)
			(xy 60.804032 -301.266988) (xy 60.784741 -301.221712) (xy 60.772964 -301.173928) (xy 60.769004 -301.124874)
			(xy 60.430156 -301.124874) (xy 60.429661 -301.149481) (xy 60.421766 -301.198058) (xy 60.406182 -301.244739)
			(xy 60.383311 -301.288316) (xy 60.353746 -301.32766) (xy 60.318253 -301.361752) (xy 60.27775 -301.389708)
			(xy 60.233288 -301.410806) (xy 60.186017 -301.424498) (xy 60.137162 -301.43043) (xy 60.087987 -301.428449)
			(xy 60.039768 -301.418605) (xy 59.993752 -301.401153) (xy 59.951131 -301.376546) (xy 59.91301 -301.345421)
			(xy 59.880375 -301.308584) (xy 59.854072 -301.266988) (xy 59.834781 -301.221712) (xy 59.823004 -301.173928)
			(xy 59.819044 -301.124874) (xy 58.530236 -301.124874) (xy 58.529741 -301.149481) (xy 58.521846 -301.198058)
			(xy 58.506262 -301.244739) (xy 58.483391 -301.288316) (xy 58.453826 -301.32766) (xy 58.418333 -301.361752)
			(xy 58.37783 -301.389708) (xy 58.333368 -301.410806) (xy 58.286097 -301.424498) (xy 58.237242 -301.43043)
			(xy 58.188067 -301.428449) (xy 58.139848 -301.418605) (xy 58.093832 -301.401153) (xy 58.051211 -301.376546)
			(xy 58.01309 -301.345421) (xy 57.980455 -301.308584) (xy 57.954152 -301.266988) (xy 57.934861 -301.221712)
			(xy 57.923084 -301.173928) (xy 57.919124 -301.124874) (xy 57.580276 -301.124874) (xy 57.579781 -301.149481)
			(xy 57.571886 -301.198058) (xy 57.556302 -301.244739) (xy 57.533431 -301.288316) (xy 57.503866 -301.32766)
			(xy 57.468373 -301.361752) (xy 57.42787 -301.389708) (xy 57.383408 -301.410806) (xy 57.336137 -301.424498)
			(xy 57.287282 -301.43043) (xy 57.238107 -301.428449) (xy 57.189888 -301.418605) (xy 57.143872 -301.401153)
			(xy 57.101251 -301.376546) (xy 57.06313 -301.345421) (xy 57.030495 -301.308584) (xy 57.004192 -301.266988)
			(xy 56.984901 -301.221712) (xy 56.973124 -301.173928) (xy 56.969164 -301.124874) (xy 56.630062 -301.124874)
			(xy 56.629567 -301.149481) (xy 56.621672 -301.198058) (xy 56.606088 -301.244739) (xy 56.583217 -301.288316)
			(xy 56.553652 -301.32766) (xy 56.518159 -301.361752) (xy 56.477656 -301.389708) (xy 56.433194 -301.410806)
			(xy 56.385923 -301.424498) (xy 56.337068 -301.43043) (xy 56.287893 -301.428449) (xy 56.239674 -301.418605)
			(xy 56.193658 -301.401153) (xy 56.151037 -301.376546) (xy 56.112916 -301.345421) (xy 56.080281 -301.308584)
			(xy 56.053978 -301.266988) (xy 56.034687 -301.221712) (xy 56.02291 -301.173928) (xy 56.01895 -301.124874)
			(xy 55.680102 -301.124874) (xy 55.679607 -301.149481) (xy 55.671712 -301.198058) (xy 55.656128 -301.244739)
			(xy 55.633257 -301.288316) (xy 55.603692 -301.32766) (xy 55.568199 -301.361752) (xy 55.527696 -301.389708)
			(xy 55.483234 -301.410806) (xy 55.435963 -301.424498) (xy 55.387108 -301.43043) (xy 55.337933 -301.428449)
			(xy 55.289714 -301.418605) (xy 55.243698 -301.401153) (xy 55.201077 -301.376546) (xy 55.162956 -301.345421)
			(xy 55.130321 -301.308584) (xy 55.104018 -301.266988) (xy 55.084727 -301.221712) (xy 55.07295 -301.173928)
			(xy 55.06899 -301.124874) (xy 54.730142 -301.124874) (xy 54.729647 -301.149481) (xy 54.721752 -301.198058)
			(xy 54.706168 -301.244739) (xy 54.683297 -301.288316) (xy 54.653732 -301.32766) (xy 54.618239 -301.361752)
			(xy 54.577736 -301.389708) (xy 54.533274 -301.410806) (xy 54.486003 -301.424498) (xy 54.437148 -301.43043)
			(xy 54.387973 -301.428449) (xy 54.339754 -301.418605) (xy 54.293738 -301.401153) (xy 54.251117 -301.376546)
			(xy 54.212996 -301.345421) (xy 54.180361 -301.308584) (xy 54.154058 -301.266988) (xy 54.134767 -301.221712)
			(xy 54.12299 -301.173928) (xy 54.11903 -301.124874) (xy 53.780182 -301.124874) (xy 53.779687 -301.149481)
			(xy 53.771792 -301.198058) (xy 53.756208 -301.244739) (xy 53.733337 -301.288316) (xy 53.703772 -301.32766)
			(xy 53.668279 -301.361752) (xy 53.627776 -301.389708) (xy 53.583314 -301.410806) (xy 53.536043 -301.424498)
			(xy 53.487188 -301.43043) (xy 53.438013 -301.428449) (xy 53.389794 -301.418605) (xy 53.343778 -301.401153)
			(xy 53.301157 -301.376546) (xy 53.263036 -301.345421) (xy 53.230401 -301.308584) (xy 53.204098 -301.266988)
			(xy 53.184807 -301.221712) (xy 53.17303 -301.173928) (xy 53.16907 -301.124874) (xy 52.830222 -301.124874)
			(xy 52.829727 -301.149481) (xy 52.821832 -301.198058) (xy 52.806248 -301.244739) (xy 52.783377 -301.288316)
			(xy 52.753812 -301.32766) (xy 52.718319 -301.361752) (xy 52.677816 -301.389708) (xy 52.633354 -301.410806)
			(xy 52.586083 -301.424498) (xy 52.537228 -301.43043) (xy 52.488053 -301.428449) (xy 52.439834 -301.418605)
			(xy 52.393818 -301.401153) (xy 52.351197 -301.376546) (xy 52.313076 -301.345421) (xy 52.280441 -301.308584)
			(xy 52.254138 -301.266988) (xy 52.234847 -301.221712) (xy 52.22307 -301.173928) (xy 52.21911 -301.124874)
			(xy 51.880262 -301.124874) (xy 51.879767 -301.149481) (xy 51.871872 -301.198058) (xy 51.856288 -301.244739)
			(xy 51.833417 -301.288316) (xy 51.803852 -301.32766) (xy 51.768359 -301.361752) (xy 51.727856 -301.389708)
			(xy 51.683394 -301.410806) (xy 51.636123 -301.424498) (xy 51.587268 -301.43043) (xy 51.538093 -301.428449)
			(xy 51.489874 -301.418605) (xy 51.443858 -301.401153) (xy 51.401237 -301.376546) (xy 51.363116 -301.345421)
			(xy 51.330481 -301.308584) (xy 51.304178 -301.266988) (xy 51.284887 -301.221712) (xy 51.27311 -301.173928)
			(xy 51.26915 -301.124874) (xy 50.930302 -301.124874) (xy 50.929807 -301.149481) (xy 50.921912 -301.198058)
			(xy 50.906328 -301.244739) (xy 50.883457 -301.288316) (xy 50.853892 -301.32766) (xy 50.818399 -301.361752)
			(xy 50.777896 -301.389708) (xy 50.733434 -301.410806) (xy 50.686163 -301.424498) (xy 50.637308 -301.43043)
			(xy 50.588133 -301.428449) (xy 50.539914 -301.418605) (xy 50.493898 -301.401153) (xy 50.451277 -301.376546)
			(xy 50.413156 -301.345421) (xy 50.380521 -301.308584) (xy 50.354218 -301.266988) (xy 50.334927 -301.221712)
			(xy 50.32315 -301.173928) (xy 50.31919 -301.124874) (xy 49.980088 -301.124874) (xy 49.979593 -301.149481)
			(xy 49.971698 -301.198058) (xy 49.956114 -301.244739) (xy 49.933243 -301.288316) (xy 49.903678 -301.32766)
			(xy 49.868185 -301.361752) (xy 49.827682 -301.389708) (xy 49.78322 -301.410806) (xy 49.735949 -301.424498)
			(xy 49.687094 -301.43043) (xy 49.637919 -301.428449) (xy 49.5897 -301.418605) (xy 49.543684 -301.401153)
			(xy 49.501063 -301.376546) (xy 49.462942 -301.345421) (xy 49.430307 -301.308584) (xy 49.404004 -301.266988)
			(xy 49.384713 -301.221712) (xy 49.372936 -301.173928) (xy 49.368976 -301.124874) (xy 48.080168 -301.124874)
			(xy 48.079914 -301.135288) (xy 48.079914 -301.141638) (xy 48.07966 -301.14621) (xy 48.07966 -301.146972)
			(xy 48.078434 -301.161372) (xy 48.073596 -301.189868) (xy 48.070008 -301.203868) (xy 48.06823 -301.210472)
			(xy 48.06823 -301.5999) (xy 75.494122 -301.5999) (xy 75.498293 -301.549559) (xy 75.510692 -301.500592)
			(xy 75.530981 -301.454332) (xy 75.558607 -301.412043) (xy 75.592815 -301.374876) (xy 75.632674 -301.343847)
			(xy 75.677097 -301.3198) (xy 75.724871 -301.303393) (xy 75.774694 -301.295071) (xy 75.79995 -301.294546)
			(xy 75.814133 -301.29473) (xy 75.842373 -301.297397) (xy 75.856338 -301.29988) (xy 75.868784 -301.302166)
			(xy 75.892406 -301.2948) (xy 75.969876 -301.21733) (xy 75.977242 -301.193708) (xy 75.974956 -301.181262)
			(xy 75.972479 -301.167296) (xy 75.969807 -301.139057) (xy 75.969622 -301.124874) (xy 75.970106 -301.100056)
			(xy 75.97814 -301.051075) (xy 75.993992 -301.004039) (xy 76.017245 -300.960187) (xy 76.047285 -300.920674)
			(xy 76.083322 -300.886542) (xy 76.124406 -300.858689) (xy 76.169455 -300.837849) (xy 76.217282 -300.824572)
			(xy 76.266627 -300.819207) (xy 76.316189 -300.821895) (xy 76.364664 -300.832566) (xy 76.410774 -300.850939)
			(xy 76.453305 -300.876529) (xy 76.491135 -300.908662) (xy 76.523269 -300.946492) (xy 76.54886 -300.989022)
			(xy 76.567233 -301.035132) (xy 76.577904 -301.083607) (xy 76.580143 -301.124874) (xy 76.919086 -301.124874)
			(xy 76.923046 -301.07582) (xy 76.934823 -301.028036) (xy 76.954114 -300.98276) (xy 76.980417 -300.941164)
			(xy 77.013052 -300.904327) (xy 77.051173 -300.873202) (xy 77.093794 -300.848595) (xy 77.13981 -300.831143)
			(xy 77.188029 -300.821299) (xy 77.237204 -300.819318) (xy 77.286059 -300.82525) (xy 77.33333 -300.838942)
			(xy 77.377792 -300.86004) (xy 77.418295 -300.887996) (xy 77.453788 -300.922088) (xy 77.483353 -300.961432)
			(xy 77.506224 -301.005009) (xy 77.521808 -301.05169) (xy 77.529703 -301.100267) (xy 77.530198 -301.124874)
			(xy 77.869046 -301.124874) (xy 77.873006 -301.07582) (xy 77.884783 -301.028036) (xy 77.904074 -300.98276)
			(xy 77.930377 -300.941164) (xy 77.963012 -300.904327) (xy 78.001133 -300.873202) (xy 78.043754 -300.848595)
			(xy 78.08977 -300.831143) (xy 78.137989 -300.821299) (xy 78.187164 -300.819318) (xy 78.236019 -300.82525)
			(xy 78.28329 -300.838942) (xy 78.327752 -300.86004) (xy 78.368255 -300.887996) (xy 78.403748 -300.922088)
			(xy 78.433313 -300.961432) (xy 78.456184 -301.005009) (xy 78.471768 -301.05169) (xy 78.479663 -301.100267)
			(xy 78.480158 -301.124874) (xy 78.819006 -301.124874) (xy 78.822966 -301.07582) (xy 78.834743 -301.028036)
			(xy 78.854034 -300.98276) (xy 78.880337 -300.941164) (xy 78.912972 -300.904327) (xy 78.951093 -300.873202)
			(xy 78.993714 -300.848595) (xy 79.03973 -300.831143) (xy 79.087949 -300.821299) (xy 79.137124 -300.819318)
			(xy 79.185979 -300.82525) (xy 79.23325 -300.838942) (xy 79.277712 -300.86004) (xy 79.318215 -300.887996)
			(xy 79.353708 -300.922088) (xy 79.383273 -300.961432) (xy 79.406144 -301.005009) (xy 79.421728 -301.05169)
			(xy 79.429623 -301.100267) (xy 79.430118 -301.124874) (xy 79.768966 -301.124874) (xy 79.772926 -301.07582)
			(xy 79.784703 -301.028036) (xy 79.803994 -300.98276) (xy 79.830297 -300.941164) (xy 79.862932 -300.904327)
			(xy 79.901053 -300.873202) (xy 79.943674 -300.848595) (xy 79.98969 -300.831143) (xy 80.037909 -300.821299)
			(xy 80.087084 -300.819318) (xy 80.135939 -300.82525) (xy 80.18321 -300.838942) (xy 80.227672 -300.86004)
			(xy 80.268175 -300.887996) (xy 80.303668 -300.922088) (xy 80.333233 -300.961432) (xy 80.356104 -301.005009)
			(xy 80.371688 -301.05169) (xy 80.379583 -301.100267) (xy 80.380078 -301.124874) (xy 80.71918 -301.124874)
			(xy 80.72314 -301.07582) (xy 80.734917 -301.028036) (xy 80.754208 -300.98276) (xy 80.780511 -300.941164)
			(xy 80.813146 -300.904327) (xy 80.851267 -300.873202) (xy 80.893888 -300.848595) (xy 80.939904 -300.831143)
			(xy 80.988123 -300.821299) (xy 81.037298 -300.819318) (xy 81.086153 -300.82525) (xy 81.133424 -300.838942)
			(xy 81.177886 -300.86004) (xy 81.218389 -300.887996) (xy 81.253882 -300.922088) (xy 81.283447 -300.961432)
			(xy 81.306318 -301.005009) (xy 81.321902 -301.05169) (xy 81.329797 -301.100267) (xy 81.330292 -301.124874)
			(xy 81.66914 -301.124874) (xy 81.6731 -301.07582) (xy 81.684877 -301.028036) (xy 81.704168 -300.98276)
			(xy 81.730471 -300.941164) (xy 81.763106 -300.904327) (xy 81.801227 -300.873202) (xy 81.843848 -300.848595)
			(xy 81.889864 -300.831143) (xy 81.938083 -300.821299) (xy 81.987258 -300.819318) (xy 82.036113 -300.82525)
			(xy 82.083384 -300.838942) (xy 82.127846 -300.86004) (xy 82.168349 -300.887996) (xy 82.203842 -300.922088)
			(xy 82.233407 -300.961432) (xy 82.256278 -301.005009) (xy 82.271862 -301.05169) (xy 82.279757 -301.100267)
			(xy 82.280252 -301.124874) (xy 82.6191 -301.124874) (xy 82.62306 -301.07582) (xy 82.634837 -301.028036)
			(xy 82.654128 -300.98276) (xy 82.680431 -300.941164) (xy 82.713066 -300.904327) (xy 82.751187 -300.873202)
			(xy 82.793808 -300.848595) (xy 82.839824 -300.831143) (xy 82.888043 -300.821299) (xy 82.937218 -300.819318)
			(xy 82.986073 -300.82525) (xy 83.033344 -300.838942) (xy 83.077806 -300.86004) (xy 83.118309 -300.887996)
			(xy 83.153802 -300.922088) (xy 83.183367 -300.961432) (xy 83.206238 -301.005009) (xy 83.221822 -301.05169)
			(xy 83.229717 -301.100267) (xy 83.230212 -301.124874) (xy 83.229717 -301.149481) (xy 83.221822 -301.198058)
			(xy 83.206238 -301.244739) (xy 83.183367 -301.288316) (xy 83.153802 -301.32766) (xy 83.118309 -301.361752)
			(xy 83.077806 -301.389708) (xy 83.033344 -301.410806) (xy 82.986073 -301.424498) (xy 82.937218 -301.43043)
			(xy 82.888043 -301.428449) (xy 82.839824 -301.418605) (xy 82.793808 -301.401153) (xy 82.751187 -301.376546)
			(xy 82.713066 -301.345421) (xy 82.680431 -301.308584) (xy 82.654128 -301.266988) (xy 82.634837 -301.221712)
			(xy 82.62306 -301.173928) (xy 82.6191 -301.124874) (xy 82.280252 -301.124874) (xy 82.279757 -301.149481)
			(xy 82.271862 -301.198058) (xy 82.256278 -301.244739) (xy 82.233407 -301.288316) (xy 82.203842 -301.32766)
			(xy 82.168349 -301.361752) (xy 82.127846 -301.389708) (xy 82.083384 -301.410806) (xy 82.036113 -301.424498)
			(xy 81.987258 -301.43043) (xy 81.938083 -301.428449) (xy 81.889864 -301.418605) (xy 81.843848 -301.401153)
			(xy 81.801227 -301.376546) (xy 81.763106 -301.345421) (xy 81.730471 -301.308584) (xy 81.704168 -301.266988)
			(xy 81.684877 -301.221712) (xy 81.6731 -301.173928) (xy 81.66914 -301.124874) (xy 81.330292 -301.124874)
			(xy 81.329797 -301.149481) (xy 81.321902 -301.198058) (xy 81.306318 -301.244739) (xy 81.283447 -301.288316)
			(xy 81.253882 -301.32766) (xy 81.218389 -301.361752) (xy 81.177886 -301.389708) (xy 81.133424 -301.410806)
			(xy 81.086153 -301.424498) (xy 81.037298 -301.43043) (xy 80.988123 -301.428449) (xy 80.939904 -301.418605)
			(xy 80.893888 -301.401153) (xy 80.851267 -301.376546) (xy 80.813146 -301.345421) (xy 80.780511 -301.308584)
			(xy 80.754208 -301.266988) (xy 80.734917 -301.221712) (xy 80.72314 -301.173928) (xy 80.71918 -301.124874)
			(xy 80.380078 -301.124874) (xy 80.379583 -301.149481) (xy 80.371688 -301.198058) (xy 80.356104 -301.244739)
			(xy 80.333233 -301.288316) (xy 80.303668 -301.32766) (xy 80.268175 -301.361752) (xy 80.227672 -301.389708)
			(xy 80.18321 -301.410806) (xy 80.135939 -301.424498) (xy 80.087084 -301.43043) (xy 80.037909 -301.428449)
			(xy 79.98969 -301.418605) (xy 79.943674 -301.401153) (xy 79.901053 -301.376546) (xy 79.862932 -301.345421)
			(xy 79.830297 -301.308584) (xy 79.803994 -301.266988) (xy 79.784703 -301.221712) (xy 79.772926 -301.173928)
			(xy 79.768966 -301.124874) (xy 79.430118 -301.124874) (xy 79.429623 -301.149481) (xy 79.421728 -301.198058)
			(xy 79.406144 -301.244739) (xy 79.383273 -301.288316) (xy 79.353708 -301.32766) (xy 79.318215 -301.361752)
			(xy 79.277712 -301.389708) (xy 79.23325 -301.410806) (xy 79.185979 -301.424498) (xy 79.137124 -301.43043)
			(xy 79.087949 -301.428449) (xy 79.03973 -301.418605) (xy 78.993714 -301.401153) (xy 78.951093 -301.376546)
			(xy 78.912972 -301.345421) (xy 78.880337 -301.308584) (xy 78.854034 -301.266988) (xy 78.834743 -301.221712)
			(xy 78.822966 -301.173928) (xy 78.819006 -301.124874) (xy 78.480158 -301.124874) (xy 78.479663 -301.149481)
			(xy 78.471768 -301.198058) (xy 78.456184 -301.244739) (xy 78.433313 -301.288316) (xy 78.403748 -301.32766)
			(xy 78.368255 -301.361752) (xy 78.327752 -301.389708) (xy 78.28329 -301.410806) (xy 78.236019 -301.424498)
			(xy 78.187164 -301.43043) (xy 78.137989 -301.428449) (xy 78.08977 -301.418605) (xy 78.043754 -301.401153)
			(xy 78.001133 -301.376546) (xy 77.963012 -301.345421) (xy 77.930377 -301.308584) (xy 77.904074 -301.266988)
			(xy 77.884783 -301.221712) (xy 77.873006 -301.173928) (xy 77.869046 -301.124874) (xy 77.530198 -301.124874)
			(xy 77.529703 -301.149481) (xy 77.521808 -301.198058) (xy 77.506224 -301.244739) (xy 77.483353 -301.288316)
			(xy 77.453788 -301.32766) (xy 77.418295 -301.361752) (xy 77.377792 -301.389708) (xy 77.33333 -301.410806)
			(xy 77.286059 -301.424498) (xy 77.237204 -301.43043) (xy 77.188029 -301.428449) (xy 77.13981 -301.418605)
			(xy 77.093794 -301.401153) (xy 77.051173 -301.376546) (xy 77.013052 -301.345421) (xy 76.980417 -301.308584)
			(xy 76.954114 -301.266988) (xy 76.934823 -301.221712) (xy 76.923046 -301.173928) (xy 76.919086 -301.124874)
			(xy 76.580143 -301.124874) (xy 76.580593 -301.133169) (xy 76.575229 -301.182514) (xy 76.561952 -301.230341)
			(xy 76.541113 -301.27539) (xy 76.513261 -301.316475) (xy 76.479129 -301.352512) (xy 76.439616 -301.382553)
			(xy 76.395765 -301.405806) (xy 76.348729 -301.421659) (xy 76.299748 -301.429694) (xy 76.27493 -301.430182)
			(xy 76.260747 -301.430002) (xy 76.232507 -301.427332) (xy 76.218542 -301.424848) (xy 76.206096 -301.422562)
			(xy 76.182474 -301.429928) (xy 76.105004 -301.507398) (xy 76.097638 -301.53102) (xy 76.099924 -301.543466)
			(xy 76.102406 -301.557431) (xy 76.105074 -301.585671) (xy 76.105258 -301.599854) (xy 76.105076 -301.614037)
			(xy 76.102408 -301.642277) (xy 76.099924 -301.656242) (xy 76.097638 -301.668688) (xy 76.105004 -301.69231)
			(xy 76.182474 -301.76978) (xy 76.206096 -301.777146) (xy 76.218542 -301.77486) (xy 76.232508 -301.772382)
			(xy 76.260747 -301.769711) (xy 76.27493 -301.769526) (xy 76.299747 -301.77001) (xy 76.348727 -301.778045)
			(xy 76.395762 -301.793897) (xy 76.439613 -301.81715) (xy 76.479125 -301.84719) (xy 76.513257 -301.883227)
			(xy 76.541109 -301.92431) (xy 76.561948 -301.969358) (xy 76.575224 -302.017184) (xy 76.580589 -302.066528)
			(xy 76.580139 -302.074834) (xy 76.919086 -302.074834) (xy 76.923046 -302.02578) (xy 76.934823 -301.977996)
			(xy 76.954114 -301.93272) (xy 76.980417 -301.891124) (xy 77.013052 -301.854287) (xy 77.051173 -301.823162)
			(xy 77.093794 -301.798555) (xy 77.13981 -301.781103) (xy 77.188029 -301.771259) (xy 77.237204 -301.769278)
			(xy 77.286059 -301.77521) (xy 77.33333 -301.788902) (xy 77.377792 -301.81) (xy 77.418295 -301.837956)
			(xy 77.453788 -301.872048) (xy 77.483353 -301.911392) (xy 77.506224 -301.954969) (xy 77.521808 -302.00165)
			(xy 77.529703 -302.050227) (xy 77.530198 -302.074834) (xy 77.869046 -302.074834) (xy 77.873006 -302.02578)
			(xy 77.884783 -301.977996) (xy 77.904074 -301.93272) (xy 77.930377 -301.891124) (xy 77.963012 -301.854287)
			(xy 78.001133 -301.823162) (xy 78.043754 -301.798555) (xy 78.08977 -301.781103) (xy 78.137989 -301.771259)
			(xy 78.187164 -301.769278) (xy 78.236019 -301.77521) (xy 78.28329 -301.788902) (xy 78.327752 -301.81)
			(xy 78.368255 -301.837956) (xy 78.403748 -301.872048) (xy 78.433313 -301.911392) (xy 78.456184 -301.954969)
			(xy 78.471768 -302.00165) (xy 78.479663 -302.050227) (xy 78.480158 -302.074834) (xy 78.819006 -302.074834)
			(xy 78.822966 -302.02578) (xy 78.834743 -301.977996) (xy 78.854034 -301.93272) (xy 78.880337 -301.891124)
			(xy 78.912972 -301.854287) (xy 78.951093 -301.823162) (xy 78.993714 -301.798555) (xy 79.03973 -301.781103)
			(xy 79.087949 -301.771259) (xy 79.137124 -301.769278) (xy 79.185979 -301.77521) (xy 79.23325 -301.788902)
			(xy 79.277712 -301.81) (xy 79.318215 -301.837956) (xy 79.353708 -301.872048) (xy 79.383273 -301.911392)
			(xy 79.406144 -301.954969) (xy 79.421728 -302.00165) (xy 79.429623 -302.050227) (xy 79.430118 -302.074834)
			(xy 79.768966 -302.074834) (xy 79.772926 -302.02578) (xy 79.784703 -301.977996) (xy 79.803994 -301.93272)
			(xy 79.830297 -301.891124) (xy 79.862932 -301.854287) (xy 79.901053 -301.823162) (xy 79.943674 -301.798555)
			(xy 79.98969 -301.781103) (xy 80.037909 -301.771259) (xy 80.087084 -301.769278) (xy 80.135939 -301.77521)
			(xy 80.18321 -301.788902) (xy 80.227672 -301.81) (xy 80.268175 -301.837956) (xy 80.303668 -301.872048)
			(xy 80.333233 -301.911392) (xy 80.356104 -301.954969) (xy 80.371688 -302.00165) (xy 80.379583 -302.050227)
			(xy 80.380078 -302.074834) (xy 80.71918 -302.074834) (xy 80.72314 -302.02578) (xy 80.734917 -301.977996)
			(xy 80.754208 -301.93272) (xy 80.780511 -301.891124) (xy 80.813146 -301.854287) (xy 80.851267 -301.823162)
			(xy 80.893888 -301.798555) (xy 80.939904 -301.781103) (xy 80.988123 -301.771259) (xy 81.037298 -301.769278)
			(xy 81.086153 -301.77521) (xy 81.133424 -301.788902) (xy 81.177886 -301.81) (xy 81.218389 -301.837956)
			(xy 81.253882 -301.872048) (xy 81.283447 -301.911392) (xy 81.306318 -301.954969) (xy 81.321902 -302.00165)
			(xy 81.329797 -302.050227) (xy 81.330292 -302.074834) (xy 81.66914 -302.074834) (xy 81.6731 -302.02578)
			(xy 81.684877 -301.977996) (xy 81.704168 -301.93272) (xy 81.730471 -301.891124) (xy 81.763106 -301.854287)
			(xy 81.801227 -301.823162) (xy 81.843848 -301.798555) (xy 81.889864 -301.781103) (xy 81.938083 -301.771259)
			(xy 81.987258 -301.769278) (xy 82.036113 -301.77521) (xy 82.083384 -301.788902) (xy 82.127846 -301.81)
			(xy 82.168349 -301.837956) (xy 82.203842 -301.872048) (xy 82.233407 -301.911392) (xy 82.256278 -301.954969)
			(xy 82.271862 -302.00165) (xy 82.279757 -302.050227) (xy 82.280252 -302.074834) (xy 82.6191 -302.074834)
			(xy 82.62306 -302.02578) (xy 82.634837 -301.977996) (xy 82.654128 -301.93272) (xy 82.680431 -301.891124)
			(xy 82.713066 -301.854287) (xy 82.751187 -301.823162) (xy 82.793808 -301.798555) (xy 82.839824 -301.781103)
			(xy 82.888043 -301.771259) (xy 82.937218 -301.769278) (xy 82.986073 -301.77521) (xy 83.033344 -301.788902)
			(xy 83.077806 -301.81) (xy 83.114972 -301.835653) (xy 84.836443 -301.835653) (xy 84.836443 -301.781145)
			(xy 84.844201 -301.727191) (xy 84.859558 -301.674891) (xy 84.882202 -301.625309) (xy 84.911671 -301.579454)
			(xy 84.947367 -301.53826) (xy 84.988562 -301.502566) (xy 85.034417 -301.473097) (xy 85.084 -301.450454)
			(xy 85.136301 -301.435099) (xy 85.190254 -301.427342) (xy 85.217508 -301.42688) (xy 85.229734 -301.426948)
			(xy 85.254137 -301.428473) (xy 85.266276 -301.429928) (xy 85.278214 -301.431452) (xy 85.300566 -301.423832)
			(xy 85.374226 -301.34941) (xy 85.381592 -301.327058) (xy 85.380068 -301.31512) (xy 85.378309 -301.301918)
			(xy 85.376401 -301.275351) (xy 85.376258 -301.262034) (xy 85.376787 -301.234759) (xy 85.384553 -301.180764)
			(xy 85.39993 -301.128426) (xy 85.422606 -301.078812) (xy 85.452118 -301.032934) (xy 85.487863 -300.991728)
			(xy 85.529114 -300.956033) (xy 85.575029 -300.926579) (xy 85.624671 -300.903964) (xy 85.677028 -300.888652)
			(xy 85.731032 -300.880954) (xy 85.785582 -300.881026) (xy 85.839566 -300.888868) (xy 85.891882 -300.90432)
			(xy 85.941464 -300.927066) (xy 85.9873 -300.956643) (xy 86.028456 -300.992448) (xy 86.064091 -301.033749)
			(xy 86.069412 -301.04207) (xy 90.317574 -301.04207) (xy 90.31806 -301.014819) (xy 90.325816 -300.960871)
			(xy 90.341171 -300.908576) (xy 90.363813 -300.858999) (xy 90.393279 -300.813149) (xy 90.42897 -300.771958)
			(xy 90.470161 -300.736267) (xy 90.516011 -300.706801) (xy 90.565588 -300.684159) (xy 90.617883 -300.668804)
			(xy 90.671831 -300.661048) (xy 90.726333 -300.661048) (xy 90.780281 -300.668804) (xy 90.832576 -300.684159)
			(xy 90.882153 -300.706801) (xy 90.928003 -300.736267) (xy 90.969194 -300.771958) (xy 91.004885 -300.813149)
			(xy 91.034351 -300.858999) (xy 91.056993 -300.908576) (xy 91.072348 -300.960871) (xy 91.080104 -301.014819)
			(xy 91.08059 -301.04207) (xy 91.08043 -301.050452) (xy 92.690948 -301.050452) (xy 92.695019 -300.99483)
			(xy 92.707145 -300.940393) (xy 92.727068 -300.888302) (xy 92.754364 -300.839667) (xy 92.78845 -300.795524)
			(xy 92.828599 -300.756815) (xy 92.873957 -300.724364) (xy 92.923557 -300.698863) (xy 92.976341 -300.680856)
			(xy 93.031184 -300.670726) (xy 93.086918 -300.668689) (xy 93.142355 -300.674789) (xy 93.196312 -300.688895)
			(xy 93.247641 -300.710707) (xy 93.295247 -300.739761) (xy 93.338115 -300.775436) (xy 93.375332 -300.816973)
			(xy 93.406105 -300.863486) (xy 93.429777 -300.913983) (xy 93.445845 -300.96739) (xy 93.453965 -301.022566)
			(xy 93.454474 -301.050452) (xy 93.453965 -301.078338) (xy 93.445845 -301.133514) (xy 93.429777 -301.186921)
			(xy 93.406105 -301.237418) (xy 93.375332 -301.283931) (xy 93.338115 -301.325468) (xy 93.295247 -301.361143)
			(xy 93.247641 -301.390197) (xy 93.196312 -301.412009) (xy 93.142355 -301.426115) (xy 93.086918 -301.432215)
			(xy 93.031184 -301.430178) (xy 92.976341 -301.420048) (xy 92.923557 -301.402041) (xy 92.873957 -301.37654)
			(xy 92.828599 -301.344089) (xy 92.78845 -301.30538) (xy 92.754364 -301.261237) (xy 92.727068 -301.212602)
			(xy 92.707145 -301.160511) (xy 92.695019 -301.106074) (xy 92.690948 -301.050452) (xy 91.08043 -301.050452)
			(xy 91.080008 -301.072563) (xy 91.070321 -301.132774) (xy 91.051188 -301.19068) (xy 91.023096 -301.24481)
			(xy 91.005406 -301.269654) (xy 90.998548 -301.278798) (xy 90.993976 -301.300896) (xy 91.018614 -301.399448)
			(xy 91.033092 -301.416974) (xy 91.043506 -301.4218) (xy 91.067638 -301.433754) (xy 91.112573 -301.463433)
			(xy 91.15289 -301.499133) (xy 91.18779 -301.540146) (xy 91.210938 -301.57674) (xy 91.51315 -301.57674)
			(xy 91.517221 -301.521118) (xy 91.529347 -301.466681) (xy 91.54927 -301.41459) (xy 91.576566 -301.365955)
			(xy 91.610652 -301.321812) (xy 91.650801 -301.283103) (xy 91.696159 -301.250652) (xy 91.745759 -301.225151)
			(xy 91.798543 -301.207144) (xy 91.853386 -301.197014) (xy 91.90912 -301.194977) (xy 91.964557 -301.201077)
			(xy 92.018514 -301.215183) (xy 92.069843 -301.236995) (xy 92.117449 -301.266049) (xy 92.160317 -301.301724)
			(xy 92.197534 -301.343261) (xy 92.228307 -301.389774) (xy 92.251979 -301.440271) (xy 92.268047 -301.493678)
			(xy 92.276167 -301.548854) (xy 92.276676 -301.57674) (xy 92.276167 -301.604626) (xy 92.268047 -301.659802)
			(xy 92.251979 -301.713209) (xy 92.228307 -301.763706) (xy 92.197534 -301.810219) (xy 92.160317 -301.851756)
			(xy 92.117449 -301.887431) (xy 92.069843 -301.916485) (xy 92.018514 -301.938297) (xy 91.964557 -301.952403)
			(xy 91.90912 -301.958503) (xy 91.853386 -301.956466) (xy 91.798543 -301.946336) (xy 91.745759 -301.928329)
			(xy 91.696159 -301.902828) (xy 91.650801 -301.870377) (xy 91.610652 -301.831668) (xy 91.576566 -301.787525)
			(xy 91.54927 -301.73889) (xy 91.529347 -301.686799) (xy 91.517221 -301.632362) (xy 91.51315 -301.57674)
			(xy 91.210938 -301.57674) (xy 91.216578 -301.585657) (xy 91.238683 -301.634763) (xy 91.253667 -301.686488)
			(xy 91.261232 -301.739806) (xy 91.261692 -301.766732) (xy 91.261206 -301.793983) (xy 91.25345 -301.847931)
			(xy 91.238095 -301.900226) (xy 91.215453 -301.949803) (xy 91.185987 -301.995653) (xy 91.150296 -302.036844)
			(xy 91.109105 -302.072535) (xy 91.063255 -302.102001) (xy 91.013678 -302.124643) (xy 90.961383 -302.139998)
			(xy 90.907435 -302.147754) (xy 90.852933 -302.147754) (xy 90.798985 -302.139998) (xy 90.74669 -302.124643)
			(xy 90.697113 -302.102001) (xy 90.651263 -302.072535) (xy 90.610072 -302.036844) (xy 90.574381 -301.995653)
			(xy 90.544915 -301.949803) (xy 90.522273 -301.900226) (xy 90.506918 -301.847931) (xy 90.499162 -301.793983)
			(xy 90.498676 -301.766732) (xy 90.499265 -301.73624) (xy 90.508951 -301.676029) (xy 90.528082 -301.618123)
			(xy 90.556171 -301.563992) (xy 90.57386 -301.539148) (xy 90.580718 -301.530004) (xy 90.58529 -301.507906)
			(xy 90.560652 -301.409354) (xy 90.546174 -301.391828) (xy 90.53576 -301.387002) (xy 90.511621 -301.375062)
			(xy 90.466688 -301.34538) (xy 90.426371 -301.309676) (xy 90.391474 -301.268661) (xy 90.362687 -301.223148)
			(xy 90.340582 -301.174041) (xy 90.325599 -301.122315) (xy 90.318034 -301.068996) (xy 90.317574 -301.04207)
			(xy 86.069412 -301.04207) (xy 86.093481 -301.079706) (xy 86.116024 -301.12938) (xy 86.131262 -301.181758)
			(xy 86.138884 -301.235774) (xy 86.139274 -301.26305) (xy 86.139274 -301.274226) (xy 86.148164 -301.294038)
			(xy 86.222078 -301.359062) (xy 86.242906 -301.365412) (xy 86.253828 -301.364142) (xy 86.26609 -301.362615)
			(xy 86.290748 -301.360962) (xy 86.303104 -301.36084) (xy 86.332328 -301.361372) (xy 86.390089 -301.370301)
			(xy 86.445814 -301.387933) (xy 86.498197 -301.413857) (xy 86.546015 -301.447466) (xy 86.588149 -301.487974)
			(xy 86.623612 -301.534433) (xy 86.651576 -301.585757) (xy 86.662006 -301.613062) (xy 86.666832 -301.626524)
			(xy 86.68893 -301.644304) (xy 86.806532 -301.660052) (xy 86.83244 -301.648876) (xy 86.840822 -301.637192)
			(xy 86.856173 -301.616072) (xy 86.891738 -301.577846) (xy 86.932188 -301.544832) (xy 86.976765 -301.517648)
			(xy 87.024636 -301.496804) (xy 87.074904 -301.482688) (xy 87.126628 -301.475566) (xy 87.152734 -301.47514)
			(xy 87.179987 -301.475532) (xy 87.233938 -301.483294) (xy 87.286235 -301.498654) (xy 87.335814 -301.5213)
			(xy 87.381666 -301.55077) (xy 87.383789 -301.55261) (xy 88.11971 -301.55261) (xy 88.123781 -301.496988)
			(xy 88.135907 -301.442551) (xy 88.15583 -301.39046) (xy 88.183126 -301.341825) (xy 88.217212 -301.297682)
			(xy 88.257361 -301.258973) (xy 88.302719 -301.226522) (xy 88.352319 -301.201021) (xy 88.405103 -301.183014)
			(xy 88.459946 -301.172884) (xy 88.51568 -301.170847) (xy 88.571117 -301.176947) (xy 88.625074 -301.191053)
			(xy 88.676403 -301.212865) (xy 88.724009 -301.241919) (xy 88.766877 -301.277594) (xy 88.804094 -301.319131)
			(xy 88.834867 -301.365644) (xy 88.858539 -301.416141) (xy 88.874607 -301.469548) (xy 88.882727 -301.524724)
			(xy 88.883236 -301.55261) (xy 88.882727 -301.580496) (xy 88.874607 -301.635672) (xy 88.858539 -301.689079)
			(xy 88.834867 -301.739576) (xy 88.804094 -301.786089) (xy 88.766877 -301.827626) (xy 88.724009 -301.863301)
			(xy 88.676403 -301.892355) (xy 88.625074 -301.914167) (xy 88.571117 -301.928273) (xy 88.51568 -301.934373)
			(xy 88.459946 -301.932336) (xy 88.405103 -301.922206) (xy 88.352319 -301.904199) (xy 88.302719 -301.878698)
			(xy 88.257361 -301.846247) (xy 88.217212 -301.807538) (xy 88.183126 -301.763395) (xy 88.15583 -301.71476)
			(xy 88.135907 -301.662669) (xy 88.123781 -301.608232) (xy 88.11971 -301.55261) (xy 87.383789 -301.55261)
			(xy 87.422858 -301.586466) (xy 87.45855 -301.627661) (xy 87.488017 -301.673516) (xy 87.510658 -301.723097)
			(xy 87.526014 -301.775395) (xy 87.53377 -301.829347) (xy 87.53377 -301.883853) (xy 87.526014 -301.937805)
			(xy 87.510658 -301.990103) (xy 87.488017 -302.039684) (xy 87.45855 -302.085539) (xy 87.422858 -302.126734)
			(xy 87.381666 -302.16243) (xy 87.335814 -302.1919) (xy 87.286235 -302.214546) (xy 87.233938 -302.229906)
			(xy 87.179987 -302.237668) (xy 87.152734 -302.238156) (xy 87.123511 -302.237594) (xy 87.065751 -302.228671)
			(xy 87.010027 -302.211043) (xy 86.957643 -302.185124) (xy 86.909825 -302.151519) (xy 86.867691 -302.111015)
			(xy 86.832227 -302.064559) (xy 86.804262 -302.013238) (xy 86.793832 -301.985934) (xy 86.789006 -301.972472)
			(xy 86.766908 -301.954692) (xy 86.649306 -301.938944) (xy 86.623398 -301.95012) (xy 86.615016 -301.961804)
			(xy 86.599641 -301.982905) (xy 86.56408 -302.021132) (xy 86.523634 -302.054148) (xy 86.479061 -302.081334)
			(xy 86.431194 -302.102181) (xy 86.38093 -302.116301) (xy 86.329209 -302.123427) (xy 86.303104 -302.123856)
			(xy 86.275807 -302.123339) (xy 86.221771 -302.115558) (xy 86.169396 -302.100153) (xy 86.119751 -302.07744)
			(xy 86.073851 -302.047883) (xy 86.032633 -302.012084) (xy 85.996939 -301.970776) (xy 85.967498 -301.924801)
			(xy 85.94491 -301.875099) (xy 85.929638 -301.822686) (xy 85.921993 -301.76863) (xy 85.921596 -301.741332)
			(xy 85.921596 -301.730156) (xy 85.912706 -301.710344) (xy 85.838792 -301.64532) (xy 85.817964 -301.63897)
			(xy 85.807042 -301.64024) (xy 85.79478 -301.64177) (xy 85.770122 -301.643421) (xy 85.757766 -301.643542)
			(xy 85.74554 -301.643474) (xy 85.721137 -301.641947) (xy 85.708998 -301.640494) (xy 85.69706 -301.63897)
			(xy 85.674708 -301.64659) (xy 85.601048 -301.721012) (xy 85.593682 -301.743364) (xy 85.595206 -301.755302)
			(xy 85.596967 -301.768503) (xy 85.598873 -301.795071) (xy 85.599016 -301.808388) (xy 85.598558 -301.835642)
			(xy 85.590802 -301.889596) (xy 85.575447 -301.941896) (xy 85.552805 -301.991479) (xy 85.523337 -302.037335)
			(xy 85.487642 -302.07853) (xy 85.446449 -302.114226) (xy 85.400594 -302.143697) (xy 85.351012 -302.166341)
			(xy 85.298713 -302.181699) (xy 85.244759 -302.189457) (xy 85.190251 -302.189457) (xy 85.136298 -302.181701)
			(xy 85.083998 -302.166345) (xy 85.034415 -302.143702) (xy 84.98856 -302.114233) (xy 84.947365 -302.078538)
			(xy 84.91167 -302.037343) (xy 84.8822 -301.991488) (xy 84.859557 -301.941906) (xy 84.8442 -301.889606)
			(xy 84.836443 -301.835653) (xy 83.114972 -301.835653) (xy 83.118309 -301.837956) (xy 83.153802 -301.872048)
			(xy 83.183367 -301.911392) (xy 83.206238 -301.954969) (xy 83.221822 -302.00165) (xy 83.229717 -302.050227)
			(xy 83.230212 -302.074834) (xy 83.229717 -302.099441) (xy 83.221822 -302.148018) (xy 83.206238 -302.194699)
			(xy 83.183367 -302.238276) (xy 83.153802 -302.27762) (xy 83.118309 -302.311712) (xy 83.077806 -302.339668)
			(xy 83.033344 -302.360766) (xy 82.986073 -302.374458) (xy 82.937218 -302.38039) (xy 82.888043 -302.378409)
			(xy 82.839824 -302.368565) (xy 82.793808 -302.351113) (xy 82.751187 -302.326506) (xy 82.713066 -302.295381)
			(xy 82.680431 -302.258544) (xy 82.654128 -302.216948) (xy 82.634837 -302.171672) (xy 82.62306 -302.123888)
			(xy 82.6191 -302.074834) (xy 82.280252 -302.074834) (xy 82.279757 -302.099441) (xy 82.271862 -302.148018)
			(xy 82.256278 -302.194699) (xy 82.233407 -302.238276) (xy 82.203842 -302.27762) (xy 82.168349 -302.311712)
			(xy 82.127846 -302.339668) (xy 82.083384 -302.360766) (xy 82.036113 -302.374458) (xy 81.987258 -302.38039)
			(xy 81.938083 -302.378409) (xy 81.889864 -302.368565) (xy 81.843848 -302.351113) (xy 81.801227 -302.326506)
			(xy 81.763106 -302.295381) (xy 81.730471 -302.258544) (xy 81.704168 -302.216948) (xy 81.684877 -302.171672)
			(xy 81.6731 -302.123888) (xy 81.66914 -302.074834) (xy 81.330292 -302.074834) (xy 81.329797 -302.099441)
			(xy 81.321902 -302.148018) (xy 81.306318 -302.194699) (xy 81.283447 -302.238276) (xy 81.253882 -302.27762)
			(xy 81.218389 -302.311712) (xy 81.177886 -302.339668) (xy 81.133424 -302.360766) (xy 81.086153 -302.374458)
			(xy 81.037298 -302.38039) (xy 80.988123 -302.378409) (xy 80.939904 -302.368565) (xy 80.893888 -302.351113)
			(xy 80.851267 -302.326506) (xy 80.813146 -302.295381) (xy 80.780511 -302.258544) (xy 80.754208 -302.216948)
			(xy 80.734917 -302.171672) (xy 80.72314 -302.123888) (xy 80.71918 -302.074834) (xy 80.380078 -302.074834)
			(xy 80.379583 -302.099441) (xy 80.371688 -302.148018) (xy 80.356104 -302.194699) (xy 80.333233 -302.238276)
			(xy 80.303668 -302.27762) (xy 80.268175 -302.311712) (xy 80.227672 -302.339668) (xy 80.18321 -302.360766)
			(xy 80.135939 -302.374458) (xy 80.087084 -302.38039) (xy 80.037909 -302.378409) (xy 79.98969 -302.368565)
			(xy 79.943674 -302.351113) (xy 79.901053 -302.326506) (xy 79.862932 -302.295381) (xy 79.830297 -302.258544)
			(xy 79.803994 -302.216948) (xy 79.784703 -302.171672) (xy 79.772926 -302.123888) (xy 79.768966 -302.074834)
			(xy 79.430118 -302.074834) (xy 79.429623 -302.099441) (xy 79.421728 -302.148018) (xy 79.406144 -302.194699)
			(xy 79.383273 -302.238276) (xy 79.353708 -302.27762) (xy 79.318215 -302.311712) (xy 79.277712 -302.339668)
			(xy 79.23325 -302.360766) (xy 79.185979 -302.374458) (xy 79.137124 -302.38039) (xy 79.087949 -302.378409)
			(xy 79.03973 -302.368565) (xy 78.993714 -302.351113) (xy 78.951093 -302.326506) (xy 78.912972 -302.295381)
			(xy 78.880337 -302.258544) (xy 78.854034 -302.216948) (xy 78.834743 -302.171672) (xy 78.822966 -302.123888)
			(xy 78.819006 -302.074834) (xy 78.480158 -302.074834) (xy 78.479663 -302.099441) (xy 78.471768 -302.148018)
			(xy 78.456184 -302.194699) (xy 78.433313 -302.238276) (xy 78.403748 -302.27762) (xy 78.368255 -302.311712)
			(xy 78.327752 -302.339668) (xy 78.28329 -302.360766) (xy 78.236019 -302.374458) (xy 78.187164 -302.38039)
			(xy 78.137989 -302.378409) (xy 78.08977 -302.368565) (xy 78.043754 -302.351113) (xy 78.001133 -302.326506)
			(xy 77.963012 -302.295381) (xy 77.930377 -302.258544) (xy 77.904074 -302.216948) (xy 77.884783 -302.171672)
			(xy 77.873006 -302.123888) (xy 77.869046 -302.074834) (xy 77.530198 -302.074834) (xy 77.529703 -302.099441)
			(xy 77.521808 -302.148018) (xy 77.506224 -302.194699) (xy 77.483353 -302.238276) (xy 77.453788 -302.27762)
			(xy 77.418295 -302.311712) (xy 77.377792 -302.339668) (xy 77.33333 -302.360766) (xy 77.286059 -302.374458)
			(xy 77.237204 -302.38039) (xy 77.188029 -302.378409) (xy 77.13981 -302.368565) (xy 77.093794 -302.351113)
			(xy 77.051173 -302.326506) (xy 77.013052 -302.295381) (xy 76.980417 -302.258544) (xy 76.954114 -302.216948)
			(xy 76.934823 -302.171672) (xy 76.923046 -302.123888) (xy 76.919086 -302.074834) (xy 76.580139 -302.074834)
			(xy 76.577901 -302.11609) (xy 76.56723 -302.164564) (xy 76.548858 -302.210673) (xy 76.523268 -302.253203)
			(xy 76.491135 -302.291033) (xy 76.453306 -302.323166) (xy 76.410777 -302.348756) (xy 76.364668 -302.367129)
			(xy 76.316194 -302.3778) (xy 76.266632 -302.380489) (xy 76.217288 -302.375125) (xy 76.169462 -302.361849)
			(xy 76.124414 -302.341011) (xy 76.08333 -302.313159) (xy 76.047293 -302.279028) (xy 76.017252 -302.239517)
			(xy 75.993999 -302.195666) (xy 75.978146 -302.148631) (xy 75.97011 -302.099651) (xy 75.969622 -302.074834)
			(xy 75.969803 -302.060651) (xy 75.972472 -302.032411) (xy 75.974956 -302.018446) (xy 75.977242 -302.006)
			(xy 75.969876 -301.982378) (xy 75.892406 -301.904908) (xy 75.868784 -301.897542) (xy 75.856338 -301.899828)
			(xy 75.842373 -301.902309) (xy 75.814133 -301.904978) (xy 75.79995 -301.905162) (xy 75.774694 -301.904729)
			(xy 75.724871 -301.896407) (xy 75.677097 -301.88) (xy 75.632674 -301.855953) (xy 75.592815 -301.824924)
			(xy 75.558607 -301.787757) (xy 75.530981 -301.745468) (xy 75.510692 -301.699208) (xy 75.498293 -301.650241)
			(xy 75.494122 -301.5999) (xy 48.06823 -301.5999) (xy 48.06823 -302.074834) (xy 49.368976 -302.074834)
			(xy 49.372936 -302.02578) (xy 49.384713 -301.977996) (xy 49.404004 -301.93272) (xy 49.430307 -301.891124)
			(xy 49.462942 -301.854287) (xy 49.501063 -301.823162) (xy 49.543684 -301.798555) (xy 49.5897 -301.781103)
			(xy 49.637919 -301.771259) (xy 49.687094 -301.769278) (xy 49.735949 -301.77521) (xy 49.78322 -301.788902)
			(xy 49.827682 -301.81) (xy 49.868185 -301.837956) (xy 49.903678 -301.872048) (xy 49.933243 -301.911392)
			(xy 49.956114 -301.954969) (xy 49.971698 -302.00165) (xy 49.979593 -302.050227) (xy 49.980088 -302.074834)
			(xy 50.31919 -302.074834) (xy 50.32315 -302.02578) (xy 50.334927 -301.977996) (xy 50.354218 -301.93272)
			(xy 50.380521 -301.891124) (xy 50.413156 -301.854287) (xy 50.451277 -301.823162) (xy 50.493898 -301.798555)
			(xy 50.539914 -301.781103) (xy 50.588133 -301.771259) (xy 50.637308 -301.769278) (xy 50.686163 -301.77521)
			(xy 50.733434 -301.788902) (xy 50.777896 -301.81) (xy 50.818399 -301.837956) (xy 50.853892 -301.872048)
			(xy 50.883457 -301.911392) (xy 50.906328 -301.954969) (xy 50.921912 -302.00165) (xy 50.929807 -302.050227)
			(xy 50.930302 -302.074834) (xy 51.26915 -302.074834) (xy 51.27311 -302.02578) (xy 51.284887 -301.977996)
			(xy 51.304178 -301.93272) (xy 51.330481 -301.891124) (xy 51.363116 -301.854287) (xy 51.401237 -301.823162)
			(xy 51.443858 -301.798555) (xy 51.489874 -301.781103) (xy 51.538093 -301.771259) (xy 51.587268 -301.769278)
			(xy 51.636123 -301.77521) (xy 51.683394 -301.788902) (xy 51.727856 -301.81) (xy 51.768359 -301.837956)
			(xy 51.803852 -301.872048) (xy 51.833417 -301.911392) (xy 51.856288 -301.954969) (xy 51.871872 -302.00165)
			(xy 51.879767 -302.050227) (xy 51.880262 -302.074834) (xy 52.21911 -302.074834) (xy 52.22307 -302.02578)
			(xy 52.234847 -301.977996) (xy 52.254138 -301.93272) (xy 52.280441 -301.891124) (xy 52.313076 -301.854287)
			(xy 52.351197 -301.823162) (xy 52.393818 -301.798555) (xy 52.439834 -301.781103) (xy 52.488053 -301.771259)
			(xy 52.537228 -301.769278) (xy 52.586083 -301.77521) (xy 52.633354 -301.788902) (xy 52.677816 -301.81)
			(xy 52.718319 -301.837956) (xy 52.753812 -301.872048) (xy 52.783377 -301.911392) (xy 52.806248 -301.954969)
			(xy 52.821832 -302.00165) (xy 52.829727 -302.050227) (xy 52.830222 -302.074834) (xy 53.16907 -302.074834)
			(xy 53.17303 -302.02578) (xy 53.184807 -301.977996) (xy 53.204098 -301.93272) (xy 53.230401 -301.891124)
			(xy 53.263036 -301.854287) (xy 53.301157 -301.823162) (xy 53.343778 -301.798555) (xy 53.389794 -301.781103)
			(xy 53.438013 -301.771259) (xy 53.487188 -301.769278) (xy 53.536043 -301.77521) (xy 53.583314 -301.788902)
			(xy 53.627776 -301.81) (xy 53.668279 -301.837956) (xy 53.703772 -301.872048) (xy 53.733337 -301.911392)
			(xy 53.756208 -301.954969) (xy 53.771792 -302.00165) (xy 53.779687 -302.050227) (xy 53.780182 -302.074834)
			(xy 54.11903 -302.074834) (xy 54.12299 -302.02578) (xy 54.134767 -301.977996) (xy 54.154058 -301.93272)
			(xy 54.180361 -301.891124) (xy 54.212996 -301.854287) (xy 54.251117 -301.823162) (xy 54.293738 -301.798555)
			(xy 54.339754 -301.781103) (xy 54.387973 -301.771259) (xy 54.437148 -301.769278) (xy 54.486003 -301.77521)
			(xy 54.533274 -301.788902) (xy 54.577736 -301.81) (xy 54.618239 -301.837956) (xy 54.653732 -301.872048)
			(xy 54.683297 -301.911392) (xy 54.706168 -301.954969) (xy 54.721752 -302.00165) (xy 54.729647 -302.050227)
			(xy 54.730142 -302.074834) (xy 55.06899 -302.074834) (xy 55.07295 -302.02578) (xy 55.084727 -301.977996)
			(xy 55.104018 -301.93272) (xy 55.130321 -301.891124) (xy 55.162956 -301.854287) (xy 55.201077 -301.823162)
			(xy 55.243698 -301.798555) (xy 55.289714 -301.781103) (xy 55.337933 -301.771259) (xy 55.387108 -301.769278)
			(xy 55.435963 -301.77521) (xy 55.483234 -301.788902) (xy 55.527696 -301.81) (xy 55.568199 -301.837956)
			(xy 55.603692 -301.872048) (xy 55.633257 -301.911392) (xy 55.656128 -301.954969) (xy 55.671712 -302.00165)
			(xy 55.679607 -302.050227) (xy 55.680102 -302.074834) (xy 56.01895 -302.074834) (xy 56.02291 -302.02578)
			(xy 56.034687 -301.977996) (xy 56.053978 -301.93272) (xy 56.080281 -301.891124) (xy 56.112916 -301.854287)
			(xy 56.151037 -301.823162) (xy 56.193658 -301.798555) (xy 56.239674 -301.781103) (xy 56.287893 -301.771259)
			(xy 56.337068 -301.769278) (xy 56.385923 -301.77521) (xy 56.433194 -301.788902) (xy 56.477656 -301.81)
			(xy 56.518159 -301.837956) (xy 56.553652 -301.872048) (xy 56.583217 -301.911392) (xy 56.606088 -301.954969)
			(xy 56.621672 -302.00165) (xy 56.629567 -302.050227) (xy 56.630062 -302.074834) (xy 56.969164 -302.074834)
			(xy 56.973124 -302.02578) (xy 56.984901 -301.977996) (xy 57.004192 -301.93272) (xy 57.030495 -301.891124)
			(xy 57.06313 -301.854287) (xy 57.101251 -301.823162) (xy 57.143872 -301.798555) (xy 57.189888 -301.781103)
			(xy 57.238107 -301.771259) (xy 57.287282 -301.769278) (xy 57.336137 -301.77521) (xy 57.383408 -301.788902)
			(xy 57.42787 -301.81) (xy 57.468373 -301.837956) (xy 57.503866 -301.872048) (xy 57.533431 -301.911392)
			(xy 57.556302 -301.954969) (xy 57.571886 -302.00165) (xy 57.579781 -302.050227) (xy 57.580276 -302.074834)
			(xy 57.919124 -302.074834) (xy 57.923084 -302.02578) (xy 57.934861 -301.977996) (xy 57.954152 -301.93272)
			(xy 57.980455 -301.891124) (xy 58.01309 -301.854287) (xy 58.051211 -301.823162) (xy 58.093832 -301.798555)
			(xy 58.139848 -301.781103) (xy 58.188067 -301.771259) (xy 58.237242 -301.769278) (xy 58.286097 -301.77521)
			(xy 58.333368 -301.788902) (xy 58.37783 -301.81) (xy 58.418333 -301.837956) (xy 58.453826 -301.872048)
			(xy 58.483391 -301.911392) (xy 58.506262 -301.954969) (xy 58.521846 -302.00165) (xy 58.529741 -302.050227)
			(xy 58.530236 -302.074834) (xy 59.819044 -302.074834) (xy 59.823004 -302.02578) (xy 59.834781 -301.977996)
			(xy 59.854072 -301.93272) (xy 59.880375 -301.891124) (xy 59.91301 -301.854287) (xy 59.951131 -301.823162)
			(xy 59.993752 -301.798555) (xy 60.039768 -301.781103) (xy 60.087987 -301.771259) (xy 60.137162 -301.769278)
			(xy 60.186017 -301.77521) (xy 60.233288 -301.788902) (xy 60.27775 -301.81) (xy 60.318253 -301.837956)
			(xy 60.353746 -301.872048) (xy 60.383311 -301.911392) (xy 60.406182 -301.954969) (xy 60.421766 -302.00165)
			(xy 60.429661 -302.050227) (xy 60.430156 -302.074834) (xy 60.769004 -302.074834) (xy 60.772964 -302.02578)
			(xy 60.784741 -301.977996) (xy 60.804032 -301.93272) (xy 60.830335 -301.891124) (xy 60.86297 -301.854287)
			(xy 60.901091 -301.823162) (xy 60.943712 -301.798555) (xy 60.989728 -301.781103) (xy 61.037947 -301.771259)
			(xy 61.087122 -301.769278) (xy 61.135977 -301.77521) (xy 61.183248 -301.788902) (xy 61.22771 -301.81)
			(xy 61.268213 -301.837956) (xy 61.303706 -301.872048) (xy 61.333271 -301.911392) (xy 61.356142 -301.954969)
			(xy 61.371726 -302.00165) (xy 61.379621 -302.050227) (xy 61.380116 -302.074834) (xy 61.718964 -302.074834)
			(xy 61.722924 -302.02578) (xy 61.734701 -301.977996) (xy 61.753992 -301.93272) (xy 61.780295 -301.891124)
			(xy 61.81293 -301.854287) (xy 61.851051 -301.823162) (xy 61.893672 -301.798555) (xy 61.939688 -301.781103)
			(xy 61.987907 -301.771259) (xy 62.037082 -301.769278) (xy 62.085937 -301.77521) (xy 62.133208 -301.788902)
			(xy 62.17767 -301.81) (xy 62.218173 -301.837956) (xy 62.253666 -301.872048) (xy 62.283231 -301.911392)
			(xy 62.306102 -301.954969) (xy 62.321686 -302.00165) (xy 62.329581 -302.050227) (xy 62.330076 -302.074834)
			(xy 62.669178 -302.074834) (xy 62.673138 -302.02578) (xy 62.684915 -301.977996) (xy 62.704206 -301.93272)
			(xy 62.730509 -301.891124) (xy 62.763144 -301.854287) (xy 62.801265 -301.823162) (xy 62.843886 -301.798555)
			(xy 62.889902 -301.781103) (xy 62.938121 -301.771259) (xy 62.987296 -301.769278) (xy 63.036151 -301.77521)
			(xy 63.083422 -301.788902) (xy 63.127884 -301.81) (xy 63.168387 -301.837956) (xy 63.20388 -301.872048)
			(xy 63.233445 -301.911392) (xy 63.256316 -301.954969) (xy 63.2719 -302.00165) (xy 63.279795 -302.050227)
			(xy 63.28029 -302.074834) (xy 63.619138 -302.074834) (xy 63.623098 -302.02578) (xy 63.634875 -301.977996)
			(xy 63.654166 -301.93272) (xy 63.680469 -301.891124) (xy 63.713104 -301.854287) (xy 63.751225 -301.823162)
			(xy 63.793846 -301.798555) (xy 63.839862 -301.781103) (xy 63.888081 -301.771259) (xy 63.937256 -301.769278)
			(xy 63.986111 -301.77521) (xy 64.033382 -301.788902) (xy 64.077844 -301.81) (xy 64.118347 -301.837956)
			(xy 64.15384 -301.872048) (xy 64.183405 -301.911392) (xy 64.206276 -301.954969) (xy 64.22186 -302.00165)
			(xy 64.229755 -302.050227) (xy 64.23025 -302.074834) (xy 64.569098 -302.074834) (xy 64.573058 -302.02578)
			(xy 64.584835 -301.977996) (xy 64.604126 -301.93272) (xy 64.630429 -301.891124) (xy 64.663064 -301.854287)
			(xy 64.701185 -301.823162) (xy 64.743806 -301.798555) (xy 64.789822 -301.781103) (xy 64.838041 -301.771259)
			(xy 64.887216 -301.769278) (xy 64.936071 -301.77521) (xy 64.983342 -301.788902) (xy 65.027804 -301.81)
			(xy 65.068307 -301.837956) (xy 65.1038 -301.872048) (xy 65.133365 -301.911392) (xy 65.156236 -301.954969)
			(xy 65.17182 -302.00165) (xy 65.179715 -302.050227) (xy 65.18021 -302.074834) (xy 65.519058 -302.074834)
			(xy 65.523018 -302.02578) (xy 65.534795 -301.977996) (xy 65.554086 -301.93272) (xy 65.580389 -301.891124)
			(xy 65.613024 -301.854287) (xy 65.651145 -301.823162) (xy 65.693766 -301.798555) (xy 65.739782 -301.781103)
			(xy 65.788001 -301.771259) (xy 65.837176 -301.769278) (xy 65.886031 -301.77521) (xy 65.933302 -301.788902)
			(xy 65.977764 -301.81) (xy 66.018267 -301.837956) (xy 66.05376 -301.872048) (xy 66.083325 -301.911392)
			(xy 66.106196 -301.954969) (xy 66.12178 -302.00165) (xy 66.129675 -302.050227) (xy 66.13017 -302.074834)
			(xy 66.469018 -302.074834) (xy 66.472978 -302.02578) (xy 66.484755 -301.977996) (xy 66.504046 -301.93272)
			(xy 66.530349 -301.891124) (xy 66.562984 -301.854287) (xy 66.601105 -301.823162) (xy 66.643726 -301.798555)
			(xy 66.689742 -301.781103) (xy 66.737961 -301.771259) (xy 66.787136 -301.769278) (xy 66.835991 -301.77521)
			(xy 66.883262 -301.788902) (xy 66.927724 -301.81) (xy 66.968227 -301.837956) (xy 67.00372 -301.872048)
			(xy 67.033285 -301.911392) (xy 67.056156 -301.954969) (xy 67.07174 -302.00165) (xy 67.079635 -302.050227)
			(xy 67.08013 -302.074834) (xy 67.418978 -302.074834) (xy 67.422938 -302.02578) (xy 67.434715 -301.977996)
			(xy 67.454006 -301.93272) (xy 67.480309 -301.891124) (xy 67.512944 -301.854287) (xy 67.551065 -301.823162)
			(xy 67.593686 -301.798555) (xy 67.639702 -301.781103) (xy 67.687921 -301.771259) (xy 67.737096 -301.769278)
			(xy 67.785951 -301.77521) (xy 67.833222 -301.788902) (xy 67.877684 -301.81) (xy 67.918187 -301.837956)
			(xy 67.95368 -301.872048) (xy 67.983245 -301.911392) (xy 68.006116 -301.954969) (xy 68.0217 -302.00165)
			(xy 68.029595 -302.050227) (xy 68.03009 -302.074834) (xy 68.368938 -302.074834) (xy 68.372898 -302.02578)
			(xy 68.384675 -301.977996) (xy 68.403966 -301.93272) (xy 68.430269 -301.891124) (xy 68.462904 -301.854287)
			(xy 68.501025 -301.823162) (xy 68.543646 -301.798555) (xy 68.589662 -301.781103) (xy 68.637881 -301.771259)
			(xy 68.687056 -301.769278) (xy 68.735911 -301.77521) (xy 68.783182 -301.788902) (xy 68.827644 -301.81)
			(xy 68.868147 -301.837956) (xy 68.90364 -301.872048) (xy 68.933205 -301.911392) (xy 68.956076 -301.954969)
			(xy 68.97166 -302.00165) (xy 68.979555 -302.050227) (xy 68.98005 -302.074834) (xy 69.319152 -302.074834)
			(xy 69.323112 -302.02578) (xy 69.334889 -301.977996) (xy 69.35418 -301.93272) (xy 69.380483 -301.891124)
			(xy 69.413118 -301.854287) (xy 69.451239 -301.823162) (xy 69.49386 -301.798555) (xy 69.539876 -301.781103)
			(xy 69.588095 -301.771259) (xy 69.63727 -301.769278) (xy 69.686125 -301.77521) (xy 69.733396 -301.788902)
			(xy 69.777858 -301.81) (xy 69.818361 -301.837956) (xy 69.853854 -301.872048) (xy 69.883419 -301.911392)
			(xy 69.90629 -301.954969) (xy 69.921874 -302.00165) (xy 69.929769 -302.050227) (xy 69.930264 -302.074834)
			(xy 70.269112 -302.074834) (xy 70.273072 -302.02578) (xy 70.284849 -301.977996) (xy 70.30414 -301.93272)
			(xy 70.330443 -301.891124) (xy 70.363078 -301.854287) (xy 70.401199 -301.823162) (xy 70.44382 -301.798555)
			(xy 70.489836 -301.781103) (xy 70.538055 -301.771259) (xy 70.58723 -301.769278) (xy 70.636085 -301.77521)
			(xy 70.683356 -301.788902) (xy 70.727818 -301.81) (xy 70.768321 -301.837956) (xy 70.803814 -301.872048)
			(xy 70.833379 -301.911392) (xy 70.85625 -301.954969) (xy 70.871834 -302.00165) (xy 70.879729 -302.050227)
			(xy 70.880224 -302.074834) (xy 71.219072 -302.074834) (xy 71.223032 -302.02578) (xy 71.234809 -301.977996)
			(xy 71.2541 -301.93272) (xy 71.280403 -301.891124) (xy 71.313038 -301.854287) (xy 71.351159 -301.823162)
			(xy 71.39378 -301.798555) (xy 71.439796 -301.781103) (xy 71.488015 -301.771259) (xy 71.53719 -301.769278)
			(xy 71.586045 -301.77521) (xy 71.633316 -301.788902) (xy 71.677778 -301.81) (xy 71.718281 -301.837956)
			(xy 71.753774 -301.872048) (xy 71.783339 -301.911392) (xy 71.80621 -301.954969) (xy 71.821794 -302.00165)
			(xy 71.829689 -302.050227) (xy 71.830184 -302.074834) (xy 72.169032 -302.074834) (xy 72.172992 -302.02578)
			(xy 72.184769 -301.977996) (xy 72.20406 -301.93272) (xy 72.230363 -301.891124) (xy 72.262998 -301.854287)
			(xy 72.301119 -301.823162) (xy 72.34374 -301.798555) (xy 72.389756 -301.781103) (xy 72.437975 -301.771259)
			(xy 72.48715 -301.769278) (xy 72.536005 -301.77521) (xy 72.583276 -301.788902) (xy 72.627738 -301.81)
			(xy 72.668241 -301.837956) (xy 72.703734 -301.872048) (xy 72.733299 -301.911392) (xy 72.75617 -301.954969)
			(xy 72.771754 -302.00165) (xy 72.779649 -302.050227) (xy 72.780144 -302.074834) (xy 72.779978 -302.083068)
			(xy 73.119085 -302.083068) (xy 73.121775 -302.033499) (xy 73.132449 -301.985018) (xy 73.150826 -301.938902)
			(xy 73.176421 -301.896368) (xy 73.208561 -301.858534) (xy 73.246398 -301.826399) (xy 73.288936 -301.800809)
			(xy 73.335054 -301.782438) (xy 73.383536 -301.77177) (xy 73.433106 -301.769086) (xy 73.482456 -301.774457)
			(xy 73.530288 -301.787742) (xy 73.57534 -301.80859) (xy 73.616426 -301.836452) (xy 73.652462 -301.870594)
			(xy 73.682501 -301.910117) (xy 73.705749 -301.953979) (xy 73.721595 -302.001024) (xy 73.729621 -302.050013)
			(xy 73.730104 -302.074834) (xy 73.729932 -302.089017) (xy 73.727257 -302.117257) (xy 73.72477 -302.131222)
			(xy 73.722484 -302.143668) (xy 73.72985 -302.16729) (xy 73.80732 -302.24476) (xy 73.830942 -302.252126)
			(xy 73.843388 -302.24984) (xy 73.857355 -302.247369) (xy 73.885594 -302.244694) (xy 73.899776 -302.244506)
			(xy 73.913959 -302.244686) (xy 73.942199 -302.247356) (xy 73.956164 -302.24984) (xy 73.96861 -302.252126)
			(xy 73.992232 -302.24476) (xy 74.069702 -302.16729) (xy 74.077068 -302.143668) (xy 74.074782 -302.131222)
			(xy 74.072299 -302.117257) (xy 74.069631 -302.089017) (xy 74.069448 -302.074834) (xy 74.069941 -302.050009)
			(xy 74.077969 -302.001012) (xy 74.093818 -301.95396) (xy 74.11707 -301.910092) (xy 74.147114 -301.870563)
			(xy 74.183158 -301.836417) (xy 74.224251 -301.808551) (xy 74.269311 -301.787702) (xy 74.31715 -301.774417)
			(xy 74.366509 -301.769047) (xy 74.416086 -301.771734) (xy 74.464575 -301.782407) (xy 74.510699 -301.800784)
			(xy 74.553242 -301.826381) (xy 74.591083 -301.858524) (xy 74.623225 -301.896366) (xy 74.648821 -301.93891)
			(xy 74.667196 -301.985034) (xy 74.677867 -302.033524) (xy 74.680552 -302.083101) (xy 74.675181 -302.13246)
			(xy 74.661895 -302.180299) (xy 74.641044 -302.225358) (xy 74.613177 -302.26645) (xy 74.579029 -302.302492)
			(xy 74.5395 -302.332535) (xy 74.495631 -302.355786) (xy 74.448578 -302.371634) (xy 74.399581 -302.379659)
			(xy 74.374756 -302.380142) (xy 74.360573 -302.379957) (xy 74.332333 -302.37729) (xy 74.318368 -302.374808)
			(xy 74.305922 -302.372522) (xy 74.2823 -302.379888) (xy 74.20483 -302.457358) (xy 74.197464 -302.48098)
			(xy 74.19975 -302.493426) (xy 74.202226 -302.507392) (xy 74.204898 -302.535632) (xy 74.205084 -302.549814)
			(xy 74.204562 -302.575069) (xy 74.196249 -302.624891) (xy 74.179848 -302.672665) (xy 74.155807 -302.717088)
			(xy 74.124783 -302.756948) (xy 74.087621 -302.791158) (xy 74.045335 -302.818784) (xy 73.999079 -302.839074)
			(xy 73.950114 -302.851474) (xy 73.899776 -302.855645) (xy 73.849438 -302.851474) (xy 73.800473 -302.839074)
			(xy 73.754217 -302.818784) (xy 73.711931 -302.791158) (xy 73.674769 -302.756948) (xy 73.643745 -302.717088)
			(xy 73.619704 -302.672665) (xy 73.603303 -302.624891) (xy 73.59499 -302.575069) (xy 73.594468 -302.549814)
			(xy 73.594647 -302.535631) (xy 73.597318 -302.507391) (xy 73.599802 -302.493426) (xy 73.602088 -302.48098)
			(xy 73.594722 -302.457358) (xy 73.517252 -302.379888) (xy 73.49363 -302.372522) (xy 73.481184 -302.374808)
			(xy 73.467218 -302.377283) (xy 73.438978 -302.379956) (xy 73.424796 -302.380142) (xy 73.399975 -302.379618)
			(xy 73.350987 -302.371586) (xy 73.303944 -302.355734) (xy 73.260085 -302.33248) (xy 73.220566 -302.302437)
			(xy 73.186428 -302.266396) (xy 73.158571 -302.225307) (xy 73.137729 -302.180252) (xy 73.12445 -302.132419)
			(xy 73.119085 -302.083068) (xy 72.779978 -302.083068) (xy 72.779649 -302.099441) (xy 72.771754 -302.148018)
			(xy 72.75617 -302.194699) (xy 72.733299 -302.238276) (xy 72.703734 -302.27762) (xy 72.668241 -302.311712)
			(xy 72.627738 -302.339668) (xy 72.583276 -302.360766) (xy 72.536005 -302.374458) (xy 72.48715 -302.38039)
			(xy 72.437975 -302.378409) (xy 72.389756 -302.368565) (xy 72.34374 -302.351113) (xy 72.301119 -302.326506)
			(xy 72.262998 -302.295381) (xy 72.230363 -302.258544) (xy 72.20406 -302.216948) (xy 72.184769 -302.171672)
			(xy 72.172992 -302.123888) (xy 72.169032 -302.074834) (xy 71.830184 -302.074834) (xy 71.829689 -302.099441)
			(xy 71.821794 -302.148018) (xy 71.80621 -302.194699) (xy 71.783339 -302.238276) (xy 71.753774 -302.27762)
			(xy 71.718281 -302.311712) (xy 71.677778 -302.339668) (xy 71.633316 -302.360766) (xy 71.586045 -302.374458)
			(xy 71.53719 -302.38039) (xy 71.488015 -302.378409) (xy 71.439796 -302.368565) (xy 71.39378 -302.351113)
			(xy 71.351159 -302.326506) (xy 71.313038 -302.295381) (xy 71.280403 -302.258544) (xy 71.2541 -302.216948)
			(xy 71.234809 -302.171672) (xy 71.223032 -302.123888) (xy 71.219072 -302.074834) (xy 70.880224 -302.074834)
			(xy 70.879729 -302.099441) (xy 70.871834 -302.148018) (xy 70.85625 -302.194699) (xy 70.833379 -302.238276)
			(xy 70.803814 -302.27762) (xy 70.768321 -302.311712) (xy 70.727818 -302.339668) (xy 70.683356 -302.360766)
			(xy 70.636085 -302.374458) (xy 70.58723 -302.38039) (xy 70.538055 -302.378409) (xy 70.489836 -302.368565)
			(xy 70.44382 -302.351113) (xy 70.401199 -302.326506) (xy 70.363078 -302.295381) (xy 70.330443 -302.258544)
			(xy 70.30414 -302.216948) (xy 70.284849 -302.171672) (xy 70.273072 -302.123888) (xy 70.269112 -302.074834)
			(xy 69.930264 -302.074834) (xy 69.929769 -302.099441) (xy 69.921874 -302.148018) (xy 69.90629 -302.194699)
			(xy 69.883419 -302.238276) (xy 69.853854 -302.27762) (xy 69.818361 -302.311712) (xy 69.777858 -302.339668)
			(xy 69.733396 -302.360766) (xy 69.686125 -302.374458) (xy 69.63727 -302.38039) (xy 69.588095 -302.378409)
			(xy 69.539876 -302.368565) (xy 69.49386 -302.351113) (xy 69.451239 -302.326506) (xy 69.413118 -302.295381)
			(xy 69.380483 -302.258544) (xy 69.35418 -302.216948) (xy 69.334889 -302.171672) (xy 69.323112 -302.123888)
			(xy 69.319152 -302.074834) (xy 68.98005 -302.074834) (xy 68.979555 -302.099441) (xy 68.97166 -302.148018)
			(xy 68.956076 -302.194699) (xy 68.933205 -302.238276) (xy 68.90364 -302.27762) (xy 68.868147 -302.311712)
			(xy 68.827644 -302.339668) (xy 68.783182 -302.360766) (xy 68.735911 -302.374458) (xy 68.687056 -302.38039)
			(xy 68.637881 -302.378409) (xy 68.589662 -302.368565) (xy 68.543646 -302.351113) (xy 68.501025 -302.326506)
			(xy 68.462904 -302.295381) (xy 68.430269 -302.258544) (xy 68.403966 -302.216948) (xy 68.384675 -302.171672)
			(xy 68.372898 -302.123888) (xy 68.368938 -302.074834) (xy 68.03009 -302.074834) (xy 68.029595 -302.099441)
			(xy 68.0217 -302.148018) (xy 68.006116 -302.194699) (xy 67.983245 -302.238276) (xy 67.95368 -302.27762)
			(xy 67.918187 -302.311712) (xy 67.877684 -302.339668) (xy 67.833222 -302.360766) (xy 67.785951 -302.374458)
			(xy 67.737096 -302.38039) (xy 67.687921 -302.378409) (xy 67.639702 -302.368565) (xy 67.593686 -302.351113)
			(xy 67.551065 -302.326506) (xy 67.512944 -302.295381) (xy 67.480309 -302.258544) (xy 67.454006 -302.216948)
			(xy 67.434715 -302.171672) (xy 67.422938 -302.123888) (xy 67.418978 -302.074834) (xy 67.08013 -302.074834)
			(xy 67.079635 -302.099441) (xy 67.07174 -302.148018) (xy 67.056156 -302.194699) (xy 67.033285 -302.238276)
			(xy 67.00372 -302.27762) (xy 66.968227 -302.311712) (xy 66.927724 -302.339668) (xy 66.883262 -302.360766)
			(xy 66.835991 -302.374458) (xy 66.787136 -302.38039) (xy 66.737961 -302.378409) (xy 66.689742 -302.368565)
			(xy 66.643726 -302.351113) (xy 66.601105 -302.326506) (xy 66.562984 -302.295381) (xy 66.530349 -302.258544)
			(xy 66.504046 -302.216948) (xy 66.484755 -302.171672) (xy 66.472978 -302.123888) (xy 66.469018 -302.074834)
			(xy 66.13017 -302.074834) (xy 66.129675 -302.099441) (xy 66.12178 -302.148018) (xy 66.106196 -302.194699)
			(xy 66.083325 -302.238276) (xy 66.05376 -302.27762) (xy 66.018267 -302.311712) (xy 65.977764 -302.339668)
			(xy 65.933302 -302.360766) (xy 65.886031 -302.374458) (xy 65.837176 -302.38039) (xy 65.788001 -302.378409)
			(xy 65.739782 -302.368565) (xy 65.693766 -302.351113) (xy 65.651145 -302.326506) (xy 65.613024 -302.295381)
			(xy 65.580389 -302.258544) (xy 65.554086 -302.216948) (xy 65.534795 -302.171672) (xy 65.523018 -302.123888)
			(xy 65.519058 -302.074834) (xy 65.18021 -302.074834) (xy 65.179715 -302.099441) (xy 65.17182 -302.148018)
			(xy 65.156236 -302.194699) (xy 65.133365 -302.238276) (xy 65.1038 -302.27762) (xy 65.068307 -302.311712)
			(xy 65.027804 -302.339668) (xy 64.983342 -302.360766) (xy 64.936071 -302.374458) (xy 64.887216 -302.38039)
			(xy 64.838041 -302.378409) (xy 64.789822 -302.368565) (xy 64.743806 -302.351113) (xy 64.701185 -302.326506)
			(xy 64.663064 -302.295381) (xy 64.630429 -302.258544) (xy 64.604126 -302.216948) (xy 64.584835 -302.171672)
			(xy 64.573058 -302.123888) (xy 64.569098 -302.074834) (xy 64.23025 -302.074834) (xy 64.229755 -302.099441)
			(xy 64.22186 -302.148018) (xy 64.206276 -302.194699) (xy 64.183405 -302.238276) (xy 64.15384 -302.27762)
			(xy 64.118347 -302.311712) (xy 64.077844 -302.339668) (xy 64.033382 -302.360766) (xy 63.986111 -302.374458)
			(xy 63.937256 -302.38039) (xy 63.888081 -302.378409) (xy 63.839862 -302.368565) (xy 63.793846 -302.351113)
			(xy 63.751225 -302.326506) (xy 63.713104 -302.295381) (xy 63.680469 -302.258544) (xy 63.654166 -302.216948)
			(xy 63.634875 -302.171672) (xy 63.623098 -302.123888) (xy 63.619138 -302.074834) (xy 63.28029 -302.074834)
			(xy 63.279795 -302.099441) (xy 63.2719 -302.148018) (xy 63.256316 -302.194699) (xy 63.233445 -302.238276)
			(xy 63.20388 -302.27762) (xy 63.168387 -302.311712) (xy 63.127884 -302.339668) (xy 63.083422 -302.360766)
			(xy 63.036151 -302.374458) (xy 62.987296 -302.38039) (xy 62.938121 -302.378409) (xy 62.889902 -302.368565)
			(xy 62.843886 -302.351113) (xy 62.801265 -302.326506) (xy 62.763144 -302.295381) (xy 62.730509 -302.258544)
			(xy 62.704206 -302.216948) (xy 62.684915 -302.171672) (xy 62.673138 -302.123888) (xy 62.669178 -302.074834)
			(xy 62.330076 -302.074834) (xy 62.329581 -302.099441) (xy 62.321686 -302.148018) (xy 62.306102 -302.194699)
			(xy 62.283231 -302.238276) (xy 62.253666 -302.27762) (xy 62.218173 -302.311712) (xy 62.17767 -302.339668)
			(xy 62.133208 -302.360766) (xy 62.085937 -302.374458) (xy 62.037082 -302.38039) (xy 61.987907 -302.378409)
			(xy 61.939688 -302.368565) (xy 61.893672 -302.351113) (xy 61.851051 -302.326506) (xy 61.81293 -302.295381)
			(xy 61.780295 -302.258544) (xy 61.753992 -302.216948) (xy 61.734701 -302.171672) (xy 61.722924 -302.123888)
			(xy 61.718964 -302.074834) (xy 61.380116 -302.074834) (xy 61.379621 -302.099441) (xy 61.371726 -302.148018)
			(xy 61.356142 -302.194699) (xy 61.333271 -302.238276) (xy 61.303706 -302.27762) (xy 61.268213 -302.311712)
			(xy 61.22771 -302.339668) (xy 61.183248 -302.360766) (xy 61.135977 -302.374458) (xy 61.087122 -302.38039)
			(xy 61.037947 -302.378409) (xy 60.989728 -302.368565) (xy 60.943712 -302.351113) (xy 60.901091 -302.326506)
			(xy 60.86297 -302.295381) (xy 60.830335 -302.258544) (xy 60.804032 -302.216948) (xy 60.784741 -302.171672)
			(xy 60.772964 -302.123888) (xy 60.769004 -302.074834) (xy 60.430156 -302.074834) (xy 60.429661 -302.099441)
			(xy 60.421766 -302.148018) (xy 60.406182 -302.194699) (xy 60.383311 -302.238276) (xy 60.353746 -302.27762)
			(xy 60.318253 -302.311712) (xy 60.27775 -302.339668) (xy 60.233288 -302.360766) (xy 60.186017 -302.374458)
			(xy 60.137162 -302.38039) (xy 60.087987 -302.378409) (xy 60.039768 -302.368565) (xy 59.993752 -302.351113)
			(xy 59.951131 -302.326506) (xy 59.91301 -302.295381) (xy 59.880375 -302.258544) (xy 59.854072 -302.216948)
			(xy 59.834781 -302.171672) (xy 59.823004 -302.123888) (xy 59.819044 -302.074834) (xy 58.530236 -302.074834)
			(xy 58.529741 -302.099441) (xy 58.521846 -302.148018) (xy 58.506262 -302.194699) (xy 58.483391 -302.238276)
			(xy 58.453826 -302.27762) (xy 58.418333 -302.311712) (xy 58.37783 -302.339668) (xy 58.333368 -302.360766)
			(xy 58.286097 -302.374458) (xy 58.237242 -302.38039) (xy 58.188067 -302.378409) (xy 58.139848 -302.368565)
			(xy 58.093832 -302.351113) (xy 58.051211 -302.326506) (xy 58.01309 -302.295381) (xy 57.980455 -302.258544)
			(xy 57.954152 -302.216948) (xy 57.934861 -302.171672) (xy 57.923084 -302.123888) (xy 57.919124 -302.074834)
			(xy 57.580276 -302.074834) (xy 57.579781 -302.099441) (xy 57.571886 -302.148018) (xy 57.556302 -302.194699)
			(xy 57.533431 -302.238276) (xy 57.503866 -302.27762) (xy 57.468373 -302.311712) (xy 57.42787 -302.339668)
			(xy 57.383408 -302.360766) (xy 57.336137 -302.374458) (xy 57.287282 -302.38039) (xy 57.238107 -302.378409)
			(xy 57.189888 -302.368565) (xy 57.143872 -302.351113) (xy 57.101251 -302.326506) (xy 57.06313 -302.295381)
			(xy 57.030495 -302.258544) (xy 57.004192 -302.216948) (xy 56.984901 -302.171672) (xy 56.973124 -302.123888)
			(xy 56.969164 -302.074834) (xy 56.630062 -302.074834) (xy 56.629567 -302.099441) (xy 56.621672 -302.148018)
			(xy 56.606088 -302.194699) (xy 56.583217 -302.238276) (xy 56.553652 -302.27762) (xy 56.518159 -302.311712)
			(xy 56.477656 -302.339668) (xy 56.433194 -302.360766) (xy 56.385923 -302.374458) (xy 56.337068 -302.38039)
			(xy 56.287893 -302.378409) (xy 56.239674 -302.368565) (xy 56.193658 -302.351113) (xy 56.151037 -302.326506)
			(xy 56.112916 -302.295381) (xy 56.080281 -302.258544) (xy 56.053978 -302.216948) (xy 56.034687 -302.171672)
			(xy 56.02291 -302.123888) (xy 56.01895 -302.074834) (xy 55.680102 -302.074834) (xy 55.679607 -302.099441)
			(xy 55.671712 -302.148018) (xy 55.656128 -302.194699) (xy 55.633257 -302.238276) (xy 55.603692 -302.27762)
			(xy 55.568199 -302.311712) (xy 55.527696 -302.339668) (xy 55.483234 -302.360766) (xy 55.435963 -302.374458)
			(xy 55.387108 -302.38039) (xy 55.337933 -302.378409) (xy 55.289714 -302.368565) (xy 55.243698 -302.351113)
			(xy 55.201077 -302.326506) (xy 55.162956 -302.295381) (xy 55.130321 -302.258544) (xy 55.104018 -302.216948)
			(xy 55.084727 -302.171672) (xy 55.07295 -302.123888) (xy 55.06899 -302.074834) (xy 54.730142 -302.074834)
			(xy 54.729647 -302.099441) (xy 54.721752 -302.148018) (xy 54.706168 -302.194699) (xy 54.683297 -302.238276)
			(xy 54.653732 -302.27762) (xy 54.618239 -302.311712) (xy 54.577736 -302.339668) (xy 54.533274 -302.360766)
			(xy 54.486003 -302.374458) (xy 54.437148 -302.38039) (xy 54.387973 -302.378409) (xy 54.339754 -302.368565)
			(xy 54.293738 -302.351113) (xy 54.251117 -302.326506) (xy 54.212996 -302.295381) (xy 54.180361 -302.258544)
			(xy 54.154058 -302.216948) (xy 54.134767 -302.171672) (xy 54.12299 -302.123888) (xy 54.11903 -302.074834)
			(xy 53.780182 -302.074834) (xy 53.779687 -302.099441) (xy 53.771792 -302.148018) (xy 53.756208 -302.194699)
			(xy 53.733337 -302.238276) (xy 53.703772 -302.27762) (xy 53.668279 -302.311712) (xy 53.627776 -302.339668)
			(xy 53.583314 -302.360766) (xy 53.536043 -302.374458) (xy 53.487188 -302.38039) (xy 53.438013 -302.378409)
			(xy 53.389794 -302.368565) (xy 53.343778 -302.351113) (xy 53.301157 -302.326506) (xy 53.263036 -302.295381)
			(xy 53.230401 -302.258544) (xy 53.204098 -302.216948) (xy 53.184807 -302.171672) (xy 53.17303 -302.123888)
			(xy 53.16907 -302.074834) (xy 52.830222 -302.074834) (xy 52.829727 -302.099441) (xy 52.821832 -302.148018)
			(xy 52.806248 -302.194699) (xy 52.783377 -302.238276) (xy 52.753812 -302.27762) (xy 52.718319 -302.311712)
			(xy 52.677816 -302.339668) (xy 52.633354 -302.360766) (xy 52.586083 -302.374458) (xy 52.537228 -302.38039)
			(xy 52.488053 -302.378409) (xy 52.439834 -302.368565) (xy 52.393818 -302.351113) (xy 52.351197 -302.326506)
			(xy 52.313076 -302.295381) (xy 52.280441 -302.258544) (xy 52.254138 -302.216948) (xy 52.234847 -302.171672)
			(xy 52.22307 -302.123888) (xy 52.21911 -302.074834) (xy 51.880262 -302.074834) (xy 51.879767 -302.099441)
			(xy 51.871872 -302.148018) (xy 51.856288 -302.194699) (xy 51.833417 -302.238276) (xy 51.803852 -302.27762)
			(xy 51.768359 -302.311712) (xy 51.727856 -302.339668) (xy 51.683394 -302.360766) (xy 51.636123 -302.374458)
			(xy 51.587268 -302.38039) (xy 51.538093 -302.378409) (xy 51.489874 -302.368565) (xy 51.443858 -302.351113)
			(xy 51.401237 -302.326506) (xy 51.363116 -302.295381) (xy 51.330481 -302.258544) (xy 51.304178 -302.216948)
			(xy 51.284887 -302.171672) (xy 51.27311 -302.123888) (xy 51.26915 -302.074834) (xy 50.930302 -302.074834)
			(xy 50.929807 -302.099441) (xy 50.921912 -302.148018) (xy 50.906328 -302.194699) (xy 50.883457 -302.238276)
			(xy 50.853892 -302.27762) (xy 50.818399 -302.311712) (xy 50.777896 -302.339668) (xy 50.733434 -302.360766)
			(xy 50.686163 -302.374458) (xy 50.637308 -302.38039) (xy 50.588133 -302.378409) (xy 50.539914 -302.368565)
			(xy 50.493898 -302.351113) (xy 50.451277 -302.326506) (xy 50.413156 -302.295381) (xy 50.380521 -302.258544)
			(xy 50.354218 -302.216948) (xy 50.334927 -302.171672) (xy 50.32315 -302.123888) (xy 50.31919 -302.074834)
			(xy 49.980088 -302.074834) (xy 49.979593 -302.099441) (xy 49.971698 -302.148018) (xy 49.956114 -302.194699)
			(xy 49.933243 -302.238276) (xy 49.903678 -302.27762) (xy 49.868185 -302.311712) (xy 49.827682 -302.339668)
			(xy 49.78322 -302.360766) (xy 49.735949 -302.374458) (xy 49.687094 -302.38039) (xy 49.637919 -302.378409)
			(xy 49.5897 -302.368565) (xy 49.543684 -302.351113) (xy 49.501063 -302.326506) (xy 49.462942 -302.295381)
			(xy 49.430307 -302.258544) (xy 49.404004 -302.216948) (xy 49.384713 -302.171672) (xy 49.372936 -302.123888)
			(xy 49.368976 -302.074834) (xy 48.06823 -302.074834) (xy 48.06823 -302.933354) (xy 48.070008 -302.946562)
			(xy 48.07077 -302.94961) (xy 48.075171 -302.968094) (xy 48.07989 -303.005796) (xy 48.080168 -303.024794)
			(xy 48.419016 -303.024794) (xy 48.422976 -302.97574) (xy 48.434753 -302.927956) (xy 48.454044 -302.88268)
			(xy 48.480347 -302.841084) (xy 48.512982 -302.804247) (xy 48.551103 -302.773122) (xy 48.593724 -302.748515)
			(xy 48.63974 -302.731063) (xy 48.687959 -302.721219) (xy 48.737134 -302.719238) (xy 48.785989 -302.72517)
			(xy 48.83326 -302.738862) (xy 48.877722 -302.75996) (xy 48.918225 -302.787916) (xy 48.953718 -302.822008)
			(xy 48.983283 -302.861352) (xy 49.006154 -302.904929) (xy 49.021738 -302.95161) (xy 49.029633 -303.000187)
			(xy 49.030128 -303.024794) (xy 49.368976 -303.024794) (xy 49.372936 -302.97574) (xy 49.384713 -302.927956)
			(xy 49.404004 -302.88268) (xy 49.430307 -302.841084) (xy 49.462942 -302.804247) (xy 49.501063 -302.773122)
			(xy 49.543684 -302.748515) (xy 49.5897 -302.731063) (xy 49.637919 -302.721219) (xy 49.687094 -302.719238)
			(xy 49.735949 -302.72517) (xy 49.78322 -302.738862) (xy 49.827682 -302.75996) (xy 49.868185 -302.787916)
			(xy 49.903678 -302.822008) (xy 49.933243 -302.861352) (xy 49.956114 -302.904929) (xy 49.971698 -302.95161)
			(xy 49.979593 -303.000187) (xy 49.980088 -303.024794) (xy 50.31919 -303.024794) (xy 50.32315 -302.97574)
			(xy 50.334927 -302.927956) (xy 50.354218 -302.88268) (xy 50.380521 -302.841084) (xy 50.413156 -302.804247)
			(xy 50.451277 -302.773122) (xy 50.493898 -302.748515) (xy 50.539914 -302.731063) (xy 50.588133 -302.721219)
			(xy 50.637308 -302.719238) (xy 50.686163 -302.72517) (xy 50.733434 -302.738862) (xy 50.777896 -302.75996)
			(xy 50.818399 -302.787916) (xy 50.853892 -302.822008) (xy 50.883457 -302.861352) (xy 50.906328 -302.904929)
			(xy 50.921912 -302.95161) (xy 50.929807 -303.000187) (xy 50.930302 -303.024794) (xy 51.26915 -303.024794)
			(xy 51.27311 -302.97574) (xy 51.284887 -302.927956) (xy 51.304178 -302.88268) (xy 51.330481 -302.841084)
			(xy 51.363116 -302.804247) (xy 51.401237 -302.773122) (xy 51.443858 -302.748515) (xy 51.489874 -302.731063)
			(xy 51.538093 -302.721219) (xy 51.587268 -302.719238) (xy 51.636123 -302.72517) (xy 51.683394 -302.738862)
			(xy 51.727856 -302.75996) (xy 51.768359 -302.787916) (xy 51.803852 -302.822008) (xy 51.833417 -302.861352)
			(xy 51.856288 -302.904929) (xy 51.871872 -302.95161) (xy 51.879767 -303.000187) (xy 51.880262 -303.024794)
			(xy 52.21911 -303.024794) (xy 52.22307 -302.97574) (xy 52.234847 -302.927956) (xy 52.254138 -302.88268)
			(xy 52.280441 -302.841084) (xy 52.313076 -302.804247) (xy 52.351197 -302.773122) (xy 52.393818 -302.748515)
			(xy 52.439834 -302.731063) (xy 52.488053 -302.721219) (xy 52.537228 -302.719238) (xy 52.586083 -302.72517)
			(xy 52.633354 -302.738862) (xy 52.677816 -302.75996) (xy 52.718319 -302.787916) (xy 52.753812 -302.822008)
			(xy 52.783377 -302.861352) (xy 52.806248 -302.904929) (xy 52.821832 -302.95161) (xy 52.829727 -303.000187)
			(xy 52.830222 -303.024794) (xy 53.16907 -303.024794) (xy 53.17303 -302.97574) (xy 53.184807 -302.927956)
			(xy 53.204098 -302.88268) (xy 53.230401 -302.841084) (xy 53.263036 -302.804247) (xy 53.301157 -302.773122)
			(xy 53.343778 -302.748515) (xy 53.389794 -302.731063) (xy 53.438013 -302.721219) (xy 53.487188 -302.719238)
			(xy 53.536043 -302.72517) (xy 53.583314 -302.738862) (xy 53.627776 -302.75996) (xy 53.668279 -302.787916)
			(xy 53.703772 -302.822008) (xy 53.733337 -302.861352) (xy 53.756208 -302.904929) (xy 53.771792 -302.95161)
			(xy 53.779687 -303.000187) (xy 53.780182 -303.024794) (xy 54.11903 -303.024794) (xy 54.12299 -302.97574)
			(xy 54.134767 -302.927956) (xy 54.154058 -302.88268) (xy 54.180361 -302.841084) (xy 54.212996 -302.804247)
			(xy 54.251117 -302.773122) (xy 54.293738 -302.748515) (xy 54.339754 -302.731063) (xy 54.387973 -302.721219)
			(xy 54.437148 -302.719238) (xy 54.486003 -302.72517) (xy 54.533274 -302.738862) (xy 54.577736 -302.75996)
			(xy 54.618239 -302.787916) (xy 54.653732 -302.822008) (xy 54.683297 -302.861352) (xy 54.706168 -302.904929)
			(xy 54.721752 -302.95161) (xy 54.729647 -303.000187) (xy 54.730142 -303.024794) (xy 55.06899 -303.024794)
			(xy 55.07295 -302.97574) (xy 55.084727 -302.927956) (xy 55.104018 -302.88268) (xy 55.130321 -302.841084)
			(xy 55.162956 -302.804247) (xy 55.201077 -302.773122) (xy 55.243698 -302.748515) (xy 55.289714 -302.731063)
			(xy 55.337933 -302.721219) (xy 55.387108 -302.719238) (xy 55.435963 -302.72517) (xy 55.483234 -302.738862)
			(xy 55.527696 -302.75996) (xy 55.568199 -302.787916) (xy 55.603692 -302.822008) (xy 55.633257 -302.861352)
			(xy 55.656128 -302.904929) (xy 55.671712 -302.95161) (xy 55.679607 -303.000187) (xy 55.680102 -303.024794)
			(xy 56.01895 -303.024794) (xy 56.02291 -302.97574) (xy 56.034687 -302.927956) (xy 56.053978 -302.88268)
			(xy 56.080281 -302.841084) (xy 56.112916 -302.804247) (xy 56.151037 -302.773122) (xy 56.193658 -302.748515)
			(xy 56.239674 -302.731063) (xy 56.287893 -302.721219) (xy 56.337068 -302.719238) (xy 56.385923 -302.72517)
			(xy 56.433194 -302.738862) (xy 56.477656 -302.75996) (xy 56.518159 -302.787916) (xy 56.553652 -302.822008)
			(xy 56.583217 -302.861352) (xy 56.606088 -302.904929) (xy 56.621672 -302.95161) (xy 56.629567 -303.000187)
			(xy 56.630062 -303.024794) (xy 56.969164 -303.024794) (xy 56.973124 -302.97574) (xy 56.984901 -302.927956)
			(xy 57.004192 -302.88268) (xy 57.030495 -302.841084) (xy 57.06313 -302.804247) (xy 57.101251 -302.773122)
			(xy 57.143872 -302.748515) (xy 57.189888 -302.731063) (xy 57.238107 -302.721219) (xy 57.287282 -302.719238)
			(xy 57.336137 -302.72517) (xy 57.383408 -302.738862) (xy 57.42787 -302.75996) (xy 57.468373 -302.787916)
			(xy 57.503866 -302.822008) (xy 57.533431 -302.861352) (xy 57.556302 -302.904929) (xy 57.571886 -302.95161)
			(xy 57.579781 -303.000187) (xy 57.580276 -303.024794) (xy 57.919124 -303.024794) (xy 57.923084 -302.97574)
			(xy 57.934861 -302.927956) (xy 57.954152 -302.88268) (xy 57.980455 -302.841084) (xy 58.01309 -302.804247)
			(xy 58.051211 -302.773122) (xy 58.093832 -302.748515) (xy 58.139848 -302.731063) (xy 58.188067 -302.721219)
			(xy 58.237242 -302.719238) (xy 58.286097 -302.72517) (xy 58.333368 -302.738862) (xy 58.37783 -302.75996)
			(xy 58.418333 -302.787916) (xy 58.453826 -302.822008) (xy 58.483391 -302.861352) (xy 58.506262 -302.904929)
			(xy 58.521846 -302.95161) (xy 58.529741 -303.000187) (xy 58.530236 -303.024794) (xy 59.819044 -303.024794)
			(xy 59.823004 -302.97574) (xy 59.834781 -302.927956) (xy 59.854072 -302.88268) (xy 59.880375 -302.841084)
			(xy 59.91301 -302.804247) (xy 59.951131 -302.773122) (xy 59.993752 -302.748515) (xy 60.039768 -302.731063)
			(xy 60.087987 -302.721219) (xy 60.137162 -302.719238) (xy 60.186017 -302.72517) (xy 60.233288 -302.738862)
			(xy 60.27775 -302.75996) (xy 60.318253 -302.787916) (xy 60.353746 -302.822008) (xy 60.383311 -302.861352)
			(xy 60.406182 -302.904929) (xy 60.421766 -302.95161) (xy 60.429661 -303.000187) (xy 60.430156 -303.024794)
			(xy 60.769004 -303.024794) (xy 60.772964 -302.97574) (xy 60.784741 -302.927956) (xy 60.804032 -302.88268)
			(xy 60.830335 -302.841084) (xy 60.86297 -302.804247) (xy 60.901091 -302.773122) (xy 60.943712 -302.748515)
			(xy 60.989728 -302.731063) (xy 61.037947 -302.721219) (xy 61.087122 -302.719238) (xy 61.135977 -302.72517)
			(xy 61.183248 -302.738862) (xy 61.22771 -302.75996) (xy 61.268213 -302.787916) (xy 61.303706 -302.822008)
			(xy 61.333271 -302.861352) (xy 61.356142 -302.904929) (xy 61.371726 -302.95161) (xy 61.379621 -303.000187)
			(xy 61.380116 -303.024794) (xy 61.718964 -303.024794) (xy 61.722924 -302.97574) (xy 61.734701 -302.927956)
			(xy 61.753992 -302.88268) (xy 61.780295 -302.841084) (xy 61.81293 -302.804247) (xy 61.851051 -302.773122)
			(xy 61.893672 -302.748515) (xy 61.939688 -302.731063) (xy 61.987907 -302.721219) (xy 62.037082 -302.719238)
			(xy 62.085937 -302.72517) (xy 62.133208 -302.738862) (xy 62.17767 -302.75996) (xy 62.218173 -302.787916)
			(xy 62.253666 -302.822008) (xy 62.283231 -302.861352) (xy 62.306102 -302.904929) (xy 62.321686 -302.95161)
			(xy 62.329581 -303.000187) (xy 62.330076 -303.024794) (xy 62.669178 -303.024794) (xy 62.673138 -302.97574)
			(xy 62.684915 -302.927956) (xy 62.704206 -302.88268) (xy 62.730509 -302.841084) (xy 62.763144 -302.804247)
			(xy 62.801265 -302.773122) (xy 62.843886 -302.748515) (xy 62.889902 -302.731063) (xy 62.938121 -302.721219)
			(xy 62.987296 -302.719238) (xy 63.036151 -302.72517) (xy 63.083422 -302.738862) (xy 63.127884 -302.75996)
			(xy 63.168387 -302.787916) (xy 63.20388 -302.822008) (xy 63.233445 -302.861352) (xy 63.256316 -302.904929)
			(xy 63.2719 -302.95161) (xy 63.279795 -303.000187) (xy 63.28029 -303.024794) (xy 63.619138 -303.024794)
			(xy 63.623098 -302.97574) (xy 63.634875 -302.927956) (xy 63.654166 -302.88268) (xy 63.680469 -302.841084)
			(xy 63.713104 -302.804247) (xy 63.751225 -302.773122) (xy 63.793846 -302.748515) (xy 63.839862 -302.731063)
			(xy 63.888081 -302.721219) (xy 63.937256 -302.719238) (xy 63.986111 -302.72517) (xy 64.033382 -302.738862)
			(xy 64.077844 -302.75996) (xy 64.118347 -302.787916) (xy 64.15384 -302.822008) (xy 64.183405 -302.861352)
			(xy 64.206276 -302.904929) (xy 64.22186 -302.95161) (xy 64.229755 -303.000187) (xy 64.23025 -303.024794)
			(xy 64.569098 -303.024794) (xy 64.573058 -302.97574) (xy 64.584835 -302.927956) (xy 64.604126 -302.88268)
			(xy 64.630429 -302.841084) (xy 64.663064 -302.804247) (xy 64.701185 -302.773122) (xy 64.743806 -302.748515)
			(xy 64.789822 -302.731063) (xy 64.838041 -302.721219) (xy 64.887216 -302.719238) (xy 64.936071 -302.72517)
			(xy 64.983342 -302.738862) (xy 65.027804 -302.75996) (xy 65.068307 -302.787916) (xy 65.1038 -302.822008)
			(xy 65.133365 -302.861352) (xy 65.156236 -302.904929) (xy 65.17182 -302.95161) (xy 65.179715 -303.000187)
			(xy 65.18021 -303.024794) (xy 65.519058 -303.024794) (xy 65.523018 -302.97574) (xy 65.534795 -302.927956)
			(xy 65.554086 -302.88268) (xy 65.580389 -302.841084) (xy 65.613024 -302.804247) (xy 65.651145 -302.773122)
			(xy 65.693766 -302.748515) (xy 65.739782 -302.731063) (xy 65.788001 -302.721219) (xy 65.837176 -302.719238)
			(xy 65.886031 -302.72517) (xy 65.933302 -302.738862) (xy 65.977764 -302.75996) (xy 66.018267 -302.787916)
			(xy 66.05376 -302.822008) (xy 66.083325 -302.861352) (xy 66.106196 -302.904929) (xy 66.12178 -302.95161)
			(xy 66.129675 -303.000187) (xy 66.13017 -303.024794) (xy 66.469018 -303.024794) (xy 66.472978 -302.97574)
			(xy 66.484755 -302.927956) (xy 66.504046 -302.88268) (xy 66.530349 -302.841084) (xy 66.562984 -302.804247)
			(xy 66.601105 -302.773122) (xy 66.643726 -302.748515) (xy 66.689742 -302.731063) (xy 66.737961 -302.721219)
			(xy 66.787136 -302.719238) (xy 66.835991 -302.72517) (xy 66.883262 -302.738862) (xy 66.927724 -302.75996)
			(xy 66.968227 -302.787916) (xy 67.00372 -302.822008) (xy 67.033285 -302.861352) (xy 67.056156 -302.904929)
			(xy 67.07174 -302.95161) (xy 67.079635 -303.000187) (xy 67.08013 -303.024794) (xy 67.418978 -303.024794)
			(xy 67.422938 -302.97574) (xy 67.434715 -302.927956) (xy 67.454006 -302.88268) (xy 67.480309 -302.841084)
			(xy 67.512944 -302.804247) (xy 67.551065 -302.773122) (xy 67.593686 -302.748515) (xy 67.639702 -302.731063)
			(xy 67.687921 -302.721219) (xy 67.737096 -302.719238) (xy 67.785951 -302.72517) (xy 67.833222 -302.738862)
			(xy 67.877684 -302.75996) (xy 67.918187 -302.787916) (xy 67.95368 -302.822008) (xy 67.983245 -302.861352)
			(xy 68.006116 -302.904929) (xy 68.0217 -302.95161) (xy 68.029595 -303.000187) (xy 68.03009 -303.024794)
			(xy 68.368938 -303.024794) (xy 68.372898 -302.97574) (xy 68.384675 -302.927956) (xy 68.403966 -302.88268)
			(xy 68.430269 -302.841084) (xy 68.462904 -302.804247) (xy 68.501025 -302.773122) (xy 68.543646 -302.748515)
			(xy 68.589662 -302.731063) (xy 68.637881 -302.721219) (xy 68.687056 -302.719238) (xy 68.735911 -302.72517)
			(xy 68.783182 -302.738862) (xy 68.827644 -302.75996) (xy 68.868147 -302.787916) (xy 68.90364 -302.822008)
			(xy 68.933205 -302.861352) (xy 68.956076 -302.904929) (xy 68.97166 -302.95161) (xy 68.979555 -303.000187)
			(xy 68.98005 -303.024794) (xy 69.319152 -303.024794) (xy 69.323112 -302.97574) (xy 69.334889 -302.927956)
			(xy 69.35418 -302.88268) (xy 69.380483 -302.841084) (xy 69.413118 -302.804247) (xy 69.451239 -302.773122)
			(xy 69.49386 -302.748515) (xy 69.539876 -302.731063) (xy 69.588095 -302.721219) (xy 69.63727 -302.719238)
			(xy 69.686125 -302.72517) (xy 69.733396 -302.738862) (xy 69.777858 -302.75996) (xy 69.818361 -302.787916)
			(xy 69.853854 -302.822008) (xy 69.883419 -302.861352) (xy 69.90629 -302.904929) (xy 69.921874 -302.95161)
			(xy 69.929769 -303.000187) (xy 69.930264 -303.024794) (xy 70.269112 -303.024794) (xy 70.273072 -302.97574)
			(xy 70.284849 -302.927956) (xy 70.30414 -302.88268) (xy 70.330443 -302.841084) (xy 70.363078 -302.804247)
			(xy 70.401199 -302.773122) (xy 70.44382 -302.748515) (xy 70.489836 -302.731063) (xy 70.538055 -302.721219)
			(xy 70.58723 -302.719238) (xy 70.636085 -302.72517) (xy 70.683356 -302.738862) (xy 70.727818 -302.75996)
			(xy 70.768321 -302.787916) (xy 70.803814 -302.822008) (xy 70.833379 -302.861352) (xy 70.85625 -302.904929)
			(xy 70.871834 -302.95161) (xy 70.879729 -303.000187) (xy 70.880224 -303.024794) (xy 71.219072 -303.024794)
			(xy 71.223032 -302.97574) (xy 71.234809 -302.927956) (xy 71.2541 -302.88268) (xy 71.280403 -302.841084)
			(xy 71.313038 -302.804247) (xy 71.351159 -302.773122) (xy 71.39378 -302.748515) (xy 71.439796 -302.731063)
			(xy 71.488015 -302.721219) (xy 71.53719 -302.719238) (xy 71.586045 -302.72517) (xy 71.633316 -302.738862)
			(xy 71.677778 -302.75996) (xy 71.718281 -302.787916) (xy 71.753774 -302.822008) (xy 71.783339 -302.861352)
			(xy 71.80621 -302.904929) (xy 71.821794 -302.95161) (xy 71.829689 -303.000187) (xy 71.830184 -303.024794)
			(xy 72.169032 -303.024794) (xy 72.172992 -302.97574) (xy 72.184769 -302.927956) (xy 72.20406 -302.88268)
			(xy 72.230363 -302.841084) (xy 72.262998 -302.804247) (xy 72.301119 -302.773122) (xy 72.34374 -302.748515)
			(xy 72.389756 -302.731063) (xy 72.437975 -302.721219) (xy 72.48715 -302.719238) (xy 72.536005 -302.72517)
			(xy 72.583276 -302.738862) (xy 72.627738 -302.75996) (xy 72.668241 -302.787916) (xy 72.703734 -302.822008)
			(xy 72.733299 -302.861352) (xy 72.75617 -302.904929) (xy 72.771754 -302.95161) (xy 72.779649 -303.000187)
			(xy 72.780144 -303.024794) (xy 76.919086 -303.024794) (xy 76.923046 -302.97574) (xy 76.934823 -302.927956)
			(xy 76.954114 -302.88268) (xy 76.980417 -302.841084) (xy 77.013052 -302.804247) (xy 77.051173 -302.773122)
			(xy 77.093794 -302.748515) (xy 77.13981 -302.731063) (xy 77.188029 -302.721219) (xy 77.237204 -302.719238)
			(xy 77.286059 -302.72517) (xy 77.33333 -302.738862) (xy 77.377792 -302.75996) (xy 77.418295 -302.787916)
			(xy 77.453788 -302.822008) (xy 77.483353 -302.861352) (xy 77.506224 -302.904929) (xy 77.521808 -302.95161)
			(xy 77.529703 -303.000187) (xy 77.530198 -303.024794) (xy 77.869046 -303.024794) (xy 77.873006 -302.97574)
			(xy 77.884783 -302.927956) (xy 77.904074 -302.88268) (xy 77.930377 -302.841084) (xy 77.963012 -302.804247)
			(xy 78.001133 -302.773122) (xy 78.043754 -302.748515) (xy 78.08977 -302.731063) (xy 78.137989 -302.721219)
			(xy 78.187164 -302.719238) (xy 78.236019 -302.72517) (xy 78.28329 -302.738862) (xy 78.327752 -302.75996)
			(xy 78.368255 -302.787916) (xy 78.403748 -302.822008) (xy 78.433313 -302.861352) (xy 78.456184 -302.904929)
			(xy 78.471768 -302.95161) (xy 78.479663 -303.000187) (xy 78.480158 -303.024794) (xy 78.819006 -303.024794)
			(xy 78.822966 -302.97574) (xy 78.834743 -302.927956) (xy 78.854034 -302.88268) (xy 78.880337 -302.841084)
			(xy 78.912972 -302.804247) (xy 78.951093 -302.773122) (xy 78.993714 -302.748515) (xy 79.03973 -302.731063)
			(xy 79.087949 -302.721219) (xy 79.137124 -302.719238) (xy 79.185979 -302.72517) (xy 79.23325 -302.738862)
			(xy 79.277712 -302.75996) (xy 79.318215 -302.787916) (xy 79.353708 -302.822008) (xy 79.383273 -302.861352)
			(xy 79.406144 -302.904929) (xy 79.421728 -302.95161) (xy 79.429623 -303.000187) (xy 79.430118 -303.024794)
			(xy 79.768966 -303.024794) (xy 79.772926 -302.97574) (xy 79.784703 -302.927956) (xy 79.803994 -302.88268)
			(xy 79.830297 -302.841084) (xy 79.862932 -302.804247) (xy 79.901053 -302.773122) (xy 79.943674 -302.748515)
			(xy 79.98969 -302.731063) (xy 80.037909 -302.721219) (xy 80.087084 -302.719238) (xy 80.135939 -302.72517)
			(xy 80.18321 -302.738862) (xy 80.227672 -302.75996) (xy 80.268175 -302.787916) (xy 80.303668 -302.822008)
			(xy 80.333233 -302.861352) (xy 80.356104 -302.904929) (xy 80.371688 -302.95161) (xy 80.379583 -303.000187)
			(xy 80.380078 -303.024794) (xy 80.71918 -303.024794) (xy 80.72314 -302.97574) (xy 80.734917 -302.927956)
			(xy 80.754208 -302.88268) (xy 80.780511 -302.841084) (xy 80.813146 -302.804247) (xy 80.851267 -302.773122)
			(xy 80.893888 -302.748515) (xy 80.939904 -302.731063) (xy 80.988123 -302.721219) (xy 81.037298 -302.719238)
			(xy 81.086153 -302.72517) (xy 81.133424 -302.738862) (xy 81.177886 -302.75996) (xy 81.218389 -302.787916)
			(xy 81.253882 -302.822008) (xy 81.283447 -302.861352) (xy 81.306318 -302.904929) (xy 81.321902 -302.95161)
			(xy 81.329797 -303.000187) (xy 81.330292 -303.024794) (xy 81.66914 -303.024794) (xy 81.6731 -302.97574)
			(xy 81.684877 -302.927956) (xy 81.704168 -302.88268) (xy 81.730471 -302.841084) (xy 81.763106 -302.804247)
			(xy 81.801227 -302.773122) (xy 81.843848 -302.748515) (xy 81.889864 -302.731063) (xy 81.938083 -302.721219)
			(xy 81.987258 -302.719238) (xy 82.036113 -302.72517) (xy 82.083384 -302.738862) (xy 82.127846 -302.75996)
			(xy 82.168349 -302.787916) (xy 82.203842 -302.822008) (xy 82.233407 -302.861352) (xy 82.256278 -302.904929)
			(xy 82.271862 -302.95161) (xy 82.279757 -303.000187) (xy 82.280252 -303.024794) (xy 82.60386 -303.024794)
			(xy 82.60782 -302.97574) (xy 82.619597 -302.927956) (xy 82.638888 -302.88268) (xy 82.665191 -302.841084)
			(xy 82.697826 -302.804247) (xy 82.735947 -302.773122) (xy 82.778568 -302.748515) (xy 82.824584 -302.731063)
			(xy 82.872803 -302.721219) (xy 82.921978 -302.719238) (xy 82.970833 -302.72517) (xy 83.018104 -302.738862)
			(xy 83.062566 -302.75996) (xy 83.103069 -302.787916) (xy 83.138562 -302.822008) (xy 83.168127 -302.861352)
			(xy 83.190998 -302.904929) (xy 83.206582 -302.95161) (xy 83.210441 -302.975356) (xy 90.372341 -302.975356)
			(xy 90.372341 -302.920844) (xy 90.380099 -302.866888) (xy 90.395458 -302.814585) (xy 90.418104 -302.765001)
			(xy 90.447577 -302.719144) (xy 90.483276 -302.677949) (xy 90.524474 -302.642254) (xy 90.570334 -302.612786)
			(xy 90.619921 -302.590144) (xy 90.672225 -302.574791) (xy 90.726182 -302.567038) (xy 90.753438 -302.566578)
			(xy 90.781901 -302.567128) (xy 90.838198 -302.575574) (xy 90.892616 -302.592287) (xy 90.943949 -302.616897)
			(xy 90.991056 -302.648858) (xy 91.032895 -302.687461) (xy 91.051126 -302.709326) (xy 91.060886 -302.72061)
			(xy 91.08546 -302.737501) (xy 91.113865 -302.746574) (xy 91.143679 -302.747054) (xy 91.172362 -302.738902)
			(xy 91.197467 -302.722812) (xy 91.216854 -302.700155) (xy 91.223338 -302.68672) (xy 91.234826 -302.661582)
			(xy 91.264054 -302.614673) (xy 91.299745 -302.572473) (xy 91.341152 -302.535864) (xy 91.387408 -302.505615)
			(xy 91.437546 -302.482357) (xy 91.490515 -302.466578) (xy 91.545207 -302.458608) (xy 91.572842 -302.45812)
			(xy 91.600093 -302.458553) (xy 91.65404 -302.466315) (xy 91.706334 -302.481675) (xy 91.75591 -302.50432)
			(xy 91.801758 -302.533789) (xy 91.842946 -302.569483) (xy 91.878636 -302.610676) (xy 91.9081 -302.656527)
			(xy 91.93074 -302.706105) (xy 91.946094 -302.758401) (xy 91.95385 -302.812349) (xy 91.95385 -302.866851)
			(xy 91.946094 -302.920799) (xy 91.93074 -302.973095) (xy 91.9081 -303.022673) (xy 91.878636 -303.068524)
			(xy 91.842946 -303.109717) (xy 91.801758 -303.145411) (xy 91.75591 -303.17488) (xy 91.706334 -303.197525)
			(xy 91.65404 -303.212885) (xy 91.600093 -303.220647) (xy 91.572842 -303.221136) (xy 91.544378 -303.220595)
			(xy 91.488081 -303.212146) (xy 91.433663 -303.195431) (xy 91.382331 -303.170819) (xy 91.335224 -303.138857)
			(xy 91.293385 -303.100253) (xy 91.275154 -303.078388) (xy 91.26542 -303.067078) (xy 91.240841 -303.050185)
			(xy 91.212429 -303.041113) (xy 91.182608 -303.040635) (xy 91.15392 -303.048793) (xy 91.128812 -303.06489)
			(xy 91.109425 -303.087554) (xy 91.102942 -303.100994) (xy 91.091476 -303.126143) (xy 91.062245 -303.173052)
			(xy 91.026551 -303.215252) (xy 90.985141 -303.251859) (xy 90.938881 -303.282108) (xy 90.88874 -303.305364)
			(xy 90.835768 -303.32114) (xy 90.781074 -303.329108) (xy 90.753438 -303.329594) (xy 90.726182 -303.329162)
			(xy 90.672225 -303.321409) (xy 90.619921 -303.306056) (xy 90.570334 -303.283414) (xy 90.524474 -303.253946)
			(xy 90.483276 -303.218251) (xy 90.447577 -303.177056) (xy 90.418104 -303.131199) (xy 90.395458 -303.081615)
			(xy 90.380099 -303.029312) (xy 90.372341 -302.975356) (xy 83.210441 -302.975356) (xy 83.214477 -303.000187)
			(xy 83.214972 -303.024794) (xy 83.214477 -303.049401) (xy 83.206582 -303.097978) (xy 83.190998 -303.144659)
			(xy 83.168127 -303.188236) (xy 83.138562 -303.22758) (xy 83.103069 -303.261672) (xy 83.062566 -303.289628)
			(xy 83.018104 -303.310726) (xy 82.970833 -303.324418) (xy 82.921978 -303.33035) (xy 82.872803 -303.328369)
			(xy 82.824584 -303.318525) (xy 82.778568 -303.301073) (xy 82.735947 -303.276466) (xy 82.697826 -303.245341)
			(xy 82.665191 -303.208504) (xy 82.638888 -303.166908) (xy 82.619597 -303.121632) (xy 82.60782 -303.073848)
			(xy 82.60386 -303.024794) (xy 82.280252 -303.024794) (xy 82.279757 -303.049401) (xy 82.271862 -303.097978)
			(xy 82.256278 -303.144659) (xy 82.233407 -303.188236) (xy 82.203842 -303.22758) (xy 82.168349 -303.261672)
			(xy 82.127846 -303.289628) (xy 82.083384 -303.310726) (xy 82.036113 -303.324418) (xy 81.987258 -303.33035)
			(xy 81.938083 -303.328369) (xy 81.889864 -303.318525) (xy 81.843848 -303.301073) (xy 81.801227 -303.276466)
			(xy 81.763106 -303.245341) (xy 81.730471 -303.208504) (xy 81.704168 -303.166908) (xy 81.684877 -303.121632)
			(xy 81.6731 -303.073848) (xy 81.66914 -303.024794) (xy 81.330292 -303.024794) (xy 81.329797 -303.049401)
			(xy 81.321902 -303.097978) (xy 81.306318 -303.144659) (xy 81.283447 -303.188236) (xy 81.253882 -303.22758)
			(xy 81.218389 -303.261672) (xy 81.177886 -303.289628) (xy 81.133424 -303.310726) (xy 81.086153 -303.324418)
			(xy 81.037298 -303.33035) (xy 80.988123 -303.328369) (xy 80.939904 -303.318525) (xy 80.893888 -303.301073)
			(xy 80.851267 -303.276466) (xy 80.813146 -303.245341) (xy 80.780511 -303.208504) (xy 80.754208 -303.166908)
			(xy 80.734917 -303.121632) (xy 80.72314 -303.073848) (xy 80.71918 -303.024794) (xy 80.380078 -303.024794)
			(xy 80.379583 -303.049401) (xy 80.371688 -303.097978) (xy 80.356104 -303.144659) (xy 80.333233 -303.188236)
			(xy 80.303668 -303.22758) (xy 80.268175 -303.261672) (xy 80.227672 -303.289628) (xy 80.18321 -303.310726)
			(xy 80.135939 -303.324418) (xy 80.087084 -303.33035) (xy 80.037909 -303.328369) (xy 79.98969 -303.318525)
			(xy 79.943674 -303.301073) (xy 79.901053 -303.276466) (xy 79.862932 -303.245341) (xy 79.830297 -303.208504)
			(xy 79.803994 -303.166908) (xy 79.784703 -303.121632) (xy 79.772926 -303.073848) (xy 79.768966 -303.024794)
			(xy 79.430118 -303.024794) (xy 79.429623 -303.049401) (xy 79.421728 -303.097978) (xy 79.406144 -303.144659)
			(xy 79.383273 -303.188236) (xy 79.353708 -303.22758) (xy 79.318215 -303.261672) (xy 79.277712 -303.289628)
			(xy 79.23325 -303.310726) (xy 79.185979 -303.324418) (xy 79.137124 -303.33035) (xy 79.087949 -303.328369)
			(xy 79.03973 -303.318525) (xy 78.993714 -303.301073) (xy 78.951093 -303.276466) (xy 78.912972 -303.245341)
			(xy 78.880337 -303.208504) (xy 78.854034 -303.166908) (xy 78.834743 -303.121632) (xy 78.822966 -303.073848)
			(xy 78.819006 -303.024794) (xy 78.480158 -303.024794) (xy 78.479663 -303.049401) (xy 78.471768 -303.097978)
			(xy 78.456184 -303.144659) (xy 78.433313 -303.188236) (xy 78.403748 -303.22758) (xy 78.368255 -303.261672)
			(xy 78.327752 -303.289628) (xy 78.28329 -303.310726) (xy 78.236019 -303.324418) (xy 78.187164 -303.33035)
			(xy 78.137989 -303.328369) (xy 78.08977 -303.318525) (xy 78.043754 -303.301073) (xy 78.001133 -303.276466)
			(xy 77.963012 -303.245341) (xy 77.930377 -303.208504) (xy 77.904074 -303.166908) (xy 77.884783 -303.121632)
			(xy 77.873006 -303.073848) (xy 77.869046 -303.024794) (xy 77.530198 -303.024794) (xy 77.529703 -303.049401)
			(xy 77.521808 -303.097978) (xy 77.506224 -303.144659) (xy 77.483353 -303.188236) (xy 77.453788 -303.22758)
			(xy 77.418295 -303.261672) (xy 77.377792 -303.289628) (xy 77.33333 -303.310726) (xy 77.286059 -303.324418)
			(xy 77.237204 -303.33035) (xy 77.188029 -303.328369) (xy 77.13981 -303.318525) (xy 77.093794 -303.301073)
			(xy 77.051173 -303.276466) (xy 77.013052 -303.245341) (xy 76.980417 -303.208504) (xy 76.954114 -303.166908)
			(xy 76.934823 -303.121632) (xy 76.923046 -303.073848) (xy 76.919086 -303.024794) (xy 72.780144 -303.024794)
			(xy 72.779649 -303.049401) (xy 72.771754 -303.097978) (xy 72.75617 -303.144659) (xy 72.733299 -303.188236)
			(xy 72.703734 -303.22758) (xy 72.668241 -303.261672) (xy 72.627738 -303.289628) (xy 72.583276 -303.310726)
			(xy 72.536005 -303.324418) (xy 72.48715 -303.33035) (xy 72.437975 -303.328369) (xy 72.389756 -303.318525)
			(xy 72.34374 -303.301073) (xy 72.301119 -303.276466) (xy 72.262998 -303.245341) (xy 72.230363 -303.208504)
			(xy 72.20406 -303.166908) (xy 72.184769 -303.121632) (xy 72.172992 -303.073848) (xy 72.169032 -303.024794)
			(xy 71.830184 -303.024794) (xy 71.829689 -303.049401) (xy 71.821794 -303.097978) (xy 71.80621 -303.144659)
			(xy 71.783339 -303.188236) (xy 71.753774 -303.22758) (xy 71.718281 -303.261672) (xy 71.677778 -303.289628)
			(xy 71.633316 -303.310726) (xy 71.586045 -303.324418) (xy 71.53719 -303.33035) (xy 71.488015 -303.328369)
			(xy 71.439796 -303.318525) (xy 71.39378 -303.301073) (xy 71.351159 -303.276466) (xy 71.313038 -303.245341)
			(xy 71.280403 -303.208504) (xy 71.2541 -303.166908) (xy 71.234809 -303.121632) (xy 71.223032 -303.073848)
			(xy 71.219072 -303.024794) (xy 70.880224 -303.024794) (xy 70.879729 -303.049401) (xy 70.871834 -303.097978)
			(xy 70.85625 -303.144659) (xy 70.833379 -303.188236) (xy 70.803814 -303.22758) (xy 70.768321 -303.261672)
			(xy 70.727818 -303.289628) (xy 70.683356 -303.310726) (xy 70.636085 -303.324418) (xy 70.58723 -303.33035)
			(xy 70.538055 -303.328369) (xy 70.489836 -303.318525) (xy 70.44382 -303.301073) (xy 70.401199 -303.276466)
			(xy 70.363078 -303.245341) (xy 70.330443 -303.208504) (xy 70.30414 -303.166908) (xy 70.284849 -303.121632)
			(xy 70.273072 -303.073848) (xy 70.269112 -303.024794) (xy 69.930264 -303.024794) (xy 69.929769 -303.049401)
			(xy 69.921874 -303.097978) (xy 69.90629 -303.144659) (xy 69.883419 -303.188236) (xy 69.853854 -303.22758)
			(xy 69.818361 -303.261672) (xy 69.777858 -303.289628) (xy 69.733396 -303.310726) (xy 69.686125 -303.324418)
			(xy 69.63727 -303.33035) (xy 69.588095 -303.328369) (xy 69.539876 -303.318525) (xy 69.49386 -303.301073)
			(xy 69.451239 -303.276466) (xy 69.413118 -303.245341) (xy 69.380483 -303.208504) (xy 69.35418 -303.166908)
			(xy 69.334889 -303.121632) (xy 69.323112 -303.073848) (xy 69.319152 -303.024794) (xy 68.98005 -303.024794)
			(xy 68.979555 -303.049401) (xy 68.97166 -303.097978) (xy 68.956076 -303.144659) (xy 68.933205 -303.188236)
			(xy 68.90364 -303.22758) (xy 68.868147 -303.261672) (xy 68.827644 -303.289628) (xy 68.783182 -303.310726)
			(xy 68.735911 -303.324418) (xy 68.687056 -303.33035) (xy 68.637881 -303.328369) (xy 68.589662 -303.318525)
			(xy 68.543646 -303.301073) (xy 68.501025 -303.276466) (xy 68.462904 -303.245341) (xy 68.430269 -303.208504)
			(xy 68.403966 -303.166908) (xy 68.384675 -303.121632) (xy 68.372898 -303.073848) (xy 68.368938 -303.024794)
			(xy 68.03009 -303.024794) (xy 68.029595 -303.049401) (xy 68.0217 -303.097978) (xy 68.006116 -303.144659)
			(xy 67.983245 -303.188236) (xy 67.95368 -303.22758) (xy 67.918187 -303.261672) (xy 67.877684 -303.289628)
			(xy 67.833222 -303.310726) (xy 67.785951 -303.324418) (xy 67.737096 -303.33035) (xy 67.687921 -303.328369)
			(xy 67.639702 -303.318525) (xy 67.593686 -303.301073) (xy 67.551065 -303.276466) (xy 67.512944 -303.245341)
			(xy 67.480309 -303.208504) (xy 67.454006 -303.166908) (xy 67.434715 -303.121632) (xy 67.422938 -303.073848)
			(xy 67.418978 -303.024794) (xy 67.08013 -303.024794) (xy 67.079635 -303.049401) (xy 67.07174 -303.097978)
			(xy 67.056156 -303.144659) (xy 67.033285 -303.188236) (xy 67.00372 -303.22758) (xy 66.968227 -303.261672)
			(xy 66.927724 -303.289628) (xy 66.883262 -303.310726) (xy 66.835991 -303.324418) (xy 66.787136 -303.33035)
			(xy 66.737961 -303.328369) (xy 66.689742 -303.318525) (xy 66.643726 -303.301073) (xy 66.601105 -303.276466)
			(xy 66.562984 -303.245341) (xy 66.530349 -303.208504) (xy 66.504046 -303.166908) (xy 66.484755 -303.121632)
			(xy 66.472978 -303.073848) (xy 66.469018 -303.024794) (xy 66.13017 -303.024794) (xy 66.129675 -303.049401)
			(xy 66.12178 -303.097978) (xy 66.106196 -303.144659) (xy 66.083325 -303.188236) (xy 66.05376 -303.22758)
			(xy 66.018267 -303.261672) (xy 65.977764 -303.289628) (xy 65.933302 -303.310726) (xy 65.886031 -303.324418)
			(xy 65.837176 -303.33035) (xy 65.788001 -303.328369) (xy 65.739782 -303.318525) (xy 65.693766 -303.301073)
			(xy 65.651145 -303.276466) (xy 65.613024 -303.245341) (xy 65.580389 -303.208504) (xy 65.554086 -303.166908)
			(xy 65.534795 -303.121632) (xy 65.523018 -303.073848) (xy 65.519058 -303.024794) (xy 65.18021 -303.024794)
			(xy 65.179715 -303.049401) (xy 65.17182 -303.097978) (xy 65.156236 -303.144659) (xy 65.133365 -303.188236)
			(xy 65.1038 -303.22758) (xy 65.068307 -303.261672) (xy 65.027804 -303.289628) (xy 64.983342 -303.310726)
			(xy 64.936071 -303.324418) (xy 64.887216 -303.33035) (xy 64.838041 -303.328369) (xy 64.789822 -303.318525)
			(xy 64.743806 -303.301073) (xy 64.701185 -303.276466) (xy 64.663064 -303.245341) (xy 64.630429 -303.208504)
			(xy 64.604126 -303.166908) (xy 64.584835 -303.121632) (xy 64.573058 -303.073848) (xy 64.569098 -303.024794)
			(xy 64.23025 -303.024794) (xy 64.229755 -303.049401) (xy 64.22186 -303.097978) (xy 64.206276 -303.144659)
			(xy 64.183405 -303.188236) (xy 64.15384 -303.22758) (xy 64.118347 -303.261672) (xy 64.077844 -303.289628)
			(xy 64.033382 -303.310726) (xy 63.986111 -303.324418) (xy 63.937256 -303.33035) (xy 63.888081 -303.328369)
			(xy 63.839862 -303.318525) (xy 63.793846 -303.301073) (xy 63.751225 -303.276466) (xy 63.713104 -303.245341)
			(xy 63.680469 -303.208504) (xy 63.654166 -303.166908) (xy 63.634875 -303.121632) (xy 63.623098 -303.073848)
			(xy 63.619138 -303.024794) (xy 63.28029 -303.024794) (xy 63.279795 -303.049401) (xy 63.2719 -303.097978)
			(xy 63.256316 -303.144659) (xy 63.233445 -303.188236) (xy 63.20388 -303.22758) (xy 63.168387 -303.261672)
			(xy 63.127884 -303.289628) (xy 63.083422 -303.310726) (xy 63.036151 -303.324418) (xy 62.987296 -303.33035)
			(xy 62.938121 -303.328369) (xy 62.889902 -303.318525) (xy 62.843886 -303.301073) (xy 62.801265 -303.276466)
			(xy 62.763144 -303.245341) (xy 62.730509 -303.208504) (xy 62.704206 -303.166908) (xy 62.684915 -303.121632)
			(xy 62.673138 -303.073848) (xy 62.669178 -303.024794) (xy 62.330076 -303.024794) (xy 62.329581 -303.049401)
			(xy 62.321686 -303.097978) (xy 62.306102 -303.144659) (xy 62.283231 -303.188236) (xy 62.253666 -303.22758)
			(xy 62.218173 -303.261672) (xy 62.17767 -303.289628) (xy 62.133208 -303.310726) (xy 62.085937 -303.324418)
			(xy 62.037082 -303.33035) (xy 61.987907 -303.328369) (xy 61.939688 -303.318525) (xy 61.893672 -303.301073)
			(xy 61.851051 -303.276466) (xy 61.81293 -303.245341) (xy 61.780295 -303.208504) (xy 61.753992 -303.166908)
			(xy 61.734701 -303.121632) (xy 61.722924 -303.073848) (xy 61.718964 -303.024794) (xy 61.380116 -303.024794)
			(xy 61.379621 -303.049401) (xy 61.371726 -303.097978) (xy 61.356142 -303.144659) (xy 61.333271 -303.188236)
			(xy 61.303706 -303.22758) (xy 61.268213 -303.261672) (xy 61.22771 -303.289628) (xy 61.183248 -303.310726)
			(xy 61.135977 -303.324418) (xy 61.087122 -303.33035) (xy 61.037947 -303.328369) (xy 60.989728 -303.318525)
			(xy 60.943712 -303.301073) (xy 60.901091 -303.276466) (xy 60.86297 -303.245341) (xy 60.830335 -303.208504)
			(xy 60.804032 -303.166908) (xy 60.784741 -303.121632) (xy 60.772964 -303.073848) (xy 60.769004 -303.024794)
			(xy 60.430156 -303.024794) (xy 60.429661 -303.049401) (xy 60.421766 -303.097978) (xy 60.406182 -303.144659)
			(xy 60.383311 -303.188236) (xy 60.353746 -303.22758) (xy 60.318253 -303.261672) (xy 60.27775 -303.289628)
			(xy 60.233288 -303.310726) (xy 60.186017 -303.324418) (xy 60.137162 -303.33035) (xy 60.087987 -303.328369)
			(xy 60.039768 -303.318525) (xy 59.993752 -303.301073) (xy 59.951131 -303.276466) (xy 59.91301 -303.245341)
			(xy 59.880375 -303.208504) (xy 59.854072 -303.166908) (xy 59.834781 -303.121632) (xy 59.823004 -303.073848)
			(xy 59.819044 -303.024794) (xy 58.530236 -303.024794) (xy 58.529741 -303.049401) (xy 58.521846 -303.097978)
			(xy 58.506262 -303.144659) (xy 58.483391 -303.188236) (xy 58.453826 -303.22758) (xy 58.418333 -303.261672)
			(xy 58.37783 -303.289628) (xy 58.333368 -303.310726) (xy 58.286097 -303.324418) (xy 58.237242 -303.33035)
			(xy 58.188067 -303.328369) (xy 58.139848 -303.318525) (xy 58.093832 -303.301073) (xy 58.051211 -303.276466)
			(xy 58.01309 -303.245341) (xy 57.980455 -303.208504) (xy 57.954152 -303.166908) (xy 57.934861 -303.121632)
			(xy 57.923084 -303.073848) (xy 57.919124 -303.024794) (xy 57.580276 -303.024794) (xy 57.579781 -303.049401)
			(xy 57.571886 -303.097978) (xy 57.556302 -303.144659) (xy 57.533431 -303.188236) (xy 57.503866 -303.22758)
			(xy 57.468373 -303.261672) (xy 57.42787 -303.289628) (xy 57.383408 -303.310726) (xy 57.336137 -303.324418)
			(xy 57.287282 -303.33035) (xy 57.238107 -303.328369) (xy 57.189888 -303.318525) (xy 57.143872 -303.301073)
			(xy 57.101251 -303.276466) (xy 57.06313 -303.245341) (xy 57.030495 -303.208504) (xy 57.004192 -303.166908)
			(xy 56.984901 -303.121632) (xy 56.973124 -303.073848) (xy 56.969164 -303.024794) (xy 56.630062 -303.024794)
			(xy 56.629567 -303.049401) (xy 56.621672 -303.097978) (xy 56.606088 -303.144659) (xy 56.583217 -303.188236)
			(xy 56.553652 -303.22758) (xy 56.518159 -303.261672) (xy 56.477656 -303.289628) (xy 56.433194 -303.310726)
			(xy 56.385923 -303.324418) (xy 56.337068 -303.33035) (xy 56.287893 -303.328369) (xy 56.239674 -303.318525)
			(xy 56.193658 -303.301073) (xy 56.151037 -303.276466) (xy 56.112916 -303.245341) (xy 56.080281 -303.208504)
			(xy 56.053978 -303.166908) (xy 56.034687 -303.121632) (xy 56.02291 -303.073848) (xy 56.01895 -303.024794)
			(xy 55.680102 -303.024794) (xy 55.679607 -303.049401) (xy 55.671712 -303.097978) (xy 55.656128 -303.144659)
			(xy 55.633257 -303.188236) (xy 55.603692 -303.22758) (xy 55.568199 -303.261672) (xy 55.527696 -303.289628)
			(xy 55.483234 -303.310726) (xy 55.435963 -303.324418) (xy 55.387108 -303.33035) (xy 55.337933 -303.328369)
			(xy 55.289714 -303.318525) (xy 55.243698 -303.301073) (xy 55.201077 -303.276466) (xy 55.162956 -303.245341)
			(xy 55.130321 -303.208504) (xy 55.104018 -303.166908) (xy 55.084727 -303.121632) (xy 55.07295 -303.073848)
			(xy 55.06899 -303.024794) (xy 54.730142 -303.024794) (xy 54.729647 -303.049401) (xy 54.721752 -303.097978)
			(xy 54.706168 -303.144659) (xy 54.683297 -303.188236) (xy 54.653732 -303.22758) (xy 54.618239 -303.261672)
			(xy 54.577736 -303.289628) (xy 54.533274 -303.310726) (xy 54.486003 -303.324418) (xy 54.437148 -303.33035)
			(xy 54.387973 -303.328369) (xy 54.339754 -303.318525) (xy 54.293738 -303.301073) (xy 54.251117 -303.276466)
			(xy 54.212996 -303.245341) (xy 54.180361 -303.208504) (xy 54.154058 -303.166908) (xy 54.134767 -303.121632)
			(xy 54.12299 -303.073848) (xy 54.11903 -303.024794) (xy 53.780182 -303.024794) (xy 53.779687 -303.049401)
			(xy 53.771792 -303.097978) (xy 53.756208 -303.144659) (xy 53.733337 -303.188236) (xy 53.703772 -303.22758)
			(xy 53.668279 -303.261672) (xy 53.627776 -303.289628) (xy 53.583314 -303.310726) (xy 53.536043 -303.324418)
			(xy 53.487188 -303.33035) (xy 53.438013 -303.328369) (xy 53.389794 -303.318525) (xy 53.343778 -303.301073)
			(xy 53.301157 -303.276466) (xy 53.263036 -303.245341) (xy 53.230401 -303.208504) (xy 53.204098 -303.166908)
			(xy 53.184807 -303.121632) (xy 53.17303 -303.073848) (xy 53.16907 -303.024794) (xy 52.830222 -303.024794)
			(xy 52.829727 -303.049401) (xy 52.821832 -303.097978) (xy 52.806248 -303.144659) (xy 52.783377 -303.188236)
			(xy 52.753812 -303.22758) (xy 52.718319 -303.261672) (xy 52.677816 -303.289628) (xy 52.633354 -303.310726)
			(xy 52.586083 -303.324418) (xy 52.537228 -303.33035) (xy 52.488053 -303.328369) (xy 52.439834 -303.318525)
			(xy 52.393818 -303.301073) (xy 52.351197 -303.276466) (xy 52.313076 -303.245341) (xy 52.280441 -303.208504)
			(xy 52.254138 -303.166908) (xy 52.234847 -303.121632) (xy 52.22307 -303.073848) (xy 52.21911 -303.024794)
			(xy 51.880262 -303.024794) (xy 51.879767 -303.049401) (xy 51.871872 -303.097978) (xy 51.856288 -303.144659)
			(xy 51.833417 -303.188236) (xy 51.803852 -303.22758) (xy 51.768359 -303.261672) (xy 51.727856 -303.289628)
			(xy 51.683394 -303.310726) (xy 51.636123 -303.324418) (xy 51.587268 -303.33035) (xy 51.538093 -303.328369)
			(xy 51.489874 -303.318525) (xy 51.443858 -303.301073) (xy 51.401237 -303.276466) (xy 51.363116 -303.245341)
			(xy 51.330481 -303.208504) (xy 51.304178 -303.166908) (xy 51.284887 -303.121632) (xy 51.27311 -303.073848)
			(xy 51.26915 -303.024794) (xy 50.930302 -303.024794) (xy 50.929807 -303.049401) (xy 50.921912 -303.097978)
			(xy 50.906328 -303.144659) (xy 50.883457 -303.188236) (xy 50.853892 -303.22758) (xy 50.818399 -303.261672)
			(xy 50.777896 -303.289628) (xy 50.733434 -303.310726) (xy 50.686163 -303.324418) (xy 50.637308 -303.33035)
			(xy 50.588133 -303.328369) (xy 50.539914 -303.318525) (xy 50.493898 -303.301073) (xy 50.451277 -303.276466)
			(xy 50.413156 -303.245341) (xy 50.380521 -303.208504) (xy 50.354218 -303.166908) (xy 50.334927 -303.121632)
			(xy 50.32315 -303.073848) (xy 50.31919 -303.024794) (xy 49.980088 -303.024794) (xy 49.979593 -303.049401)
			(xy 49.971698 -303.097978) (xy 49.956114 -303.144659) (xy 49.933243 -303.188236) (xy 49.903678 -303.22758)
			(xy 49.868185 -303.261672) (xy 49.827682 -303.289628) (xy 49.78322 -303.310726) (xy 49.735949 -303.324418)
			(xy 49.687094 -303.33035) (xy 49.637919 -303.328369) (xy 49.5897 -303.318525) (xy 49.543684 -303.301073)
			(xy 49.501063 -303.276466) (xy 49.462942 -303.245341) (xy 49.430307 -303.208504) (xy 49.404004 -303.166908)
			(xy 49.384713 -303.121632) (xy 49.372936 -303.073848) (xy 49.368976 -303.024794) (xy 49.030128 -303.024794)
			(xy 49.029633 -303.049401) (xy 49.021738 -303.097978) (xy 49.006154 -303.144659) (xy 48.983283 -303.188236)
			(xy 48.953718 -303.22758) (xy 48.918225 -303.261672) (xy 48.877722 -303.289628) (xy 48.83326 -303.310726)
			(xy 48.785989 -303.324418) (xy 48.737134 -303.33035) (xy 48.687959 -303.328369) (xy 48.63974 -303.318525)
			(xy 48.593724 -303.301073) (xy 48.551103 -303.276466) (xy 48.512982 -303.245341) (xy 48.480347 -303.208504)
			(xy 48.454044 -303.166908) (xy 48.434753 -303.121632) (xy 48.422976 -303.073848) (xy 48.419016 -303.024794)
			(xy 48.080168 -303.024794) (xy 48.079914 -303.035208) (xy 48.079914 -303.041558) (xy 48.07966 -303.04613)
			(xy 48.07966 -303.046892) (xy 48.078438 -303.061293) (xy 48.073607 -303.08979) (xy 48.070008 -303.103788)
			(xy 48.06823 -303.110392) (xy 48.06823 -303.499774) (xy 73.593972 -303.499774) (xy 73.597932 -303.45072)
			(xy 73.609709 -303.402936) (xy 73.629 -303.35766) (xy 73.655303 -303.316064) (xy 73.687938 -303.279227)
			(xy 73.726059 -303.248102) (xy 73.76868 -303.223495) (xy 73.814696 -303.206043) (xy 73.862915 -303.196199)
			(xy 73.91209 -303.194218) (xy 73.960945 -303.20015) (xy 74.008216 -303.213842) (xy 74.052678 -303.23494)
			(xy 74.093181 -303.262896) (xy 74.128674 -303.296988) (xy 74.158239 -303.336332) (xy 74.18111 -303.379909)
			(xy 74.196694 -303.42659) (xy 74.204589 -303.475167) (xy 74.205084 -303.499774) (xy 74.544186 -303.499774)
			(xy 74.548146 -303.45072) (xy 74.559923 -303.402936) (xy 74.579214 -303.35766) (xy 74.605517 -303.316064)
			(xy 74.638152 -303.279227) (xy 74.676273 -303.248102) (xy 74.718894 -303.223495) (xy 74.76491 -303.206043)
			(xy 74.813129 -303.196199) (xy 74.862304 -303.194218) (xy 74.911159 -303.20015) (xy 74.95843 -303.213842)
			(xy 75.002892 -303.23494) (xy 75.043395 -303.262896) (xy 75.078888 -303.296988) (xy 75.108453 -303.336332)
			(xy 75.131324 -303.379909) (xy 75.146908 -303.42659) (xy 75.154803 -303.475167) (xy 75.155298 -303.499774)
			(xy 75.494146 -303.499774) (xy 75.498106 -303.45072) (xy 75.509883 -303.402936) (xy 75.529174 -303.35766)
			(xy 75.555477 -303.316064) (xy 75.588112 -303.279227) (xy 75.626233 -303.248102) (xy 75.668854 -303.223495)
			(xy 75.71487 -303.206043) (xy 75.763089 -303.196199) (xy 75.812264 -303.194218) (xy 75.861119 -303.20015)
			(xy 75.90839 -303.213842) (xy 75.952852 -303.23494) (xy 75.993355 -303.262896) (xy 76.028848 -303.296988)
			(xy 76.058413 -303.336332) (xy 76.081284 -303.379909) (xy 76.096868 -303.42659) (xy 76.104763 -303.475167)
			(xy 76.105258 -303.499774) (xy 76.104763 -303.524381) (xy 76.096868 -303.572958) (xy 76.081284 -303.619639)
			(xy 76.058413 -303.663216) (xy 76.028848 -303.70256) (xy 75.993355 -303.736652) (xy 75.952852 -303.764608)
			(xy 75.90839 -303.785706) (xy 75.861119 -303.799398) (xy 75.812264 -303.80533) (xy 75.763089 -303.803349)
			(xy 75.71487 -303.793505) (xy 75.668854 -303.776053) (xy 75.626233 -303.751446) (xy 75.588112 -303.720321)
			(xy 75.555477 -303.683484) (xy 75.529174 -303.641888) (xy 75.509883 -303.596612) (xy 75.498106 -303.548828)
			(xy 75.494146 -303.499774) (xy 75.155298 -303.499774) (xy 75.154803 -303.524381) (xy 75.146908 -303.572958)
			(xy 75.131324 -303.619639) (xy 75.108453 -303.663216) (xy 75.078888 -303.70256) (xy 75.043395 -303.736652)
			(xy 75.002892 -303.764608) (xy 74.95843 -303.785706) (xy 74.911159 -303.799398) (xy 74.862304 -303.80533)
			(xy 74.813129 -303.803349) (xy 74.76491 -303.793505) (xy 74.718894 -303.776053) (xy 74.676273 -303.751446)
			(xy 74.638152 -303.720321) (xy 74.605517 -303.683484) (xy 74.579214 -303.641888) (xy 74.559923 -303.596612)
			(xy 74.548146 -303.548828) (xy 74.544186 -303.499774) (xy 74.205084 -303.499774) (xy 74.204589 -303.524381)
			(xy 74.196694 -303.572958) (xy 74.18111 -303.619639) (xy 74.158239 -303.663216) (xy 74.128674 -303.70256)
			(xy 74.093181 -303.736652) (xy 74.052678 -303.764608) (xy 74.008216 -303.785706) (xy 73.960945 -303.799398)
			(xy 73.91209 -303.80533) (xy 73.862915 -303.803349) (xy 73.814696 -303.793505) (xy 73.76868 -303.776053)
			(xy 73.726059 -303.751446) (xy 73.687938 -303.720321) (xy 73.655303 -303.683484) (xy 73.629 -303.641888)
			(xy 73.609709 -303.596612) (xy 73.597932 -303.548828) (xy 73.593972 -303.499774) (xy 48.06823 -303.499774)
			(xy 48.06823 -303.883314) (xy 48.070008 -303.896522) (xy 48.07077 -303.89957) (xy 48.075168 -303.918054)
			(xy 48.079879 -303.955756) (xy 48.080168 -303.974754) (xy 48.419016 -303.974754) (xy 48.422976 -303.9257)
			(xy 48.434753 -303.877916) (xy 48.454044 -303.83264) (xy 48.480347 -303.791044) (xy 48.512982 -303.754207)
			(xy 48.551103 -303.723082) (xy 48.593724 -303.698475) (xy 48.63974 -303.681023) (xy 48.687959 -303.671179)
			(xy 48.737134 -303.669198) (xy 48.785989 -303.67513) (xy 48.83326 -303.688822) (xy 48.877722 -303.70992)
			(xy 48.918225 -303.737876) (xy 48.953718 -303.771968) (xy 48.983283 -303.811312) (xy 49.006154 -303.854889)
			(xy 49.021738 -303.90157) (xy 49.029633 -303.950147) (xy 49.030128 -303.974754) (xy 49.368976 -303.974754)
			(xy 49.372936 -303.9257) (xy 49.384713 -303.877916) (xy 49.404004 -303.83264) (xy 49.430307 -303.791044)
			(xy 49.462942 -303.754207) (xy 49.501063 -303.723082) (xy 49.543684 -303.698475) (xy 49.5897 -303.681023)
			(xy 49.637919 -303.671179) (xy 49.687094 -303.669198) (xy 49.735949 -303.67513) (xy 49.78322 -303.688822)
			(xy 49.827682 -303.70992) (xy 49.868185 -303.737876) (xy 49.903678 -303.771968) (xy 49.933243 -303.811312)
			(xy 49.956114 -303.854889) (xy 49.971698 -303.90157) (xy 49.979593 -303.950147) (xy 49.980088 -303.974754)
			(xy 50.31919 -303.974754) (xy 50.32315 -303.9257) (xy 50.334927 -303.877916) (xy 50.354218 -303.83264)
			(xy 50.380521 -303.791044) (xy 50.413156 -303.754207) (xy 50.451277 -303.723082) (xy 50.493898 -303.698475)
			(xy 50.539914 -303.681023) (xy 50.588133 -303.671179) (xy 50.637308 -303.669198) (xy 50.686163 -303.67513)
			(xy 50.733434 -303.688822) (xy 50.777896 -303.70992) (xy 50.818399 -303.737876) (xy 50.853892 -303.771968)
			(xy 50.883457 -303.811312) (xy 50.906328 -303.854889) (xy 50.921912 -303.90157) (xy 50.929807 -303.950147)
			(xy 50.930302 -303.974754) (xy 51.26915 -303.974754) (xy 51.27311 -303.9257) (xy 51.284887 -303.877916)
			(xy 51.304178 -303.83264) (xy 51.330481 -303.791044) (xy 51.363116 -303.754207) (xy 51.401237 -303.723082)
			(xy 51.443858 -303.698475) (xy 51.489874 -303.681023) (xy 51.538093 -303.671179) (xy 51.587268 -303.669198)
			(xy 51.636123 -303.67513) (xy 51.683394 -303.688822) (xy 51.727856 -303.70992) (xy 51.768359 -303.737876)
			(xy 51.803852 -303.771968) (xy 51.833417 -303.811312) (xy 51.856288 -303.854889) (xy 51.871872 -303.90157)
			(xy 51.879767 -303.950147) (xy 51.880262 -303.974754) (xy 52.21911 -303.974754) (xy 52.22307 -303.9257)
			(xy 52.234847 -303.877916) (xy 52.254138 -303.83264) (xy 52.280441 -303.791044) (xy 52.313076 -303.754207)
			(xy 52.351197 -303.723082) (xy 52.393818 -303.698475) (xy 52.439834 -303.681023) (xy 52.488053 -303.671179)
			(xy 52.537228 -303.669198) (xy 52.586083 -303.67513) (xy 52.633354 -303.688822) (xy 52.677816 -303.70992)
			(xy 52.718319 -303.737876) (xy 52.753812 -303.771968) (xy 52.783377 -303.811312) (xy 52.806248 -303.854889)
			(xy 52.821832 -303.90157) (xy 52.829727 -303.950147) (xy 52.830222 -303.974754) (xy 53.16907 -303.974754)
			(xy 53.17303 -303.9257) (xy 53.184807 -303.877916) (xy 53.204098 -303.83264) (xy 53.230401 -303.791044)
			(xy 53.263036 -303.754207) (xy 53.301157 -303.723082) (xy 53.343778 -303.698475) (xy 53.389794 -303.681023)
			(xy 53.438013 -303.671179) (xy 53.487188 -303.669198) (xy 53.536043 -303.67513) (xy 53.583314 -303.688822)
			(xy 53.627776 -303.70992) (xy 53.668279 -303.737876) (xy 53.703772 -303.771968) (xy 53.733337 -303.811312)
			(xy 53.756208 -303.854889) (xy 53.771792 -303.90157) (xy 53.779687 -303.950147) (xy 53.780182 -303.974754)
			(xy 54.11903 -303.974754) (xy 54.12299 -303.9257) (xy 54.134767 -303.877916) (xy 54.154058 -303.83264)
			(xy 54.180361 -303.791044) (xy 54.212996 -303.754207) (xy 54.251117 -303.723082) (xy 54.293738 -303.698475)
			(xy 54.339754 -303.681023) (xy 54.387973 -303.671179) (xy 54.437148 -303.669198) (xy 54.486003 -303.67513)
			(xy 54.533274 -303.688822) (xy 54.577736 -303.70992) (xy 54.618239 -303.737876) (xy 54.653732 -303.771968)
			(xy 54.683297 -303.811312) (xy 54.706168 -303.854889) (xy 54.721752 -303.90157) (xy 54.729647 -303.950147)
			(xy 54.730142 -303.974754) (xy 55.06899 -303.974754) (xy 55.07295 -303.9257) (xy 55.084727 -303.877916)
			(xy 55.104018 -303.83264) (xy 55.130321 -303.791044) (xy 55.162956 -303.754207) (xy 55.201077 -303.723082)
			(xy 55.243698 -303.698475) (xy 55.289714 -303.681023) (xy 55.337933 -303.671179) (xy 55.387108 -303.669198)
			(xy 55.435963 -303.67513) (xy 55.483234 -303.688822) (xy 55.527696 -303.70992) (xy 55.568199 -303.737876)
			(xy 55.603692 -303.771968) (xy 55.633257 -303.811312) (xy 55.656128 -303.854889) (xy 55.671712 -303.90157)
			(xy 55.679607 -303.950147) (xy 55.680102 -303.974754) (xy 56.01895 -303.974754) (xy 56.02291 -303.9257)
			(xy 56.034687 -303.877916) (xy 56.053978 -303.83264) (xy 56.080281 -303.791044) (xy 56.112916 -303.754207)
			(xy 56.151037 -303.723082) (xy 56.193658 -303.698475) (xy 56.239674 -303.681023) (xy 56.287893 -303.671179)
			(xy 56.337068 -303.669198) (xy 56.385923 -303.67513) (xy 56.433194 -303.688822) (xy 56.477656 -303.70992)
			(xy 56.518159 -303.737876) (xy 56.553652 -303.771968) (xy 56.583217 -303.811312) (xy 56.606088 -303.854889)
			(xy 56.621672 -303.90157) (xy 56.629567 -303.950147) (xy 56.630062 -303.974754) (xy 56.969164 -303.974754)
			(xy 56.973124 -303.9257) (xy 56.984901 -303.877916) (xy 57.004192 -303.83264) (xy 57.030495 -303.791044)
			(xy 57.06313 -303.754207) (xy 57.101251 -303.723082) (xy 57.143872 -303.698475) (xy 57.189888 -303.681023)
			(xy 57.238107 -303.671179) (xy 57.287282 -303.669198) (xy 57.336137 -303.67513) (xy 57.383408 -303.688822)
			(xy 57.42787 -303.70992) (xy 57.468373 -303.737876) (xy 57.503866 -303.771968) (xy 57.533431 -303.811312)
			(xy 57.556302 -303.854889) (xy 57.571886 -303.90157) (xy 57.579781 -303.950147) (xy 57.580276 -303.974754)
			(xy 57.919124 -303.974754) (xy 57.923084 -303.9257) (xy 57.934861 -303.877916) (xy 57.954152 -303.83264)
			(xy 57.980455 -303.791044) (xy 58.01309 -303.754207) (xy 58.051211 -303.723082) (xy 58.093832 -303.698475)
			(xy 58.139848 -303.681023) (xy 58.188067 -303.671179) (xy 58.237242 -303.669198) (xy 58.286097 -303.67513)
			(xy 58.333368 -303.688822) (xy 58.37783 -303.70992) (xy 58.418333 -303.737876) (xy 58.453826 -303.771968)
			(xy 58.483391 -303.811312) (xy 58.506262 -303.854889) (xy 58.521846 -303.90157) (xy 58.529741 -303.950147)
			(xy 58.530236 -303.974754) (xy 59.819044 -303.974754) (xy 59.823004 -303.9257) (xy 59.834781 -303.877916)
			(xy 59.854072 -303.83264) (xy 59.880375 -303.791044) (xy 59.91301 -303.754207) (xy 59.951131 -303.723082)
			(xy 59.993752 -303.698475) (xy 60.039768 -303.681023) (xy 60.087987 -303.671179) (xy 60.137162 -303.669198)
			(xy 60.186017 -303.67513) (xy 60.233288 -303.688822) (xy 60.27775 -303.70992) (xy 60.318253 -303.737876)
			(xy 60.353746 -303.771968) (xy 60.383311 -303.811312) (xy 60.406182 -303.854889) (xy 60.421766 -303.90157)
			(xy 60.429661 -303.950147) (xy 60.430156 -303.974754) (xy 60.769004 -303.974754) (xy 60.772964 -303.9257)
			(xy 60.784741 -303.877916) (xy 60.804032 -303.83264) (xy 60.830335 -303.791044) (xy 60.86297 -303.754207)
			(xy 60.901091 -303.723082) (xy 60.943712 -303.698475) (xy 60.989728 -303.681023) (xy 61.037947 -303.671179)
			(xy 61.087122 -303.669198) (xy 61.135977 -303.67513) (xy 61.183248 -303.688822) (xy 61.22771 -303.70992)
			(xy 61.268213 -303.737876) (xy 61.303706 -303.771968) (xy 61.333271 -303.811312) (xy 61.356142 -303.854889)
			(xy 61.371726 -303.90157) (xy 61.379621 -303.950147) (xy 61.380116 -303.974754) (xy 61.718964 -303.974754)
			(xy 61.722924 -303.9257) (xy 61.734701 -303.877916) (xy 61.753992 -303.83264) (xy 61.780295 -303.791044)
			(xy 61.81293 -303.754207) (xy 61.851051 -303.723082) (xy 61.893672 -303.698475) (xy 61.939688 -303.681023)
			(xy 61.987907 -303.671179) (xy 62.037082 -303.669198) (xy 62.085937 -303.67513) (xy 62.133208 -303.688822)
			(xy 62.17767 -303.70992) (xy 62.218173 -303.737876) (xy 62.253666 -303.771968) (xy 62.283231 -303.811312)
			(xy 62.306102 -303.854889) (xy 62.321686 -303.90157) (xy 62.329581 -303.950147) (xy 62.330076 -303.974754)
			(xy 62.669178 -303.974754) (xy 62.673138 -303.9257) (xy 62.684915 -303.877916) (xy 62.704206 -303.83264)
			(xy 62.730509 -303.791044) (xy 62.763144 -303.754207) (xy 62.801265 -303.723082) (xy 62.843886 -303.698475)
			(xy 62.889902 -303.681023) (xy 62.938121 -303.671179) (xy 62.987296 -303.669198) (xy 63.036151 -303.67513)
			(xy 63.083422 -303.688822) (xy 63.127884 -303.70992) (xy 63.168387 -303.737876) (xy 63.20388 -303.771968)
			(xy 63.233445 -303.811312) (xy 63.256316 -303.854889) (xy 63.2719 -303.90157) (xy 63.279795 -303.950147)
			(xy 63.28029 -303.974754) (xy 63.619138 -303.974754) (xy 63.623098 -303.9257) (xy 63.634875 -303.877916)
			(xy 63.654166 -303.83264) (xy 63.680469 -303.791044) (xy 63.713104 -303.754207) (xy 63.751225 -303.723082)
			(xy 63.793846 -303.698475) (xy 63.839862 -303.681023) (xy 63.888081 -303.671179) (xy 63.937256 -303.669198)
			(xy 63.986111 -303.67513) (xy 64.033382 -303.688822) (xy 64.077844 -303.70992) (xy 64.118347 -303.737876)
			(xy 64.15384 -303.771968) (xy 64.183405 -303.811312) (xy 64.206276 -303.854889) (xy 64.22186 -303.90157)
			(xy 64.229755 -303.950147) (xy 64.23025 -303.974754) (xy 64.569098 -303.974754) (xy 64.573058 -303.9257)
			(xy 64.584835 -303.877916) (xy 64.604126 -303.83264) (xy 64.630429 -303.791044) (xy 64.663064 -303.754207)
			(xy 64.701185 -303.723082) (xy 64.743806 -303.698475) (xy 64.789822 -303.681023) (xy 64.838041 -303.671179)
			(xy 64.887216 -303.669198) (xy 64.936071 -303.67513) (xy 64.983342 -303.688822) (xy 65.027804 -303.70992)
			(xy 65.068307 -303.737876) (xy 65.1038 -303.771968) (xy 65.133365 -303.811312) (xy 65.156236 -303.854889)
			(xy 65.17182 -303.90157) (xy 65.179715 -303.950147) (xy 65.18021 -303.974754) (xy 65.519058 -303.974754)
			(xy 65.523018 -303.9257) (xy 65.534795 -303.877916) (xy 65.554086 -303.83264) (xy 65.580389 -303.791044)
			(xy 65.613024 -303.754207) (xy 65.651145 -303.723082) (xy 65.693766 -303.698475) (xy 65.739782 -303.681023)
			(xy 65.788001 -303.671179) (xy 65.837176 -303.669198) (xy 65.886031 -303.67513) (xy 65.933302 -303.688822)
			(xy 65.977764 -303.70992) (xy 66.018267 -303.737876) (xy 66.05376 -303.771968) (xy 66.083325 -303.811312)
			(xy 66.106196 -303.854889) (xy 66.12178 -303.90157) (xy 66.129675 -303.950147) (xy 66.13017 -303.974754)
			(xy 66.469018 -303.974754) (xy 66.472978 -303.9257) (xy 66.484755 -303.877916) (xy 66.504046 -303.83264)
			(xy 66.530349 -303.791044) (xy 66.562984 -303.754207) (xy 66.601105 -303.723082) (xy 66.643726 -303.698475)
			(xy 66.689742 -303.681023) (xy 66.737961 -303.671179) (xy 66.787136 -303.669198) (xy 66.835991 -303.67513)
			(xy 66.883262 -303.688822) (xy 66.927724 -303.70992) (xy 66.968227 -303.737876) (xy 67.00372 -303.771968)
			(xy 67.033285 -303.811312) (xy 67.056156 -303.854889) (xy 67.07174 -303.90157) (xy 67.079635 -303.950147)
			(xy 67.08013 -303.974754) (xy 67.418978 -303.974754) (xy 67.422938 -303.9257) (xy 67.434715 -303.877916)
			(xy 67.454006 -303.83264) (xy 67.480309 -303.791044) (xy 67.512944 -303.754207) (xy 67.551065 -303.723082)
			(xy 67.593686 -303.698475) (xy 67.639702 -303.681023) (xy 67.687921 -303.671179) (xy 67.737096 -303.669198)
			(xy 67.785951 -303.67513) (xy 67.833222 -303.688822) (xy 67.877684 -303.70992) (xy 67.918187 -303.737876)
			(xy 67.95368 -303.771968) (xy 67.983245 -303.811312) (xy 68.006116 -303.854889) (xy 68.0217 -303.90157)
			(xy 68.029595 -303.950147) (xy 68.029993 -303.969928) (xy 68.374018 -303.969928) (xy 68.377978 -303.920874)
			(xy 68.389755 -303.87309) (xy 68.409046 -303.827814) (xy 68.435349 -303.786218) (xy 68.467984 -303.749381)
			(xy 68.506105 -303.718256) (xy 68.548726 -303.693649) (xy 68.594742 -303.676197) (xy 68.642961 -303.666353)
			(xy 68.692136 -303.664372) (xy 68.740991 -303.670304) (xy 68.788262 -303.683996) (xy 68.832724 -303.705094)
			(xy 68.873227 -303.73305) (xy 68.90872 -303.767142) (xy 68.938285 -303.806486) (xy 68.961156 -303.850063)
			(xy 68.97674 -303.896744) (xy 68.984635 -303.945321) (xy 68.98513 -303.969928) (xy 68.985033 -303.974754)
			(xy 69.319152 -303.974754) (xy 69.323112 -303.9257) (xy 69.334889 -303.877916) (xy 69.35418 -303.83264)
			(xy 69.380483 -303.791044) (xy 69.413118 -303.754207) (xy 69.451239 -303.723082) (xy 69.49386 -303.698475)
			(xy 69.539876 -303.681023) (xy 69.588095 -303.671179) (xy 69.63727 -303.669198) (xy 69.686125 -303.67513)
			(xy 69.733396 -303.688822) (xy 69.777858 -303.70992) (xy 69.818361 -303.737876) (xy 69.853854 -303.771968)
			(xy 69.883419 -303.811312) (xy 69.90629 -303.854889) (xy 69.921874 -303.90157) (xy 69.929769 -303.950147)
			(xy 69.930264 -303.974754) (xy 70.269112 -303.974754) (xy 70.273072 -303.9257) (xy 70.284849 -303.877916)
			(xy 70.30414 -303.83264) (xy 70.330443 -303.791044) (xy 70.363078 -303.754207) (xy 70.401199 -303.723082)
			(xy 70.44382 -303.698475) (xy 70.489836 -303.681023) (xy 70.538055 -303.671179) (xy 70.58723 -303.669198)
			(xy 70.636085 -303.67513) (xy 70.683356 -303.688822) (xy 70.727818 -303.70992) (xy 70.768321 -303.737876)
			(xy 70.803814 -303.771968) (xy 70.833379 -303.811312) (xy 70.85625 -303.854889) (xy 70.871834 -303.90157)
			(xy 70.879729 -303.950147) (xy 70.880224 -303.974754) (xy 71.219072 -303.974754) (xy 71.223032 -303.9257)
			(xy 71.234809 -303.877916) (xy 71.2541 -303.83264) (xy 71.280403 -303.791044) (xy 71.313038 -303.754207)
			(xy 71.351159 -303.723082) (xy 71.39378 -303.698475) (xy 71.439796 -303.681023) (xy 71.488015 -303.671179)
			(xy 71.53719 -303.669198) (xy 71.586045 -303.67513) (xy 71.633316 -303.688822) (xy 71.677778 -303.70992)
			(xy 71.718281 -303.737876) (xy 71.753774 -303.771968) (xy 71.783339 -303.811312) (xy 71.80621 -303.854889)
			(xy 71.821794 -303.90157) (xy 71.829689 -303.950147) (xy 71.830184 -303.974754) (xy 72.169032 -303.974754)
			(xy 72.172992 -303.9257) (xy 72.184769 -303.877916) (xy 72.20406 -303.83264) (xy 72.230363 -303.791044)
			(xy 72.262998 -303.754207) (xy 72.301119 -303.723082) (xy 72.34374 -303.698475) (xy 72.389756 -303.681023)
			(xy 72.437975 -303.671179) (xy 72.48715 -303.669198) (xy 72.536005 -303.67513) (xy 72.583276 -303.688822)
			(xy 72.627738 -303.70992) (xy 72.668241 -303.737876) (xy 72.703734 -303.771968) (xy 72.733299 -303.811312)
			(xy 72.75617 -303.854889) (xy 72.771754 -303.90157) (xy 72.779649 -303.950147) (xy 72.780144 -303.974754)
			(xy 72.779649 -303.999361) (xy 72.771754 -304.047938) (xy 72.75617 -304.094619) (xy 72.733299 -304.138196)
			(xy 72.703734 -304.17754) (xy 72.668241 -304.211632) (xy 72.627738 -304.239588) (xy 72.583276 -304.260686)
			(xy 72.536005 -304.274378) (xy 72.48715 -304.28031) (xy 72.437975 -304.278329) (xy 72.389756 -304.268485)
			(xy 72.34374 -304.251033) (xy 72.301119 -304.226426) (xy 72.262998 -304.195301) (xy 72.230363 -304.158464)
			(xy 72.20406 -304.116868) (xy 72.184769 -304.071592) (xy 72.172992 -304.023808) (xy 72.169032 -303.974754)
			(xy 71.830184 -303.974754) (xy 71.829689 -303.999361) (xy 71.821794 -304.047938) (xy 71.80621 -304.094619)
			(xy 71.783339 -304.138196) (xy 71.753774 -304.17754) (xy 71.718281 -304.211632) (xy 71.677778 -304.239588)
			(xy 71.633316 -304.260686) (xy 71.586045 -304.274378) (xy 71.53719 -304.28031) (xy 71.488015 -304.278329)
			(xy 71.439796 -304.268485) (xy 71.39378 -304.251033) (xy 71.351159 -304.226426) (xy 71.313038 -304.195301)
			(xy 71.280403 -304.158464) (xy 71.2541 -304.116868) (xy 71.234809 -304.071592) (xy 71.223032 -304.023808)
			(xy 71.219072 -303.974754) (xy 70.880224 -303.974754) (xy 70.879729 -303.999361) (xy 70.871834 -304.047938)
			(xy 70.85625 -304.094619) (xy 70.833379 -304.138196) (xy 70.803814 -304.17754) (xy 70.768321 -304.211632)
			(xy 70.727818 -304.239588) (xy 70.683356 -304.260686) (xy 70.636085 -304.274378) (xy 70.58723 -304.28031)
			(xy 70.538055 -304.278329) (xy 70.489836 -304.268485) (xy 70.44382 -304.251033) (xy 70.401199 -304.226426)
			(xy 70.363078 -304.195301) (xy 70.330443 -304.158464) (xy 70.30414 -304.116868) (xy 70.284849 -304.071592)
			(xy 70.273072 -304.023808) (xy 70.269112 -303.974754) (xy 69.930264 -303.974754) (xy 69.929769 -303.999361)
			(xy 69.921874 -304.047938) (xy 69.90629 -304.094619) (xy 69.883419 -304.138196) (xy 69.853854 -304.17754)
			(xy 69.818361 -304.211632) (xy 69.777858 -304.239588) (xy 69.733396 -304.260686) (xy 69.686125 -304.274378)
			(xy 69.63727 -304.28031) (xy 69.588095 -304.278329) (xy 69.539876 -304.268485) (xy 69.49386 -304.251033)
			(xy 69.451239 -304.226426) (xy 69.413118 -304.195301) (xy 69.380483 -304.158464) (xy 69.35418 -304.116868)
			(xy 69.334889 -304.071592) (xy 69.323112 -304.023808) (xy 69.319152 -303.974754) (xy 68.985033 -303.974754)
			(xy 68.984635 -303.994535) (xy 68.97674 -304.043112) (xy 68.961156 -304.089793) (xy 68.938285 -304.13337)
			(xy 68.90872 -304.172714) (xy 68.873227 -304.206806) (xy 68.832724 -304.234762) (xy 68.788262 -304.25586)
			(xy 68.740991 -304.269552) (xy 68.692136 -304.275484) (xy 68.642961 -304.273503) (xy 68.594742 -304.263659)
			(xy 68.548726 -304.246207) (xy 68.506105 -304.2216) (xy 68.467984 -304.190475) (xy 68.435349 -304.153638)
			(xy 68.409046 -304.112042) (xy 68.389755 -304.066766) (xy 68.377978 -304.018982) (xy 68.374018 -303.969928)
			(xy 68.029993 -303.969928) (xy 68.03009 -303.974754) (xy 68.029595 -303.999361) (xy 68.0217 -304.047938)
			(xy 68.006116 -304.094619) (xy 67.983245 -304.138196) (xy 67.95368 -304.17754) (xy 67.918187 -304.211632)
			(xy 67.877684 -304.239588) (xy 67.833222 -304.260686) (xy 67.785951 -304.274378) (xy 67.737096 -304.28031)
			(xy 67.687921 -304.278329) (xy 67.639702 -304.268485) (xy 67.593686 -304.251033) (xy 67.551065 -304.226426)
			(xy 67.512944 -304.195301) (xy 67.480309 -304.158464) (xy 67.454006 -304.116868) (xy 67.434715 -304.071592)
			(xy 67.422938 -304.023808) (xy 67.418978 -303.974754) (xy 67.08013 -303.974754) (xy 67.079635 -303.999361)
			(xy 67.07174 -304.047938) (xy 67.056156 -304.094619) (xy 67.033285 -304.138196) (xy 67.00372 -304.17754)
			(xy 66.968227 -304.211632) (xy 66.927724 -304.239588) (xy 66.883262 -304.260686) (xy 66.835991 -304.274378)
			(xy 66.787136 -304.28031) (xy 66.737961 -304.278329) (xy 66.689742 -304.268485) (xy 66.643726 -304.251033)
			(xy 66.601105 -304.226426) (xy 66.562984 -304.195301) (xy 66.530349 -304.158464) (xy 66.504046 -304.116868)
			(xy 66.484755 -304.071592) (xy 66.472978 -304.023808) (xy 66.469018 -303.974754) (xy 66.13017 -303.974754)
			(xy 66.129675 -303.999361) (xy 66.12178 -304.047938) (xy 66.106196 -304.094619) (xy 66.083325 -304.138196)
			(xy 66.05376 -304.17754) (xy 66.018267 -304.211632) (xy 65.977764 -304.239588) (xy 65.933302 -304.260686)
			(xy 65.886031 -304.274378) (xy 65.837176 -304.28031) (xy 65.788001 -304.278329) (xy 65.739782 -304.268485)
			(xy 65.693766 -304.251033) (xy 65.651145 -304.226426) (xy 65.613024 -304.195301) (xy 65.580389 -304.158464)
			(xy 65.554086 -304.116868) (xy 65.534795 -304.071592) (xy 65.523018 -304.023808) (xy 65.519058 -303.974754)
			(xy 65.18021 -303.974754) (xy 65.179715 -303.999361) (xy 65.17182 -304.047938) (xy 65.156236 -304.094619)
			(xy 65.133365 -304.138196) (xy 65.1038 -304.17754) (xy 65.068307 -304.211632) (xy 65.027804 -304.239588)
			(xy 64.983342 -304.260686) (xy 64.936071 -304.274378) (xy 64.887216 -304.28031) (xy 64.838041 -304.278329)
			(xy 64.789822 -304.268485) (xy 64.743806 -304.251033) (xy 64.701185 -304.226426) (xy 64.663064 -304.195301)
			(xy 64.630429 -304.158464) (xy 64.604126 -304.116868) (xy 64.584835 -304.071592) (xy 64.573058 -304.023808)
			(xy 64.569098 -303.974754) (xy 64.23025 -303.974754) (xy 64.229755 -303.999361) (xy 64.22186 -304.047938)
			(xy 64.206276 -304.094619) (xy 64.183405 -304.138196) (xy 64.15384 -304.17754) (xy 64.118347 -304.211632)
			(xy 64.077844 -304.239588) (xy 64.033382 -304.260686) (xy 63.986111 -304.274378) (xy 63.937256 -304.28031)
			(xy 63.888081 -304.278329) (xy 63.839862 -304.268485) (xy 63.793846 -304.251033) (xy 63.751225 -304.226426)
			(xy 63.713104 -304.195301) (xy 63.680469 -304.158464) (xy 63.654166 -304.116868) (xy 63.634875 -304.071592)
			(xy 63.623098 -304.023808) (xy 63.619138 -303.974754) (xy 63.28029 -303.974754) (xy 63.279795 -303.999361)
			(xy 63.2719 -304.047938) (xy 63.256316 -304.094619) (xy 63.233445 -304.138196) (xy 63.20388 -304.17754)
			(xy 63.168387 -304.211632) (xy 63.127884 -304.239588) (xy 63.083422 -304.260686) (xy 63.036151 -304.274378)
			(xy 62.987296 -304.28031) (xy 62.938121 -304.278329) (xy 62.889902 -304.268485) (xy 62.843886 -304.251033)
			(xy 62.801265 -304.226426) (xy 62.763144 -304.195301) (xy 62.730509 -304.158464) (xy 62.704206 -304.116868)
			(xy 62.684915 -304.071592) (xy 62.673138 -304.023808) (xy 62.669178 -303.974754) (xy 62.330076 -303.974754)
			(xy 62.329581 -303.999361) (xy 62.321686 -304.047938) (xy 62.306102 -304.094619) (xy 62.283231 -304.138196)
			(xy 62.253666 -304.17754) (xy 62.218173 -304.211632) (xy 62.17767 -304.239588) (xy 62.133208 -304.260686)
			(xy 62.085937 -304.274378) (xy 62.037082 -304.28031) (xy 61.987907 -304.278329) (xy 61.939688 -304.268485)
			(xy 61.893672 -304.251033) (xy 61.851051 -304.226426) (xy 61.81293 -304.195301) (xy 61.780295 -304.158464)
			(xy 61.753992 -304.116868) (xy 61.734701 -304.071592) (xy 61.722924 -304.023808) (xy 61.718964 -303.974754)
			(xy 61.380116 -303.974754) (xy 61.379621 -303.999361) (xy 61.371726 -304.047938) (xy 61.356142 -304.094619)
			(xy 61.333271 -304.138196) (xy 61.303706 -304.17754) (xy 61.268213 -304.211632) (xy 61.22771 -304.239588)
			(xy 61.183248 -304.260686) (xy 61.135977 -304.274378) (xy 61.087122 -304.28031) (xy 61.037947 -304.278329)
			(xy 60.989728 -304.268485) (xy 60.943712 -304.251033) (xy 60.901091 -304.226426) (xy 60.86297 -304.195301)
			(xy 60.830335 -304.158464) (xy 60.804032 -304.116868) (xy 60.784741 -304.071592) (xy 60.772964 -304.023808)
			(xy 60.769004 -303.974754) (xy 60.430156 -303.974754) (xy 60.429661 -303.999361) (xy 60.421766 -304.047938)
			(xy 60.406182 -304.094619) (xy 60.383311 -304.138196) (xy 60.353746 -304.17754) (xy 60.318253 -304.211632)
			(xy 60.27775 -304.239588) (xy 60.233288 -304.260686) (xy 60.186017 -304.274378) (xy 60.137162 -304.28031)
			(xy 60.087987 -304.278329) (xy 60.039768 -304.268485) (xy 59.993752 -304.251033) (xy 59.951131 -304.226426)
			(xy 59.91301 -304.195301) (xy 59.880375 -304.158464) (xy 59.854072 -304.116868) (xy 59.834781 -304.071592)
			(xy 59.823004 -304.023808) (xy 59.819044 -303.974754) (xy 58.530236 -303.974754) (xy 58.529741 -303.999361)
			(xy 58.521846 -304.047938) (xy 58.506262 -304.094619) (xy 58.483391 -304.138196) (xy 58.453826 -304.17754)
			(xy 58.418333 -304.211632) (xy 58.37783 -304.239588) (xy 58.333368 -304.260686) (xy 58.286097 -304.274378)
			(xy 58.237242 -304.28031) (xy 58.188067 -304.278329) (xy 58.139848 -304.268485) (xy 58.093832 -304.251033)
			(xy 58.051211 -304.226426) (xy 58.01309 -304.195301) (xy 57.980455 -304.158464) (xy 57.954152 -304.116868)
			(xy 57.934861 -304.071592) (xy 57.923084 -304.023808) (xy 57.919124 -303.974754) (xy 57.580276 -303.974754)
			(xy 57.579781 -303.999361) (xy 57.571886 -304.047938) (xy 57.556302 -304.094619) (xy 57.533431 -304.138196)
			(xy 57.503866 -304.17754) (xy 57.468373 -304.211632) (xy 57.42787 -304.239588) (xy 57.383408 -304.260686)
			(xy 57.336137 -304.274378) (xy 57.287282 -304.28031) (xy 57.238107 -304.278329) (xy 57.189888 -304.268485)
			(xy 57.143872 -304.251033) (xy 57.101251 -304.226426) (xy 57.06313 -304.195301) (xy 57.030495 -304.158464)
			(xy 57.004192 -304.116868) (xy 56.984901 -304.071592) (xy 56.973124 -304.023808) (xy 56.969164 -303.974754)
			(xy 56.630062 -303.974754) (xy 56.629567 -303.999361) (xy 56.621672 -304.047938) (xy 56.606088 -304.094619)
			(xy 56.583217 -304.138196) (xy 56.553652 -304.17754) (xy 56.518159 -304.211632) (xy 56.477656 -304.239588)
			(xy 56.433194 -304.260686) (xy 56.385923 -304.274378) (xy 56.337068 -304.28031) (xy 56.287893 -304.278329)
			(xy 56.239674 -304.268485) (xy 56.193658 -304.251033) (xy 56.151037 -304.226426) (xy 56.112916 -304.195301)
			(xy 56.080281 -304.158464) (xy 56.053978 -304.116868) (xy 56.034687 -304.071592) (xy 56.02291 -304.023808)
			(xy 56.01895 -303.974754) (xy 55.680102 -303.974754) (xy 55.679607 -303.999361) (xy 55.671712 -304.047938)
			(xy 55.656128 -304.094619) (xy 55.633257 -304.138196) (xy 55.603692 -304.17754) (xy 55.568199 -304.211632)
			(xy 55.527696 -304.239588) (xy 55.483234 -304.260686) (xy 55.435963 -304.274378) (xy 55.387108 -304.28031)
			(xy 55.337933 -304.278329) (xy 55.289714 -304.268485) (xy 55.243698 -304.251033) (xy 55.201077 -304.226426)
			(xy 55.162956 -304.195301) (xy 55.130321 -304.158464) (xy 55.104018 -304.116868) (xy 55.084727 -304.071592)
			(xy 55.07295 -304.023808) (xy 55.06899 -303.974754) (xy 54.730142 -303.974754) (xy 54.729647 -303.999361)
			(xy 54.721752 -304.047938) (xy 54.706168 -304.094619) (xy 54.683297 -304.138196) (xy 54.653732 -304.17754)
			(xy 54.618239 -304.211632) (xy 54.577736 -304.239588) (xy 54.533274 -304.260686) (xy 54.486003 -304.274378)
			(xy 54.437148 -304.28031) (xy 54.387973 -304.278329) (xy 54.339754 -304.268485) (xy 54.293738 -304.251033)
			(xy 54.251117 -304.226426) (xy 54.212996 -304.195301) (xy 54.180361 -304.158464) (xy 54.154058 -304.116868)
			(xy 54.134767 -304.071592) (xy 54.12299 -304.023808) (xy 54.11903 -303.974754) (xy 53.780182 -303.974754)
			(xy 53.779687 -303.999361) (xy 53.771792 -304.047938) (xy 53.756208 -304.094619) (xy 53.733337 -304.138196)
			(xy 53.703772 -304.17754) (xy 53.668279 -304.211632) (xy 53.627776 -304.239588) (xy 53.583314 -304.260686)
			(xy 53.536043 -304.274378) (xy 53.487188 -304.28031) (xy 53.438013 -304.278329) (xy 53.389794 -304.268485)
			(xy 53.343778 -304.251033) (xy 53.301157 -304.226426) (xy 53.263036 -304.195301) (xy 53.230401 -304.158464)
			(xy 53.204098 -304.116868) (xy 53.184807 -304.071592) (xy 53.17303 -304.023808) (xy 53.16907 -303.974754)
			(xy 52.830222 -303.974754) (xy 52.829727 -303.999361) (xy 52.821832 -304.047938) (xy 52.806248 -304.094619)
			(xy 52.783377 -304.138196) (xy 52.753812 -304.17754) (xy 52.718319 -304.211632) (xy 52.677816 -304.239588)
			(xy 52.633354 -304.260686) (xy 52.586083 -304.274378) (xy 52.537228 -304.28031) (xy 52.488053 -304.278329)
			(xy 52.439834 -304.268485) (xy 52.393818 -304.251033) (xy 52.351197 -304.226426) (xy 52.313076 -304.195301)
			(xy 52.280441 -304.158464) (xy 52.254138 -304.116868) (xy 52.234847 -304.071592) (xy 52.22307 -304.023808)
			(xy 52.21911 -303.974754) (xy 51.880262 -303.974754) (xy 51.879767 -303.999361) (xy 51.871872 -304.047938)
			(xy 51.856288 -304.094619) (xy 51.833417 -304.138196) (xy 51.803852 -304.17754) (xy 51.768359 -304.211632)
			(xy 51.727856 -304.239588) (xy 51.683394 -304.260686) (xy 51.636123 -304.274378) (xy 51.587268 -304.28031)
			(xy 51.538093 -304.278329) (xy 51.489874 -304.268485) (xy 51.443858 -304.251033) (xy 51.401237 -304.226426)
			(xy 51.363116 -304.195301) (xy 51.330481 -304.158464) (xy 51.304178 -304.116868) (xy 51.284887 -304.071592)
			(xy 51.27311 -304.023808) (xy 51.26915 -303.974754) (xy 50.930302 -303.974754) (xy 50.929807 -303.999361)
			(xy 50.921912 -304.047938) (xy 50.906328 -304.094619) (xy 50.883457 -304.138196) (xy 50.853892 -304.17754)
			(xy 50.818399 -304.211632) (xy 50.777896 -304.239588) (xy 50.733434 -304.260686) (xy 50.686163 -304.274378)
			(xy 50.637308 -304.28031) (xy 50.588133 -304.278329) (xy 50.539914 -304.268485) (xy 50.493898 -304.251033)
			(xy 50.451277 -304.226426) (xy 50.413156 -304.195301) (xy 50.380521 -304.158464) (xy 50.354218 -304.116868)
			(xy 50.334927 -304.071592) (xy 50.32315 -304.023808) (xy 50.31919 -303.974754) (xy 49.980088 -303.974754)
			(xy 49.979593 -303.999361) (xy 49.971698 -304.047938) (xy 49.956114 -304.094619) (xy 49.933243 -304.138196)
			(xy 49.903678 -304.17754) (xy 49.868185 -304.211632) (xy 49.827682 -304.239588) (xy 49.78322 -304.260686)
			(xy 49.735949 -304.274378) (xy 49.687094 -304.28031) (xy 49.637919 -304.278329) (xy 49.5897 -304.268485)
			(xy 49.543684 -304.251033) (xy 49.501063 -304.226426) (xy 49.462942 -304.195301) (xy 49.430307 -304.158464)
			(xy 49.404004 -304.116868) (xy 49.384713 -304.071592) (xy 49.372936 -304.023808) (xy 49.368976 -303.974754)
			(xy 49.030128 -303.974754) (xy 49.029633 -303.999361) (xy 49.021738 -304.047938) (xy 49.006154 -304.094619)
			(xy 48.983283 -304.138196) (xy 48.953718 -304.17754) (xy 48.918225 -304.211632) (xy 48.877722 -304.239588)
			(xy 48.83326 -304.260686) (xy 48.785989 -304.274378) (xy 48.737134 -304.28031) (xy 48.687959 -304.278329)
			(xy 48.63974 -304.268485) (xy 48.593724 -304.251033) (xy 48.551103 -304.226426) (xy 48.512982 -304.195301)
			(xy 48.480347 -304.158464) (xy 48.454044 -304.116868) (xy 48.434753 -304.071592) (xy 48.422976 -304.023808)
			(xy 48.419016 -303.974754) (xy 48.080168 -303.974754) (xy 48.079914 -303.985168) (xy 48.079914 -303.991518)
			(xy 48.07966 -303.99609) (xy 48.07966 -303.996852) (xy 48.078435 -304.011253) (xy 48.073598 -304.039748)
			(xy 48.070008 -304.053748) (xy 48.06823 -304.060352) (xy 48.06823 -304.449734) (xy 73.593972 -304.449734)
			(xy 73.597932 -304.40068) (xy 73.609709 -304.352896) (xy 73.629 -304.30762) (xy 73.655303 -304.266024)
			(xy 73.687938 -304.229187) (xy 73.726059 -304.198062) (xy 73.76868 -304.173455) (xy 73.814696 -304.156003)
			(xy 73.862915 -304.146159) (xy 73.91209 -304.144178) (xy 73.960945 -304.15011) (xy 74.008216 -304.163802)
			(xy 74.052678 -304.1849) (xy 74.093181 -304.212856) (xy 74.128674 -304.246948) (xy 74.158239 -304.286292)
			(xy 74.18111 -304.329869) (xy 74.196694 -304.37655) (xy 74.204589 -304.425127) (xy 74.205084 -304.449734)
			(xy 74.544186 -304.449734) (xy 74.548146 -304.40068) (xy 74.559923 -304.352896) (xy 74.579214 -304.30762)
			(xy 74.605517 -304.266024) (xy 74.638152 -304.229187) (xy 74.676273 -304.198062) (xy 74.718894 -304.173455)
			(xy 74.76491 -304.156003) (xy 74.813129 -304.146159) (xy 74.862304 -304.144178) (xy 74.911159 -304.15011)
			(xy 74.95843 -304.163802) (xy 75.002892 -304.1849) (xy 75.043395 -304.212856) (xy 75.078888 -304.246948)
			(xy 75.108453 -304.286292) (xy 75.131324 -304.329869) (xy 75.146908 -304.37655) (xy 75.154803 -304.425127)
			(xy 75.155298 -304.449734) (xy 75.494146 -304.449734) (xy 75.498106 -304.40068) (xy 75.509883 -304.352896)
			(xy 75.529174 -304.30762) (xy 75.555477 -304.266024) (xy 75.588112 -304.229187) (xy 75.626233 -304.198062)
			(xy 75.668854 -304.173455) (xy 75.71487 -304.156003) (xy 75.763089 -304.146159) (xy 75.812264 -304.144178)
			(xy 75.861119 -304.15011) (xy 75.90839 -304.163802) (xy 75.952852 -304.1849) (xy 75.993355 -304.212856)
			(xy 76.028848 -304.246948) (xy 76.058413 -304.286292) (xy 76.081284 -304.329869) (xy 76.096868 -304.37655)
			(xy 76.104763 -304.425127) (xy 76.105258 -304.449734) (xy 76.444106 -304.449734) (xy 76.448066 -304.40068)
			(xy 76.459843 -304.352896) (xy 76.479134 -304.30762) (xy 76.505437 -304.266024) (xy 76.538072 -304.229187)
			(xy 76.576193 -304.198062) (xy 76.618814 -304.173455) (xy 76.66483 -304.156003) (xy 76.713049 -304.146159)
			(xy 76.762224 -304.144178) (xy 76.811079 -304.15011) (xy 76.85835 -304.163802) (xy 76.902812 -304.1849)
			(xy 76.943315 -304.212856) (xy 76.978808 -304.246948) (xy 77.008373 -304.286292) (xy 77.031244 -304.329869)
			(xy 77.046828 -304.37655) (xy 77.054723 -304.425127) (xy 77.055218 -304.449734) (xy 77.394066 -304.449734)
			(xy 77.398026 -304.40068) (xy 77.409803 -304.352896) (xy 77.429094 -304.30762) (xy 77.455397 -304.266024)
			(xy 77.488032 -304.229187) (xy 77.526153 -304.198062) (xy 77.568774 -304.173455) (xy 77.61479 -304.156003)
			(xy 77.663009 -304.146159) (xy 77.712184 -304.144178) (xy 77.761039 -304.15011) (xy 77.80831 -304.163802)
			(xy 77.852772 -304.1849) (xy 77.893275 -304.212856) (xy 77.928768 -304.246948) (xy 77.958333 -304.286292)
			(xy 77.981204 -304.329869) (xy 77.996788 -304.37655) (xy 78.004683 -304.425127) (xy 78.00501 -304.441388)
			(xy 78.344116 -304.441388) (xy 78.349488 -304.392043) (xy 78.362772 -304.344218) (xy 78.383618 -304.299172)
			(xy 78.411477 -304.258091) (xy 78.445615 -304.222059) (xy 78.485133 -304.192024) (xy 78.52899 -304.168779)
			(xy 78.576029 -304.152935) (xy 78.625012 -304.144909) (xy 78.64983 -304.144426) (xy 78.664013 -304.144598)
			(xy 78.692253 -304.147273) (xy 78.706218 -304.14976) (xy 78.718664 -304.152046) (xy 78.742286 -304.14468)
			(xy 78.819756 -304.06721) (xy 78.827122 -304.043588) (xy 78.824836 -304.031142) (xy 78.822356 -304.017177)
			(xy 78.819686 -303.988937) (xy 78.819502 -303.974754) (xy 78.820024 -303.949499) (xy 78.828337 -303.899677)
			(xy 78.844738 -303.851903) (xy 78.868779 -303.80748) (xy 78.899803 -303.76762) (xy 78.936965 -303.73341)
			(xy 78.979251 -303.705784) (xy 79.025507 -303.685494) (xy 79.074472 -303.673094) (xy 79.12481 -303.668923)
			(xy 79.175148 -303.673094) (xy 79.224113 -303.685494) (xy 79.270369 -303.705784) (xy 79.312655 -303.73341)
			(xy 79.349817 -303.76762) (xy 79.380841 -303.80748) (xy 79.404882 -303.851903) (xy 79.421283 -303.899677)
			(xy 79.423781 -303.914651) (xy 85.191856 -303.914651) (xy 85.191856 -303.860149) (xy 85.199611 -303.806202)
			(xy 85.214965 -303.753908) (xy 85.237604 -303.704331) (xy 85.267068 -303.658481) (xy 85.302757 -303.617289)
			(xy 85.343944 -303.581596) (xy 85.389791 -303.552126) (xy 85.439365 -303.529481) (xy 85.491657 -303.514121)
			(xy 85.545603 -303.506359) (xy 85.572854 -303.50587) (xy 85.599171 -303.506293) (xy 85.651305 -303.513523)
			(xy 85.70195 -303.527852) (xy 85.750144 -303.549008) (xy 85.794972 -303.57659) (xy 85.835582 -303.610073)
			(xy 85.871203 -303.648821) (xy 85.886544 -303.670208) (xy 85.892386 -303.678844) (xy 85.908896 -303.689512)
			(xy 85.999828 -303.706276) (xy 86.019132 -303.702212) (xy 86.027514 -303.69637) (xy 86.051436 -303.68057)
			(xy 86.103046 -303.655608) (xy 86.15781 -303.63865) (xy 86.214495 -303.63008) (xy 86.24316 -303.629568)
			(xy 86.270413 -303.630077) (xy 86.314606 -303.636426) (xy 93.3229 -303.636426) (xy 93.326971 -303.580804)
			(xy 93.339097 -303.526367) (xy 93.35902 -303.474276) (xy 93.386316 -303.425641) (xy 93.420402 -303.381498)
			(xy 93.460551 -303.342789) (xy 93.505909 -303.310338) (xy 93.555509 -303.284837) (xy 93.608293 -303.26683)
			(xy 93.663136 -303.2567) (xy 93.71887 -303.254663) (xy 93.774307 -303.260763) (xy 93.828264 -303.274869)
			(xy 93.879593 -303.296681) (xy 93.927199 -303.325735) (xy 93.970067 -303.36141) (xy 94.007284 -303.402947)
			(xy 94.038057 -303.44946) (xy 94.061729 -303.499957) (xy 94.077797 -303.553364) (xy 94.085917 -303.60854)
			(xy 94.086426 -303.636426) (xy 94.085917 -303.664312) (xy 94.077797 -303.719488) (xy 94.061729 -303.772895)
			(xy 94.038057 -303.823392) (xy 94.007284 -303.869905) (xy 93.970067 -303.911442) (xy 93.927199 -303.947117)
			(xy 93.879593 -303.976171) (xy 93.828264 -303.997983) (xy 93.774307 -304.012089) (xy 93.71887 -304.018189)
			(xy 93.663136 -304.016152) (xy 93.608293 -304.006022) (xy 93.555509 -303.988015) (xy 93.505909 -303.962514)
			(xy 93.460551 -303.930063) (xy 93.420402 -303.891354) (xy 93.386316 -303.847211) (xy 93.35902 -303.798576)
			(xy 93.339097 -303.746485) (xy 93.326971 -303.692048) (xy 93.3229 -303.636426) (xy 86.314606 -303.636426)
			(xy 86.324365 -303.637828) (xy 86.376664 -303.65318) (xy 86.426246 -303.675819) (xy 86.472102 -303.705284)
			(xy 86.513296 -303.740975) (xy 86.548992 -303.782166) (xy 86.578462 -303.828019) (xy 86.601106 -303.877598)
			(xy 86.616463 -303.929896) (xy 86.624221 -303.983847) (xy 86.624221 -304.038353) (xy 86.616463 -304.092304)
			(xy 86.601106 -304.144602) (xy 86.578462 -304.194181) (xy 86.548992 -304.240034) (xy 86.513296 -304.281225)
			(xy 86.472102 -304.316916) (xy 86.426246 -304.346381) (xy 86.376664 -304.36902) (xy 86.324365 -304.384372)
			(xy 86.270413 -304.392123) (xy 86.24316 -304.392584) (xy 86.216845 -304.392128) (xy 86.164713 -304.384901)
			(xy 86.114069 -304.370575) (xy 86.065876 -304.349424) (xy 86.021048 -304.321848) (xy 85.980437 -304.288372)
			(xy 85.944813 -304.24963) (xy 85.92947 -304.228246) (xy 85.923628 -304.21961) (xy 85.907118 -304.208942)
			(xy 85.816186 -304.192178) (xy 85.796882 -304.196242) (xy 85.7885 -304.202084) (xy 85.764571 -304.217872)
			(xy 85.712964 -304.242839) (xy 85.658202 -304.2598) (xy 85.601518 -304.268373) (xy 85.572854 -304.268886)
			(xy 85.545603 -304.268441) (xy 85.491657 -304.260679) (xy 85.439365 -304.245319) (xy 85.389791 -304.222674)
			(xy 85.343944 -304.193204) (xy 85.302757 -304.157511) (xy 85.267068 -304.116319) (xy 85.237604 -304.070469)
			(xy 85.214965 -304.020892) (xy 85.199611 -303.968598) (xy 85.191856 -303.914651) (xy 79.423781 -303.914651)
			(xy 79.429596 -303.949499) (xy 79.430118 -303.974754) (xy 79.429935 -303.988937) (xy 79.427267 -304.017177)
			(xy 79.424784 -304.031142) (xy 79.422498 -304.043588) (xy 79.429864 -304.06721) (xy 79.507334 -304.14468)
			(xy 79.530956 -304.152046) (xy 79.543402 -304.14976) (xy 79.557369 -304.147288) (xy 79.585608 -304.144613)
			(xy 79.59979 -304.144426) (xy 79.624611 -304.144867) (xy 79.6736 -304.152897) (xy 79.720645 -304.168746)
			(xy 79.764505 -304.191997) (xy 79.804027 -304.222038) (xy 79.838167 -304.258076) (xy 79.866028 -304.299163)
			(xy 79.886875 -304.344217) (xy 79.900158 -304.392049) (xy 79.905528 -304.4414) (xy 79.905077 -304.449734)
			(xy 80.243946 -304.449734) (xy 80.247906 -304.40068) (xy 80.259683 -304.352896) (xy 80.278974 -304.30762)
			(xy 80.305277 -304.266024) (xy 80.337912 -304.229187) (xy 80.376033 -304.198062) (xy 80.418654 -304.173455)
			(xy 80.46467 -304.156003) (xy 80.512889 -304.146159) (xy 80.562064 -304.144178) (xy 80.610919 -304.15011)
			(xy 80.65819 -304.163802) (xy 80.702652 -304.1849) (xy 80.743155 -304.212856) (xy 80.778648 -304.246948)
			(xy 80.808213 -304.286292) (xy 80.831084 -304.329869) (xy 80.846668 -304.37655) (xy 80.854563 -304.425127)
			(xy 80.855058 -304.449734) (xy 81.19416 -304.449734) (xy 81.19812 -304.40068) (xy 81.209897 -304.352896)
			(xy 81.229188 -304.30762) (xy 81.255491 -304.266024) (xy 81.288126 -304.229187) (xy 81.326247 -304.198062)
			(xy 81.368868 -304.173455) (xy 81.414884 -304.156003) (xy 81.463103 -304.146159) (xy 81.512278 -304.144178)
			(xy 81.561133 -304.15011) (xy 81.608404 -304.163802) (xy 81.652866 -304.1849) (xy 81.693369 -304.212856)
			(xy 81.728862 -304.246948) (xy 81.758427 -304.286292) (xy 81.781298 -304.329869) (xy 81.796882 -304.37655)
			(xy 81.804777 -304.425127) (xy 81.805272 -304.449734) (xy 82.14412 -304.449734) (xy 82.14808 -304.40068)
			(xy 82.159857 -304.352896) (xy 82.179148 -304.30762) (xy 82.205451 -304.266024) (xy 82.238086 -304.229187)
			(xy 82.276207 -304.198062) (xy 82.318828 -304.173455) (xy 82.364844 -304.156003) (xy 82.413063 -304.146159)
			(xy 82.462238 -304.144178) (xy 82.511093 -304.15011) (xy 82.558364 -304.163802) (xy 82.602826 -304.1849)
			(xy 82.643329 -304.212856) (xy 82.678822 -304.246948) (xy 82.708387 -304.286292) (xy 82.731258 -304.329869)
			(xy 82.746842 -304.37655) (xy 82.754737 -304.425127) (xy 82.755232 -304.449734) (xy 83.094334 -304.449734)
			(xy 83.098294 -304.40068) (xy 83.110071 -304.352896) (xy 83.129362 -304.30762) (xy 83.155665 -304.266024)
			(xy 83.1883 -304.229187) (xy 83.226421 -304.198062) (xy 83.269042 -304.173455) (xy 83.315058 -304.156003)
			(xy 83.363277 -304.146159) (xy 83.412452 -304.144178) (xy 83.461307 -304.15011) (xy 83.508578 -304.163802)
			(xy 83.55304 -304.1849) (xy 83.593543 -304.212856) (xy 83.629036 -304.246948) (xy 83.658601 -304.286292)
			(xy 83.681472 -304.329869) (xy 83.697056 -304.37655) (xy 83.704951 -304.425127) (xy 83.705446 -304.449734)
			(xy 83.704951 -304.474341) (xy 83.697056 -304.522918) (xy 83.681472 -304.569599) (xy 83.65973 -304.611024)
			(xy 87.60028 -304.611024) (xy 87.604351 -304.555402) (xy 87.616477 -304.500965) (xy 87.6364 -304.448874)
			(xy 87.663696 -304.400239) (xy 87.697782 -304.356096) (xy 87.737931 -304.317387) (xy 87.783289 -304.284936)
			(xy 87.832889 -304.259435) (xy 87.885673 -304.241428) (xy 87.940516 -304.231298) (xy 87.99625 -304.229261)
			(xy 88.051687 -304.235361) (xy 88.105644 -304.249467) (xy 88.156973 -304.271279) (xy 88.204579 -304.300333)
			(xy 88.247447 -304.336008) (xy 88.284664 -304.377545) (xy 88.315437 -304.424058) (xy 88.339109 -304.474555)
			(xy 88.355177 -304.527962) (xy 88.363297 -304.583138) (xy 88.363806 -304.611024) (xy 88.363297 -304.63891)
			(xy 88.355177 -304.694086) (xy 88.339109 -304.747493) (xy 88.315437 -304.79799) (xy 88.284664 -304.844503)
			(xy 88.247447 -304.88604) (xy 88.204579 -304.921715) (xy 88.156973 -304.950769) (xy 88.105644 -304.972581)
			(xy 88.051687 -304.986687) (xy 87.99625 -304.992787) (xy 87.940516 -304.99075) (xy 87.885673 -304.98062)
			(xy 87.832889 -304.962613) (xy 87.783289 -304.937112) (xy 87.737931 -304.904661) (xy 87.697782 -304.865952)
			(xy 87.663696 -304.821809) (xy 87.6364 -304.773174) (xy 87.616477 -304.721083) (xy 87.604351 -304.666646)
			(xy 87.60028 -304.611024) (xy 83.65973 -304.611024) (xy 83.658601 -304.613176) (xy 83.629036 -304.65252)
			(xy 83.593543 -304.686612) (xy 83.55304 -304.714568) (xy 83.508578 -304.735666) (xy 83.461307 -304.749358)
			(xy 83.412452 -304.75529) (xy 83.363277 -304.753309) (xy 83.315058 -304.743465) (xy 83.269042 -304.726013)
			(xy 83.226421 -304.701406) (xy 83.1883 -304.670281) (xy 83.155665 -304.633444) (xy 83.129362 -304.591848)
			(xy 83.110071 -304.546572) (xy 83.098294 -304.498788) (xy 83.094334 -304.449734) (xy 82.755232 -304.449734)
			(xy 82.754737 -304.474341) (xy 82.746842 -304.522918) (xy 82.731258 -304.569599) (xy 82.708387 -304.613176)
			(xy 82.678822 -304.65252) (xy 82.643329 -304.686612) (xy 82.602826 -304.714568) (xy 82.558364 -304.735666)
			(xy 82.511093 -304.749358) (xy 82.462238 -304.75529) (xy 82.413063 -304.753309) (xy 82.364844 -304.743465)
			(xy 82.318828 -304.726013) (xy 82.276207 -304.701406) (xy 82.238086 -304.670281) (xy 82.205451 -304.633444)
			(xy 82.179148 -304.591848) (xy 82.159857 -304.546572) (xy 82.14808 -304.498788) (xy 82.14412 -304.449734)
			(xy 81.805272 -304.449734) (xy 81.804777 -304.474341) (xy 81.796882 -304.522918) (xy 81.781298 -304.569599)
			(xy 81.758427 -304.613176) (xy 81.728862 -304.65252) (xy 81.693369 -304.686612) (xy 81.652866 -304.714568)
			(xy 81.608404 -304.735666) (xy 81.561133 -304.749358) (xy 81.512278 -304.75529) (xy 81.463103 -304.753309)
			(xy 81.414884 -304.743465) (xy 81.368868 -304.726013) (xy 81.326247 -304.701406) (xy 81.288126 -304.670281)
			(xy 81.255491 -304.633444) (xy 81.229188 -304.591848) (xy 81.209897 -304.546572) (xy 81.19812 -304.498788)
			(xy 81.19416 -304.449734) (xy 80.855058 -304.449734) (xy 80.854563 -304.474341) (xy 80.846668 -304.522918)
			(xy 80.831084 -304.569599) (xy 80.808213 -304.613176) (xy 80.778648 -304.65252) (xy 80.743155 -304.686612)
			(xy 80.702652 -304.714568) (xy 80.65819 -304.735666) (xy 80.610919 -304.749358) (xy 80.562064 -304.75529)
			(xy 80.512889 -304.753309) (xy 80.46467 -304.743465) (xy 80.418654 -304.726013) (xy 80.376033 -304.701406)
			(xy 80.337912 -304.670281) (xy 80.305277 -304.633444) (xy 80.278974 -304.591848) (xy 80.259683 -304.546572)
			(xy 80.247906 -304.498788) (xy 80.243946 -304.449734) (xy 79.905077 -304.449734) (xy 79.902844 -304.49097)
			(xy 79.892175 -304.539453) (xy 79.873804 -304.58557) (xy 79.848213 -304.628109) (xy 79.816078 -304.665947)
			(xy 79.778245 -304.698087) (xy 79.73571 -304.723684) (xy 79.689595 -304.742062) (xy 79.641114 -304.752738)
			(xy 79.591544 -304.75543) (xy 79.542192 -304.750067) (xy 79.494358 -304.73679) (xy 79.449302 -304.71595)
			(xy 79.408211 -304.688095) (xy 79.372167 -304.653959) (xy 79.342121 -304.614442) (xy 79.318863 -304.570585)
			(xy 79.303007 -304.523543) (xy 79.294971 -304.474555) (xy 79.294482 -304.449734) (xy 79.294664 -304.435551)
			(xy 79.297332 -304.407311) (xy 79.299816 -304.393346) (xy 79.302102 -304.3809) (xy 79.294736 -304.357278)
			(xy 79.217266 -304.279808) (xy 79.193644 -304.272442) (xy 79.181198 -304.274728) (xy 79.167232 -304.277201)
			(xy 79.138992 -304.279875) (xy 79.12481 -304.280062) (xy 79.110627 -304.279885) (xy 79.082387 -304.277213)
			(xy 79.068422 -304.274728) (xy 79.055976 -304.272442) (xy 79.032354 -304.279808) (xy 78.954884 -304.357278)
			(xy 78.947518 -304.3809) (xy 78.949804 -304.393346) (xy 78.952283 -304.407311) (xy 78.954953 -304.435551)
			(xy 78.955138 -304.449734) (xy 78.954585 -304.474552) (xy 78.94655 -304.523533) (xy 78.930696 -304.570569)
			(xy 78.907441 -304.614421) (xy 78.877398 -304.653932) (xy 78.841359 -304.688063) (xy 78.800273 -304.715914)
			(xy 78.755222 -304.736751) (xy 78.707394 -304.750024) (xy 78.658048 -304.755386) (xy 78.608485 -304.752693)
			(xy 78.560011 -304.742018) (xy 78.513902 -304.723641) (xy 78.471374 -304.698046) (xy 78.433546 -304.665908)
			(xy 78.401416 -304.628074) (xy 78.375831 -304.585541) (xy 78.357463 -304.539428) (xy 78.346798 -304.490951)
			(xy 78.344116 -304.441388) (xy 78.00501 -304.441388) (xy 78.005178 -304.449734) (xy 78.004683 -304.474341)
			(xy 77.996788 -304.522918) (xy 77.981204 -304.569599) (xy 77.958333 -304.613176) (xy 77.928768 -304.65252)
			(xy 77.893275 -304.686612) (xy 77.852772 -304.714568) (xy 77.80831 -304.735666) (xy 77.761039 -304.749358)
			(xy 77.712184 -304.75529) (xy 77.663009 -304.753309) (xy 77.61479 -304.743465) (xy 77.568774 -304.726013)
			(xy 77.526153 -304.701406) (xy 77.488032 -304.670281) (xy 77.455397 -304.633444) (xy 77.429094 -304.591848)
			(xy 77.409803 -304.546572) (xy 77.398026 -304.498788) (xy 77.394066 -304.449734) (xy 77.055218 -304.449734)
			(xy 77.054723 -304.474341) (xy 77.046828 -304.522918) (xy 77.031244 -304.569599) (xy 77.008373 -304.613176)
			(xy 76.978808 -304.65252) (xy 76.943315 -304.686612) (xy 76.902812 -304.714568) (xy 76.85835 -304.735666)
			(xy 76.811079 -304.749358) (xy 76.762224 -304.75529) (xy 76.713049 -304.753309) (xy 76.66483 -304.743465)
			(xy 76.618814 -304.726013) (xy 76.576193 -304.701406) (xy 76.538072 -304.670281) (xy 76.505437 -304.633444)
			(xy 76.479134 -304.591848) (xy 76.459843 -304.546572) (xy 76.448066 -304.498788) (xy 76.444106 -304.449734)
			(xy 76.105258 -304.449734) (xy 76.104763 -304.474341) (xy 76.096868 -304.522918) (xy 76.081284 -304.569599)
			(xy 76.058413 -304.613176) (xy 76.028848 -304.65252) (xy 75.993355 -304.686612) (xy 75.952852 -304.714568)
			(xy 75.90839 -304.735666) (xy 75.861119 -304.749358) (xy 75.812264 -304.75529) (xy 75.763089 -304.753309)
			(xy 75.71487 -304.743465) (xy 75.668854 -304.726013) (xy 75.626233 -304.701406) (xy 75.588112 -304.670281)
			(xy 75.555477 -304.633444) (xy 75.529174 -304.591848) (xy 75.509883 -304.546572) (xy 75.498106 -304.498788)
			(xy 75.494146 -304.449734) (xy 75.155298 -304.449734) (xy 75.154803 -304.474341) (xy 75.146908 -304.522918)
			(xy 75.131324 -304.569599) (xy 75.108453 -304.613176) (xy 75.078888 -304.65252) (xy 75.043395 -304.686612)
			(xy 75.002892 -304.714568) (xy 74.95843 -304.735666) (xy 74.911159 -304.749358) (xy 74.862304 -304.75529)
			(xy 74.813129 -304.753309) (xy 74.76491 -304.743465) (xy 74.718894 -304.726013) (xy 74.676273 -304.701406)
			(xy 74.638152 -304.670281) (xy 74.605517 -304.633444) (xy 74.579214 -304.591848) (xy 74.559923 -304.546572)
			(xy 74.548146 -304.498788) (xy 74.544186 -304.449734) (xy 74.205084 -304.449734) (xy 74.204589 -304.474341)
			(xy 74.196694 -304.522918) (xy 74.18111 -304.569599) (xy 74.158239 -304.613176) (xy 74.128674 -304.65252)
			(xy 74.093181 -304.686612) (xy 74.052678 -304.714568) (xy 74.008216 -304.735666) (xy 73.960945 -304.749358)
			(xy 73.91209 -304.75529) (xy 73.862915 -304.753309) (xy 73.814696 -304.743465) (xy 73.76868 -304.726013)
			(xy 73.726059 -304.701406) (xy 73.687938 -304.670281) (xy 73.655303 -304.633444) (xy 73.629 -304.591848)
			(xy 73.609709 -304.546572) (xy 73.597932 -304.498788) (xy 73.593972 -304.449734) (xy 48.06823 -304.449734)
			(xy 48.06823 -304.833274) (xy 48.070008 -304.846482) (xy 48.07077 -304.84953) (xy 48.07517 -304.868014)
			(xy 48.079887 -304.905716) (xy 48.080168 -304.924714) (xy 48.419016 -304.924714) (xy 48.422976 -304.87566)
			(xy 48.434753 -304.827876) (xy 48.454044 -304.7826) (xy 48.480347 -304.741004) (xy 48.512982 -304.704167)
			(xy 48.551103 -304.673042) (xy 48.593724 -304.648435) (xy 48.63974 -304.630983) (xy 48.687959 -304.621139)
			(xy 48.737134 -304.619158) (xy 48.785989 -304.62509) (xy 48.83326 -304.638782) (xy 48.877722 -304.65988)
			(xy 48.918225 -304.687836) (xy 48.953718 -304.721928) (xy 48.983283 -304.761272) (xy 49.006154 -304.804849)
			(xy 49.021738 -304.85153) (xy 49.029633 -304.900107) (xy 49.030128 -304.924714) (xy 49.368976 -304.924714)
			(xy 49.372936 -304.87566) (xy 49.384713 -304.827876) (xy 49.404004 -304.7826) (xy 49.430307 -304.741004)
			(xy 49.462942 -304.704167) (xy 49.501063 -304.673042) (xy 49.543684 -304.648435) (xy 49.5897 -304.630983)
			(xy 49.637919 -304.621139) (xy 49.687094 -304.619158) (xy 49.735949 -304.62509) (xy 49.78322 -304.638782)
			(xy 49.827682 -304.65988) (xy 49.868185 -304.687836) (xy 49.903678 -304.721928) (xy 49.933243 -304.761272)
			(xy 49.956114 -304.804849) (xy 49.971698 -304.85153) (xy 49.979593 -304.900107) (xy 49.980088 -304.924714)
			(xy 50.31919 -304.924714) (xy 50.32315 -304.87566) (xy 50.334927 -304.827876) (xy 50.354218 -304.7826)
			(xy 50.380521 -304.741004) (xy 50.413156 -304.704167) (xy 50.451277 -304.673042) (xy 50.493898 -304.648435)
			(xy 50.539914 -304.630983) (xy 50.588133 -304.621139) (xy 50.637308 -304.619158) (xy 50.686163 -304.62509)
			(xy 50.733434 -304.638782) (xy 50.777896 -304.65988) (xy 50.818399 -304.687836) (xy 50.853892 -304.721928)
			(xy 50.883457 -304.761272) (xy 50.906328 -304.804849) (xy 50.921912 -304.85153) (xy 50.929807 -304.900107)
			(xy 50.930302 -304.924714) (xy 51.26915 -304.924714) (xy 51.27311 -304.87566) (xy 51.284887 -304.827876)
			(xy 51.304178 -304.7826) (xy 51.330481 -304.741004) (xy 51.363116 -304.704167) (xy 51.401237 -304.673042)
			(xy 51.443858 -304.648435) (xy 51.489874 -304.630983) (xy 51.538093 -304.621139) (xy 51.587268 -304.619158)
			(xy 51.636123 -304.62509) (xy 51.683394 -304.638782) (xy 51.727856 -304.65988) (xy 51.768359 -304.687836)
			(xy 51.803852 -304.721928) (xy 51.833417 -304.761272) (xy 51.856288 -304.804849) (xy 51.871872 -304.85153)
			(xy 51.879767 -304.900107) (xy 51.880262 -304.924714) (xy 52.21911 -304.924714) (xy 52.22307 -304.87566)
			(xy 52.234847 -304.827876) (xy 52.254138 -304.7826) (xy 52.280441 -304.741004) (xy 52.313076 -304.704167)
			(xy 52.351197 -304.673042) (xy 52.393818 -304.648435) (xy 52.439834 -304.630983) (xy 52.488053 -304.621139)
			(xy 52.537228 -304.619158) (xy 52.586083 -304.62509) (xy 52.633354 -304.638782) (xy 52.677816 -304.65988)
			(xy 52.718319 -304.687836) (xy 52.753812 -304.721928) (xy 52.783377 -304.761272) (xy 52.806248 -304.804849)
			(xy 52.821832 -304.85153) (xy 52.829727 -304.900107) (xy 52.830222 -304.924714) (xy 53.16907 -304.924714)
			(xy 53.17303 -304.87566) (xy 53.184807 -304.827876) (xy 53.204098 -304.7826) (xy 53.230401 -304.741004)
			(xy 53.263036 -304.704167) (xy 53.301157 -304.673042) (xy 53.343778 -304.648435) (xy 53.389794 -304.630983)
			(xy 53.438013 -304.621139) (xy 53.487188 -304.619158) (xy 53.536043 -304.62509) (xy 53.583314 -304.638782)
			(xy 53.627776 -304.65988) (xy 53.668279 -304.687836) (xy 53.703772 -304.721928) (xy 53.733337 -304.761272)
			(xy 53.756208 -304.804849) (xy 53.771792 -304.85153) (xy 53.779687 -304.900107) (xy 53.780182 -304.924714)
			(xy 54.11903 -304.924714) (xy 54.12299 -304.87566) (xy 54.134767 -304.827876) (xy 54.154058 -304.7826)
			(xy 54.180361 -304.741004) (xy 54.212996 -304.704167) (xy 54.251117 -304.673042) (xy 54.293738 -304.648435)
			(xy 54.339754 -304.630983) (xy 54.387973 -304.621139) (xy 54.437148 -304.619158) (xy 54.486003 -304.62509)
			(xy 54.533274 -304.638782) (xy 54.577736 -304.65988) (xy 54.618239 -304.687836) (xy 54.653732 -304.721928)
			(xy 54.683297 -304.761272) (xy 54.706168 -304.804849) (xy 54.721752 -304.85153) (xy 54.729647 -304.900107)
			(xy 54.730142 -304.924714) (xy 55.06899 -304.924714) (xy 55.07295 -304.87566) (xy 55.084727 -304.827876)
			(xy 55.104018 -304.7826) (xy 55.130321 -304.741004) (xy 55.162956 -304.704167) (xy 55.201077 -304.673042)
			(xy 55.243698 -304.648435) (xy 55.289714 -304.630983) (xy 55.337933 -304.621139) (xy 55.387108 -304.619158)
			(xy 55.435963 -304.62509) (xy 55.483234 -304.638782) (xy 55.527696 -304.65988) (xy 55.568199 -304.687836)
			(xy 55.603692 -304.721928) (xy 55.633257 -304.761272) (xy 55.656128 -304.804849) (xy 55.671712 -304.85153)
			(xy 55.679607 -304.900107) (xy 55.680102 -304.924714) (xy 56.01895 -304.924714) (xy 56.02291 -304.87566)
			(xy 56.034687 -304.827876) (xy 56.053978 -304.7826) (xy 56.080281 -304.741004) (xy 56.112916 -304.704167)
			(xy 56.151037 -304.673042) (xy 56.193658 -304.648435) (xy 56.239674 -304.630983) (xy 56.287893 -304.621139)
			(xy 56.337068 -304.619158) (xy 56.385923 -304.62509) (xy 56.433194 -304.638782) (xy 56.477656 -304.65988)
			(xy 56.518159 -304.687836) (xy 56.553652 -304.721928) (xy 56.583217 -304.761272) (xy 56.606088 -304.804849)
			(xy 56.621672 -304.85153) (xy 56.629567 -304.900107) (xy 56.630062 -304.924714) (xy 56.969164 -304.924714)
			(xy 56.973124 -304.87566) (xy 56.984901 -304.827876) (xy 57.004192 -304.7826) (xy 57.030495 -304.741004)
			(xy 57.06313 -304.704167) (xy 57.101251 -304.673042) (xy 57.143872 -304.648435) (xy 57.189888 -304.630983)
			(xy 57.238107 -304.621139) (xy 57.287282 -304.619158) (xy 57.336137 -304.62509) (xy 57.383408 -304.638782)
			(xy 57.42787 -304.65988) (xy 57.468373 -304.687836) (xy 57.503866 -304.721928) (xy 57.533431 -304.761272)
			(xy 57.556302 -304.804849) (xy 57.571886 -304.85153) (xy 57.579781 -304.900107) (xy 57.580276 -304.924714)
			(xy 57.919124 -304.924714) (xy 57.923084 -304.87566) (xy 57.934861 -304.827876) (xy 57.954152 -304.7826)
			(xy 57.980455 -304.741004) (xy 58.01309 -304.704167) (xy 58.051211 -304.673042) (xy 58.093832 -304.648435)
			(xy 58.139848 -304.630983) (xy 58.188067 -304.621139) (xy 58.237242 -304.619158) (xy 58.286097 -304.62509)
			(xy 58.333368 -304.638782) (xy 58.37783 -304.65988) (xy 58.418333 -304.687836) (xy 58.453826 -304.721928)
			(xy 58.483391 -304.761272) (xy 58.506262 -304.804849) (xy 58.521846 -304.85153) (xy 58.529741 -304.900107)
			(xy 58.530236 -304.924714) (xy 59.819044 -304.924714) (xy 59.823004 -304.87566) (xy 59.834781 -304.827876)
			(xy 59.854072 -304.7826) (xy 59.880375 -304.741004) (xy 59.91301 -304.704167) (xy 59.951131 -304.673042)
			(xy 59.993752 -304.648435) (xy 60.039768 -304.630983) (xy 60.087987 -304.621139) (xy 60.137162 -304.619158)
			(xy 60.186017 -304.62509) (xy 60.233288 -304.638782) (xy 60.27775 -304.65988) (xy 60.318253 -304.687836)
			(xy 60.353746 -304.721928) (xy 60.383311 -304.761272) (xy 60.406182 -304.804849) (xy 60.421766 -304.85153)
			(xy 60.429661 -304.900107) (xy 60.430156 -304.924714) (xy 60.769004 -304.924714) (xy 60.772964 -304.87566)
			(xy 60.784741 -304.827876) (xy 60.804032 -304.7826) (xy 60.830335 -304.741004) (xy 60.86297 -304.704167)
			(xy 60.901091 -304.673042) (xy 60.943712 -304.648435) (xy 60.989728 -304.630983) (xy 61.037947 -304.621139)
			(xy 61.087122 -304.619158) (xy 61.135977 -304.62509) (xy 61.183248 -304.638782) (xy 61.22771 -304.65988)
			(xy 61.268213 -304.687836) (xy 61.303706 -304.721928) (xy 61.333271 -304.761272) (xy 61.356142 -304.804849)
			(xy 61.371726 -304.85153) (xy 61.379621 -304.900107) (xy 61.380116 -304.924714) (xy 61.718964 -304.924714)
			(xy 61.722924 -304.87566) (xy 61.734701 -304.827876) (xy 61.753992 -304.7826) (xy 61.780295 -304.741004)
			(xy 61.81293 -304.704167) (xy 61.851051 -304.673042) (xy 61.893672 -304.648435) (xy 61.939688 -304.630983)
			(xy 61.987907 -304.621139) (xy 62.037082 -304.619158) (xy 62.085937 -304.62509) (xy 62.133208 -304.638782)
			(xy 62.17767 -304.65988) (xy 62.218173 -304.687836) (xy 62.253666 -304.721928) (xy 62.283231 -304.761272)
			(xy 62.306102 -304.804849) (xy 62.321686 -304.85153) (xy 62.329581 -304.900107) (xy 62.330076 -304.924714)
			(xy 62.669178 -304.924714) (xy 62.673138 -304.87566) (xy 62.684915 -304.827876) (xy 62.704206 -304.7826)
			(xy 62.730509 -304.741004) (xy 62.763144 -304.704167) (xy 62.801265 -304.673042) (xy 62.843886 -304.648435)
			(xy 62.889902 -304.630983) (xy 62.938121 -304.621139) (xy 62.987296 -304.619158) (xy 63.036151 -304.62509)
			(xy 63.083422 -304.638782) (xy 63.127884 -304.65988) (xy 63.168387 -304.687836) (xy 63.20388 -304.721928)
			(xy 63.233445 -304.761272) (xy 63.256316 -304.804849) (xy 63.2719 -304.85153) (xy 63.279795 -304.900107)
			(xy 63.28029 -304.924714) (xy 63.619138 -304.924714) (xy 63.623098 -304.87566) (xy 63.634875 -304.827876)
			(xy 63.654166 -304.7826) (xy 63.680469 -304.741004) (xy 63.713104 -304.704167) (xy 63.751225 -304.673042)
			(xy 63.793846 -304.648435) (xy 63.839862 -304.630983) (xy 63.888081 -304.621139) (xy 63.937256 -304.619158)
			(xy 63.986111 -304.62509) (xy 64.033382 -304.638782) (xy 64.077844 -304.65988) (xy 64.118347 -304.687836)
			(xy 64.15384 -304.721928) (xy 64.183405 -304.761272) (xy 64.206276 -304.804849) (xy 64.22186 -304.85153)
			(xy 64.229755 -304.900107) (xy 64.23025 -304.924714) (xy 64.569098 -304.924714) (xy 64.573058 -304.87566)
			(xy 64.584835 -304.827876) (xy 64.604126 -304.7826) (xy 64.630429 -304.741004) (xy 64.663064 -304.704167)
			(xy 64.701185 -304.673042) (xy 64.743806 -304.648435) (xy 64.789822 -304.630983) (xy 64.838041 -304.621139)
			(xy 64.887216 -304.619158) (xy 64.936071 -304.62509) (xy 64.983342 -304.638782) (xy 65.027804 -304.65988)
			(xy 65.068307 -304.687836) (xy 65.1038 -304.721928) (xy 65.133365 -304.761272) (xy 65.156236 -304.804849)
			(xy 65.17182 -304.85153) (xy 65.179715 -304.900107) (xy 65.18021 -304.924714) (xy 65.519058 -304.924714)
			(xy 65.523018 -304.87566) (xy 65.534795 -304.827876) (xy 65.554086 -304.7826) (xy 65.580389 -304.741004)
			(xy 65.613024 -304.704167) (xy 65.651145 -304.673042) (xy 65.693766 -304.648435) (xy 65.739782 -304.630983)
			(xy 65.788001 -304.621139) (xy 65.837176 -304.619158) (xy 65.886031 -304.62509) (xy 65.933302 -304.638782)
			(xy 65.977764 -304.65988) (xy 66.018267 -304.687836) (xy 66.05376 -304.721928) (xy 66.083325 -304.761272)
			(xy 66.106196 -304.804849) (xy 66.12178 -304.85153) (xy 66.129675 -304.900107) (xy 66.13017 -304.924714)
			(xy 66.469018 -304.924714) (xy 66.472978 -304.87566) (xy 66.484755 -304.827876) (xy 66.504046 -304.7826)
			(xy 66.530349 -304.741004) (xy 66.562984 -304.704167) (xy 66.601105 -304.673042) (xy 66.643726 -304.648435)
			(xy 66.689742 -304.630983) (xy 66.737961 -304.621139) (xy 66.787136 -304.619158) (xy 66.835991 -304.62509)
			(xy 66.883262 -304.638782) (xy 66.927724 -304.65988) (xy 66.968227 -304.687836) (xy 67.00372 -304.721928)
			(xy 67.033285 -304.761272) (xy 67.056156 -304.804849) (xy 67.07174 -304.85153) (xy 67.079635 -304.900107)
			(xy 67.08013 -304.924714) (xy 67.418978 -304.924714) (xy 67.422938 -304.87566) (xy 67.434715 -304.827876)
			(xy 67.454006 -304.7826) (xy 67.480309 -304.741004) (xy 67.512944 -304.704167) (xy 67.551065 -304.673042)
			(xy 67.593686 -304.648435) (xy 67.639702 -304.630983) (xy 67.687921 -304.621139) (xy 67.737096 -304.619158)
			(xy 67.785951 -304.62509) (xy 67.833222 -304.638782) (xy 67.877684 -304.65988) (xy 67.918187 -304.687836)
			(xy 67.95368 -304.721928) (xy 67.983245 -304.761272) (xy 68.006116 -304.804849) (xy 68.0217 -304.85153)
			(xy 68.029595 -304.900107) (xy 68.03009 -304.924714) (xy 68.368938 -304.924714) (xy 68.372898 -304.87566)
			(xy 68.384675 -304.827876) (xy 68.403966 -304.7826) (xy 68.430269 -304.741004) (xy 68.462904 -304.704167)
			(xy 68.501025 -304.673042) (xy 68.543646 -304.648435) (xy 68.589662 -304.630983) (xy 68.637881 -304.621139)
			(xy 68.687056 -304.619158) (xy 68.735911 -304.62509) (xy 68.783182 -304.638782) (xy 68.827644 -304.65988)
			(xy 68.868147 -304.687836) (xy 68.90364 -304.721928) (xy 68.933205 -304.761272) (xy 68.956076 -304.804849)
			(xy 68.97166 -304.85153) (xy 68.979555 -304.900107) (xy 68.98005 -304.924714) (xy 69.319152 -304.924714)
			(xy 69.323112 -304.87566) (xy 69.334889 -304.827876) (xy 69.35418 -304.7826) (xy 69.380483 -304.741004)
			(xy 69.413118 -304.704167) (xy 69.451239 -304.673042) (xy 69.49386 -304.648435) (xy 69.539876 -304.630983)
			(xy 69.588095 -304.621139) (xy 69.63727 -304.619158) (xy 69.686125 -304.62509) (xy 69.733396 -304.638782)
			(xy 69.777858 -304.65988) (xy 69.818361 -304.687836) (xy 69.853854 -304.721928) (xy 69.883419 -304.761272)
			(xy 69.90629 -304.804849) (xy 69.921874 -304.85153) (xy 69.929769 -304.900107) (xy 69.930264 -304.924714)
			(xy 70.269112 -304.924714) (xy 70.273072 -304.87566) (xy 70.284849 -304.827876) (xy 70.30414 -304.7826)
			(xy 70.330443 -304.741004) (xy 70.363078 -304.704167) (xy 70.401199 -304.673042) (xy 70.44382 -304.648435)
			(xy 70.489836 -304.630983) (xy 70.538055 -304.621139) (xy 70.58723 -304.619158) (xy 70.636085 -304.62509)
			(xy 70.683356 -304.638782) (xy 70.727818 -304.65988) (xy 70.768321 -304.687836) (xy 70.803814 -304.721928)
			(xy 70.833379 -304.761272) (xy 70.85625 -304.804849) (xy 70.871834 -304.85153) (xy 70.879729 -304.900107)
			(xy 70.880224 -304.924714) (xy 71.219072 -304.924714) (xy 71.223032 -304.87566) (xy 71.234809 -304.827876)
			(xy 71.2541 -304.7826) (xy 71.280403 -304.741004) (xy 71.313038 -304.704167) (xy 71.351159 -304.673042)
			(xy 71.39378 -304.648435) (xy 71.439796 -304.630983) (xy 71.488015 -304.621139) (xy 71.53719 -304.619158)
			(xy 71.586045 -304.62509) (xy 71.633316 -304.638782) (xy 71.677778 -304.65988) (xy 71.718281 -304.687836)
			(xy 71.753774 -304.721928) (xy 71.783339 -304.761272) (xy 71.80621 -304.804849) (xy 71.821794 -304.85153)
			(xy 71.829689 -304.900107) (xy 71.830184 -304.924714) (xy 72.169032 -304.924714) (xy 72.172992 -304.87566)
			(xy 72.184769 -304.827876) (xy 72.20406 -304.7826) (xy 72.230363 -304.741004) (xy 72.262998 -304.704167)
			(xy 72.301119 -304.673042) (xy 72.34374 -304.648435) (xy 72.389756 -304.630983) (xy 72.437975 -304.621139)
			(xy 72.48715 -304.619158) (xy 72.536005 -304.62509) (xy 72.583276 -304.638782) (xy 72.627738 -304.65988)
			(xy 72.668241 -304.687836) (xy 72.703734 -304.721928) (xy 72.733299 -304.761272) (xy 72.75617 -304.804849)
			(xy 72.771754 -304.85153) (xy 72.779649 -304.900107) (xy 72.780144 -304.924714) (xy 72.779649 -304.949321)
			(xy 72.771754 -304.997898) (xy 72.75617 -305.044579) (xy 72.745493 -305.064922) (xy 88.62009 -305.064922)
			(xy 88.624161 -305.0093) (xy 88.636287 -304.954863) (xy 88.65621 -304.902772) (xy 88.683506 -304.854137)
			(xy 88.717592 -304.809994) (xy 88.757741 -304.771285) (xy 88.803099 -304.738834) (xy 88.852699 -304.713333)
			(xy 88.905483 -304.695326) (xy 88.960326 -304.685196) (xy 89.01606 -304.683159) (xy 89.071497 -304.689259)
			(xy 89.125454 -304.703365) (xy 89.176783 -304.725177) (xy 89.224389 -304.754231) (xy 89.267257 -304.789906)
			(xy 89.304474 -304.831443) (xy 89.335247 -304.877956) (xy 89.358919 -304.928453) (xy 89.374987 -304.98186)
			(xy 89.383107 -305.037036) (xy 89.383616 -305.064922) (xy 89.635074 -305.064922) (xy 89.639145 -305.0093)
			(xy 89.651271 -304.954863) (xy 89.671194 -304.902772) (xy 89.69849 -304.854137) (xy 89.732576 -304.809994)
			(xy 89.772725 -304.771285) (xy 89.818083 -304.738834) (xy 89.867683 -304.713333) (xy 89.920467 -304.695326)
			(xy 89.97531 -304.685196) (xy 90.031044 -304.683159) (xy 90.086481 -304.689259) (xy 90.140438 -304.703365)
			(xy 90.191767 -304.725177) (xy 90.239373 -304.754231) (xy 90.282241 -304.789906) (xy 90.319458 -304.831443)
			(xy 90.350231 -304.877956) (xy 90.373903 -304.928453) (xy 90.389971 -304.98186) (xy 90.398091 -305.037036)
			(xy 90.3986 -305.064922) (xy 90.643454 -305.064922) (xy 90.647525 -305.0093) (xy 90.659651 -304.954863)
			(xy 90.679574 -304.902772) (xy 90.70687 -304.854137) (xy 90.740956 -304.809994) (xy 90.781105 -304.771285)
			(xy 90.826463 -304.738834) (xy 90.876063 -304.713333) (xy 90.928847 -304.695326) (xy 90.98369 -304.685196)
			(xy 91.039424 -304.683159) (xy 91.094861 -304.689259) (xy 91.148818 -304.703365) (xy 91.200147 -304.725177)
			(xy 91.247753 -304.754231) (xy 91.290621 -304.789906) (xy 91.327838 -304.831443) (xy 91.358611 -304.877956)
			(xy 91.382283 -304.928453) (xy 91.398351 -304.98186) (xy 91.406471 -305.037036) (xy 91.406961 -305.063906)
			(xy 91.66809 -305.063906) (xy 91.672161 -305.008284) (xy 91.684287 -304.953847) (xy 91.70421 -304.901756)
			(xy 91.731506 -304.853121) (xy 91.765592 -304.808978) (xy 91.805741 -304.770269) (xy 91.851099 -304.737818)
			(xy 91.900699 -304.712317) (xy 91.953483 -304.69431) (xy 92.008326 -304.68418) (xy 92.06406 -304.682143)
			(xy 92.119497 -304.688243) (xy 92.173454 -304.702349) (xy 92.224783 -304.724161) (xy 92.272389 -304.753215)
			(xy 92.315257 -304.78889) (xy 92.352474 -304.830427) (xy 92.383247 -304.87694) (xy 92.406919 -304.927437)
			(xy 92.422987 -304.980844) (xy 92.431107 -305.03602) (xy 92.431291 -305.046126) (xy 92.68409 -305.046126)
			(xy 92.688161 -304.990504) (xy 92.700287 -304.936067) (xy 92.72021 -304.883976) (xy 92.747506 -304.835341)
			(xy 92.781592 -304.791198) (xy 92.821741 -304.752489) (xy 92.867099 -304.720038) (xy 92.916699 -304.694537)
			(xy 92.969483 -304.67653) (xy 93.024326 -304.6664) (xy 93.08006 -304.664363) (xy 93.135497 -304.670463)
			(xy 93.189454 -304.684569) (xy 93.240783 -304.706381) (xy 93.288389 -304.735435) (xy 93.331257 -304.77111)
			(xy 93.368474 -304.812647) (xy 93.399247 -304.85916) (xy 93.422919 -304.909657) (xy 93.438987 -304.963064)
			(xy 93.445679 -305.008534) (xy 102.235508 -305.008534) (xy 102.235992 -304.981164) (xy 102.243805 -304.926986)
			(xy 102.25929 -304.874483) (xy 102.282128 -304.824736) (xy 102.311849 -304.778768) (xy 102.329488 -304.757836)
			(xy 102.335584 -304.750724) (xy 102.341934 -304.733706) (xy 102.341934 -304.648362) (xy 102.335584 -304.631344)
			(xy 102.329488 -304.624232) (xy 102.311849 -304.6033) (xy 102.282137 -304.557327) (xy 102.259302 -304.50758)
			(xy 102.24381 -304.455079) (xy 102.235982 -304.400903) (xy 102.235508 -304.373534) (xy 102.235994 -304.346283)
			(xy 102.24375 -304.292335) (xy 102.259105 -304.24004) (xy 102.281747 -304.190463) (xy 102.311213 -304.144613)
			(xy 102.346904 -304.103422) (xy 102.388095 -304.067731) (xy 102.433945 -304.038265) (xy 102.483522 -304.015623)
			(xy 102.535817 -304.000268) (xy 102.589765 -303.992512) (xy 102.644267 -303.992512) (xy 102.698215 -304.000268)
			(xy 102.75051 -304.015623) (xy 102.800087 -304.038265) (xy 102.845937 -304.067731) (xy 102.887128 -304.103422)
			(xy 102.922819 -304.144613) (xy 102.952285 -304.190463) (xy 102.974927 -304.24004) (xy 102.990282 -304.292335)
			(xy 102.998038 -304.346283) (xy 102.998524 -304.373534) (xy 102.998096 -304.400906) (xy 102.990272 -304.455087)
			(xy 102.974775 -304.507592) (xy 102.951924 -304.557338) (xy 102.92219 -304.603302) (xy 102.904544 -304.624232)
			(xy 102.898448 -304.631344) (xy 102.892098 -304.648362) (xy 102.892098 -304.733706) (xy 102.898448 -304.750724)
			(xy 102.904544 -304.757836) (xy 102.922174 -304.778775) (xy 102.951886 -304.824747) (xy 102.974723 -304.874493)
			(xy 102.990216 -304.926991) (xy 102.998048 -304.981165) (xy 102.998524 -305.008534) (xy 105.655618 -305.008534)
			(xy 105.6561 -304.981164) (xy 105.663913 -304.926986) (xy 105.679398 -304.874483) (xy 105.702237 -304.824735)
			(xy 105.731958 -304.778768) (xy 105.749598 -304.757836) (xy 105.755694 -304.750724) (xy 105.762044 -304.733706)
			(xy 105.762044 -304.648362) (xy 105.755694 -304.631344) (xy 105.749598 -304.624232) (xy 105.73196 -304.603299)
			(xy 105.702248 -304.557326) (xy 105.679412 -304.507579) (xy 105.663921 -304.455079) (xy 105.656092 -304.400903)
			(xy 105.655618 -304.373534) (xy 105.656104 -304.346283) (xy 105.66386 -304.292335) (xy 105.679215 -304.24004)
			(xy 105.701857 -304.190463) (xy 105.731323 -304.144613) (xy 105.767014 -304.103422) (xy 105.808205 -304.067731)
			(xy 105.854055 -304.038265) (xy 105.903632 -304.015623) (xy 105.955927 -304.000268) (xy 106.009875 -303.992512)
			(xy 106.064377 -303.992512) (xy 106.118325 -304.000268) (xy 106.17062 -304.015623) (xy 106.220197 -304.038265)
			(xy 106.266047 -304.067731) (xy 106.307238 -304.103422) (xy 106.342929 -304.144613) (xy 106.372395 -304.190463)
			(xy 106.395037 -304.24004) (xy 106.410392 -304.292335) (xy 106.418148 -304.346283) (xy 106.418634 -304.373534)
			(xy 106.418204 -304.400906) (xy 106.41038 -304.455087) (xy 106.394883 -304.507591) (xy 106.372033 -304.557337)
			(xy 106.3423 -304.603302) (xy 106.324654 -304.624232) (xy 106.318558 -304.631344) (xy 106.312208 -304.648362)
			(xy 106.312208 -304.733706) (xy 106.318558 -304.750724) (xy 106.324654 -304.757836) (xy 106.342269 -304.778787)
			(xy 106.371986 -304.824754) (xy 106.394828 -304.874497) (xy 106.410324 -304.926993) (xy 106.418157 -304.981166)
			(xy 106.418634 -305.008534) (xy 107.043728 -305.008534) (xy 107.044207 -304.981164) (xy 107.052021 -304.926985)
			(xy 107.067506 -304.874482) (xy 107.090345 -304.824735) (xy 107.120068 -304.778768) (xy 107.137708 -304.757836)
			(xy 107.143804 -304.750724) (xy 107.150154 -304.733706) (xy 107.150154 -304.648362) (xy 107.143804 -304.631344)
			(xy 107.137708 -304.624232) (xy 107.120072 -304.603298) (xy 107.090359 -304.557326) (xy 107.067523 -304.507579)
			(xy 107.052031 -304.455078) (xy 107.044202 -304.400903) (xy 107.043728 -304.373534) (xy 107.044214 -304.346283)
			(xy 107.05197 -304.292335) (xy 107.067325 -304.24004) (xy 107.089967 -304.190463) (xy 107.119433 -304.144613)
			(xy 107.155124 -304.103422) (xy 107.196315 -304.067731) (xy 107.242165 -304.038265) (xy 107.291742 -304.015623)
			(xy 107.344037 -304.000268) (xy 107.397985 -303.992512) (xy 107.452487 -303.992512) (xy 107.506435 -304.000268)
			(xy 107.55873 -304.015623) (xy 107.608307 -304.038265) (xy 107.654157 -304.067731) (xy 107.695348 -304.103422)
			(xy 107.731039 -304.144613) (xy 107.760505 -304.190463) (xy 107.783147 -304.24004) (xy 107.798502 -304.292335)
			(xy 107.806258 -304.346283) (xy 107.806744 -304.373534) (xy 107.806312 -304.400906) (xy 107.798488 -304.455087)
			(xy 107.782992 -304.507591) (xy 107.760142 -304.557337) (xy 107.730409 -304.603302) (xy 107.712764 -304.624232)
			(xy 107.706668 -304.631344) (xy 107.700318 -304.648362) (xy 107.700318 -304.733706) (xy 107.706668 -304.750724)
			(xy 107.712764 -304.757836) (xy 107.730381 -304.778786) (xy 107.760097 -304.824753) (xy 107.782938 -304.874496)
			(xy 107.798434 -304.926993) (xy 107.806267 -304.981166) (xy 107.806744 -305.008534) (xy 109.075728 -305.008534)
			(xy 109.076207 -304.981164) (xy 109.084021 -304.926985) (xy 109.099506 -304.874482) (xy 109.122345 -304.824735)
			(xy 109.152068 -304.778768) (xy 109.169708 -304.757836) (xy 109.175804 -304.750724) (xy 109.182154 -304.733706)
			(xy 109.182154 -304.648362) (xy 109.175804 -304.631344) (xy 109.169708 -304.624232) (xy 109.152072 -304.603298)
			(xy 109.122359 -304.557326) (xy 109.099523 -304.507579) (xy 109.084031 -304.455078) (xy 109.076202 -304.400903)
			(xy 109.075728 -304.373534) (xy 109.076214 -304.346283) (xy 109.08397 -304.292335) (xy 109.099325 -304.24004)
			(xy 109.121967 -304.190463) (xy 109.151433 -304.144613) (xy 109.187124 -304.103422) (xy 109.228315 -304.067731)
			(xy 109.274165 -304.038265) (xy 109.323742 -304.015623) (xy 109.376037 -304.000268) (xy 109.429985 -303.992512)
			(xy 109.484487 -303.992512) (xy 109.538435 -304.000268) (xy 109.59073 -304.015623) (xy 109.640307 -304.038265)
			(xy 109.686157 -304.067731) (xy 109.727348 -304.103422) (xy 109.763039 -304.144613) (xy 109.792505 -304.190463)
			(xy 109.815147 -304.24004) (xy 109.830502 -304.292335) (xy 109.838258 -304.346283) (xy 109.838744 -304.373534)
			(xy 109.838312 -304.400906) (xy 109.830488 -304.455087) (xy 109.814992 -304.507591) (xy 109.792142 -304.557337)
			(xy 109.762409 -304.603302) (xy 109.744764 -304.624232) (xy 109.738668 -304.631344) (xy 109.732318 -304.648362)
			(xy 109.732318 -304.733706) (xy 109.738668 -304.750724) (xy 109.744764 -304.757836) (xy 109.762381 -304.778786)
			(xy 109.792097 -304.824753) (xy 109.814938 -304.874496) (xy 109.830434 -304.926993) (xy 109.838267 -304.981166)
			(xy 109.838744 -305.008534) (xy 113.883948 -305.008534) (xy 113.884422 -304.981164) (xy 113.892236 -304.926985)
			(xy 113.907723 -304.874481) (xy 113.930563 -304.824734) (xy 113.960287 -304.778767) (xy 113.977928 -304.757836)
			(xy 113.984024 -304.750724) (xy 113.990374 -304.733706) (xy 113.990374 -304.648362) (xy 113.984024 -304.631344)
			(xy 113.977928 -304.624232) (xy 113.960295 -304.603295) (xy 113.930581 -304.557324) (xy 113.907744 -304.507578)
			(xy 113.892251 -304.455078) (xy 113.884422 -304.400903) (xy 113.883948 -304.373534) (xy 113.884434 -304.346283)
			(xy 113.89219 -304.292335) (xy 113.907545 -304.24004) (xy 113.930187 -304.190463) (xy 113.959653 -304.144613)
			(xy 113.995344 -304.103422) (xy 114.036535 -304.067731) (xy 114.082385 -304.038265) (xy 114.131962 -304.015623)
			(xy 114.184257 -304.000268) (xy 114.238205 -303.992512) (xy 114.292707 -303.992512) (xy 114.346655 -304.000268)
			(xy 114.39895 -304.015623) (xy 114.448527 -304.038265) (xy 114.494377 -304.067731) (xy 114.535568 -304.103422)
			(xy 114.571259 -304.144613) (xy 114.600725 -304.190463) (xy 114.623367 -304.24004) (xy 114.638722 -304.292335)
			(xy 114.646478 -304.346283) (xy 114.646964 -304.373534) (xy 114.646527 -304.400905) (xy 114.638703 -304.455086)
			(xy 114.623208 -304.50759) (xy 114.60036 -304.557336) (xy 114.570628 -304.603302) (xy 114.552984 -304.624232)
			(xy 114.546888 -304.631344) (xy 114.540538 -304.648362) (xy 114.540538 -304.733706) (xy 114.546888 -304.750724)
			(xy 114.552984 -304.757836) (xy 114.570604 -304.778783) (xy 114.600319 -304.824752) (xy 114.623159 -304.874495)
			(xy 114.638655 -304.926993) (xy 114.646488 -304.981166) (xy 114.646964 -305.008534) (xy 114.646478 -305.035785)
			(xy 114.638722 -305.089733) (xy 114.623367 -305.142028) (xy 114.600725 -305.191605) (xy 114.571259 -305.237455)
			(xy 114.535568 -305.278646) (xy 114.494377 -305.314337) (xy 114.448527 -305.343803) (xy 114.39895 -305.366445)
			(xy 114.346655 -305.3818) (xy 114.292707 -305.389556) (xy 114.238205 -305.389556) (xy 114.184257 -305.3818)
			(xy 114.131962 -305.366445) (xy 114.082385 -305.343803) (xy 114.036535 -305.314337) (xy 113.995344 -305.278646)
			(xy 113.959653 -305.237455) (xy 113.930187 -305.191605) (xy 113.907545 -305.142028) (xy 113.89219 -305.089733)
			(xy 113.884434 -305.035785) (xy 113.883948 -305.008534) (xy 109.838744 -305.008534) (xy 109.838258 -305.035785)
			(xy 109.830502 -305.089733) (xy 109.815147 -305.142028) (xy 109.792505 -305.191605) (xy 109.763039 -305.237455)
			(xy 109.727348 -305.278646) (xy 109.686157 -305.314337) (xy 109.640307 -305.343803) (xy 109.59073 -305.366445)
			(xy 109.538435 -305.3818) (xy 109.484487 -305.389556) (xy 109.429985 -305.389556) (xy 109.376037 -305.3818)
			(xy 109.323742 -305.366445) (xy 109.274165 -305.343803) (xy 109.228315 -305.314337) (xy 109.187124 -305.278646)
			(xy 109.151433 -305.237455) (xy 109.121967 -305.191605) (xy 109.099325 -305.142028) (xy 109.08397 -305.089733)
			(xy 109.076214 -305.035785) (xy 109.075728 -305.008534) (xy 107.806744 -305.008534) (xy 107.806258 -305.035785)
			(xy 107.798502 -305.089733) (xy 107.783147 -305.142028) (xy 107.760505 -305.191605) (xy 107.731039 -305.237455)
			(xy 107.695348 -305.278646) (xy 107.654157 -305.314337) (xy 107.608307 -305.343803) (xy 107.55873 -305.366445)
			(xy 107.506435 -305.3818) (xy 107.452487 -305.389556) (xy 107.397985 -305.389556) (xy 107.344037 -305.3818)
			(xy 107.291742 -305.366445) (xy 107.242165 -305.343803) (xy 107.196315 -305.314337) (xy 107.155124 -305.278646)
			(xy 107.119433 -305.237455) (xy 107.089967 -305.191605) (xy 107.067325 -305.142028) (xy 107.05197 -305.089733)
			(xy 107.044214 -305.035785) (xy 107.043728 -305.008534) (xy 106.418634 -305.008534) (xy 106.418148 -305.035785)
			(xy 106.410392 -305.089733) (xy 106.395037 -305.142028) (xy 106.372395 -305.191605) (xy 106.342929 -305.237455)
			(xy 106.307238 -305.278646) (xy 106.266047 -305.314337) (xy 106.220197 -305.343803) (xy 106.17062 -305.366445)
			(xy 106.118325 -305.3818) (xy 106.064377 -305.389556) (xy 106.009875 -305.389556) (xy 105.955927 -305.3818)
			(xy 105.903632 -305.366445) (xy 105.854055 -305.343803) (xy 105.808205 -305.314337) (xy 105.767014 -305.278646)
			(xy 105.731323 -305.237455) (xy 105.701857 -305.191605) (xy 105.679215 -305.142028) (xy 105.66386 -305.089733)
			(xy 105.656104 -305.035785) (xy 105.655618 -305.008534) (xy 102.998524 -305.008534) (xy 102.998038 -305.035785)
			(xy 102.990282 -305.089733) (xy 102.974927 -305.142028) (xy 102.952285 -305.191605) (xy 102.922819 -305.237455)
			(xy 102.887128 -305.278646) (xy 102.845937 -305.314337) (xy 102.800087 -305.343803) (xy 102.75051 -305.366445)
			(xy 102.698215 -305.3818) (xy 102.644267 -305.389556) (xy 102.589765 -305.389556) (xy 102.535817 -305.3818)
			(xy 102.483522 -305.366445) (xy 102.433945 -305.343803) (xy 102.388095 -305.314337) (xy 102.346904 -305.278646)
			(xy 102.311213 -305.237455) (xy 102.281747 -305.191605) (xy 102.259105 -305.142028) (xy 102.24375 -305.089733)
			(xy 102.235994 -305.035785) (xy 102.235508 -305.008534) (xy 93.445679 -305.008534) (xy 93.447107 -305.01824)
			(xy 93.447616 -305.046126) (xy 93.447107 -305.074012) (xy 93.438987 -305.129188) (xy 93.422919 -305.182595)
			(xy 93.399247 -305.233092) (xy 93.368474 -305.279605) (xy 93.331257 -305.321142) (xy 93.288389 -305.356817)
			(xy 93.240783 -305.385871) (xy 93.189454 -305.407683) (xy 93.135497 -305.421789) (xy 93.08006 -305.427889)
			(xy 93.024326 -305.425852) (xy 92.969483 -305.415722) (xy 92.916699 -305.397715) (xy 92.867099 -305.372214)
			(xy 92.821741 -305.339763) (xy 92.781592 -305.301054) (xy 92.747506 -305.256911) (xy 92.72021 -305.208276)
			(xy 92.700287 -305.156185) (xy 92.688161 -305.101748) (xy 92.68409 -305.046126) (xy 92.431291 -305.046126)
			(xy 92.431616 -305.063906) (xy 92.431107 -305.091792) (xy 92.422987 -305.146968) (xy 92.406919 -305.200375)
			(xy 92.383247 -305.250872) (xy 92.352474 -305.297385) (xy 92.315257 -305.338922) (xy 92.272389 -305.374597)
			(xy 92.224783 -305.403651) (xy 92.173454 -305.425463) (xy 92.119497 -305.439569) (xy 92.06406 -305.445669)
			(xy 92.008326 -305.443632) (xy 91.953483 -305.433502) (xy 91.900699 -305.415495) (xy 91.851099 -305.389994)
			(xy 91.805741 -305.357543) (xy 91.765592 -305.318834) (xy 91.731506 -305.274691) (xy 91.70421 -305.226056)
			(xy 91.684287 -305.173965) (xy 91.672161 -305.119528) (xy 91.66809 -305.063906) (xy 91.406961 -305.063906)
			(xy 91.40698 -305.064922) (xy 91.406471 -305.092808) (xy 91.398351 -305.147984) (xy 91.382283 -305.201391)
			(xy 91.358611 -305.251888) (xy 91.327838 -305.298401) (xy 91.290621 -305.339938) (xy 91.247753 -305.375613)
			(xy 91.200147 -305.404667) (xy 91.148818 -305.426479) (xy 91.094861 -305.440585) (xy 91.039424 -305.446685)
			(xy 90.98369 -305.444648) (xy 90.928847 -305.434518) (xy 90.876063 -305.416511) (xy 90.826463 -305.39101)
			(xy 90.781105 -305.358559) (xy 90.740956 -305.31985) (xy 90.70687 -305.275707) (xy 90.679574 -305.227072)
			(xy 90.659651 -305.174981) (xy 90.647525 -305.120544) (xy 90.643454 -305.064922) (xy 90.3986 -305.064922)
			(xy 90.398091 -305.092808) (xy 90.389971 -305.147984) (xy 90.373903 -305.201391) (xy 90.350231 -305.251888)
			(xy 90.319458 -305.298401) (xy 90.282241 -305.339938) (xy 90.239373 -305.375613) (xy 90.191767 -305.404667)
			(xy 90.140438 -305.426479) (xy 90.086481 -305.440585) (xy 90.031044 -305.446685) (xy 89.97531 -305.444648)
			(xy 89.920467 -305.434518) (xy 89.867683 -305.416511) (xy 89.818083 -305.39101) (xy 89.772725 -305.358559)
			(xy 89.732576 -305.31985) (xy 89.69849 -305.275707) (xy 89.671194 -305.227072) (xy 89.651271 -305.174981)
			(xy 89.639145 -305.120544) (xy 89.635074 -305.064922) (xy 89.383616 -305.064922) (xy 89.383107 -305.092808)
			(xy 89.374987 -305.147984) (xy 89.358919 -305.201391) (xy 89.335247 -305.251888) (xy 89.304474 -305.298401)
			(xy 89.267257 -305.339938) (xy 89.224389 -305.375613) (xy 89.176783 -305.404667) (xy 89.125454 -305.426479)
			(xy 89.071497 -305.440585) (xy 89.01606 -305.446685) (xy 88.960326 -305.444648) (xy 88.905483 -305.434518)
			(xy 88.852699 -305.416511) (xy 88.803099 -305.39101) (xy 88.757741 -305.358559) (xy 88.717592 -305.31985)
			(xy 88.683506 -305.275707) (xy 88.65621 -305.227072) (xy 88.636287 -305.174981) (xy 88.624161 -305.120544)
			(xy 88.62009 -305.064922) (xy 72.745493 -305.064922) (xy 72.733299 -305.088156) (xy 72.703734 -305.1275)
			(xy 72.668241 -305.161592) (xy 72.627738 -305.189548) (xy 72.583276 -305.210646) (xy 72.536005 -305.224338)
			(xy 72.48715 -305.23027) (xy 72.437975 -305.228289) (xy 72.389756 -305.218445) (xy 72.34374 -305.200993)
			(xy 72.301119 -305.176386) (xy 72.262998 -305.145261) (xy 72.230363 -305.108424) (xy 72.20406 -305.066828)
			(xy 72.184769 -305.021552) (xy 72.172992 -304.973768) (xy 72.169032 -304.924714) (xy 71.830184 -304.924714)
			(xy 71.829689 -304.949321) (xy 71.821794 -304.997898) (xy 71.80621 -305.044579) (xy 71.783339 -305.088156)
			(xy 71.753774 -305.1275) (xy 71.718281 -305.161592) (xy 71.677778 -305.189548) (xy 71.633316 -305.210646)
			(xy 71.586045 -305.224338) (xy 71.53719 -305.23027) (xy 71.488015 -305.228289) (xy 71.439796 -305.218445)
			(xy 71.39378 -305.200993) (xy 71.351159 -305.176386) (xy 71.313038 -305.145261) (xy 71.280403 -305.108424)
			(xy 71.2541 -305.066828) (xy 71.234809 -305.021552) (xy 71.223032 -304.973768) (xy 71.219072 -304.924714)
			(xy 70.880224 -304.924714) (xy 70.879729 -304.949321) (xy 70.871834 -304.997898) (xy 70.85625 -305.044579)
			(xy 70.833379 -305.088156) (xy 70.803814 -305.1275) (xy 70.768321 -305.161592) (xy 70.727818 -305.189548)
			(xy 70.683356 -305.210646) (xy 70.636085 -305.224338) (xy 70.58723 -305.23027) (xy 70.538055 -305.228289)
			(xy 70.489836 -305.218445) (xy 70.44382 -305.200993) (xy 70.401199 -305.176386) (xy 70.363078 -305.145261)
			(xy 70.330443 -305.108424) (xy 70.30414 -305.066828) (xy 70.284849 -305.021552) (xy 70.273072 -304.973768)
			(xy 70.269112 -304.924714) (xy 69.930264 -304.924714) (xy 69.929769 -304.949321) (xy 69.921874 -304.997898)
			(xy 69.90629 -305.044579) (xy 69.883419 -305.088156) (xy 69.853854 -305.1275) (xy 69.818361 -305.161592)
			(xy 69.777858 -305.189548) (xy 69.733396 -305.210646) (xy 69.686125 -305.224338) (xy 69.63727 -305.23027)
			(xy 69.588095 -305.228289) (xy 69.539876 -305.218445) (xy 69.49386 -305.200993) (xy 69.451239 -305.176386)
			(xy 69.413118 -305.145261) (xy 69.380483 -305.108424) (xy 69.35418 -305.066828) (xy 69.334889 -305.021552)
			(xy 69.323112 -304.973768) (xy 69.319152 -304.924714) (xy 68.98005 -304.924714) (xy 68.979555 -304.949321)
			(xy 68.97166 -304.997898) (xy 68.956076 -305.044579) (xy 68.933205 -305.088156) (xy 68.90364 -305.1275)
			(xy 68.868147 -305.161592) (xy 68.827644 -305.189548) (xy 68.783182 -305.210646) (xy 68.735911 -305.224338)
			(xy 68.687056 -305.23027) (xy 68.637881 -305.228289) (xy 68.589662 -305.218445) (xy 68.543646 -305.200993)
			(xy 68.501025 -305.176386) (xy 68.462904 -305.145261) (xy 68.430269 -305.108424) (xy 68.403966 -305.066828)
			(xy 68.384675 -305.021552) (xy 68.372898 -304.973768) (xy 68.368938 -304.924714) (xy 68.03009 -304.924714)
			(xy 68.029595 -304.949321) (xy 68.0217 -304.997898) (xy 68.006116 -305.044579) (xy 67.983245 -305.088156)
			(xy 67.95368 -305.1275) (xy 67.918187 -305.161592) (xy 67.877684 -305.189548) (xy 67.833222 -305.210646)
			(xy 67.785951 -305.224338) (xy 67.737096 -305.23027) (xy 67.687921 -305.228289) (xy 67.639702 -305.218445)
			(xy 67.593686 -305.200993) (xy 67.551065 -305.176386) (xy 67.512944 -305.145261) (xy 67.480309 -305.108424)
			(xy 67.454006 -305.066828) (xy 67.434715 -305.021552) (xy 67.422938 -304.973768) (xy 67.418978 -304.924714)
			(xy 67.08013 -304.924714) (xy 67.079635 -304.949321) (xy 67.07174 -304.997898) (xy 67.056156 -305.044579)
			(xy 67.033285 -305.088156) (xy 67.00372 -305.1275) (xy 66.968227 -305.161592) (xy 66.927724 -305.189548)
			(xy 66.883262 -305.210646) (xy 66.835991 -305.224338) (xy 66.787136 -305.23027) (xy 66.737961 -305.228289)
			(xy 66.689742 -305.218445) (xy 66.643726 -305.200993) (xy 66.601105 -305.176386) (xy 66.562984 -305.145261)
			(xy 66.530349 -305.108424) (xy 66.504046 -305.066828) (xy 66.484755 -305.021552) (xy 66.472978 -304.973768)
			(xy 66.469018 -304.924714) (xy 66.13017 -304.924714) (xy 66.129675 -304.949321) (xy 66.12178 -304.997898)
			(xy 66.106196 -305.044579) (xy 66.083325 -305.088156) (xy 66.05376 -305.1275) (xy 66.018267 -305.161592)
			(xy 65.977764 -305.189548) (xy 65.933302 -305.210646) (xy 65.886031 -305.224338) (xy 65.837176 -305.23027)
			(xy 65.788001 -305.228289) (xy 65.739782 -305.218445) (xy 65.693766 -305.200993) (xy 65.651145 -305.176386)
			(xy 65.613024 -305.145261) (xy 65.580389 -305.108424) (xy 65.554086 -305.066828) (xy 65.534795 -305.021552)
			(xy 65.523018 -304.973768) (xy 65.519058 -304.924714) (xy 65.18021 -304.924714) (xy 65.179715 -304.949321)
			(xy 65.17182 -304.997898) (xy 65.156236 -305.044579) (xy 65.133365 -305.088156) (xy 65.1038 -305.1275)
			(xy 65.068307 -305.161592) (xy 65.027804 -305.189548) (xy 64.983342 -305.210646) (xy 64.936071 -305.224338)
			(xy 64.887216 -305.23027) (xy 64.838041 -305.228289) (xy 64.789822 -305.218445) (xy 64.743806 -305.200993)
			(xy 64.701185 -305.176386) (xy 64.663064 -305.145261) (xy 64.630429 -305.108424) (xy 64.604126 -305.066828)
			(xy 64.584835 -305.021552) (xy 64.573058 -304.973768) (xy 64.569098 -304.924714) (xy 64.23025 -304.924714)
			(xy 64.229755 -304.949321) (xy 64.22186 -304.997898) (xy 64.206276 -305.044579) (xy 64.183405 -305.088156)
			(xy 64.15384 -305.1275) (xy 64.118347 -305.161592) (xy 64.077844 -305.189548) (xy 64.033382 -305.210646)
			(xy 63.986111 -305.224338) (xy 63.937256 -305.23027) (xy 63.888081 -305.228289) (xy 63.839862 -305.218445)
			(xy 63.793846 -305.200993) (xy 63.751225 -305.176386) (xy 63.713104 -305.145261) (xy 63.680469 -305.108424)
			(xy 63.654166 -305.066828) (xy 63.634875 -305.021552) (xy 63.623098 -304.973768) (xy 63.619138 -304.924714)
			(xy 63.28029 -304.924714) (xy 63.279795 -304.949321) (xy 63.2719 -304.997898) (xy 63.256316 -305.044579)
			(xy 63.233445 -305.088156) (xy 63.20388 -305.1275) (xy 63.168387 -305.161592) (xy 63.127884 -305.189548)
			(xy 63.083422 -305.210646) (xy 63.036151 -305.224338) (xy 62.987296 -305.23027) (xy 62.938121 -305.228289)
			(xy 62.889902 -305.218445) (xy 62.843886 -305.200993) (xy 62.801265 -305.176386) (xy 62.763144 -305.145261)
			(xy 62.730509 -305.108424) (xy 62.704206 -305.066828) (xy 62.684915 -305.021552) (xy 62.673138 -304.973768)
			(xy 62.669178 -304.924714) (xy 62.330076 -304.924714) (xy 62.329581 -304.949321) (xy 62.321686 -304.997898)
			(xy 62.306102 -305.044579) (xy 62.283231 -305.088156) (xy 62.253666 -305.1275) (xy 62.218173 -305.161592)
			(xy 62.17767 -305.189548) (xy 62.133208 -305.210646) (xy 62.085937 -305.224338) (xy 62.037082 -305.23027)
			(xy 61.987907 -305.228289) (xy 61.939688 -305.218445) (xy 61.893672 -305.200993) (xy 61.851051 -305.176386)
			(xy 61.81293 -305.145261) (xy 61.780295 -305.108424) (xy 61.753992 -305.066828) (xy 61.734701 -305.021552)
			(xy 61.722924 -304.973768) (xy 61.718964 -304.924714) (xy 61.380116 -304.924714) (xy 61.379621 -304.949321)
			(xy 61.371726 -304.997898) (xy 61.356142 -305.044579) (xy 61.333271 -305.088156) (xy 61.303706 -305.1275)
			(xy 61.268213 -305.161592) (xy 61.22771 -305.189548) (xy 61.183248 -305.210646) (xy 61.135977 -305.224338)
			(xy 61.087122 -305.23027) (xy 61.037947 -305.228289) (xy 60.989728 -305.218445) (xy 60.943712 -305.200993)
			(xy 60.901091 -305.176386) (xy 60.86297 -305.145261) (xy 60.830335 -305.108424) (xy 60.804032 -305.066828)
			(xy 60.784741 -305.021552) (xy 60.772964 -304.973768) (xy 60.769004 -304.924714) (xy 60.430156 -304.924714)
			(xy 60.429661 -304.949321) (xy 60.421766 -304.997898) (xy 60.406182 -305.044579) (xy 60.383311 -305.088156)
			(xy 60.353746 -305.1275) (xy 60.318253 -305.161592) (xy 60.27775 -305.189548) (xy 60.233288 -305.210646)
			(xy 60.186017 -305.224338) (xy 60.137162 -305.23027) (xy 60.087987 -305.228289) (xy 60.039768 -305.218445)
			(xy 59.993752 -305.200993) (xy 59.951131 -305.176386) (xy 59.91301 -305.145261) (xy 59.880375 -305.108424)
			(xy 59.854072 -305.066828) (xy 59.834781 -305.021552) (xy 59.823004 -304.973768) (xy 59.819044 -304.924714)
			(xy 58.530236 -304.924714) (xy 58.529741 -304.949321) (xy 58.521846 -304.997898) (xy 58.506262 -305.044579)
			(xy 58.483391 -305.088156) (xy 58.453826 -305.1275) (xy 58.418333 -305.161592) (xy 58.37783 -305.189548)
			(xy 58.333368 -305.210646) (xy 58.286097 -305.224338) (xy 58.237242 -305.23027) (xy 58.188067 -305.228289)
			(xy 58.139848 -305.218445) (xy 58.093832 -305.200993) (xy 58.051211 -305.176386) (xy 58.01309 -305.145261)
			(xy 57.980455 -305.108424) (xy 57.954152 -305.066828) (xy 57.934861 -305.021552) (xy 57.923084 -304.973768)
			(xy 57.919124 -304.924714) (xy 57.580276 -304.924714) (xy 57.579781 -304.949321) (xy 57.571886 -304.997898)
			(xy 57.556302 -305.044579) (xy 57.533431 -305.088156) (xy 57.503866 -305.1275) (xy 57.468373 -305.161592)
			(xy 57.42787 -305.189548) (xy 57.383408 -305.210646) (xy 57.336137 -305.224338) (xy 57.287282 -305.23027)
			(xy 57.238107 -305.228289) (xy 57.189888 -305.218445) (xy 57.143872 -305.200993) (xy 57.101251 -305.176386)
			(xy 57.06313 -305.145261) (xy 57.030495 -305.108424) (xy 57.004192 -305.066828) (xy 56.984901 -305.021552)
			(xy 56.973124 -304.973768) (xy 56.969164 -304.924714) (xy 56.630062 -304.924714) (xy 56.629567 -304.949321)
			(xy 56.621672 -304.997898) (xy 56.606088 -305.044579) (xy 56.583217 -305.088156) (xy 56.553652 -305.1275)
			(xy 56.518159 -305.161592) (xy 56.477656 -305.189548) (xy 56.433194 -305.210646) (xy 56.385923 -305.224338)
			(xy 56.337068 -305.23027) (xy 56.287893 -305.228289) (xy 56.239674 -305.218445) (xy 56.193658 -305.200993)
			(xy 56.151037 -305.176386) (xy 56.112916 -305.145261) (xy 56.080281 -305.108424) (xy 56.053978 -305.066828)
			(xy 56.034687 -305.021552) (xy 56.02291 -304.973768) (xy 56.01895 -304.924714) (xy 55.680102 -304.924714)
			(xy 55.679607 -304.949321) (xy 55.671712 -304.997898) (xy 55.656128 -305.044579) (xy 55.633257 -305.088156)
			(xy 55.603692 -305.1275) (xy 55.568199 -305.161592) (xy 55.527696 -305.189548) (xy 55.483234 -305.210646)
			(xy 55.435963 -305.224338) (xy 55.387108 -305.23027) (xy 55.337933 -305.228289) (xy 55.289714 -305.218445)
			(xy 55.243698 -305.200993) (xy 55.201077 -305.176386) (xy 55.162956 -305.145261) (xy 55.130321 -305.108424)
			(xy 55.104018 -305.066828) (xy 55.084727 -305.021552) (xy 55.07295 -304.973768) (xy 55.06899 -304.924714)
			(xy 54.730142 -304.924714) (xy 54.729647 -304.949321) (xy 54.721752 -304.997898) (xy 54.706168 -305.044579)
			(xy 54.683297 -305.088156) (xy 54.653732 -305.1275) (xy 54.618239 -305.161592) (xy 54.577736 -305.189548)
			(xy 54.533274 -305.210646) (xy 54.486003 -305.224338) (xy 54.437148 -305.23027) (xy 54.387973 -305.228289)
			(xy 54.339754 -305.218445) (xy 54.293738 -305.200993) (xy 54.251117 -305.176386) (xy 54.212996 -305.145261)
			(xy 54.180361 -305.108424) (xy 54.154058 -305.066828) (xy 54.134767 -305.021552) (xy 54.12299 -304.973768)
			(xy 54.11903 -304.924714) (xy 53.780182 -304.924714) (xy 53.779687 -304.949321) (xy 53.771792 -304.997898)
			(xy 53.756208 -305.044579) (xy 53.733337 -305.088156) (xy 53.703772 -305.1275) (xy 53.668279 -305.161592)
			(xy 53.627776 -305.189548) (xy 53.583314 -305.210646) (xy 53.536043 -305.224338) (xy 53.487188 -305.23027)
			(xy 53.438013 -305.228289) (xy 53.389794 -305.218445) (xy 53.343778 -305.200993) (xy 53.301157 -305.176386)
			(xy 53.263036 -305.145261) (xy 53.230401 -305.108424) (xy 53.204098 -305.066828) (xy 53.184807 -305.021552)
			(xy 53.17303 -304.973768) (xy 53.16907 -304.924714) (xy 52.830222 -304.924714) (xy 52.829727 -304.949321)
			(xy 52.821832 -304.997898) (xy 52.806248 -305.044579) (xy 52.783377 -305.088156) (xy 52.753812 -305.1275)
			(xy 52.718319 -305.161592) (xy 52.677816 -305.189548) (xy 52.633354 -305.210646) (xy 52.586083 -305.224338)
			(xy 52.537228 -305.23027) (xy 52.488053 -305.228289) (xy 52.439834 -305.218445) (xy 52.393818 -305.200993)
			(xy 52.351197 -305.176386) (xy 52.313076 -305.145261) (xy 52.280441 -305.108424) (xy 52.254138 -305.066828)
			(xy 52.234847 -305.021552) (xy 52.22307 -304.973768) (xy 52.21911 -304.924714) (xy 51.880262 -304.924714)
			(xy 51.879767 -304.949321) (xy 51.871872 -304.997898) (xy 51.856288 -305.044579) (xy 51.833417 -305.088156)
			(xy 51.803852 -305.1275) (xy 51.768359 -305.161592) (xy 51.727856 -305.189548) (xy 51.683394 -305.210646)
			(xy 51.636123 -305.224338) (xy 51.587268 -305.23027) (xy 51.538093 -305.228289) (xy 51.489874 -305.218445)
			(xy 51.443858 -305.200993) (xy 51.401237 -305.176386) (xy 51.363116 -305.145261) (xy 51.330481 -305.108424)
			(xy 51.304178 -305.066828) (xy 51.284887 -305.021552) (xy 51.27311 -304.973768) (xy 51.26915 -304.924714)
			(xy 50.930302 -304.924714) (xy 50.929807 -304.949321) (xy 50.921912 -304.997898) (xy 50.906328 -305.044579)
			(xy 50.883457 -305.088156) (xy 50.853892 -305.1275) (xy 50.818399 -305.161592) (xy 50.777896 -305.189548)
			(xy 50.733434 -305.210646) (xy 50.686163 -305.224338) (xy 50.637308 -305.23027) (xy 50.588133 -305.228289)
			(xy 50.539914 -305.218445) (xy 50.493898 -305.200993) (xy 50.451277 -305.176386) (xy 50.413156 -305.145261)
			(xy 50.380521 -305.108424) (xy 50.354218 -305.066828) (xy 50.334927 -305.021552) (xy 50.32315 -304.973768)
			(xy 50.31919 -304.924714) (xy 49.980088 -304.924714) (xy 49.979593 -304.949321) (xy 49.971698 -304.997898)
			(xy 49.956114 -305.044579) (xy 49.933243 -305.088156) (xy 49.903678 -305.1275) (xy 49.868185 -305.161592)
			(xy 49.827682 -305.189548) (xy 49.78322 -305.210646) (xy 49.735949 -305.224338) (xy 49.687094 -305.23027)
			(xy 49.637919 -305.228289) (xy 49.5897 -305.218445) (xy 49.543684 -305.200993) (xy 49.501063 -305.176386)
			(xy 49.462942 -305.145261) (xy 49.430307 -305.108424) (xy 49.404004 -305.066828) (xy 49.384713 -305.021552)
			(xy 49.372936 -304.973768) (xy 49.368976 -304.924714) (xy 49.030128 -304.924714) (xy 49.029633 -304.949321)
			(xy 49.021738 -304.997898) (xy 49.006154 -305.044579) (xy 48.983283 -305.088156) (xy 48.953718 -305.1275)
			(xy 48.918225 -305.161592) (xy 48.877722 -305.189548) (xy 48.83326 -305.210646) (xy 48.785989 -305.224338)
			(xy 48.737134 -305.23027) (xy 48.687959 -305.228289) (xy 48.63974 -305.218445) (xy 48.593724 -305.200993)
			(xy 48.551103 -305.176386) (xy 48.512982 -305.145261) (xy 48.480347 -305.108424) (xy 48.454044 -305.066828)
			(xy 48.434753 -305.021552) (xy 48.422976 -304.973768) (xy 48.419016 -304.924714) (xy 48.080168 -304.924714)
			(xy 48.079914 -304.935128) (xy 48.079914 -304.941478) (xy 48.07966 -304.94605) (xy 48.07966 -304.946812)
			(xy 48.078437 -304.961213) (xy 48.073604 -304.98971) (xy 48.070008 -305.003708) (xy 48.06823 -305.010312)
			(xy 48.06823 -305.399948) (xy 73.593972 -305.399948) (xy 73.597932 -305.350894) (xy 73.609709 -305.30311)
			(xy 73.629 -305.257834) (xy 73.655303 -305.216238) (xy 73.687938 -305.179401) (xy 73.726059 -305.148276)
			(xy 73.76868 -305.123669) (xy 73.814696 -305.106217) (xy 73.862915 -305.096373) (xy 73.91209 -305.094392)
			(xy 73.960945 -305.100324) (xy 74.008216 -305.114016) (xy 74.052678 -305.135114) (xy 74.093181 -305.16307)
			(xy 74.128674 -305.197162) (xy 74.158239 -305.236506) (xy 74.18111 -305.280083) (xy 74.196694 -305.326764)
			(xy 74.204589 -305.375341) (xy 74.205084 -305.399948) (xy 74.544186 -305.399948) (xy 74.548146 -305.350894)
			(xy 74.559923 -305.30311) (xy 74.579214 -305.257834) (xy 74.605517 -305.216238) (xy 74.638152 -305.179401)
			(xy 74.676273 -305.148276) (xy 74.718894 -305.123669) (xy 74.76491 -305.106217) (xy 74.813129 -305.096373)
			(xy 74.862304 -305.094392) (xy 74.911159 -305.100324) (xy 74.95843 -305.114016) (xy 75.002892 -305.135114)
			(xy 75.043395 -305.16307) (xy 75.078888 -305.197162) (xy 75.108453 -305.236506) (xy 75.131324 -305.280083)
			(xy 75.146908 -305.326764) (xy 75.154803 -305.375341) (xy 75.155298 -305.399948) (xy 75.494146 -305.399948)
			(xy 75.498106 -305.350894) (xy 75.509883 -305.30311) (xy 75.529174 -305.257834) (xy 75.555477 -305.216238)
			(xy 75.588112 -305.179401) (xy 75.626233 -305.148276) (xy 75.668854 -305.123669) (xy 75.71487 -305.106217)
			(xy 75.763089 -305.096373) (xy 75.812264 -305.094392) (xy 75.861119 -305.100324) (xy 75.90839 -305.114016)
			(xy 75.952852 -305.135114) (xy 75.993355 -305.16307) (xy 76.028848 -305.197162) (xy 76.058413 -305.236506)
			(xy 76.081284 -305.280083) (xy 76.096868 -305.326764) (xy 76.104763 -305.375341) (xy 76.105258 -305.399948)
			(xy 76.444106 -305.399948) (xy 76.448066 -305.350894) (xy 76.459843 -305.30311) (xy 76.479134 -305.257834)
			(xy 76.505437 -305.216238) (xy 76.538072 -305.179401) (xy 76.576193 -305.148276) (xy 76.618814 -305.123669)
			(xy 76.66483 -305.106217) (xy 76.713049 -305.096373) (xy 76.762224 -305.094392) (xy 76.811079 -305.100324)
			(xy 76.85835 -305.114016) (xy 76.902812 -305.135114) (xy 76.943315 -305.16307) (xy 76.978808 -305.197162)
			(xy 77.008373 -305.236506) (xy 77.031244 -305.280083) (xy 77.046828 -305.326764) (xy 77.054723 -305.375341)
			(xy 77.055218 -305.399948) (xy 77.394066 -305.399948) (xy 77.398026 -305.350894) (xy 77.409803 -305.30311)
			(xy 77.429094 -305.257834) (xy 77.455397 -305.216238) (xy 77.488032 -305.179401) (xy 77.526153 -305.148276)
			(xy 77.568774 -305.123669) (xy 77.61479 -305.106217) (xy 77.663009 -305.096373) (xy 77.712184 -305.094392)
			(xy 77.761039 -305.100324) (xy 77.80831 -305.114016) (xy 77.852772 -305.135114) (xy 77.893275 -305.16307)
			(xy 77.928768 -305.197162) (xy 77.958333 -305.236506) (xy 77.981204 -305.280083) (xy 77.996788 -305.326764)
			(xy 78.004683 -305.375341) (xy 78.005178 -305.399948) (xy 78.344026 -305.399948) (xy 78.347986 -305.350894)
			(xy 78.359763 -305.30311) (xy 78.379054 -305.257834) (xy 78.405357 -305.216238) (xy 78.437992 -305.179401)
			(xy 78.476113 -305.148276) (xy 78.518734 -305.123669) (xy 78.56475 -305.106217) (xy 78.612969 -305.096373)
			(xy 78.662144 -305.094392) (xy 78.710999 -305.100324) (xy 78.75827 -305.114016) (xy 78.802732 -305.135114)
			(xy 78.843235 -305.16307) (xy 78.878728 -305.197162) (xy 78.908293 -305.236506) (xy 78.931164 -305.280083)
			(xy 78.946748 -305.326764) (xy 78.954643 -305.375341) (xy 78.955138 -305.399948) (xy 79.293986 -305.399948)
			(xy 79.297946 -305.350894) (xy 79.309723 -305.30311) (xy 79.329014 -305.257834) (xy 79.355317 -305.216238)
			(xy 79.387952 -305.179401) (xy 79.426073 -305.148276) (xy 79.468694 -305.123669) (xy 79.51471 -305.106217)
			(xy 79.562929 -305.096373) (xy 79.612104 -305.094392) (xy 79.660959 -305.100324) (xy 79.70823 -305.114016)
			(xy 79.752692 -305.135114) (xy 79.793195 -305.16307) (xy 79.828688 -305.197162) (xy 79.858253 -305.236506)
			(xy 79.881124 -305.280083) (xy 79.896708 -305.326764) (xy 79.904603 -305.375341) (xy 79.905098 -305.399948)
			(xy 80.243946 -305.399948) (xy 80.247906 -305.350894) (xy 80.259683 -305.30311) (xy 80.278974 -305.257834)
			(xy 80.305277 -305.216238) (xy 80.337912 -305.179401) (xy 80.376033 -305.148276) (xy 80.418654 -305.123669)
			(xy 80.46467 -305.106217) (xy 80.512889 -305.096373) (xy 80.562064 -305.094392) (xy 80.610919 -305.100324)
			(xy 80.65819 -305.114016) (xy 80.702652 -305.135114) (xy 80.743155 -305.16307) (xy 80.778648 -305.197162)
			(xy 80.808213 -305.236506) (xy 80.831084 -305.280083) (xy 80.846668 -305.326764) (xy 80.854563 -305.375341)
			(xy 80.855058 -305.399948) (xy 81.19416 -305.399948) (xy 81.19812 -305.350894) (xy 81.209897 -305.30311)
			(xy 81.229188 -305.257834) (xy 81.255491 -305.216238) (xy 81.288126 -305.179401) (xy 81.326247 -305.148276)
			(xy 81.368868 -305.123669) (xy 81.414884 -305.106217) (xy 81.463103 -305.096373) (xy 81.512278 -305.094392)
			(xy 81.561133 -305.100324) (xy 81.608404 -305.114016) (xy 81.652866 -305.135114) (xy 81.693369 -305.16307)
			(xy 81.728862 -305.197162) (xy 81.758427 -305.236506) (xy 81.781298 -305.280083) (xy 81.796882 -305.326764)
			(xy 81.804777 -305.375341) (xy 81.805272 -305.399948) (xy 82.14412 -305.399948) (xy 82.14808 -305.350894)
			(xy 82.159857 -305.30311) (xy 82.179148 -305.257834) (xy 82.205451 -305.216238) (xy 82.238086 -305.179401)
			(xy 82.276207 -305.148276) (xy 82.318828 -305.123669) (xy 82.364844 -305.106217) (xy 82.413063 -305.096373)
			(xy 82.462238 -305.094392) (xy 82.511093 -305.100324) (xy 82.558364 -305.114016) (xy 82.602826 -305.135114)
			(xy 82.643329 -305.16307) (xy 82.678822 -305.197162) (xy 82.708387 -305.236506) (xy 82.731258 -305.280083)
			(xy 82.746842 -305.326764) (xy 82.754737 -305.375341) (xy 82.755232 -305.399948) (xy 82.754737 -305.424555)
			(xy 82.746842 -305.473132) (xy 82.731258 -305.519813) (xy 82.708387 -305.56339) (xy 82.678822 -305.602734)
			(xy 82.643329 -305.636826) (xy 82.602826 -305.664782) (xy 82.558364 -305.68588) (xy 82.511093 -305.699572)
			(xy 82.462238 -305.705504) (xy 82.413063 -305.703523) (xy 82.364844 -305.693679) (xy 82.318828 -305.676227)
			(xy 82.276207 -305.65162) (xy 82.238086 -305.620495) (xy 82.205451 -305.583658) (xy 82.179148 -305.542062)
			(xy 82.159857 -305.496786) (xy 82.14808 -305.449002) (xy 82.14412 -305.399948) (xy 81.805272 -305.399948)
			(xy 81.804777 -305.424555) (xy 81.796882 -305.473132) (xy 81.781298 -305.519813) (xy 81.758427 -305.56339)
			(xy 81.728862 -305.602734) (xy 81.693369 -305.636826) (xy 81.652866 -305.664782) (xy 81.608404 -305.68588)
			(xy 81.561133 -305.699572) (xy 81.512278 -305.705504) (xy 81.463103 -305.703523) (xy 81.414884 -305.693679)
			(xy 81.368868 -305.676227) (xy 81.326247 -305.65162) (xy 81.288126 -305.620495) (xy 81.255491 -305.583658)
			(xy 81.229188 -305.542062) (xy 81.209897 -305.496786) (xy 81.19812 -305.449002) (xy 81.19416 -305.399948)
			(xy 80.855058 -305.399948) (xy 80.854563 -305.424555) (xy 80.846668 -305.473132) (xy 80.831084 -305.519813)
			(xy 80.808213 -305.56339) (xy 80.778648 -305.602734) (xy 80.743155 -305.636826) (xy 80.702652 -305.664782)
			(xy 80.65819 -305.68588) (xy 80.610919 -305.699572) (xy 80.562064 -305.705504) (xy 80.512889 -305.703523)
			(xy 80.46467 -305.693679) (xy 80.418654 -305.676227) (xy 80.376033 -305.65162) (xy 80.337912 -305.620495)
			(xy 80.305277 -305.583658) (xy 80.278974 -305.542062) (xy 80.259683 -305.496786) (xy 80.247906 -305.449002)
			(xy 80.243946 -305.399948) (xy 79.905098 -305.399948) (xy 79.904603 -305.424555) (xy 79.896708 -305.473132)
			(xy 79.881124 -305.519813) (xy 79.858253 -305.56339) (xy 79.828688 -305.602734) (xy 79.793195 -305.636826)
			(xy 79.752692 -305.664782) (xy 79.70823 -305.68588) (xy 79.660959 -305.699572) (xy 79.612104 -305.705504)
			(xy 79.562929 -305.703523) (xy 79.51471 -305.693679) (xy 79.468694 -305.676227) (xy 79.426073 -305.65162)
			(xy 79.387952 -305.620495) (xy 79.355317 -305.583658) (xy 79.329014 -305.542062) (xy 79.309723 -305.496786)
			(xy 79.297946 -305.449002) (xy 79.293986 -305.399948) (xy 78.955138 -305.399948) (xy 78.954643 -305.424555)
			(xy 78.946748 -305.473132) (xy 78.931164 -305.519813) (xy 78.908293 -305.56339) (xy 78.878728 -305.602734)
			(xy 78.843235 -305.636826) (xy 78.802732 -305.664782) (xy 78.75827 -305.68588) (xy 78.710999 -305.699572)
			(xy 78.662144 -305.705504) (xy 78.612969 -305.703523) (xy 78.56475 -305.693679) (xy 78.518734 -305.676227)
			(xy 78.476113 -305.65162) (xy 78.437992 -305.620495) (xy 78.405357 -305.583658) (xy 78.379054 -305.542062)
			(xy 78.359763 -305.496786) (xy 78.347986 -305.449002) (xy 78.344026 -305.399948) (xy 78.005178 -305.399948)
			(xy 78.004683 -305.424555) (xy 77.996788 -305.473132) (xy 77.981204 -305.519813) (xy 77.958333 -305.56339)
			(xy 77.928768 -305.602734) (xy 77.893275 -305.636826) (xy 77.852772 -305.664782) (xy 77.80831 -305.68588)
			(xy 77.761039 -305.699572) (xy 77.712184 -305.705504) (xy 77.663009 -305.703523) (xy 77.61479 -305.693679)
			(xy 77.568774 -305.676227) (xy 77.526153 -305.65162) (xy 77.488032 -305.620495) (xy 77.455397 -305.583658)
			(xy 77.429094 -305.542062) (xy 77.409803 -305.496786) (xy 77.398026 -305.449002) (xy 77.394066 -305.399948)
			(xy 77.055218 -305.399948) (xy 77.054723 -305.424555) (xy 77.046828 -305.473132) (xy 77.031244 -305.519813)
			(xy 77.008373 -305.56339) (xy 76.978808 -305.602734) (xy 76.943315 -305.636826) (xy 76.902812 -305.664782)
			(xy 76.85835 -305.68588) (xy 76.811079 -305.699572) (xy 76.762224 -305.705504) (xy 76.713049 -305.703523)
			(xy 76.66483 -305.693679) (xy 76.618814 -305.676227) (xy 76.576193 -305.65162) (xy 76.538072 -305.620495)
			(xy 76.505437 -305.583658) (xy 76.479134 -305.542062) (xy 76.459843 -305.496786) (xy 76.448066 -305.449002)
			(xy 76.444106 -305.399948) (xy 76.105258 -305.399948) (xy 76.104763 -305.424555) (xy 76.096868 -305.473132)
			(xy 76.081284 -305.519813) (xy 76.058413 -305.56339) (xy 76.028848 -305.602734) (xy 75.993355 -305.636826)
			(xy 75.952852 -305.664782) (xy 75.90839 -305.68588) (xy 75.861119 -305.699572) (xy 75.812264 -305.705504)
			(xy 75.763089 -305.703523) (xy 75.71487 -305.693679) (xy 75.668854 -305.676227) (xy 75.626233 -305.65162)
			(xy 75.588112 -305.620495) (xy 75.555477 -305.583658) (xy 75.529174 -305.542062) (xy 75.509883 -305.496786)
			(xy 75.498106 -305.449002) (xy 75.494146 -305.399948) (xy 75.155298 -305.399948) (xy 75.154803 -305.424555)
			(xy 75.146908 -305.473132) (xy 75.131324 -305.519813) (xy 75.108453 -305.56339) (xy 75.078888 -305.602734)
			(xy 75.043395 -305.636826) (xy 75.002892 -305.664782) (xy 74.95843 -305.68588) (xy 74.911159 -305.699572)
			(xy 74.862304 -305.705504) (xy 74.813129 -305.703523) (xy 74.76491 -305.693679) (xy 74.718894 -305.676227)
			(xy 74.676273 -305.65162) (xy 74.638152 -305.620495) (xy 74.605517 -305.583658) (xy 74.579214 -305.542062)
			(xy 74.559923 -305.496786) (xy 74.548146 -305.449002) (xy 74.544186 -305.399948) (xy 74.205084 -305.399948)
			(xy 74.204589 -305.424555) (xy 74.196694 -305.473132) (xy 74.18111 -305.519813) (xy 74.158239 -305.56339)
			(xy 74.128674 -305.602734) (xy 74.093181 -305.636826) (xy 74.052678 -305.664782) (xy 74.008216 -305.68588)
			(xy 73.960945 -305.699572) (xy 73.91209 -305.705504) (xy 73.862915 -305.703523) (xy 73.814696 -305.693679)
			(xy 73.76868 -305.676227) (xy 73.726059 -305.65162) (xy 73.687938 -305.620495) (xy 73.655303 -305.583658)
			(xy 73.629 -305.542062) (xy 73.609709 -305.496786) (xy 73.597932 -305.449002) (xy 73.593972 -305.399948)
			(xy 48.06823 -305.399948) (xy 48.06823 -305.783488) (xy 48.070008 -305.796696) (xy 48.07077 -305.799744)
			(xy 48.075169 -305.818228) (xy 48.079884 -305.85593) (xy 48.080168 -305.874928) (xy 48.419016 -305.874928)
			(xy 48.422976 -305.825874) (xy 48.434753 -305.77809) (xy 48.454044 -305.732814) (xy 48.480347 -305.691218)
			(xy 48.512982 -305.654381) (xy 48.551103 -305.623256) (xy 48.593724 -305.598649) (xy 48.63974 -305.581197)
			(xy 48.687959 -305.571353) (xy 48.737134 -305.569372) (xy 48.785989 -305.575304) (xy 48.83326 -305.588996)
			(xy 48.877722 -305.610094) (xy 48.918225 -305.63805) (xy 48.953718 -305.672142) (xy 48.983283 -305.711486)
			(xy 49.006154 -305.755063) (xy 49.021738 -305.801744) (xy 49.029633 -305.850321) (xy 49.030128 -305.874928)
			(xy 49.368976 -305.874928) (xy 49.372936 -305.825874) (xy 49.384713 -305.77809) (xy 49.404004 -305.732814)
			(xy 49.430307 -305.691218) (xy 49.462942 -305.654381) (xy 49.501063 -305.623256) (xy 49.543684 -305.598649)
			(xy 49.5897 -305.581197) (xy 49.637919 -305.571353) (xy 49.687094 -305.569372) (xy 49.735949 -305.575304)
			(xy 49.78322 -305.588996) (xy 49.827682 -305.610094) (xy 49.868185 -305.63805) (xy 49.903678 -305.672142)
			(xy 49.933243 -305.711486) (xy 49.956114 -305.755063) (xy 49.971698 -305.801744) (xy 49.979593 -305.850321)
			(xy 49.980088 -305.874928) (xy 50.31919 -305.874928) (xy 50.32315 -305.825874) (xy 50.334927 -305.77809)
			(xy 50.354218 -305.732814) (xy 50.380521 -305.691218) (xy 50.413156 -305.654381) (xy 50.451277 -305.623256)
			(xy 50.493898 -305.598649) (xy 50.539914 -305.581197) (xy 50.588133 -305.571353) (xy 50.637308 -305.569372)
			(xy 50.686163 -305.575304) (xy 50.733434 -305.588996) (xy 50.777896 -305.610094) (xy 50.818399 -305.63805)
			(xy 50.853892 -305.672142) (xy 50.883457 -305.711486) (xy 50.906328 -305.755063) (xy 50.921912 -305.801744)
			(xy 50.929807 -305.850321) (xy 50.930302 -305.874928) (xy 51.26915 -305.874928) (xy 51.27311 -305.825874)
			(xy 51.284887 -305.77809) (xy 51.304178 -305.732814) (xy 51.330481 -305.691218) (xy 51.363116 -305.654381)
			(xy 51.401237 -305.623256) (xy 51.443858 -305.598649) (xy 51.489874 -305.581197) (xy 51.538093 -305.571353)
			(xy 51.587268 -305.569372) (xy 51.636123 -305.575304) (xy 51.683394 -305.588996) (xy 51.727856 -305.610094)
			(xy 51.768359 -305.63805) (xy 51.803852 -305.672142) (xy 51.833417 -305.711486) (xy 51.856288 -305.755063)
			(xy 51.871872 -305.801744) (xy 51.879767 -305.850321) (xy 51.880262 -305.874928) (xy 52.21911 -305.874928)
			(xy 52.22307 -305.825874) (xy 52.234847 -305.77809) (xy 52.254138 -305.732814) (xy 52.280441 -305.691218)
			(xy 52.313076 -305.654381) (xy 52.351197 -305.623256) (xy 52.393818 -305.598649) (xy 52.439834 -305.581197)
			(xy 52.488053 -305.571353) (xy 52.537228 -305.569372) (xy 52.586083 -305.575304) (xy 52.633354 -305.588996)
			(xy 52.677816 -305.610094) (xy 52.718319 -305.63805) (xy 52.753812 -305.672142) (xy 52.783377 -305.711486)
			(xy 52.806248 -305.755063) (xy 52.821832 -305.801744) (xy 52.829727 -305.850321) (xy 52.830222 -305.874928)
			(xy 53.16907 -305.874928) (xy 53.17303 -305.825874) (xy 53.184807 -305.77809) (xy 53.204098 -305.732814)
			(xy 53.230401 -305.691218) (xy 53.263036 -305.654381) (xy 53.301157 -305.623256) (xy 53.343778 -305.598649)
			(xy 53.389794 -305.581197) (xy 53.438013 -305.571353) (xy 53.487188 -305.569372) (xy 53.536043 -305.575304)
			(xy 53.583314 -305.588996) (xy 53.627776 -305.610094) (xy 53.668279 -305.63805) (xy 53.703772 -305.672142)
			(xy 53.733337 -305.711486) (xy 53.756208 -305.755063) (xy 53.771792 -305.801744) (xy 53.779687 -305.850321)
			(xy 53.780182 -305.874928) (xy 54.11903 -305.874928) (xy 54.12299 -305.825874) (xy 54.134767 -305.77809)
			(xy 54.154058 -305.732814) (xy 54.180361 -305.691218) (xy 54.212996 -305.654381) (xy 54.251117 -305.623256)
			(xy 54.293738 -305.598649) (xy 54.339754 -305.581197) (xy 54.387973 -305.571353) (xy 54.437148 -305.569372)
			(xy 54.486003 -305.575304) (xy 54.533274 -305.588996) (xy 54.577736 -305.610094) (xy 54.618239 -305.63805)
			(xy 54.653732 -305.672142) (xy 54.683297 -305.711486) (xy 54.706168 -305.755063) (xy 54.721752 -305.801744)
			(xy 54.729647 -305.850321) (xy 54.730142 -305.874928) (xy 55.06899 -305.874928) (xy 55.07295 -305.825874)
			(xy 55.084727 -305.77809) (xy 55.104018 -305.732814) (xy 55.130321 -305.691218) (xy 55.162956 -305.654381)
			(xy 55.201077 -305.623256) (xy 55.243698 -305.598649) (xy 55.289714 -305.581197) (xy 55.337933 -305.571353)
			(xy 55.387108 -305.569372) (xy 55.435963 -305.575304) (xy 55.483234 -305.588996) (xy 55.527696 -305.610094)
			(xy 55.568199 -305.63805) (xy 55.603692 -305.672142) (xy 55.633257 -305.711486) (xy 55.656128 -305.755063)
			(xy 55.671712 -305.801744) (xy 55.679607 -305.850321) (xy 55.680102 -305.874928) (xy 56.01895 -305.874928)
			(xy 56.02291 -305.825874) (xy 56.034687 -305.77809) (xy 56.053978 -305.732814) (xy 56.080281 -305.691218)
			(xy 56.112916 -305.654381) (xy 56.151037 -305.623256) (xy 56.193658 -305.598649) (xy 56.239674 -305.581197)
			(xy 56.287893 -305.571353) (xy 56.337068 -305.569372) (xy 56.385923 -305.575304) (xy 56.433194 -305.588996)
			(xy 56.477656 -305.610094) (xy 56.518159 -305.63805) (xy 56.553652 -305.672142) (xy 56.583217 -305.711486)
			(xy 56.606088 -305.755063) (xy 56.621672 -305.801744) (xy 56.629567 -305.850321) (xy 56.630062 -305.874928)
			(xy 56.969164 -305.874928) (xy 56.973124 -305.825874) (xy 56.984901 -305.77809) (xy 57.004192 -305.732814)
			(xy 57.030495 -305.691218) (xy 57.06313 -305.654381) (xy 57.101251 -305.623256) (xy 57.143872 -305.598649)
			(xy 57.189888 -305.581197) (xy 57.238107 -305.571353) (xy 57.287282 -305.569372) (xy 57.336137 -305.575304)
			(xy 57.383408 -305.588996) (xy 57.42787 -305.610094) (xy 57.468373 -305.63805) (xy 57.503866 -305.672142)
			(xy 57.533431 -305.711486) (xy 57.556302 -305.755063) (xy 57.571886 -305.801744) (xy 57.579781 -305.850321)
			(xy 57.580276 -305.874928) (xy 57.919124 -305.874928) (xy 57.923084 -305.825874) (xy 57.934861 -305.77809)
			(xy 57.954152 -305.732814) (xy 57.980455 -305.691218) (xy 58.01309 -305.654381) (xy 58.051211 -305.623256)
			(xy 58.093832 -305.598649) (xy 58.139848 -305.581197) (xy 58.188067 -305.571353) (xy 58.237242 -305.569372)
			(xy 58.286097 -305.575304) (xy 58.333368 -305.588996) (xy 58.37783 -305.610094) (xy 58.418333 -305.63805)
			(xy 58.453826 -305.672142) (xy 58.483391 -305.711486) (xy 58.506262 -305.755063) (xy 58.521846 -305.801744)
			(xy 58.529741 -305.850321) (xy 58.530236 -305.874928) (xy 59.819044 -305.874928) (xy 59.823004 -305.825874)
			(xy 59.834781 -305.77809) (xy 59.854072 -305.732814) (xy 59.880375 -305.691218) (xy 59.91301 -305.654381)
			(xy 59.951131 -305.623256) (xy 59.993752 -305.598649) (xy 60.039768 -305.581197) (xy 60.087987 -305.571353)
			(xy 60.137162 -305.569372) (xy 60.186017 -305.575304) (xy 60.233288 -305.588996) (xy 60.27775 -305.610094)
			(xy 60.318253 -305.63805) (xy 60.353746 -305.672142) (xy 60.383311 -305.711486) (xy 60.406182 -305.755063)
			(xy 60.421766 -305.801744) (xy 60.429661 -305.850321) (xy 60.430156 -305.874928) (xy 60.769004 -305.874928)
			(xy 60.772964 -305.825874) (xy 60.784741 -305.77809) (xy 60.804032 -305.732814) (xy 60.830335 -305.691218)
			(xy 60.86297 -305.654381) (xy 60.901091 -305.623256) (xy 60.943712 -305.598649) (xy 60.989728 -305.581197)
			(xy 61.037947 -305.571353) (xy 61.087122 -305.569372) (xy 61.135977 -305.575304) (xy 61.183248 -305.588996)
			(xy 61.22771 -305.610094) (xy 61.268213 -305.63805) (xy 61.303706 -305.672142) (xy 61.333271 -305.711486)
			(xy 61.356142 -305.755063) (xy 61.371726 -305.801744) (xy 61.379621 -305.850321) (xy 61.380116 -305.874928)
			(xy 61.718964 -305.874928) (xy 61.722924 -305.825874) (xy 61.734701 -305.77809) (xy 61.753992 -305.732814)
			(xy 61.780295 -305.691218) (xy 61.81293 -305.654381) (xy 61.851051 -305.623256) (xy 61.893672 -305.598649)
			(xy 61.939688 -305.581197) (xy 61.987907 -305.571353) (xy 62.037082 -305.569372) (xy 62.085937 -305.575304)
			(xy 62.133208 -305.588996) (xy 62.17767 -305.610094) (xy 62.218173 -305.63805) (xy 62.253666 -305.672142)
			(xy 62.283231 -305.711486) (xy 62.306102 -305.755063) (xy 62.321686 -305.801744) (xy 62.329581 -305.850321)
			(xy 62.330076 -305.874928) (xy 62.669178 -305.874928) (xy 62.673138 -305.825874) (xy 62.684915 -305.77809)
			(xy 62.704206 -305.732814) (xy 62.730509 -305.691218) (xy 62.763144 -305.654381) (xy 62.801265 -305.623256)
			(xy 62.843886 -305.598649) (xy 62.889902 -305.581197) (xy 62.938121 -305.571353) (xy 62.987296 -305.569372)
			(xy 63.036151 -305.575304) (xy 63.083422 -305.588996) (xy 63.127884 -305.610094) (xy 63.168387 -305.63805)
			(xy 63.20388 -305.672142) (xy 63.233445 -305.711486) (xy 63.256316 -305.755063) (xy 63.2719 -305.801744)
			(xy 63.279795 -305.850321) (xy 63.28029 -305.874928) (xy 63.619138 -305.874928) (xy 63.623098 -305.825874)
			(xy 63.634875 -305.77809) (xy 63.654166 -305.732814) (xy 63.680469 -305.691218) (xy 63.713104 -305.654381)
			(xy 63.751225 -305.623256) (xy 63.793846 -305.598649) (xy 63.839862 -305.581197) (xy 63.888081 -305.571353)
			(xy 63.937256 -305.569372) (xy 63.986111 -305.575304) (xy 64.033382 -305.588996) (xy 64.077844 -305.610094)
			(xy 64.118347 -305.63805) (xy 64.15384 -305.672142) (xy 64.183405 -305.711486) (xy 64.206276 -305.755063)
			(xy 64.22186 -305.801744) (xy 64.229755 -305.850321) (xy 64.23025 -305.874928) (xy 64.569098 -305.874928)
			(xy 64.573058 -305.825874) (xy 64.584835 -305.77809) (xy 64.604126 -305.732814) (xy 64.630429 -305.691218)
			(xy 64.663064 -305.654381) (xy 64.701185 -305.623256) (xy 64.743806 -305.598649) (xy 64.789822 -305.581197)
			(xy 64.838041 -305.571353) (xy 64.887216 -305.569372) (xy 64.936071 -305.575304) (xy 64.983342 -305.588996)
			(xy 65.027804 -305.610094) (xy 65.068307 -305.63805) (xy 65.1038 -305.672142) (xy 65.133365 -305.711486)
			(xy 65.156236 -305.755063) (xy 65.17182 -305.801744) (xy 65.179715 -305.850321) (xy 65.18021 -305.874928)
			(xy 65.519058 -305.874928) (xy 65.523018 -305.825874) (xy 65.534795 -305.77809) (xy 65.554086 -305.732814)
			(xy 65.580389 -305.691218) (xy 65.613024 -305.654381) (xy 65.651145 -305.623256) (xy 65.693766 -305.598649)
			(xy 65.739782 -305.581197) (xy 65.788001 -305.571353) (xy 65.837176 -305.569372) (xy 65.886031 -305.575304)
			(xy 65.933302 -305.588996) (xy 65.977764 -305.610094) (xy 66.018267 -305.63805) (xy 66.05376 -305.672142)
			(xy 66.083325 -305.711486) (xy 66.106196 -305.755063) (xy 66.12178 -305.801744) (xy 66.129675 -305.850321)
			(xy 66.13017 -305.874928) (xy 66.469018 -305.874928) (xy 66.472978 -305.825874) (xy 66.484755 -305.77809)
			(xy 66.504046 -305.732814) (xy 66.530349 -305.691218) (xy 66.562984 -305.654381) (xy 66.601105 -305.623256)
			(xy 66.643726 -305.598649) (xy 66.689742 -305.581197) (xy 66.737961 -305.571353) (xy 66.787136 -305.569372)
			(xy 66.835991 -305.575304) (xy 66.883262 -305.588996) (xy 66.927724 -305.610094) (xy 66.968227 -305.63805)
			(xy 67.00372 -305.672142) (xy 67.033285 -305.711486) (xy 67.056156 -305.755063) (xy 67.07174 -305.801744)
			(xy 67.079635 -305.850321) (xy 67.08013 -305.874928) (xy 67.418978 -305.874928) (xy 67.422938 -305.825874)
			(xy 67.434715 -305.77809) (xy 67.454006 -305.732814) (xy 67.480309 -305.691218) (xy 67.512944 -305.654381)
			(xy 67.551065 -305.623256) (xy 67.593686 -305.598649) (xy 67.639702 -305.581197) (xy 67.687921 -305.571353)
			(xy 67.737096 -305.569372) (xy 67.785951 -305.575304) (xy 67.833222 -305.588996) (xy 67.877684 -305.610094)
			(xy 67.918187 -305.63805) (xy 67.95368 -305.672142) (xy 67.983245 -305.711486) (xy 68.006116 -305.755063)
			(xy 68.0217 -305.801744) (xy 68.029595 -305.850321) (xy 68.03009 -305.874928) (xy 68.368938 -305.874928)
			(xy 68.372898 -305.825874) (xy 68.384675 -305.77809) (xy 68.403966 -305.732814) (xy 68.430269 -305.691218)
			(xy 68.462904 -305.654381) (xy 68.501025 -305.623256) (xy 68.543646 -305.598649) (xy 68.589662 -305.581197)
			(xy 68.637881 -305.571353) (xy 68.687056 -305.569372) (xy 68.735911 -305.575304) (xy 68.783182 -305.588996)
			(xy 68.827644 -305.610094) (xy 68.868147 -305.63805) (xy 68.90364 -305.672142) (xy 68.933205 -305.711486)
			(xy 68.956076 -305.755063) (xy 68.97166 -305.801744) (xy 68.979555 -305.850321) (xy 68.98005 -305.874928)
			(xy 69.319152 -305.874928) (xy 69.323112 -305.825874) (xy 69.334889 -305.77809) (xy 69.35418 -305.732814)
			(xy 69.380483 -305.691218) (xy 69.413118 -305.654381) (xy 69.451239 -305.623256) (xy 69.49386 -305.598649)
			(xy 69.539876 -305.581197) (xy 69.588095 -305.571353) (xy 69.63727 -305.569372) (xy 69.686125 -305.575304)
			(xy 69.733396 -305.588996) (xy 69.777858 -305.610094) (xy 69.818361 -305.63805) (xy 69.853854 -305.672142)
			(xy 69.883419 -305.711486) (xy 69.90629 -305.755063) (xy 69.921874 -305.801744) (xy 69.929769 -305.850321)
			(xy 69.930264 -305.874928) (xy 70.269112 -305.874928) (xy 70.273072 -305.825874) (xy 70.284849 -305.77809)
			(xy 70.30414 -305.732814) (xy 70.330443 -305.691218) (xy 70.363078 -305.654381) (xy 70.401199 -305.623256)
			(xy 70.44382 -305.598649) (xy 70.489836 -305.581197) (xy 70.538055 -305.571353) (xy 70.58723 -305.569372)
			(xy 70.636085 -305.575304) (xy 70.683356 -305.588996) (xy 70.727818 -305.610094) (xy 70.768321 -305.63805)
			(xy 70.803814 -305.672142) (xy 70.833379 -305.711486) (xy 70.85625 -305.755063) (xy 70.871834 -305.801744)
			(xy 70.879729 -305.850321) (xy 70.880224 -305.874928) (xy 71.219072 -305.874928) (xy 71.223032 -305.825874)
			(xy 71.234809 -305.77809) (xy 71.2541 -305.732814) (xy 71.280403 -305.691218) (xy 71.313038 -305.654381)
			(xy 71.351159 -305.623256) (xy 71.39378 -305.598649) (xy 71.439796 -305.581197) (xy 71.488015 -305.571353)
			(xy 71.53719 -305.569372) (xy 71.586045 -305.575304) (xy 71.633316 -305.588996) (xy 71.677778 -305.610094)
			(xy 71.718281 -305.63805) (xy 71.753774 -305.672142) (xy 71.783339 -305.711486) (xy 71.80621 -305.755063)
			(xy 71.821794 -305.801744) (xy 71.829689 -305.850321) (xy 71.830184 -305.874928) (xy 72.169032 -305.874928)
			(xy 72.172992 -305.825874) (xy 72.184769 -305.77809) (xy 72.20406 -305.732814) (xy 72.230363 -305.691218)
			(xy 72.262998 -305.654381) (xy 72.301119 -305.623256) (xy 72.34374 -305.598649) (xy 72.389756 -305.581197)
			(xy 72.437975 -305.571353) (xy 72.48715 -305.569372) (xy 72.536005 -305.575304) (xy 72.583276 -305.588996)
			(xy 72.627738 -305.610094) (xy 72.668241 -305.63805) (xy 72.703734 -305.672142) (xy 72.733299 -305.711486)
			(xy 72.75617 -305.755063) (xy 72.771754 -305.801744) (xy 72.779649 -305.850321) (xy 72.780144 -305.874928)
			(xy 72.779649 -305.899535) (xy 72.771754 -305.948112) (xy 72.75617 -305.994793) (xy 72.733299 -306.03837)
			(xy 72.703734 -306.077714) (xy 72.668241 -306.111806) (xy 72.627738 -306.139762) (xy 72.583276 -306.16086)
			(xy 72.536005 -306.174552) (xy 72.48715 -306.180484) (xy 72.437975 -306.178503) (xy 72.389756 -306.168659)
			(xy 72.34374 -306.151207) (xy 72.301119 -306.1266) (xy 72.262998 -306.095475) (xy 72.230363 -306.058638)
			(xy 72.20406 -306.017042) (xy 72.184769 -305.971766) (xy 72.172992 -305.923982) (xy 72.169032 -305.874928)
			(xy 71.830184 -305.874928) (xy 71.829689 -305.899535) (xy 71.821794 -305.948112) (xy 71.80621 -305.994793)
			(xy 71.783339 -306.03837) (xy 71.753774 -306.077714) (xy 71.718281 -306.111806) (xy 71.677778 -306.139762)
			(xy 71.633316 -306.16086) (xy 71.586045 -306.174552) (xy 71.53719 -306.180484) (xy 71.488015 -306.178503)
			(xy 71.439796 -306.168659) (xy 71.39378 -306.151207) (xy 71.351159 -306.1266) (xy 71.313038 -306.095475)
			(xy 71.280403 -306.058638) (xy 71.2541 -306.017042) (xy 71.234809 -305.971766) (xy 71.223032 -305.923982)
			(xy 71.219072 -305.874928) (xy 70.880224 -305.874928) (xy 70.879729 -305.899535) (xy 70.871834 -305.948112)
			(xy 70.85625 -305.994793) (xy 70.833379 -306.03837) (xy 70.803814 -306.077714) (xy 70.768321 -306.111806)
			(xy 70.727818 -306.139762) (xy 70.683356 -306.16086) (xy 70.636085 -306.174552) (xy 70.58723 -306.180484)
			(xy 70.538055 -306.178503) (xy 70.489836 -306.168659) (xy 70.44382 -306.151207) (xy 70.401199 -306.1266)
			(xy 70.363078 -306.095475) (xy 70.330443 -306.058638) (xy 70.30414 -306.017042) (xy 70.284849 -305.971766)
			(xy 70.273072 -305.923982) (xy 70.269112 -305.874928) (xy 69.930264 -305.874928) (xy 69.929769 -305.899535)
			(xy 69.921874 -305.948112) (xy 69.90629 -305.994793) (xy 69.883419 -306.03837) (xy 69.853854 -306.077714)
			(xy 69.818361 -306.111806) (xy 69.777858 -306.139762) (xy 69.733396 -306.16086) (xy 69.686125 -306.174552)
			(xy 69.63727 -306.180484) (xy 69.588095 -306.178503) (xy 69.539876 -306.168659) (xy 69.49386 -306.151207)
			(xy 69.451239 -306.1266) (xy 69.413118 -306.095475) (xy 69.380483 -306.058638) (xy 69.35418 -306.017042)
			(xy 69.334889 -305.971766) (xy 69.323112 -305.923982) (xy 69.319152 -305.874928) (xy 68.98005 -305.874928)
			(xy 68.979555 -305.899535) (xy 68.97166 -305.948112) (xy 68.956076 -305.994793) (xy 68.933205 -306.03837)
			(xy 68.90364 -306.077714) (xy 68.868147 -306.111806) (xy 68.827644 -306.139762) (xy 68.783182 -306.16086)
			(xy 68.735911 -306.174552) (xy 68.687056 -306.180484) (xy 68.637881 -306.178503) (xy 68.589662 -306.168659)
			(xy 68.543646 -306.151207) (xy 68.501025 -306.1266) (xy 68.462904 -306.095475) (xy 68.430269 -306.058638)
			(xy 68.403966 -306.017042) (xy 68.384675 -305.971766) (xy 68.372898 -305.923982) (xy 68.368938 -305.874928)
			(xy 68.03009 -305.874928) (xy 68.029595 -305.899535) (xy 68.0217 -305.948112) (xy 68.006116 -305.994793)
			(xy 67.983245 -306.03837) (xy 67.95368 -306.077714) (xy 67.918187 -306.111806) (xy 67.877684 -306.139762)
			(xy 67.833222 -306.16086) (xy 67.785951 -306.174552) (xy 67.737096 -306.180484) (xy 67.687921 -306.178503)
			(xy 67.639702 -306.168659) (xy 67.593686 -306.151207) (xy 67.551065 -306.1266) (xy 67.512944 -306.095475)
			(xy 67.480309 -306.058638) (xy 67.454006 -306.017042) (xy 67.434715 -305.971766) (xy 67.422938 -305.923982)
			(xy 67.418978 -305.874928) (xy 67.08013 -305.874928) (xy 67.079635 -305.899535) (xy 67.07174 -305.948112)
			(xy 67.056156 -305.994793) (xy 67.033285 -306.03837) (xy 67.00372 -306.077714) (xy 66.968227 -306.111806)
			(xy 66.927724 -306.139762) (xy 66.883262 -306.16086) (xy 66.835991 -306.174552) (xy 66.787136 -306.180484)
			(xy 66.737961 -306.178503) (xy 66.689742 -306.168659) (xy 66.643726 -306.151207) (xy 66.601105 -306.1266)
			(xy 66.562984 -306.095475) (xy 66.530349 -306.058638) (xy 66.504046 -306.017042) (xy 66.484755 -305.971766)
			(xy 66.472978 -305.923982) (xy 66.469018 -305.874928) (xy 66.13017 -305.874928) (xy 66.129675 -305.899535)
			(xy 66.12178 -305.948112) (xy 66.106196 -305.994793) (xy 66.083325 -306.03837) (xy 66.05376 -306.077714)
			(xy 66.018267 -306.111806) (xy 65.977764 -306.139762) (xy 65.933302 -306.16086) (xy 65.886031 -306.174552)
			(xy 65.837176 -306.180484) (xy 65.788001 -306.178503) (xy 65.739782 -306.168659) (xy 65.693766 -306.151207)
			(xy 65.651145 -306.1266) (xy 65.613024 -306.095475) (xy 65.580389 -306.058638) (xy 65.554086 -306.017042)
			(xy 65.534795 -305.971766) (xy 65.523018 -305.923982) (xy 65.519058 -305.874928) (xy 65.18021 -305.874928)
			(xy 65.179715 -305.899535) (xy 65.17182 -305.948112) (xy 65.156236 -305.994793) (xy 65.133365 -306.03837)
			(xy 65.1038 -306.077714) (xy 65.068307 -306.111806) (xy 65.027804 -306.139762) (xy 64.983342 -306.16086)
			(xy 64.936071 -306.174552) (xy 64.887216 -306.180484) (xy 64.838041 -306.178503) (xy 64.789822 -306.168659)
			(xy 64.743806 -306.151207) (xy 64.701185 -306.1266) (xy 64.663064 -306.095475) (xy 64.630429 -306.058638)
			(xy 64.604126 -306.017042) (xy 64.584835 -305.971766) (xy 64.573058 -305.923982) (xy 64.569098 -305.874928)
			(xy 64.23025 -305.874928) (xy 64.229755 -305.899535) (xy 64.22186 -305.948112) (xy 64.206276 -305.994793)
			(xy 64.183405 -306.03837) (xy 64.15384 -306.077714) (xy 64.118347 -306.111806) (xy 64.077844 -306.139762)
			(xy 64.033382 -306.16086) (xy 63.986111 -306.174552) (xy 63.937256 -306.180484) (xy 63.888081 -306.178503)
			(xy 63.839862 -306.168659) (xy 63.793846 -306.151207) (xy 63.751225 -306.1266) (xy 63.713104 -306.095475)
			(xy 63.680469 -306.058638) (xy 63.654166 -306.017042) (xy 63.634875 -305.971766) (xy 63.623098 -305.923982)
			(xy 63.619138 -305.874928) (xy 63.28029 -305.874928) (xy 63.279795 -305.899535) (xy 63.2719 -305.948112)
			(xy 63.256316 -305.994793) (xy 63.233445 -306.03837) (xy 63.20388 -306.077714) (xy 63.168387 -306.111806)
			(xy 63.127884 -306.139762) (xy 63.083422 -306.16086) (xy 63.036151 -306.174552) (xy 62.987296 -306.180484)
			(xy 62.938121 -306.178503) (xy 62.889902 -306.168659) (xy 62.843886 -306.151207) (xy 62.801265 -306.1266)
			(xy 62.763144 -306.095475) (xy 62.730509 -306.058638) (xy 62.704206 -306.017042) (xy 62.684915 -305.971766)
			(xy 62.673138 -305.923982) (xy 62.669178 -305.874928) (xy 62.330076 -305.874928) (xy 62.329581 -305.899535)
			(xy 62.321686 -305.948112) (xy 62.306102 -305.994793) (xy 62.283231 -306.03837) (xy 62.253666 -306.077714)
			(xy 62.218173 -306.111806) (xy 62.17767 -306.139762) (xy 62.133208 -306.16086) (xy 62.085937 -306.174552)
			(xy 62.037082 -306.180484) (xy 61.987907 -306.178503) (xy 61.939688 -306.168659) (xy 61.893672 -306.151207)
			(xy 61.851051 -306.1266) (xy 61.81293 -306.095475) (xy 61.780295 -306.058638) (xy 61.753992 -306.017042)
			(xy 61.734701 -305.971766) (xy 61.722924 -305.923982) (xy 61.718964 -305.874928) (xy 61.380116 -305.874928)
			(xy 61.379621 -305.899535) (xy 61.371726 -305.948112) (xy 61.356142 -305.994793) (xy 61.333271 -306.03837)
			(xy 61.303706 -306.077714) (xy 61.268213 -306.111806) (xy 61.22771 -306.139762) (xy 61.183248 -306.16086)
			(xy 61.135977 -306.174552) (xy 61.087122 -306.180484) (xy 61.037947 -306.178503) (xy 60.989728 -306.168659)
			(xy 60.943712 -306.151207) (xy 60.901091 -306.1266) (xy 60.86297 -306.095475) (xy 60.830335 -306.058638)
			(xy 60.804032 -306.017042) (xy 60.784741 -305.971766) (xy 60.772964 -305.923982) (xy 60.769004 -305.874928)
			(xy 60.430156 -305.874928) (xy 60.429661 -305.899535) (xy 60.421766 -305.948112) (xy 60.406182 -305.994793)
			(xy 60.383311 -306.03837) (xy 60.353746 -306.077714) (xy 60.318253 -306.111806) (xy 60.27775 -306.139762)
			(xy 60.233288 -306.16086) (xy 60.186017 -306.174552) (xy 60.137162 -306.180484) (xy 60.087987 -306.178503)
			(xy 60.039768 -306.168659) (xy 59.993752 -306.151207) (xy 59.951131 -306.1266) (xy 59.91301 -306.095475)
			(xy 59.880375 -306.058638) (xy 59.854072 -306.017042) (xy 59.834781 -305.971766) (xy 59.823004 -305.923982)
			(xy 59.819044 -305.874928) (xy 58.530236 -305.874928) (xy 58.529741 -305.899535) (xy 58.521846 -305.948112)
			(xy 58.506262 -305.994793) (xy 58.483391 -306.03837) (xy 58.453826 -306.077714) (xy 58.418333 -306.111806)
			(xy 58.37783 -306.139762) (xy 58.333368 -306.16086) (xy 58.286097 -306.174552) (xy 58.237242 -306.180484)
			(xy 58.188067 -306.178503) (xy 58.139848 -306.168659) (xy 58.093832 -306.151207) (xy 58.051211 -306.1266)
			(xy 58.01309 -306.095475) (xy 57.980455 -306.058638) (xy 57.954152 -306.017042) (xy 57.934861 -305.971766)
			(xy 57.923084 -305.923982) (xy 57.919124 -305.874928) (xy 57.580276 -305.874928) (xy 57.579781 -305.899535)
			(xy 57.571886 -305.948112) (xy 57.556302 -305.994793) (xy 57.533431 -306.03837) (xy 57.503866 -306.077714)
			(xy 57.468373 -306.111806) (xy 57.42787 -306.139762) (xy 57.383408 -306.16086) (xy 57.336137 -306.174552)
			(xy 57.287282 -306.180484) (xy 57.238107 -306.178503) (xy 57.189888 -306.168659) (xy 57.143872 -306.151207)
			(xy 57.101251 -306.1266) (xy 57.06313 -306.095475) (xy 57.030495 -306.058638) (xy 57.004192 -306.017042)
			(xy 56.984901 -305.971766) (xy 56.973124 -305.923982) (xy 56.969164 -305.874928) (xy 56.630062 -305.874928)
			(xy 56.629567 -305.899535) (xy 56.621672 -305.948112) (xy 56.606088 -305.994793) (xy 56.583217 -306.03837)
			(xy 56.553652 -306.077714) (xy 56.518159 -306.111806) (xy 56.477656 -306.139762) (xy 56.433194 -306.16086)
			(xy 56.385923 -306.174552) (xy 56.337068 -306.180484) (xy 56.287893 -306.178503) (xy 56.239674 -306.168659)
			(xy 56.193658 -306.151207) (xy 56.151037 -306.1266) (xy 56.112916 -306.095475) (xy 56.080281 -306.058638)
			(xy 56.053978 -306.017042) (xy 56.034687 -305.971766) (xy 56.02291 -305.923982) (xy 56.01895 -305.874928)
			(xy 55.680102 -305.874928) (xy 55.679607 -305.899535) (xy 55.671712 -305.948112) (xy 55.656128 -305.994793)
			(xy 55.633257 -306.03837) (xy 55.603692 -306.077714) (xy 55.568199 -306.111806) (xy 55.527696 -306.139762)
			(xy 55.483234 -306.16086) (xy 55.435963 -306.174552) (xy 55.387108 -306.180484) (xy 55.337933 -306.178503)
			(xy 55.289714 -306.168659) (xy 55.243698 -306.151207) (xy 55.201077 -306.1266) (xy 55.162956 -306.095475)
			(xy 55.130321 -306.058638) (xy 55.104018 -306.017042) (xy 55.084727 -305.971766) (xy 55.07295 -305.923982)
			(xy 55.06899 -305.874928) (xy 54.730142 -305.874928) (xy 54.729647 -305.899535) (xy 54.721752 -305.948112)
			(xy 54.706168 -305.994793) (xy 54.683297 -306.03837) (xy 54.653732 -306.077714) (xy 54.618239 -306.111806)
			(xy 54.577736 -306.139762) (xy 54.533274 -306.16086) (xy 54.486003 -306.174552) (xy 54.437148 -306.180484)
			(xy 54.387973 -306.178503) (xy 54.339754 -306.168659) (xy 54.293738 -306.151207) (xy 54.251117 -306.1266)
			(xy 54.212996 -306.095475) (xy 54.180361 -306.058638) (xy 54.154058 -306.017042) (xy 54.134767 -305.971766)
			(xy 54.12299 -305.923982) (xy 54.11903 -305.874928) (xy 53.780182 -305.874928) (xy 53.779687 -305.899535)
			(xy 53.771792 -305.948112) (xy 53.756208 -305.994793) (xy 53.733337 -306.03837) (xy 53.703772 -306.077714)
			(xy 53.668279 -306.111806) (xy 53.627776 -306.139762) (xy 53.583314 -306.16086) (xy 53.536043 -306.174552)
			(xy 53.487188 -306.180484) (xy 53.438013 -306.178503) (xy 53.389794 -306.168659) (xy 53.343778 -306.151207)
			(xy 53.301157 -306.1266) (xy 53.263036 -306.095475) (xy 53.230401 -306.058638) (xy 53.204098 -306.017042)
			(xy 53.184807 -305.971766) (xy 53.17303 -305.923982) (xy 53.16907 -305.874928) (xy 52.830222 -305.874928)
			(xy 52.829727 -305.899535) (xy 52.821832 -305.948112) (xy 52.806248 -305.994793) (xy 52.783377 -306.03837)
			(xy 52.753812 -306.077714) (xy 52.718319 -306.111806) (xy 52.677816 -306.139762) (xy 52.633354 -306.16086)
			(xy 52.586083 -306.174552) (xy 52.537228 -306.180484) (xy 52.488053 -306.178503) (xy 52.439834 -306.168659)
			(xy 52.393818 -306.151207) (xy 52.351197 -306.1266) (xy 52.313076 -306.095475) (xy 52.280441 -306.058638)
			(xy 52.254138 -306.017042) (xy 52.234847 -305.971766) (xy 52.22307 -305.923982) (xy 52.21911 -305.874928)
			(xy 51.880262 -305.874928) (xy 51.879767 -305.899535) (xy 51.871872 -305.948112) (xy 51.856288 -305.994793)
			(xy 51.833417 -306.03837) (xy 51.803852 -306.077714) (xy 51.768359 -306.111806) (xy 51.727856 -306.139762)
			(xy 51.683394 -306.16086) (xy 51.636123 -306.174552) (xy 51.587268 -306.180484) (xy 51.538093 -306.178503)
			(xy 51.489874 -306.168659) (xy 51.443858 -306.151207) (xy 51.401237 -306.1266) (xy 51.363116 -306.095475)
			(xy 51.330481 -306.058638) (xy 51.304178 -306.017042) (xy 51.284887 -305.971766) (xy 51.27311 -305.923982)
			(xy 51.26915 -305.874928) (xy 50.930302 -305.874928) (xy 50.929807 -305.899535) (xy 50.921912 -305.948112)
			(xy 50.906328 -305.994793) (xy 50.883457 -306.03837) (xy 50.853892 -306.077714) (xy 50.818399 -306.111806)
			(xy 50.777896 -306.139762) (xy 50.733434 -306.16086) (xy 50.686163 -306.174552) (xy 50.637308 -306.180484)
			(xy 50.588133 -306.178503) (xy 50.539914 -306.168659) (xy 50.493898 -306.151207) (xy 50.451277 -306.1266)
			(xy 50.413156 -306.095475) (xy 50.380521 -306.058638) (xy 50.354218 -306.017042) (xy 50.334927 -305.971766)
			(xy 50.32315 -305.923982) (xy 50.31919 -305.874928) (xy 49.980088 -305.874928) (xy 49.979593 -305.899535)
			(xy 49.971698 -305.948112) (xy 49.956114 -305.994793) (xy 49.933243 -306.03837) (xy 49.903678 -306.077714)
			(xy 49.868185 -306.111806) (xy 49.827682 -306.139762) (xy 49.78322 -306.16086) (xy 49.735949 -306.174552)
			(xy 49.687094 -306.180484) (xy 49.637919 -306.178503) (xy 49.5897 -306.168659) (xy 49.543684 -306.151207)
			(xy 49.501063 -306.1266) (xy 49.462942 -306.095475) (xy 49.430307 -306.058638) (xy 49.404004 -306.017042)
			(xy 49.384713 -305.971766) (xy 49.372936 -305.923982) (xy 49.368976 -305.874928) (xy 49.030128 -305.874928)
			(xy 49.029633 -305.899535) (xy 49.021738 -305.948112) (xy 49.006154 -305.994793) (xy 48.983283 -306.03837)
			(xy 48.953718 -306.077714) (xy 48.918225 -306.111806) (xy 48.877722 -306.139762) (xy 48.83326 -306.16086)
			(xy 48.785989 -306.174552) (xy 48.737134 -306.180484) (xy 48.687959 -306.178503) (xy 48.63974 -306.168659)
			(xy 48.593724 -306.151207) (xy 48.551103 -306.1266) (xy 48.512982 -306.095475) (xy 48.480347 -306.058638)
			(xy 48.454044 -306.017042) (xy 48.434753 -305.971766) (xy 48.422976 -305.923982) (xy 48.419016 -305.874928)
			(xy 48.080168 -305.874928) (xy 48.079914 -305.885342) (xy 48.079914 -305.891692) (xy 48.07966 -305.896264)
			(xy 48.07966 -305.897026) (xy 48.078436 -305.911427) (xy 48.073602 -305.939923) (xy 48.070008 -305.953922)
			(xy 48.06823 -305.960526) (xy 48.06823 -306.349908) (xy 73.593972 -306.349908) (xy 73.597932 -306.300854)
			(xy 73.609709 -306.25307) (xy 73.629 -306.207794) (xy 73.655303 -306.166198) (xy 73.687938 -306.129361)
			(xy 73.726059 -306.098236) (xy 73.76868 -306.073629) (xy 73.814696 -306.056177) (xy 73.862915 -306.046333)
			(xy 73.91209 -306.044352) (xy 73.960945 -306.050284) (xy 74.008216 -306.063976) (xy 74.052678 -306.085074)
			(xy 74.093181 -306.11303) (xy 74.128674 -306.147122) (xy 74.158239 -306.186466) (xy 74.18111 -306.230043)
			(xy 74.196694 -306.276724) (xy 74.204589 -306.325301) (xy 74.205084 -306.349908) (xy 74.544186 -306.349908)
			(xy 74.548146 -306.300854) (xy 74.559923 -306.25307) (xy 74.579214 -306.207794) (xy 74.605517 -306.166198)
			(xy 74.638152 -306.129361) (xy 74.676273 -306.098236) (xy 74.718894 -306.073629) (xy 74.76491 -306.056177)
			(xy 74.813129 -306.046333) (xy 74.862304 -306.044352) (xy 74.911159 -306.050284) (xy 74.95843 -306.063976)
			(xy 75.002892 -306.085074) (xy 75.043395 -306.11303) (xy 75.078888 -306.147122) (xy 75.108453 -306.186466)
			(xy 75.131324 -306.230043) (xy 75.146908 -306.276724) (xy 75.154803 -306.325301) (xy 75.155298 -306.349908)
			(xy 75.494146 -306.349908) (xy 75.498106 -306.300854) (xy 75.509883 -306.25307) (xy 75.529174 -306.207794)
			(xy 75.555477 -306.166198) (xy 75.588112 -306.129361) (xy 75.626233 -306.098236) (xy 75.668854 -306.073629)
			(xy 75.71487 -306.056177) (xy 75.763089 -306.046333) (xy 75.812264 -306.044352) (xy 75.861119 -306.050284)
			(xy 75.90839 -306.063976) (xy 75.952852 -306.085074) (xy 75.993355 -306.11303) (xy 76.028848 -306.147122)
			(xy 76.058413 -306.186466) (xy 76.081284 -306.230043) (xy 76.096868 -306.276724) (xy 76.104763 -306.325301)
			(xy 76.105258 -306.349908) (xy 76.444106 -306.349908) (xy 76.448066 -306.300854) (xy 76.459843 -306.25307)
			(xy 76.479134 -306.207794) (xy 76.505437 -306.166198) (xy 76.538072 -306.129361) (xy 76.576193 -306.098236)
			(xy 76.618814 -306.073629) (xy 76.66483 -306.056177) (xy 76.713049 -306.046333) (xy 76.762224 -306.044352)
			(xy 76.811079 -306.050284) (xy 76.85835 -306.063976) (xy 76.902812 -306.085074) (xy 76.943315 -306.11303)
			(xy 76.978808 -306.147122) (xy 77.008373 -306.186466) (xy 77.031244 -306.230043) (xy 77.046828 -306.276724)
			(xy 77.054723 -306.325301) (xy 77.055218 -306.349908) (xy 77.394066 -306.349908) (xy 77.398026 -306.300854)
			(xy 77.409803 -306.25307) (xy 77.429094 -306.207794) (xy 77.455397 -306.166198) (xy 77.488032 -306.129361)
			(xy 77.526153 -306.098236) (xy 77.568774 -306.073629) (xy 77.61479 -306.056177) (xy 77.663009 -306.046333)
			(xy 77.712184 -306.044352) (xy 77.761039 -306.050284) (xy 77.80831 -306.063976) (xy 77.852772 -306.085074)
			(xy 77.893275 -306.11303) (xy 77.928768 -306.147122) (xy 77.958333 -306.186466) (xy 77.981204 -306.230043)
			(xy 77.996788 -306.276724) (xy 78.004683 -306.325301) (xy 78.005178 -306.349908) (xy 78.344026 -306.349908)
			(xy 78.347986 -306.300854) (xy 78.359763 -306.25307) (xy 78.379054 -306.207794) (xy 78.405357 -306.166198)
			(xy 78.437992 -306.129361) (xy 78.476113 -306.098236) (xy 78.518734 -306.073629) (xy 78.56475 -306.056177)
			(xy 78.612969 -306.046333) (xy 78.662144 -306.044352) (xy 78.710999 -306.050284) (xy 78.75827 -306.063976)
			(xy 78.802732 -306.085074) (xy 78.843235 -306.11303) (xy 78.878728 -306.147122) (xy 78.908293 -306.186466)
			(xy 78.931164 -306.230043) (xy 78.946748 -306.276724) (xy 78.954643 -306.325301) (xy 78.955138 -306.349908)
			(xy 79.293986 -306.349908) (xy 79.297946 -306.300854) (xy 79.309723 -306.25307) (xy 79.329014 -306.207794)
			(xy 79.355317 -306.166198) (xy 79.387952 -306.129361) (xy 79.426073 -306.098236) (xy 79.468694 -306.073629)
			(xy 79.51471 -306.056177) (xy 79.562929 -306.046333) (xy 79.612104 -306.044352) (xy 79.660959 -306.050284)
			(xy 79.70823 -306.063976) (xy 79.752692 -306.085074) (xy 79.793195 -306.11303) (xy 79.828688 -306.147122)
			(xy 79.858253 -306.186466) (xy 79.881124 -306.230043) (xy 79.896708 -306.276724) (xy 79.904603 -306.325301)
			(xy 79.905098 -306.349908) (xy 80.243946 -306.349908) (xy 80.247906 -306.300854) (xy 80.259683 -306.25307)
			(xy 80.278974 -306.207794) (xy 80.305277 -306.166198) (xy 80.337912 -306.129361) (xy 80.376033 -306.098236)
			(xy 80.418654 -306.073629) (xy 80.46467 -306.056177) (xy 80.512889 -306.046333) (xy 80.562064 -306.044352)
			(xy 80.610919 -306.050284) (xy 80.65819 -306.063976) (xy 80.702652 -306.085074) (xy 80.743155 -306.11303)
			(xy 80.778648 -306.147122) (xy 80.808213 -306.186466) (xy 80.831084 -306.230043) (xy 80.846668 -306.276724)
			(xy 80.854563 -306.325301) (xy 80.855058 -306.349908) (xy 81.19416 -306.349908) (xy 81.19812 -306.300854)
			(xy 81.209897 -306.25307) (xy 81.229188 -306.207794) (xy 81.255491 -306.166198) (xy 81.288126 -306.129361)
			(xy 81.326247 -306.098236) (xy 81.368868 -306.073629) (xy 81.414884 -306.056177) (xy 81.463103 -306.046333)
			(xy 81.512278 -306.044352) (xy 81.561133 -306.050284) (xy 81.608404 -306.063976) (xy 81.652866 -306.085074)
			(xy 81.693369 -306.11303) (xy 81.728862 -306.147122) (xy 81.758427 -306.186466) (xy 81.781298 -306.230043)
			(xy 81.796882 -306.276724) (xy 81.804777 -306.325301) (xy 81.805272 -306.349908) (xy 82.14412 -306.349908)
			(xy 82.14808 -306.300854) (xy 82.159857 -306.25307) (xy 82.179148 -306.207794) (xy 82.205451 -306.166198)
			(xy 82.238086 -306.129361) (xy 82.276207 -306.098236) (xy 82.318828 -306.073629) (xy 82.364844 -306.056177)
			(xy 82.413063 -306.046333) (xy 82.462238 -306.044352) (xy 82.511093 -306.050284) (xy 82.558364 -306.063976)
			(xy 82.602826 -306.085074) (xy 82.643329 -306.11303) (xy 82.678822 -306.147122) (xy 82.708387 -306.186466)
			(xy 82.731258 -306.230043) (xy 82.746842 -306.276724) (xy 82.754737 -306.325301) (xy 82.755232 -306.349908)
			(xy 83.094334 -306.349908) (xy 83.098294 -306.300854) (xy 83.110071 -306.25307) (xy 83.129362 -306.207794)
			(xy 83.155665 -306.166198) (xy 83.1883 -306.129361) (xy 83.226421 -306.098236) (xy 83.269042 -306.073629)
			(xy 83.315058 -306.056177) (xy 83.363277 -306.046333) (xy 83.412452 -306.044352) (xy 83.461307 -306.050284)
			(xy 83.508578 -306.063976) (xy 83.55304 -306.085074) (xy 83.593543 -306.11303) (xy 83.629036 -306.147122)
			(xy 83.658601 -306.186466) (xy 83.681472 -306.230043) (xy 83.697056 -306.276724) (xy 83.704951 -306.325301)
			(xy 83.705446 -306.349908) (xy 83.704951 -306.374515) (xy 83.697056 -306.423092) (xy 83.681472 -306.469773)
			(xy 83.658601 -306.51335) (xy 83.629036 -306.552694) (xy 83.593543 -306.586786) (xy 83.55304 -306.614742)
			(xy 83.508578 -306.63584) (xy 83.461307 -306.649532) (xy 83.412452 -306.655464) (xy 83.363277 -306.653483)
			(xy 83.315058 -306.643639) (xy 83.269042 -306.626187) (xy 83.226421 -306.60158) (xy 83.1883 -306.570455)
			(xy 83.155665 -306.533618) (xy 83.129362 -306.492022) (xy 83.110071 -306.446746) (xy 83.098294 -306.398962)
			(xy 83.094334 -306.349908) (xy 82.755232 -306.349908) (xy 82.754737 -306.374515) (xy 82.746842 -306.423092)
			(xy 82.731258 -306.469773) (xy 82.708387 -306.51335) (xy 82.678822 -306.552694) (xy 82.643329 -306.586786)
			(xy 82.602826 -306.614742) (xy 82.558364 -306.63584) (xy 82.511093 -306.649532) (xy 82.462238 -306.655464)
			(xy 82.413063 -306.653483) (xy 82.364844 -306.643639) (xy 82.318828 -306.626187) (xy 82.276207 -306.60158)
			(xy 82.238086 -306.570455) (xy 82.205451 -306.533618) (xy 82.179148 -306.492022) (xy 82.159857 -306.446746)
			(xy 82.14808 -306.398962) (xy 82.14412 -306.349908) (xy 81.805272 -306.349908) (xy 81.804777 -306.374515)
			(xy 81.796882 -306.423092) (xy 81.781298 -306.469773) (xy 81.758427 -306.51335) (xy 81.728862 -306.552694)
			(xy 81.693369 -306.586786) (xy 81.652866 -306.614742) (xy 81.608404 -306.63584) (xy 81.561133 -306.649532)
			(xy 81.512278 -306.655464) (xy 81.463103 -306.653483) (xy 81.414884 -306.643639) (xy 81.368868 -306.626187)
			(xy 81.326247 -306.60158) (xy 81.288126 -306.570455) (xy 81.255491 -306.533618) (xy 81.229188 -306.492022)
			(xy 81.209897 -306.446746) (xy 81.19812 -306.398962) (xy 81.19416 -306.349908) (xy 80.855058 -306.349908)
			(xy 80.854563 -306.374515) (xy 80.846668 -306.423092) (xy 80.831084 -306.469773) (xy 80.808213 -306.51335)
			(xy 80.778648 -306.552694) (xy 80.743155 -306.586786) (xy 80.702652 -306.614742) (xy 80.65819 -306.63584)
			(xy 80.610919 -306.649532) (xy 80.562064 -306.655464) (xy 80.512889 -306.653483) (xy 80.46467 -306.643639)
			(xy 80.418654 -306.626187) (xy 80.376033 -306.60158) (xy 80.337912 -306.570455) (xy 80.305277 -306.533618)
			(xy 80.278974 -306.492022) (xy 80.259683 -306.446746) (xy 80.247906 -306.398962) (xy 80.243946 -306.349908)
			(xy 79.905098 -306.349908) (xy 79.904603 -306.374515) (xy 79.896708 -306.423092) (xy 79.881124 -306.469773)
			(xy 79.858253 -306.51335) (xy 79.828688 -306.552694) (xy 79.793195 -306.586786) (xy 79.752692 -306.614742)
			(xy 79.70823 -306.63584) (xy 79.660959 -306.649532) (xy 79.612104 -306.655464) (xy 79.562929 -306.653483)
			(xy 79.51471 -306.643639) (xy 79.468694 -306.626187) (xy 79.426073 -306.60158) (xy 79.387952 -306.570455)
			(xy 79.355317 -306.533618) (xy 79.329014 -306.492022) (xy 79.309723 -306.446746) (xy 79.297946 -306.398962)
			(xy 79.293986 -306.349908) (xy 78.955138 -306.349908) (xy 78.954643 -306.374515) (xy 78.946748 -306.423092)
			(xy 78.931164 -306.469773) (xy 78.908293 -306.51335) (xy 78.878728 -306.552694) (xy 78.843235 -306.586786)
			(xy 78.802732 -306.614742) (xy 78.75827 -306.63584) (xy 78.710999 -306.649532) (xy 78.662144 -306.655464)
			(xy 78.612969 -306.653483) (xy 78.56475 -306.643639) (xy 78.518734 -306.626187) (xy 78.476113 -306.60158)
			(xy 78.437992 -306.570455) (xy 78.405357 -306.533618) (xy 78.379054 -306.492022) (xy 78.359763 -306.446746)
			(xy 78.347986 -306.398962) (xy 78.344026 -306.349908) (xy 78.005178 -306.349908) (xy 78.004683 -306.374515)
			(xy 77.996788 -306.423092) (xy 77.981204 -306.469773) (xy 77.958333 -306.51335) (xy 77.928768 -306.552694)
			(xy 77.893275 -306.586786) (xy 77.852772 -306.614742) (xy 77.80831 -306.63584) (xy 77.761039 -306.649532)
			(xy 77.712184 -306.655464) (xy 77.663009 -306.653483) (xy 77.61479 -306.643639) (xy 77.568774 -306.626187)
			(xy 77.526153 -306.60158) (xy 77.488032 -306.570455) (xy 77.455397 -306.533618) (xy 77.429094 -306.492022)
			(xy 77.409803 -306.446746) (xy 77.398026 -306.398962) (xy 77.394066 -306.349908) (xy 77.055218 -306.349908)
			(xy 77.054723 -306.374515) (xy 77.046828 -306.423092) (xy 77.031244 -306.469773) (xy 77.008373 -306.51335)
			(xy 76.978808 -306.552694) (xy 76.943315 -306.586786) (xy 76.902812 -306.614742) (xy 76.85835 -306.63584)
			(xy 76.811079 -306.649532) (xy 76.762224 -306.655464) (xy 76.713049 -306.653483) (xy 76.66483 -306.643639)
			(xy 76.618814 -306.626187) (xy 76.576193 -306.60158) (xy 76.538072 -306.570455) (xy 76.505437 -306.533618)
			(xy 76.479134 -306.492022) (xy 76.459843 -306.446746) (xy 76.448066 -306.398962) (xy 76.444106 -306.349908)
			(xy 76.105258 -306.349908) (xy 76.104763 -306.374515) (xy 76.096868 -306.423092) (xy 76.081284 -306.469773)
			(xy 76.058413 -306.51335) (xy 76.028848 -306.552694) (xy 75.993355 -306.586786) (xy 75.952852 -306.614742)
			(xy 75.90839 -306.63584) (xy 75.861119 -306.649532) (xy 75.812264 -306.655464) (xy 75.763089 -306.653483)
			(xy 75.71487 -306.643639) (xy 75.668854 -306.626187) (xy 75.626233 -306.60158) (xy 75.588112 -306.570455)
			(xy 75.555477 -306.533618) (xy 75.529174 -306.492022) (xy 75.509883 -306.446746) (xy 75.498106 -306.398962)
			(xy 75.494146 -306.349908) (xy 75.155298 -306.349908) (xy 75.154803 -306.374515) (xy 75.146908 -306.423092)
			(xy 75.131324 -306.469773) (xy 75.108453 -306.51335) (xy 75.078888 -306.552694) (xy 75.043395 -306.586786)
			(xy 75.002892 -306.614742) (xy 74.95843 -306.63584) (xy 74.911159 -306.649532) (xy 74.862304 -306.655464)
			(xy 74.813129 -306.653483) (xy 74.76491 -306.643639) (xy 74.718894 -306.626187) (xy 74.676273 -306.60158)
			(xy 74.638152 -306.570455) (xy 74.605517 -306.533618) (xy 74.579214 -306.492022) (xy 74.559923 -306.446746)
			(xy 74.548146 -306.398962) (xy 74.544186 -306.349908) (xy 74.205084 -306.349908) (xy 74.204589 -306.374515)
			(xy 74.196694 -306.423092) (xy 74.18111 -306.469773) (xy 74.158239 -306.51335) (xy 74.128674 -306.552694)
			(xy 74.093181 -306.586786) (xy 74.052678 -306.614742) (xy 74.008216 -306.63584) (xy 73.960945 -306.649532)
			(xy 73.91209 -306.655464) (xy 73.862915 -306.653483) (xy 73.814696 -306.643639) (xy 73.76868 -306.626187)
			(xy 73.726059 -306.60158) (xy 73.687938 -306.570455) (xy 73.655303 -306.533618) (xy 73.629 -306.492022)
			(xy 73.609709 -306.446746) (xy 73.597932 -306.398962) (xy 73.593972 -306.349908) (xy 48.06823 -306.349908)
			(xy 48.06823 -306.733448) (xy 48.070008 -306.746656) (xy 48.07077 -306.749704) (xy 48.075155 -306.768126)
			(xy 48.079864 -306.8057) (xy 48.080168 -306.824634) (xy 48.080168 -306.825142) (xy 48.079914 -306.834286)
			(xy 48.079914 -306.841652) (xy 48.079914 -306.845208) (xy 48.07966 -306.846986) (xy 48.07966 -306.848002)
			(xy 48.078411 -306.862212) (xy 48.07358 -306.890326) (xy 48.070008 -306.904136) (xy 48.06823 -306.91074)
			(xy 48.06823 -306.968652) (xy 48.068642 -306.978677) (xy 48.076304 -306.997206) (xy 48.090479 -307.011386)
			(xy 48.109005 -307.019055) (xy 48.11903 -307.019452) (xy 48.128682 -307.019452) (xy 48.137572 -307.015896)
			(xy 48.164509 -307.005978) (xy 48.22089 -306.995242) (xy 48.249586 -306.99456) (xy 48.24984 -306.99456)
			(xy 48.263959 -306.994759) (xy 48.292071 -306.99743) (xy 48.305974 -306.999894) (xy 48.31842 -307.00218)
			(xy 48.342296 -306.994814) (xy 48.419766 -306.917344) (xy 48.427132 -306.893468) (xy 48.424846 -306.881022)
			(xy 48.422368 -306.86712) (xy 48.419693 -306.839008) (xy 48.419512 -306.824888) (xy 48.420034 -306.799633)
			(xy 48.428347 -306.749811) (xy 48.444748 -306.702037) (xy 48.468789 -306.657614) (xy 48.499813 -306.617754)
			(xy 48.536975 -306.583544) (xy 48.579261 -306.555918) (xy 48.625517 -306.535628) (xy 48.674482 -306.523228)
			(xy 48.72482 -306.519057) (xy 48.775158 -306.523228) (xy 48.824123 -306.535628) (xy 48.870379 -306.555918)
			(xy 48.912665 -306.583544) (xy 48.949827 -306.617754) (xy 48.980851 -306.657614) (xy 49.004892 -306.702037)
			(xy 49.021293 -306.749811) (xy 49.029606 -306.799633) (xy 49.030128 -306.824888) (xy 49.029926 -306.839006)
			(xy 49.027251 -306.867117) (xy 49.024794 -306.881022) (xy 49.022508 -306.893468) (xy 49.029874 -306.917344)
			(xy 49.107344 -306.994814) (xy 49.13122 -307.00218) (xy 49.143666 -306.999894) (xy 49.157568 -306.997416)
			(xy 49.18568 -306.99474) (xy 49.1998 -306.99456) (xy 49.213919 -306.994758) (xy 49.242031 -306.997425)
			(xy 49.255934 -306.999894) (xy 49.26838 -307.00218) (xy 49.292256 -306.994814) (xy 49.369726 -306.917344)
			(xy 49.377092 -306.893468) (xy 49.374806 -306.881022) (xy 49.372328 -306.86712) (xy 49.369653 -306.839008)
			(xy 49.369472 -306.824888) (xy 49.369994 -306.799633) (xy 49.378307 -306.749811) (xy 49.394708 -306.702037)
			(xy 49.418749 -306.657614) (xy 49.449773 -306.617754) (xy 49.486935 -306.583544) (xy 49.529221 -306.555918)
			(xy 49.575477 -306.535628) (xy 49.624442 -306.523228) (xy 49.67478 -306.519057) (xy 49.725118 -306.523228)
			(xy 49.774083 -306.535628) (xy 49.820339 -306.555918) (xy 49.862625 -306.583544) (xy 49.899787 -306.617754)
			(xy 49.930811 -306.657614) (xy 49.954852 -306.702037) (xy 49.971253 -306.749811) (xy 49.979566 -306.799633)
			(xy 49.980088 -306.824888) (xy 49.979886 -306.839006) (xy 49.977211 -306.867117) (xy 49.974754 -306.881022)
			(xy 49.972468 -306.893468) (xy 49.979834 -306.917344) (xy 50.057304 -306.994814) (xy 50.08118 -307.00218)
			(xy 50.093626 -306.999894) (xy 50.107528 -306.997419) (xy 50.135641 -306.994748) (xy 50.14976 -306.99456)
			(xy 50.163943 -306.994745) (xy 50.192183 -306.997414) (xy 50.206148 -306.999894) (xy 50.212243 -307.000898)
			(xy 50.224576 -307.00026) (xy 50.230532 -306.998624) (xy 50.236418 -306.996601) (xy 50.247076 -306.990183)
			(xy 50.251614 -306.985924) (xy 50.31105 -306.926488) (xy 50.31923 -306.917191) (xy 50.326526 -306.893568)
			(xy 50.32502 -306.881276) (xy 50.322535 -306.867311) (xy 50.319864 -306.839071) (xy 50.319686 -306.824888)
			(xy 50.320173 -306.800067) (xy 50.328206 -306.751079) (xy 50.344059 -306.704035) (xy 50.367313 -306.660176)
			(xy 50.397357 -306.620658) (xy 50.433399 -306.58652) (xy 50.474488 -306.558662) (xy 50.519543 -306.53782)
			(xy 50.567377 -306.524541) (xy 50.616728 -306.519175) (xy 50.666298 -306.521864) (xy 50.714779 -306.532537)
			(xy 50.760895 -306.550913) (xy 50.803431 -306.576508) (xy 50.841266 -306.608647) (xy 50.873403 -306.646484)
			(xy 50.898995 -306.689021) (xy 50.917368 -306.735138) (xy 50.928038 -306.78362) (xy 50.930275 -306.824888)
			(xy 51.26915 -306.824888) (xy 51.27311 -306.775834) (xy 51.284887 -306.72805) (xy 51.304178 -306.682774)
			(xy 51.330481 -306.641178) (xy 51.363116 -306.604341) (xy 51.401237 -306.573216) (xy 51.443858 -306.548609)
			(xy 51.489874 -306.531157) (xy 51.538093 -306.521313) (xy 51.587268 -306.519332) (xy 51.636123 -306.525264)
			(xy 51.683394 -306.538956) (xy 51.727856 -306.560054) (xy 51.768359 -306.58801) (xy 51.803852 -306.622102)
			(xy 51.833417 -306.661446) (xy 51.856288 -306.705023) (xy 51.871872 -306.751704) (xy 51.879767 -306.800281)
			(xy 51.880262 -306.824888) (xy 52.21911 -306.824888) (xy 52.22307 -306.775834) (xy 52.234847 -306.72805)
			(xy 52.254138 -306.682774) (xy 52.280441 -306.641178) (xy 52.313076 -306.604341) (xy 52.351197 -306.573216)
			(xy 52.393818 -306.548609) (xy 52.439834 -306.531157) (xy 52.488053 -306.521313) (xy 52.537228 -306.519332)
			(xy 52.586083 -306.525264) (xy 52.633354 -306.538956) (xy 52.677816 -306.560054) (xy 52.718319 -306.58801)
			(xy 52.753812 -306.622102) (xy 52.783377 -306.661446) (xy 52.806248 -306.705023) (xy 52.821832 -306.751704)
			(xy 52.829727 -306.800281) (xy 52.830222 -306.824888) (xy 53.16907 -306.824888) (xy 53.17303 -306.775834)
			(xy 53.184807 -306.72805) (xy 53.204098 -306.682774) (xy 53.230401 -306.641178) (xy 53.263036 -306.604341)
			(xy 53.301157 -306.573216) (xy 53.343778 -306.548609) (xy 53.389794 -306.531157) (xy 53.438013 -306.521313)
			(xy 53.487188 -306.519332) (xy 53.536043 -306.525264) (xy 53.583314 -306.538956) (xy 53.627776 -306.560054)
			(xy 53.668279 -306.58801) (xy 53.703772 -306.622102) (xy 53.733337 -306.661446) (xy 53.756208 -306.705023)
			(xy 53.771792 -306.751704) (xy 53.779687 -306.800281) (xy 53.780182 -306.824888) (xy 54.11903 -306.824888)
			(xy 54.12299 -306.775834) (xy 54.134767 -306.72805) (xy 54.154058 -306.682774) (xy 54.180361 -306.641178)
			(xy 54.212996 -306.604341) (xy 54.251117 -306.573216) (xy 54.293738 -306.548609) (xy 54.339754 -306.531157)
			(xy 54.387973 -306.521313) (xy 54.437148 -306.519332) (xy 54.486003 -306.525264) (xy 54.533274 -306.538956)
			(xy 54.577736 -306.560054) (xy 54.618239 -306.58801) (xy 54.653732 -306.622102) (xy 54.683297 -306.661446)
			(xy 54.706168 -306.705023) (xy 54.721752 -306.751704) (xy 54.729647 -306.800281) (xy 54.730142 -306.824888)
			(xy 55.06899 -306.824888) (xy 55.07295 -306.775834) (xy 55.084727 -306.72805) (xy 55.104018 -306.682774)
			(xy 55.130321 -306.641178) (xy 55.162956 -306.604341) (xy 55.201077 -306.573216) (xy 55.243698 -306.548609)
			(xy 55.289714 -306.531157) (xy 55.337933 -306.521313) (xy 55.387108 -306.519332) (xy 55.435963 -306.525264)
			(xy 55.483234 -306.538956) (xy 55.527696 -306.560054) (xy 55.568199 -306.58801) (xy 55.603692 -306.622102)
			(xy 55.633257 -306.661446) (xy 55.656128 -306.705023) (xy 55.671712 -306.751704) (xy 55.679607 -306.800281)
			(xy 55.680102 -306.824888) (xy 56.01895 -306.824888) (xy 56.02291 -306.775834) (xy 56.034687 -306.72805)
			(xy 56.053978 -306.682774) (xy 56.080281 -306.641178) (xy 56.112916 -306.604341) (xy 56.151037 -306.573216)
			(xy 56.193658 -306.548609) (xy 56.239674 -306.531157) (xy 56.287893 -306.521313) (xy 56.337068 -306.519332)
			(xy 56.385923 -306.525264) (xy 56.433194 -306.538956) (xy 56.477656 -306.560054) (xy 56.518159 -306.58801)
			(xy 56.553652 -306.622102) (xy 56.583217 -306.661446) (xy 56.606088 -306.705023) (xy 56.621672 -306.751704)
			(xy 56.629567 -306.800281) (xy 56.630062 -306.824888) (xy 56.969164 -306.824888) (xy 56.973124 -306.775834)
			(xy 56.984901 -306.72805) (xy 57.004192 -306.682774) (xy 57.030495 -306.641178) (xy 57.06313 -306.604341)
			(xy 57.101251 -306.573216) (xy 57.143872 -306.548609) (xy 57.189888 -306.531157) (xy 57.238107 -306.521313)
			(xy 57.287282 -306.519332) (xy 57.336137 -306.525264) (xy 57.383408 -306.538956) (xy 57.42787 -306.560054)
			(xy 57.468373 -306.58801) (xy 57.503866 -306.622102) (xy 57.533431 -306.661446) (xy 57.556302 -306.705023)
			(xy 57.571886 -306.751704) (xy 57.579781 -306.800281) (xy 57.580276 -306.824888) (xy 57.919124 -306.824888)
			(xy 57.923084 -306.775834) (xy 57.934861 -306.72805) (xy 57.954152 -306.682774) (xy 57.980455 -306.641178)
			(xy 58.01309 -306.604341) (xy 58.051211 -306.573216) (xy 58.093832 -306.548609) (xy 58.139848 -306.531157)
			(xy 58.188067 -306.521313) (xy 58.237242 -306.519332) (xy 58.286097 -306.525264) (xy 58.333368 -306.538956)
			(xy 58.37783 -306.560054) (xy 58.418333 -306.58801) (xy 58.453826 -306.622102) (xy 58.483391 -306.661446)
			(xy 58.506262 -306.705023) (xy 58.521846 -306.751704) (xy 58.529741 -306.800281) (xy 58.530236 -306.824888)
			(xy 59.819044 -306.824888) (xy 59.823004 -306.775834) (xy 59.834781 -306.72805) (xy 59.854072 -306.682774)
			(xy 59.880375 -306.641178) (xy 59.91301 -306.604341) (xy 59.951131 -306.573216) (xy 59.993752 -306.548609)
			(xy 60.039768 -306.531157) (xy 60.087987 -306.521313) (xy 60.137162 -306.519332) (xy 60.186017 -306.525264)
			(xy 60.233288 -306.538956) (xy 60.27775 -306.560054) (xy 60.318253 -306.58801) (xy 60.353746 -306.622102)
			(xy 60.383311 -306.661446) (xy 60.406182 -306.705023) (xy 60.421766 -306.751704) (xy 60.429661 -306.800281)
			(xy 60.430156 -306.824888) (xy 60.769004 -306.824888) (xy 60.772964 -306.775834) (xy 60.784741 -306.72805)
			(xy 60.804032 -306.682774) (xy 60.830335 -306.641178) (xy 60.86297 -306.604341) (xy 60.901091 -306.573216)
			(xy 60.943712 -306.548609) (xy 60.989728 -306.531157) (xy 61.037947 -306.521313) (xy 61.087122 -306.519332)
			(xy 61.135977 -306.525264) (xy 61.183248 -306.538956) (xy 61.22771 -306.560054) (xy 61.268213 -306.58801)
			(xy 61.303706 -306.622102) (xy 61.333271 -306.661446) (xy 61.356142 -306.705023) (xy 61.371726 -306.751704)
			(xy 61.379621 -306.800281) (xy 61.380116 -306.824888) (xy 61.718964 -306.824888) (xy 61.722924 -306.775834)
			(xy 61.734701 -306.72805) (xy 61.753992 -306.682774) (xy 61.780295 -306.641178) (xy 61.81293 -306.604341)
			(xy 61.851051 -306.573216) (xy 61.893672 -306.548609) (xy 61.939688 -306.531157) (xy 61.987907 -306.521313)
			(xy 62.037082 -306.519332) (xy 62.085937 -306.525264) (xy 62.133208 -306.538956) (xy 62.17767 -306.560054)
			(xy 62.218173 -306.58801) (xy 62.253666 -306.622102) (xy 62.283231 -306.661446) (xy 62.306102 -306.705023)
			(xy 62.321686 -306.751704) (xy 62.329581 -306.800281) (xy 62.330076 -306.824888) (xy 62.669178 -306.824888)
			(xy 62.673138 -306.775834) (xy 62.684915 -306.72805) (xy 62.704206 -306.682774) (xy 62.730509 -306.641178)
			(xy 62.763144 -306.604341) (xy 62.801265 -306.573216) (xy 62.843886 -306.548609) (xy 62.889902 -306.531157)
			(xy 62.938121 -306.521313) (xy 62.987296 -306.519332) (xy 63.036151 -306.525264) (xy 63.083422 -306.538956)
			(xy 63.127884 -306.560054) (xy 63.168387 -306.58801) (xy 63.20388 -306.622102) (xy 63.233445 -306.661446)
			(xy 63.256316 -306.705023) (xy 63.2719 -306.751704) (xy 63.279795 -306.800281) (xy 63.28029 -306.824888)
			(xy 63.619138 -306.824888) (xy 63.623098 -306.775834) (xy 63.634875 -306.72805) (xy 63.654166 -306.682774)
			(xy 63.680469 -306.641178) (xy 63.713104 -306.604341) (xy 63.751225 -306.573216) (xy 63.793846 -306.548609)
			(xy 63.839862 -306.531157) (xy 63.888081 -306.521313) (xy 63.937256 -306.519332) (xy 63.986111 -306.525264)
			(xy 64.033382 -306.538956) (xy 64.077844 -306.560054) (xy 64.118347 -306.58801) (xy 64.15384 -306.622102)
			(xy 64.183405 -306.661446) (xy 64.206276 -306.705023) (xy 64.22186 -306.751704) (xy 64.229755 -306.800281)
			(xy 64.23025 -306.824888) (xy 64.569098 -306.824888) (xy 64.573058 -306.775834) (xy 64.584835 -306.72805)
			(xy 64.604126 -306.682774) (xy 64.630429 -306.641178) (xy 64.663064 -306.604341) (xy 64.701185 -306.573216)
			(xy 64.743806 -306.548609) (xy 64.789822 -306.531157) (xy 64.838041 -306.521313) (xy 64.887216 -306.519332)
			(xy 64.936071 -306.525264) (xy 64.983342 -306.538956) (xy 65.027804 -306.560054) (xy 65.068307 -306.58801)
			(xy 65.1038 -306.622102) (xy 65.133365 -306.661446) (xy 65.156236 -306.705023) (xy 65.17182 -306.751704)
			(xy 65.179715 -306.800281) (xy 65.18021 -306.824888) (xy 65.519058 -306.824888) (xy 65.523018 -306.775834)
			(xy 65.534795 -306.72805) (xy 65.554086 -306.682774) (xy 65.580389 -306.641178) (xy 65.613024 -306.604341)
			(xy 65.651145 -306.573216) (xy 65.693766 -306.548609) (xy 65.739782 -306.531157) (xy 65.788001 -306.521313)
			(xy 65.837176 -306.519332) (xy 65.886031 -306.525264) (xy 65.933302 -306.538956) (xy 65.977764 -306.560054)
			(xy 66.018267 -306.58801) (xy 66.05376 -306.622102) (xy 66.083325 -306.661446) (xy 66.106196 -306.705023)
			(xy 66.12178 -306.751704) (xy 66.129675 -306.800281) (xy 66.13017 -306.824888) (xy 66.469018 -306.824888)
			(xy 66.472978 -306.775834) (xy 66.484755 -306.72805) (xy 66.504046 -306.682774) (xy 66.530349 -306.641178)
			(xy 66.562984 -306.604341) (xy 66.601105 -306.573216) (xy 66.643726 -306.548609) (xy 66.689742 -306.531157)
			(xy 66.737961 -306.521313) (xy 66.787136 -306.519332) (xy 66.835991 -306.525264) (xy 66.883262 -306.538956)
			(xy 66.927724 -306.560054) (xy 66.968227 -306.58801) (xy 67.00372 -306.622102) (xy 67.033285 -306.661446)
			(xy 67.056156 -306.705023) (xy 67.07174 -306.751704) (xy 67.079635 -306.800281) (xy 67.08013 -306.824888)
			(xy 67.418978 -306.824888) (xy 67.422938 -306.775834) (xy 67.434715 -306.72805) (xy 67.454006 -306.682774)
			(xy 67.480309 -306.641178) (xy 67.512944 -306.604341) (xy 67.551065 -306.573216) (xy 67.593686 -306.548609)
			(xy 67.639702 -306.531157) (xy 67.687921 -306.521313) (xy 67.737096 -306.519332) (xy 67.785951 -306.525264)
			(xy 67.833222 -306.538956) (xy 67.877684 -306.560054) (xy 67.918187 -306.58801) (xy 67.95368 -306.622102)
			(xy 67.983245 -306.661446) (xy 68.006116 -306.705023) (xy 68.0217 -306.751704) (xy 68.029595 -306.800281)
			(xy 68.03009 -306.824888) (xy 68.368938 -306.824888) (xy 68.372898 -306.775834) (xy 68.384675 -306.72805)
			(xy 68.403966 -306.682774) (xy 68.430269 -306.641178) (xy 68.462904 -306.604341) (xy 68.501025 -306.573216)
			(xy 68.543646 -306.548609) (xy 68.589662 -306.531157) (xy 68.637881 -306.521313) (xy 68.687056 -306.519332)
			(xy 68.735911 -306.525264) (xy 68.783182 -306.538956) (xy 68.827644 -306.560054) (xy 68.868147 -306.58801)
			(xy 68.90364 -306.622102) (xy 68.933205 -306.661446) (xy 68.956076 -306.705023) (xy 68.97166 -306.751704)
			(xy 68.979555 -306.800281) (xy 68.98005 -306.824888) (xy 69.319152 -306.824888) (xy 69.323112 -306.775834)
			(xy 69.334889 -306.72805) (xy 69.35418 -306.682774) (xy 69.380483 -306.641178) (xy 69.413118 -306.604341)
			(xy 69.451239 -306.573216) (xy 69.49386 -306.548609) (xy 69.539876 -306.531157) (xy 69.588095 -306.521313)
			(xy 69.63727 -306.519332) (xy 69.686125 -306.525264) (xy 69.733396 -306.538956) (xy 69.777858 -306.560054)
			(xy 69.818361 -306.58801) (xy 69.853854 -306.622102) (xy 69.883419 -306.661446) (xy 69.90629 -306.705023)
			(xy 69.921874 -306.751704) (xy 69.929769 -306.800281) (xy 69.930264 -306.824888) (xy 70.269112 -306.824888)
			(xy 70.273072 -306.775834) (xy 70.284849 -306.72805) (xy 70.30414 -306.682774) (xy 70.330443 -306.641178)
			(xy 70.363078 -306.604341) (xy 70.401199 -306.573216) (xy 70.44382 -306.548609) (xy 70.489836 -306.531157)
			(xy 70.538055 -306.521313) (xy 70.58723 -306.519332) (xy 70.636085 -306.525264) (xy 70.683356 -306.538956)
			(xy 70.727818 -306.560054) (xy 70.768321 -306.58801) (xy 70.803814 -306.622102) (xy 70.833379 -306.661446)
			(xy 70.85625 -306.705023) (xy 70.871834 -306.751704) (xy 70.879729 -306.800281) (xy 70.880224 -306.824888)
			(xy 71.219072 -306.824888) (xy 71.223032 -306.775834) (xy 71.234809 -306.72805) (xy 71.2541 -306.682774)
			(xy 71.280403 -306.641178) (xy 71.313038 -306.604341) (xy 71.351159 -306.573216) (xy 71.39378 -306.548609)
			(xy 71.439796 -306.531157) (xy 71.488015 -306.521313) (xy 71.53719 -306.519332) (xy 71.586045 -306.525264)
			(xy 71.633316 -306.538956) (xy 71.677778 -306.560054) (xy 71.718281 -306.58801) (xy 71.753774 -306.622102)
			(xy 71.783339 -306.661446) (xy 71.80621 -306.705023) (xy 71.821794 -306.751704) (xy 71.829689 -306.800281)
			(xy 71.830184 -306.824888) (xy 72.169032 -306.824888) (xy 72.172992 -306.775834) (xy 72.184769 -306.72805)
			(xy 72.20406 -306.682774) (xy 72.230363 -306.641178) (xy 72.262998 -306.604341) (xy 72.301119 -306.573216)
			(xy 72.34374 -306.548609) (xy 72.389756 -306.531157) (xy 72.437975 -306.521313) (xy 72.48715 -306.519332)
			(xy 72.536005 -306.525264) (xy 72.583276 -306.538956) (xy 72.627738 -306.560054) (xy 72.668241 -306.58801)
			(xy 72.703734 -306.622102) (xy 72.733299 -306.661446) (xy 72.75617 -306.705023) (xy 72.771754 -306.751704)
			(xy 72.779649 -306.800281) (xy 72.780144 -306.824888) (xy 72.779649 -306.849495) (xy 72.771754 -306.898072)
			(xy 72.75617 -306.944753) (xy 72.733299 -306.98833) (xy 72.703734 -307.027674) (xy 72.668241 -307.061766)
			(xy 72.627738 -307.089722) (xy 72.583276 -307.11082) (xy 72.536005 -307.124512) (xy 72.48715 -307.130444)
			(xy 72.437975 -307.128463) (xy 72.389756 -307.118619) (xy 72.34374 -307.101167) (xy 72.301119 -307.07656)
			(xy 72.262998 -307.045435) (xy 72.230363 -307.008598) (xy 72.20406 -306.967002) (xy 72.184769 -306.921726)
			(xy 72.172992 -306.873942) (xy 72.169032 -306.824888) (xy 71.830184 -306.824888) (xy 71.829689 -306.849495)
			(xy 71.821794 -306.898072) (xy 71.80621 -306.944753) (xy 71.783339 -306.98833) (xy 71.753774 -307.027674)
			(xy 71.718281 -307.061766) (xy 71.677778 -307.089722) (xy 71.633316 -307.11082) (xy 71.586045 -307.124512)
			(xy 71.53719 -307.130444) (xy 71.488015 -307.128463) (xy 71.439796 -307.118619) (xy 71.39378 -307.101167)
			(xy 71.351159 -307.07656) (xy 71.313038 -307.045435) (xy 71.280403 -307.008598) (xy 71.2541 -306.967002)
			(xy 71.234809 -306.921726) (xy 71.223032 -306.873942) (xy 71.219072 -306.824888) (xy 70.880224 -306.824888)
			(xy 70.879729 -306.849495) (xy 70.871834 -306.898072) (xy 70.85625 -306.944753) (xy 70.833379 -306.98833)
			(xy 70.803814 -307.027674) (xy 70.768321 -307.061766) (xy 70.727818 -307.089722) (xy 70.683356 -307.11082)
			(xy 70.636085 -307.124512) (xy 70.58723 -307.130444) (xy 70.538055 -307.128463) (xy 70.489836 -307.118619)
			(xy 70.44382 -307.101167) (xy 70.401199 -307.07656) (xy 70.363078 -307.045435) (xy 70.330443 -307.008598)
			(xy 70.30414 -306.967002) (xy 70.284849 -306.921726) (xy 70.273072 -306.873942) (xy 70.269112 -306.824888)
			(xy 69.930264 -306.824888) (xy 69.929769 -306.849495) (xy 69.921874 -306.898072) (xy 69.90629 -306.944753)
			(xy 69.883419 -306.98833) (xy 69.853854 -307.027674) (xy 69.818361 -307.061766) (xy 69.777858 -307.089722)
			(xy 69.733396 -307.11082) (xy 69.686125 -307.124512) (xy 69.63727 -307.130444) (xy 69.588095 -307.128463)
			(xy 69.539876 -307.118619) (xy 69.49386 -307.101167) (xy 69.451239 -307.07656) (xy 69.413118 -307.045435)
			(xy 69.380483 -307.008598) (xy 69.35418 -306.967002) (xy 69.334889 -306.921726) (xy 69.323112 -306.873942)
			(xy 69.319152 -306.824888) (xy 68.98005 -306.824888) (xy 68.979555 -306.849495) (xy 68.97166 -306.898072)
			(xy 68.956076 -306.944753) (xy 68.933205 -306.98833) (xy 68.90364 -307.027674) (xy 68.868147 -307.061766)
			(xy 68.827644 -307.089722) (xy 68.783182 -307.11082) (xy 68.735911 -307.124512) (xy 68.687056 -307.130444)
			(xy 68.637881 -307.128463) (xy 68.589662 -307.118619) (xy 68.543646 -307.101167) (xy 68.501025 -307.07656)
			(xy 68.462904 -307.045435) (xy 68.430269 -307.008598) (xy 68.403966 -306.967002) (xy 68.384675 -306.921726)
			(xy 68.372898 -306.873942) (xy 68.368938 -306.824888) (xy 68.03009 -306.824888) (xy 68.029595 -306.849495)
			(xy 68.0217 -306.898072) (xy 68.006116 -306.944753) (xy 67.983245 -306.98833) (xy 67.95368 -307.027674)
			(xy 67.918187 -307.061766) (xy 67.877684 -307.089722) (xy 67.833222 -307.11082) (xy 67.785951 -307.124512)
			(xy 67.737096 -307.130444) (xy 67.687921 -307.128463) (xy 67.639702 -307.118619) (xy 67.593686 -307.101167)
			(xy 67.551065 -307.07656) (xy 67.512944 -307.045435) (xy 67.480309 -307.008598) (xy 67.454006 -306.967002)
			(xy 67.434715 -306.921726) (xy 67.422938 -306.873942) (xy 67.418978 -306.824888) (xy 67.08013 -306.824888)
			(xy 67.079635 -306.849495) (xy 67.07174 -306.898072) (xy 67.056156 -306.944753) (xy 67.033285 -306.98833)
			(xy 67.00372 -307.027674) (xy 66.968227 -307.061766) (xy 66.927724 -307.089722) (xy 66.883262 -307.11082)
			(xy 66.835991 -307.124512) (xy 66.787136 -307.130444) (xy 66.737961 -307.128463) (xy 66.689742 -307.118619)
			(xy 66.643726 -307.101167) (xy 66.601105 -307.07656) (xy 66.562984 -307.045435) (xy 66.530349 -307.008598)
			(xy 66.504046 -306.967002) (xy 66.484755 -306.921726) (xy 66.472978 -306.873942) (xy 66.469018 -306.824888)
			(xy 66.13017 -306.824888) (xy 66.129675 -306.849495) (xy 66.12178 -306.898072) (xy 66.106196 -306.944753)
			(xy 66.083325 -306.98833) (xy 66.05376 -307.027674) (xy 66.018267 -307.061766) (xy 65.977764 -307.089722)
			(xy 65.933302 -307.11082) (xy 65.886031 -307.124512) (xy 65.837176 -307.130444) (xy 65.788001 -307.128463)
			(xy 65.739782 -307.118619) (xy 65.693766 -307.101167) (xy 65.651145 -307.07656) (xy 65.613024 -307.045435)
			(xy 65.580389 -307.008598) (xy 65.554086 -306.967002) (xy 65.534795 -306.921726) (xy 65.523018 -306.873942)
			(xy 65.519058 -306.824888) (xy 65.18021 -306.824888) (xy 65.179715 -306.849495) (xy 65.17182 -306.898072)
			(xy 65.156236 -306.944753) (xy 65.133365 -306.98833) (xy 65.1038 -307.027674) (xy 65.068307 -307.061766)
			(xy 65.027804 -307.089722) (xy 64.983342 -307.11082) (xy 64.936071 -307.124512) (xy 64.887216 -307.130444)
			(xy 64.838041 -307.128463) (xy 64.789822 -307.118619) (xy 64.743806 -307.101167) (xy 64.701185 -307.07656)
			(xy 64.663064 -307.045435) (xy 64.630429 -307.008598) (xy 64.604126 -306.967002) (xy 64.584835 -306.921726)
			(xy 64.573058 -306.873942) (xy 64.569098 -306.824888) (xy 64.23025 -306.824888) (xy 64.229755 -306.849495)
			(xy 64.22186 -306.898072) (xy 64.206276 -306.944753) (xy 64.183405 -306.98833) (xy 64.15384 -307.027674)
			(xy 64.118347 -307.061766) (xy 64.077844 -307.089722) (xy 64.033382 -307.11082) (xy 63.986111 -307.124512)
			(xy 63.937256 -307.130444) (xy 63.888081 -307.128463) (xy 63.839862 -307.118619) (xy 63.793846 -307.101167)
			(xy 63.751225 -307.07656) (xy 63.713104 -307.045435) (xy 63.680469 -307.008598) (xy 63.654166 -306.967002)
			(xy 63.634875 -306.921726) (xy 63.623098 -306.873942) (xy 63.619138 -306.824888) (xy 63.28029 -306.824888)
			(xy 63.279795 -306.849495) (xy 63.2719 -306.898072) (xy 63.256316 -306.944753) (xy 63.233445 -306.98833)
			(xy 63.20388 -307.027674) (xy 63.168387 -307.061766) (xy 63.127884 -307.089722) (xy 63.083422 -307.11082)
			(xy 63.036151 -307.124512) (xy 62.987296 -307.130444) (xy 62.938121 -307.128463) (xy 62.889902 -307.118619)
			(xy 62.843886 -307.101167) (xy 62.801265 -307.07656) (xy 62.763144 -307.045435) (xy 62.730509 -307.008598)
			(xy 62.704206 -306.967002) (xy 62.684915 -306.921726) (xy 62.673138 -306.873942) (xy 62.669178 -306.824888)
			(xy 62.330076 -306.824888) (xy 62.329581 -306.849495) (xy 62.321686 -306.898072) (xy 62.306102 -306.944753)
			(xy 62.283231 -306.98833) (xy 62.253666 -307.027674) (xy 62.218173 -307.061766) (xy 62.17767 -307.089722)
			(xy 62.133208 -307.11082) (xy 62.085937 -307.124512) (xy 62.037082 -307.130444) (xy 61.987907 -307.128463)
			(xy 61.939688 -307.118619) (xy 61.893672 -307.101167) (xy 61.851051 -307.07656) (xy 61.81293 -307.045435)
			(xy 61.780295 -307.008598) (xy 61.753992 -306.967002) (xy 61.734701 -306.921726) (xy 61.722924 -306.873942)
			(xy 61.718964 -306.824888) (xy 61.380116 -306.824888) (xy 61.379621 -306.849495) (xy 61.371726 -306.898072)
			(xy 61.356142 -306.944753) (xy 61.333271 -306.98833) (xy 61.303706 -307.027674) (xy 61.268213 -307.061766)
			(xy 61.22771 -307.089722) (xy 61.183248 -307.11082) (xy 61.135977 -307.124512) (xy 61.087122 -307.130444)
			(xy 61.037947 -307.128463) (xy 60.989728 -307.118619) (xy 60.943712 -307.101167) (xy 60.901091 -307.07656)
			(xy 60.86297 -307.045435) (xy 60.830335 -307.008598) (xy 60.804032 -306.967002) (xy 60.784741 -306.921726)
			(xy 60.772964 -306.873942) (xy 60.769004 -306.824888) (xy 60.430156 -306.824888) (xy 60.429661 -306.849495)
			(xy 60.421766 -306.898072) (xy 60.406182 -306.944753) (xy 60.383311 -306.98833) (xy 60.353746 -307.027674)
			(xy 60.318253 -307.061766) (xy 60.27775 -307.089722) (xy 60.233288 -307.11082) (xy 60.186017 -307.124512)
			(xy 60.137162 -307.130444) (xy 60.087987 -307.128463) (xy 60.039768 -307.118619) (xy 59.993752 -307.101167)
			(xy 59.951131 -307.07656) (xy 59.91301 -307.045435) (xy 59.880375 -307.008598) (xy 59.854072 -306.967002)
			(xy 59.834781 -306.921726) (xy 59.823004 -306.873942) (xy 59.819044 -306.824888) (xy 58.530236 -306.824888)
			(xy 58.529741 -306.849495) (xy 58.521846 -306.898072) (xy 58.506262 -306.944753) (xy 58.483391 -306.98833)
			(xy 58.453826 -307.027674) (xy 58.418333 -307.061766) (xy 58.37783 -307.089722) (xy 58.333368 -307.11082)
			(xy 58.286097 -307.124512) (xy 58.237242 -307.130444) (xy 58.188067 -307.128463) (xy 58.139848 -307.118619)
			(xy 58.093832 -307.101167) (xy 58.051211 -307.07656) (xy 58.01309 -307.045435) (xy 57.980455 -307.008598)
			(xy 57.954152 -306.967002) (xy 57.934861 -306.921726) (xy 57.923084 -306.873942) (xy 57.919124 -306.824888)
			(xy 57.580276 -306.824888) (xy 57.579781 -306.849495) (xy 57.571886 -306.898072) (xy 57.556302 -306.944753)
			(xy 57.533431 -306.98833) (xy 57.503866 -307.027674) (xy 57.468373 -307.061766) (xy 57.42787 -307.089722)
			(xy 57.383408 -307.11082) (xy 57.336137 -307.124512) (xy 57.287282 -307.130444) (xy 57.238107 -307.128463)
			(xy 57.189888 -307.118619) (xy 57.143872 -307.101167) (xy 57.101251 -307.07656) (xy 57.06313 -307.045435)
			(xy 57.030495 -307.008598) (xy 57.004192 -306.967002) (xy 56.984901 -306.921726) (xy 56.973124 -306.873942)
			(xy 56.969164 -306.824888) (xy 56.630062 -306.824888) (xy 56.629567 -306.849495) (xy 56.621672 -306.898072)
			(xy 56.606088 -306.944753) (xy 56.583217 -306.98833) (xy 56.553652 -307.027674) (xy 56.518159 -307.061766)
			(xy 56.477656 -307.089722) (xy 56.433194 -307.11082) (xy 56.385923 -307.124512) (xy 56.337068 -307.130444)
			(xy 56.287893 -307.128463) (xy 56.239674 -307.118619) (xy 56.193658 -307.101167) (xy 56.151037 -307.07656)
			(xy 56.112916 -307.045435) (xy 56.080281 -307.008598) (xy 56.053978 -306.967002) (xy 56.034687 -306.921726)
			(xy 56.02291 -306.873942) (xy 56.01895 -306.824888) (xy 55.680102 -306.824888) (xy 55.679607 -306.849495)
			(xy 55.671712 -306.898072) (xy 55.656128 -306.944753) (xy 55.633257 -306.98833) (xy 55.603692 -307.027674)
			(xy 55.568199 -307.061766) (xy 55.527696 -307.089722) (xy 55.483234 -307.11082) (xy 55.435963 -307.124512)
			(xy 55.387108 -307.130444) (xy 55.337933 -307.128463) (xy 55.289714 -307.118619) (xy 55.243698 -307.101167)
			(xy 55.201077 -307.07656) (xy 55.162956 -307.045435) (xy 55.130321 -307.008598) (xy 55.104018 -306.967002)
			(xy 55.084727 -306.921726) (xy 55.07295 -306.873942) (xy 55.06899 -306.824888) (xy 54.730142 -306.824888)
			(xy 54.729647 -306.849495) (xy 54.721752 -306.898072) (xy 54.706168 -306.944753) (xy 54.683297 -306.98833)
			(xy 54.653732 -307.027674) (xy 54.618239 -307.061766) (xy 54.577736 -307.089722) (xy 54.533274 -307.11082)
			(xy 54.486003 -307.124512) (xy 54.437148 -307.130444) (xy 54.387973 -307.128463) (xy 54.339754 -307.118619)
			(xy 54.293738 -307.101167) (xy 54.251117 -307.07656) (xy 54.212996 -307.045435) (xy 54.180361 -307.008598)
			(xy 54.154058 -306.967002) (xy 54.134767 -306.921726) (xy 54.12299 -306.873942) (xy 54.11903 -306.824888)
			(xy 53.780182 -306.824888) (xy 53.779687 -306.849495) (xy 53.771792 -306.898072) (xy 53.756208 -306.944753)
			(xy 53.733337 -306.98833) (xy 53.703772 -307.027674) (xy 53.668279 -307.061766) (xy 53.627776 -307.089722)
			(xy 53.583314 -307.11082) (xy 53.536043 -307.124512) (xy 53.487188 -307.130444) (xy 53.438013 -307.128463)
			(xy 53.389794 -307.118619) (xy 53.343778 -307.101167) (xy 53.301157 -307.07656) (xy 53.263036 -307.045435)
			(xy 53.230401 -307.008598) (xy 53.204098 -306.967002) (xy 53.184807 -306.921726) (xy 53.17303 -306.873942)
			(xy 53.16907 -306.824888) (xy 52.830222 -306.824888) (xy 52.829727 -306.849495) (xy 52.821832 -306.898072)
			(xy 52.806248 -306.944753) (xy 52.783377 -306.98833) (xy 52.753812 -307.027674) (xy 52.718319 -307.061766)
			(xy 52.677816 -307.089722) (xy 52.633354 -307.11082) (xy 52.586083 -307.124512) (xy 52.537228 -307.130444)
			(xy 52.488053 -307.128463) (xy 52.439834 -307.118619) (xy 52.393818 -307.101167) (xy 52.351197 -307.07656)
			(xy 52.313076 -307.045435) (xy 52.280441 -307.008598) (xy 52.254138 -306.967002) (xy 52.234847 -306.921726)
			(xy 52.22307 -306.873942) (xy 52.21911 -306.824888) (xy 51.880262 -306.824888) (xy 51.879767 -306.849495)
			(xy 51.871872 -306.898072) (xy 51.856288 -306.944753) (xy 51.833417 -306.98833) (xy 51.803852 -307.027674)
			(xy 51.768359 -307.061766) (xy 51.727856 -307.089722) (xy 51.683394 -307.11082) (xy 51.636123 -307.124512)
			(xy 51.587268 -307.130444) (xy 51.538093 -307.128463) (xy 51.489874 -307.118619) (xy 51.443858 -307.101167)
			(xy 51.401237 -307.07656) (xy 51.363116 -307.045435) (xy 51.330481 -307.008598) (xy 51.304178 -306.967002)
			(xy 51.284887 -306.921726) (xy 51.27311 -306.873942) (xy 51.26915 -306.824888) (xy 50.930275 -306.824888)
			(xy 50.930725 -306.83319) (xy 50.925356 -306.882541) (xy 50.912074 -306.930374) (xy 50.891229 -306.975428)
			(xy 50.863369 -307.016516) (xy 50.829229 -307.052555) (xy 50.789708 -307.082596) (xy 50.745848 -307.105848)
			(xy 50.698804 -307.121698) (xy 50.649815 -307.129729) (xy 50.624994 -307.130196) (xy 50.610812 -307.130009)
			(xy 50.582572 -307.127335) (xy 50.568606 -307.124862) (xy 50.562512 -307.123863) (xy 50.550182 -307.124512)
			(xy 50.544222 -307.126132) (xy 50.538338 -307.128158) (xy 50.527682 -307.134578) (xy 50.52314 -307.138832)
			(xy 50.463704 -307.198268) (xy 50.455521 -307.207565) (xy 50.448212 -307.231189) (xy 50.449734 -307.24348)
			(xy 50.452221 -307.257445) (xy 50.454896 -307.285685) (xy 50.455068 -307.299868) (xy 73.593972 -307.299868)
			(xy 73.597932 -307.250814) (xy 73.609709 -307.20303) (xy 73.629 -307.157754) (xy 73.655303 -307.116158)
			(xy 73.687938 -307.079321) (xy 73.726059 -307.048196) (xy 73.76868 -307.023589) (xy 73.814696 -307.006137)
			(xy 73.862915 -306.996293) (xy 73.91209 -306.994312) (xy 73.960945 -307.000244) (xy 74.008216 -307.013936)
			(xy 74.052678 -307.035034) (xy 74.093181 -307.06299) (xy 74.128674 -307.097082) (xy 74.158239 -307.136426)
			(xy 74.18111 -307.180003) (xy 74.196694 -307.226684) (xy 74.204589 -307.275261) (xy 74.205084 -307.299868)
			(xy 74.544186 -307.299868) (xy 74.548146 -307.250814) (xy 74.559923 -307.20303) (xy 74.579214 -307.157754)
			(xy 74.605517 -307.116158) (xy 74.638152 -307.079321) (xy 74.676273 -307.048196) (xy 74.718894 -307.023589)
			(xy 74.76491 -307.006137) (xy 74.813129 -306.996293) (xy 74.862304 -306.994312) (xy 74.911159 -307.000244)
			(xy 74.95843 -307.013936) (xy 75.002892 -307.035034) (xy 75.043395 -307.06299) (xy 75.078888 -307.097082)
			(xy 75.108453 -307.136426) (xy 75.131324 -307.180003) (xy 75.146908 -307.226684) (xy 75.154803 -307.275261)
			(xy 75.155298 -307.299868) (xy 75.494146 -307.299868) (xy 75.498106 -307.250814) (xy 75.509883 -307.20303)
			(xy 75.529174 -307.157754) (xy 75.555477 -307.116158) (xy 75.588112 -307.079321) (xy 75.626233 -307.048196)
			(xy 75.668854 -307.023589) (xy 75.71487 -307.006137) (xy 75.763089 -306.996293) (xy 75.812264 -306.994312)
			(xy 75.861119 -307.000244) (xy 75.90839 -307.013936) (xy 75.952852 -307.035034) (xy 75.993355 -307.06299)
			(xy 76.028848 -307.097082) (xy 76.058413 -307.136426) (xy 76.081284 -307.180003) (xy 76.096868 -307.226684)
			(xy 76.104763 -307.275261) (xy 76.105258 -307.299868) (xy 76.444106 -307.299868) (xy 76.448066 -307.250814)
			(xy 76.459843 -307.20303) (xy 76.479134 -307.157754) (xy 76.505437 -307.116158) (xy 76.538072 -307.079321)
			(xy 76.576193 -307.048196) (xy 76.618814 -307.023589) (xy 76.66483 -307.006137) (xy 76.713049 -306.996293)
			(xy 76.762224 -306.994312) (xy 76.811079 -307.000244) (xy 76.85835 -307.013936) (xy 76.902812 -307.035034)
			(xy 76.943315 -307.06299) (xy 76.978808 -307.097082) (xy 77.008373 -307.136426) (xy 77.031244 -307.180003)
			(xy 77.046828 -307.226684) (xy 77.054723 -307.275261) (xy 77.055218 -307.299868) (xy 77.394066 -307.299868)
			(xy 77.398026 -307.250814) (xy 77.409803 -307.20303) (xy 77.429094 -307.157754) (xy 77.455397 -307.116158)
			(xy 77.488032 -307.079321) (xy 77.526153 -307.048196) (xy 77.568774 -307.023589) (xy 77.61479 -307.006137)
			(xy 77.663009 -306.996293) (xy 77.712184 -306.994312) (xy 77.761039 -307.000244) (xy 77.80831 -307.013936)
			(xy 77.852772 -307.035034) (xy 77.893275 -307.06299) (xy 77.928768 -307.097082) (xy 77.958333 -307.136426)
			(xy 77.981204 -307.180003) (xy 77.996788 -307.226684) (xy 78.004683 -307.275261) (xy 78.005178 -307.299868)
			(xy 78.344026 -307.299868) (xy 78.347986 -307.250814) (xy 78.359763 -307.20303) (xy 78.379054 -307.157754)
			(xy 78.405357 -307.116158) (xy 78.437992 -307.079321) (xy 78.476113 -307.048196) (xy 78.518734 -307.023589)
			(xy 78.56475 -307.006137) (xy 78.612969 -306.996293) (xy 78.662144 -306.994312) (xy 78.710999 -307.000244)
			(xy 78.75827 -307.013936) (xy 78.802732 -307.035034) (xy 78.843235 -307.06299) (xy 78.878728 -307.097082)
			(xy 78.908293 -307.136426) (xy 78.931164 -307.180003) (xy 78.946748 -307.226684) (xy 78.954643 -307.275261)
			(xy 78.955138 -307.299868) (xy 79.293986 -307.299868) (xy 79.297946 -307.250814) (xy 79.309723 -307.20303)
			(xy 79.329014 -307.157754) (xy 79.355317 -307.116158) (xy 79.387952 -307.079321) (xy 79.426073 -307.048196)
			(xy 79.468694 -307.023589) (xy 79.51471 -307.006137) (xy 79.562929 -306.996293) (xy 79.612104 -306.994312)
			(xy 79.660959 -307.000244) (xy 79.70823 -307.013936) (xy 79.752692 -307.035034) (xy 79.793195 -307.06299)
			(xy 79.828688 -307.097082) (xy 79.858253 -307.136426) (xy 79.881124 -307.180003) (xy 79.896708 -307.226684)
			(xy 79.904603 -307.275261) (xy 79.905098 -307.299868) (xy 80.243946 -307.299868) (xy 80.247906 -307.250814)
			(xy 80.259683 -307.20303) (xy 80.278974 -307.157754) (xy 80.305277 -307.116158) (xy 80.337912 -307.079321)
			(xy 80.376033 -307.048196) (xy 80.418654 -307.023589) (xy 80.46467 -307.006137) (xy 80.512889 -306.996293)
			(xy 80.562064 -306.994312) (xy 80.610919 -307.000244) (xy 80.65819 -307.013936) (xy 80.702652 -307.035034)
			(xy 80.743155 -307.06299) (xy 80.778648 -307.097082) (xy 80.808213 -307.136426) (xy 80.831084 -307.180003)
			(xy 80.846668 -307.226684) (xy 80.854563 -307.275261) (xy 80.855058 -307.299868) (xy 81.19416 -307.299868)
			(xy 81.19812 -307.250814) (xy 81.209897 -307.20303) (xy 81.229188 -307.157754) (xy 81.255491 -307.116158)
			(xy 81.288126 -307.079321) (xy 81.326247 -307.048196) (xy 81.368868 -307.023589) (xy 81.414884 -307.006137)
			(xy 81.463103 -306.996293) (xy 81.512278 -306.994312) (xy 81.561133 -307.000244) (xy 81.608404 -307.013936)
			(xy 81.652866 -307.035034) (xy 81.693369 -307.06299) (xy 81.728862 -307.097082) (xy 81.758427 -307.136426)
			(xy 81.781298 -307.180003) (xy 81.796882 -307.226684) (xy 81.804777 -307.275261) (xy 81.805272 -307.299868)
			(xy 82.14412 -307.299868) (xy 82.14808 -307.250814) (xy 82.159857 -307.20303) (xy 82.179148 -307.157754)
			(xy 82.205451 -307.116158) (xy 82.238086 -307.079321) (xy 82.276207 -307.048196) (xy 82.318828 -307.023589)
			(xy 82.364844 -307.006137) (xy 82.413063 -306.996293) (xy 82.462238 -306.994312) (xy 82.511093 -307.000244)
			(xy 82.558364 -307.013936) (xy 82.602826 -307.035034) (xy 82.643329 -307.06299) (xy 82.678822 -307.097082)
			(xy 82.708387 -307.136426) (xy 82.731258 -307.180003) (xy 82.746842 -307.226684) (xy 82.754737 -307.275261)
			(xy 82.755232 -307.299868) (xy 82.754955 -307.313639) (xy 91.226391 -307.313639) (xy 91.226393 -307.259139)
			(xy 91.234151 -307.205193) (xy 91.249507 -307.152901) (xy 91.272148 -307.103327) (xy 91.301615 -307.057479)
			(xy 91.337306 -307.016292) (xy 91.378495 -306.980603) (xy 91.424344 -306.951139) (xy 91.47392 -306.9285)
			(xy 91.526213 -306.913147) (xy 91.580159 -306.905392) (xy 91.634659 -306.905393) (xy 91.688604 -306.91315)
			(xy 91.740896 -306.928506) (xy 91.790471 -306.951147) (xy 91.836319 -306.980613) (xy 91.877507 -307.016304)
			(xy 91.913196 -307.057493) (xy 91.930373 -307.084222) (xy 92.714316 -307.084222) (xy 92.718387 -307.0286)
			(xy 92.730513 -306.974163) (xy 92.750436 -306.922072) (xy 92.777732 -306.873437) (xy 92.811818 -306.829294)
			(xy 92.851967 -306.790585) (xy 92.897325 -306.758134) (xy 92.946925 -306.732633) (xy 92.999709 -306.714626)
			(xy 93.054552 -306.704496) (xy 93.110286 -306.702459) (xy 93.165723 -306.708559) (xy 93.21968 -306.722665)
			(xy 93.271009 -306.744477) (xy 93.318615 -306.773531) (xy 93.361483 -306.809206) (xy 93.3987 -306.850743)
			(xy 93.429473 -306.897256) (xy 93.453145 -306.947753) (xy 93.469213 -307.00116) (xy 93.477333 -307.056336)
			(xy 93.477842 -307.084222) (xy 93.477333 -307.112108) (xy 93.469213 -307.167284) (xy 93.453145 -307.220691)
			(xy 93.429473 -307.271188) (xy 93.3987 -307.317701) (xy 93.361483 -307.359238) (xy 93.318615 -307.394913)
			(xy 93.271009 -307.423967) (xy 93.21968 -307.445779) (xy 93.165723 -307.459885) (xy 93.110286 -307.465985)
			(xy 93.054552 -307.463948) (xy 92.999709 -307.453818) (xy 92.946925 -307.435811) (xy 92.897325 -307.41031)
			(xy 92.851967 -307.377859) (xy 92.811818 -307.33915) (xy 92.777732 -307.295007) (xy 92.750436 -307.246372)
			(xy 92.730513 -307.194281) (xy 92.718387 -307.139844) (xy 92.714316 -307.084222) (xy 91.930373 -307.084222)
			(xy 91.94266 -307.103342) (xy 91.965299 -307.152918) (xy 91.980653 -307.20521) (xy 91.988408 -307.259156)
			(xy 91.988894 -307.286406) (xy 91.987116 -307.322982) (xy 91.9861 -307.334412) (xy 91.99372 -307.355494)
			(xy 92.065348 -307.427122) (xy 92.086684 -307.434742) (xy 92.098114 -307.433726) (xy 92.13469 -307.431948)
			(xy 92.161939 -307.432487) (xy 92.215882 -307.440241) (xy 92.268173 -307.455593) (xy 92.317748 -307.47823)
			(xy 92.363596 -307.507691) (xy 92.404785 -307.543377) (xy 92.440477 -307.584561) (xy 92.469944 -307.630405)
			(xy 92.492588 -307.679976) (xy 92.507947 -307.732265) (xy 92.515709 -307.786207) (xy 92.516198 -307.813456)
			(xy 92.516033 -307.82387) (xy 102.823518 -307.82387) (xy 102.823962 -307.796499) (xy 102.831785 -307.742319)
			(xy 102.847279 -307.689815) (xy 102.870125 -307.640069) (xy 102.899855 -307.594103) (xy 102.917498 -307.573172)
			(xy 102.923594 -307.56606) (xy 102.929944 -307.549042) (xy 102.929944 -307.463698) (xy 102.923594 -307.44668)
			(xy 102.917498 -307.439568) (xy 102.899829 -307.418658) (xy 102.870108 -307.372686) (xy 102.847266 -307.322936)
			(xy 102.831773 -307.27043) (xy 102.823948 -307.216249) (xy 102.823951 -307.161506) (xy 102.831783 -307.107325)
			(xy 102.847282 -307.054822) (xy 102.87013 -307.005074) (xy 102.899856 -306.959105) (xy 102.917498 -306.938172)
			(xy 102.923594 -306.93106) (xy 102.929944 -306.914042) (xy 102.929944 -306.828698) (xy 102.923594 -306.81168)
			(xy 102.917498 -306.804568) (xy 102.899829 -306.783658) (xy 102.870108 -306.737686) (xy 102.847266 -306.687936)
			(xy 102.831773 -306.63543) (xy 102.823948 -306.581249) (xy 102.823951 -306.526506) (xy 102.831783 -306.472325)
			(xy 102.847282 -306.419822) (xy 102.87013 -306.370074) (xy 102.899856 -306.324105) (xy 102.917498 -306.303172)
			(xy 102.923594 -306.29606) (xy 102.929944 -306.279042) (xy 102.929944 -306.193698) (xy 102.923594 -306.17668)
			(xy 102.917498 -306.169568) (xy 102.899877 -306.148621) (xy 102.870163 -306.102653) (xy 102.847323 -306.052909)
			(xy 102.831828 -306.000411) (xy 102.823995 -305.946238) (xy 102.823518 -305.91887) (xy 102.824004 -305.891619)
			(xy 102.83176 -305.837671) (xy 102.847115 -305.785376) (xy 102.869757 -305.735799) (xy 102.899223 -305.689949)
			(xy 102.934914 -305.648758) (xy 102.976105 -305.613067) (xy 103.021955 -305.583601) (xy 103.071532 -305.560959)
			(xy 103.123827 -305.545604) (xy 103.177775 -305.537848) (xy 103.232277 -305.537848) (xy 103.286225 -305.545604)
			(xy 103.33852 -305.560959) (xy 103.388097 -305.583601) (xy 103.433947 -305.613067) (xy 103.475138 -305.648758)
			(xy 103.510829 -305.689949) (xy 103.540295 -305.735799) (xy 103.562937 -305.785376) (xy 103.578292 -305.837671)
			(xy 103.586048 -305.891619) (xy 103.586534 -305.91887) (xy 103.586066 -305.94624) (xy 103.578251 -306.00042)
			(xy 103.562764 -306.052924) (xy 103.539922 -306.102671) (xy 103.510196 -306.148637) (xy 103.492554 -306.169568)
			(xy 103.486458 -306.17668) (xy 103.480108 -306.193698) (xy 103.480108 -306.279042) (xy 103.486458 -306.29606)
			(xy 103.492554 -306.303172) (xy 103.510166 -306.324128) (xy 103.539894 -306.370091) (xy 103.562742 -306.419834)
			(xy 103.578241 -306.472332) (xy 103.586073 -306.526508) (xy 103.586076 -306.581247) (xy 103.578251 -306.635423)
			(xy 103.562758 -306.687924) (xy 103.539915 -306.737669) (xy 103.510193 -306.783636) (xy 103.492554 -306.804568)
			(xy 103.486458 -306.81168) (xy 103.480108 -306.828698) (xy 103.480108 -306.914042) (xy 103.486458 -306.93106)
			(xy 103.492554 -306.938172) (xy 103.510166 -306.959128) (xy 103.539894 -307.005091) (xy 103.562742 -307.054834)
			(xy 103.578241 -307.107332) (xy 103.586073 -307.161508) (xy 103.586076 -307.216247) (xy 103.578251 -307.270423)
			(xy 103.562758 -307.322924) (xy 103.539915 -307.372669) (xy 103.510193 -307.418636) (xy 103.492554 -307.439568)
			(xy 103.486458 -307.44668) (xy 103.480108 -307.463698) (xy 103.480108 -307.549042) (xy 103.486458 -307.56606)
			(xy 103.492554 -307.573172) (xy 103.510186 -307.59411) (xy 103.539901 -307.64008) (xy 103.562739 -307.689826)
			(xy 103.578231 -307.742326) (xy 103.58606 -307.796501) (xy 103.586534 -307.82387) (xy 103.586048 -307.851121)
			(xy 103.582224 -307.877718) (xy 106.455718 -307.877718) (xy 106.45619 -307.850348) (xy 106.464006 -307.796169)
			(xy 106.479493 -307.743666) (xy 106.502334 -307.693919) (xy 106.532057 -307.647952) (xy 106.549698 -307.62702)
			(xy 106.555794 -307.619908) (xy 106.562144 -307.60289) (xy 106.562144 -307.517546) (xy 106.555794 -307.500528)
			(xy 106.549698 -307.493416) (xy 106.532076 -307.472468) (xy 106.502353 -307.426502) (xy 106.479508 -307.376759)
			(xy 106.464012 -307.324259) (xy 106.456182 -307.270083) (xy 106.45618 -307.215344) (xy 106.464006 -307.161168)
			(xy 106.479499 -307.108667) (xy 106.50234 -307.058921) (xy 106.53206 -307.012953) (xy 106.549698 -306.99202)
			(xy 106.555794 -306.984908) (xy 106.562144 -306.96789) (xy 106.562144 -306.882546) (xy 106.555794 -306.865528)
			(xy 106.549698 -306.858416) (xy 106.532076 -306.837468) (xy 106.502353 -306.791502) (xy 106.479508 -306.741759)
			(xy 106.464012 -306.689259) (xy 106.456182 -306.635083) (xy 106.45618 -306.580344) (xy 106.464006 -306.526168)
			(xy 106.479499 -306.473667) (xy 106.50234 -306.423921) (xy 106.53206 -306.377953) (xy 106.549698 -306.35702)
			(xy 106.555794 -306.349908) (xy 106.562144 -306.33289) (xy 106.562144 -306.247546) (xy 106.555794 -306.230528)
			(xy 106.549698 -306.223416) (xy 106.532053 -306.202489) (xy 106.502342 -306.156515) (xy 106.479507 -306.106766)
			(xy 106.464018 -306.054264) (xy 106.456191 -306.000088) (xy 106.455718 -305.972718) (xy 106.456204 -305.945467)
			(xy 106.46396 -305.891519) (xy 106.479315 -305.839224) (xy 106.501957 -305.789647) (xy 106.531423 -305.743797)
			(xy 106.567114 -305.702606) (xy 106.608305 -305.666915) (xy 106.654155 -305.637449) (xy 106.703732 -305.614807)
			(xy 106.756027 -305.599452) (xy 106.809975 -305.591696) (xy 106.864477 -305.591696) (xy 106.918425 -305.599452)
			(xy 106.97072 -305.614807) (xy 107.020297 -305.637449) (xy 107.066147 -305.666915) (xy 107.107338 -305.702606)
			(xy 107.143029 -305.743797) (xy 107.172495 -305.789647) (xy 107.195137 -305.839224) (xy 107.210492 -305.891519)
			(xy 107.218248 -305.945467) (xy 107.218734 -305.972718) (xy 107.218295 -306.000089) (xy 107.210473 -306.05427)
			(xy 107.194978 -306.106774) (xy 107.17213 -306.156521) (xy 107.142399 -306.202486) (xy 107.124754 -306.223416)
			(xy 107.118658 -306.230528) (xy 107.112308 -306.247546) (xy 107.112308 -306.33289) (xy 107.118658 -306.349908)
			(xy 107.124754 -306.35702) (xy 107.142413 -306.377938) (xy 107.172139 -306.423908) (xy 107.194984 -306.473657)
			(xy 107.21048 -306.526161) (xy 107.218307 -306.580342) (xy 107.218305 -306.635085) (xy 107.210474 -306.689266)
			(xy 107.194975 -306.741769) (xy 107.172126 -306.791516) (xy 107.142397 -306.837484) (xy 107.124754 -306.858416)
			(xy 107.118658 -306.865528) (xy 107.112308 -306.882546) (xy 107.112308 -306.96789) (xy 107.118658 -306.984908)
			(xy 107.124754 -306.99202) (xy 107.142413 -307.012938) (xy 107.172139 -307.058908) (xy 107.194984 -307.108657)
			(xy 107.21048 -307.161161) (xy 107.218307 -307.215342) (xy 107.218305 -307.270085) (xy 107.210474 -307.324266)
			(xy 107.194975 -307.376769) (xy 107.172126 -307.426516) (xy 107.142397 -307.472484) (xy 107.124754 -307.493416)
			(xy 107.118658 -307.500528) (xy 107.112308 -307.517546) (xy 107.112308 -307.60289) (xy 107.118658 -307.619908)
			(xy 107.124754 -307.62702) (xy 107.142362 -307.647977) (xy 107.17208 -307.693942) (xy 107.194923 -307.743683)
			(xy 107.210421 -307.796179) (xy 107.214426 -307.82387) (xy 109.663738 -307.82387) (xy 109.664177 -307.796499)
			(xy 109.672 -307.742318) (xy 109.687495 -307.689814) (xy 109.710343 -307.640068) (xy 109.740074 -307.594103)
			(xy 109.757718 -307.573172) (xy 109.763814 -307.56606) (xy 109.770164 -307.549042) (xy 109.770164 -307.463698)
			(xy 109.763814 -307.44668) (xy 109.757718 -307.439568) (xy 109.740048 -307.418659) (xy 109.710325 -307.372687)
			(xy 109.687482 -307.322937) (xy 109.671989 -307.270431) (xy 109.664163 -307.216249) (xy 109.664166 -307.161506)
			(xy 109.671998 -307.107325) (xy 109.687498 -307.054821) (xy 109.710347 -307.005074) (xy 109.740076 -306.959105)
			(xy 109.757718 -306.938172) (xy 109.763814 -306.93106) (xy 109.770164 -306.914042) (xy 109.770164 -306.828698)
			(xy 109.763814 -306.81168) (xy 109.757718 -306.804568) (xy 109.740048 -306.783659) (xy 109.710325 -306.737687)
			(xy 109.687482 -306.687937) (xy 109.671989 -306.635431) (xy 109.664163 -306.581249) (xy 109.664166 -306.526506)
			(xy 109.671998 -306.472325) (xy 109.687498 -306.419821) (xy 109.710347 -306.370074) (xy 109.740076 -306.324105)
			(xy 109.757718 -306.303172) (xy 109.763814 -306.29606) (xy 109.770164 -306.279042) (xy 109.770164 -306.193698)
			(xy 109.763814 -306.17668) (xy 109.757718 -306.169568) (xy 109.7401 -306.148619) (xy 109.710384 -306.102651)
			(xy 109.687544 -306.052908) (xy 109.672048 -306.000411) (xy 109.664215 -305.946238) (xy 109.663738 -305.91887)
			(xy 109.664224 -305.891619) (xy 109.67198 -305.837671) (xy 109.687335 -305.785376) (xy 109.709977 -305.735799)
			(xy 109.739443 -305.689949) (xy 109.775134 -305.648758) (xy 109.816325 -305.613067) (xy 109.862175 -305.583601)
			(xy 109.911752 -305.560959) (xy 109.964047 -305.545604) (xy 110.017995 -305.537848) (xy 110.072497 -305.537848)
			(xy 110.126445 -305.545604) (xy 110.17874 -305.560959) (xy 110.228317 -305.583601) (xy 110.274167 -305.613067)
			(xy 110.315358 -305.648758) (xy 110.351049 -305.689949) (xy 110.380515 -305.735799) (xy 110.403157 -305.785376)
			(xy 110.418512 -305.837671) (xy 110.426268 -305.891619) (xy 110.426754 -305.91887) (xy 110.426282 -305.94624)
			(xy 110.418467 -306.000419) (xy 110.40298 -306.052923) (xy 110.380139 -306.10267) (xy 110.350415 -306.148637)
			(xy 110.332774 -306.169568) (xy 110.326678 -306.17668) (xy 110.320328 -306.193698) (xy 110.320328 -306.279042)
			(xy 110.326678 -306.29606) (xy 110.332774 -306.303172) (xy 110.350385 -306.324129) (xy 110.380111 -306.370092)
			(xy 110.402958 -306.419835) (xy 110.418457 -306.472333) (xy 110.426288 -306.526508) (xy 110.426291 -306.581247)
			(xy 110.418466 -306.635423) (xy 110.402974 -306.687923) (xy 110.380133 -306.737668) (xy 110.350413 -306.783635)
			(xy 110.332774 -306.804568) (xy 110.326678 -306.81168) (xy 110.320328 -306.828698) (xy 110.320328 -306.914042)
			(xy 110.326678 -306.93106) (xy 110.332774 -306.938172) (xy 110.350385 -306.959129) (xy 110.380111 -307.005092)
			(xy 110.402958 -307.054835) (xy 110.418457 -307.107333) (xy 110.426288 -307.161508) (xy 110.426291 -307.216247)
			(xy 110.418466 -307.270423) (xy 110.402974 -307.322923) (xy 110.380133 -307.372668) (xy 110.350413 -307.418635)
			(xy 110.332774 -307.439568) (xy 110.326678 -307.44668) (xy 110.320328 -307.463698) (xy 110.320328 -307.549042)
			(xy 110.326678 -307.56606) (xy 110.332774 -307.573172) (xy 110.350409 -307.594107) (xy 110.380123 -307.640079)
			(xy 110.40296 -307.689825) (xy 110.418452 -307.742326) (xy 110.42628 -307.796501) (xy 110.426754 -307.82387)
			(xy 110.426268 -307.851121) (xy 110.422444 -307.877718) (xy 113.295938 -307.877718) (xy 113.296405 -307.850348)
			(xy 113.304221 -307.796168) (xy 113.31971 -307.743665) (xy 113.342551 -307.693918) (xy 113.372276 -307.647951)
			(xy 113.389918 -307.62702) (xy 113.396014 -307.619908) (xy 113.402364 -307.60289) (xy 113.402364 -307.517546)
			(xy 113.396014 -307.500528) (xy 113.389918 -307.493416) (xy 113.372295 -307.472469) (xy 113.34257 -307.426503)
			(xy 113.319725 -307.376759) (xy 113.304227 -307.32426) (xy 113.296397 -307.270083) (xy 113.296395 -307.215344)
			(xy 113.304222 -307.161167) (xy 113.319715 -307.108666) (xy 113.342557 -307.05892) (xy 113.372279 -307.012953)
			(xy 113.389918 -306.99202) (xy 113.396014 -306.984908) (xy 113.402364 -306.96789) (xy 113.402364 -306.882546)
			(xy 113.396014 -306.865528) (xy 113.389918 -306.858416) (xy 113.372295 -306.837469) (xy 113.34257 -306.791503)
			(xy 113.319725 -306.741759) (xy 113.304227 -306.68926) (xy 113.296397 -306.635083) (xy 113.296395 -306.580344)
			(xy 113.304222 -306.526167) (xy 113.319715 -306.473666) (xy 113.342557 -306.42392) (xy 113.372279 -306.377953)
			(xy 113.389918 -306.35702) (xy 113.396014 -306.349908) (xy 113.402364 -306.33289) (xy 113.402364 -306.247546)
			(xy 113.396014 -306.230528) (xy 113.389918 -306.223416) (xy 113.372276 -306.202486) (xy 113.342564 -306.156513)
			(xy 113.319728 -306.106765) (xy 113.304238 -306.054264) (xy 113.296411 -306.000087) (xy 113.295938 -305.972718)
			(xy 113.296424 -305.945467) (xy 113.30418 -305.891519) (xy 113.319535 -305.839224) (xy 113.342177 -305.789647)
			(xy 113.371643 -305.743797) (xy 113.407334 -305.702606) (xy 113.448525 -305.666915) (xy 113.494375 -305.637449)
			(xy 113.543952 -305.614807) (xy 113.596247 -305.599452) (xy 113.650195 -305.591696) (xy 113.704697 -305.591696)
			(xy 113.758645 -305.599452) (xy 113.81094 -305.614807) (xy 113.860517 -305.637449) (xy 113.906367 -305.666915)
			(xy 113.947558 -305.702606) (xy 113.983249 -305.743797) (xy 114.012715 -305.789647) (xy 114.035357 -305.839224)
			(xy 114.050712 -305.891519) (xy 114.058468 -305.945467) (xy 114.058954 -305.972718) (xy 114.05851 -306.000089)
			(xy 114.050688 -306.05427) (xy 114.035195 -306.106773) (xy 114.012348 -306.15652) (xy 113.982618 -306.202485)
			(xy 113.964974 -306.223416) (xy 113.958878 -306.230528) (xy 113.952528 -306.247546) (xy 113.952528 -306.33289)
			(xy 113.958878 -306.349908) (xy 113.964974 -306.35702) (xy 113.982632 -306.377938) (xy 114.012356 -306.423909)
			(xy 114.035201 -306.473657) (xy 114.050695 -306.526162) (xy 114.058522 -306.580342) (xy 114.05852 -306.635085)
			(xy 114.05069 -306.689265) (xy 114.035191 -306.741768) (xy 114.012343 -306.791515) (xy 113.982616 -306.837483)
			(xy 113.964974 -306.858416) (xy 113.958878 -306.865528) (xy 113.952528 -306.882546) (xy 113.952528 -306.96789)
			(xy 113.958878 -306.984908) (xy 113.964974 -306.99202) (xy 113.982632 -307.012938) (xy 114.012356 -307.058909)
			(xy 114.035201 -307.108657) (xy 114.050695 -307.161162) (xy 114.058522 -307.215342) (xy 114.05852 -307.270085)
			(xy 114.05069 -307.324265) (xy 114.035191 -307.376768) (xy 114.012343 -307.426515) (xy 113.982616 -307.472483)
			(xy 113.964974 -307.493416) (xy 113.958878 -307.500528) (xy 113.952528 -307.517546) (xy 113.952528 -307.60289)
			(xy 113.958878 -307.619908) (xy 113.964974 -307.62702) (xy 113.982585 -307.647975) (xy 114.012302 -307.693941)
			(xy 114.035144 -307.743683) (xy 114.050641 -307.796178) (xy 114.058476 -307.85035) (xy 114.058954 -307.877718)
			(xy 114.058468 -307.904969) (xy 114.050712 -307.958917) (xy 114.035357 -308.011212) (xy 114.012715 -308.060789)
			(xy 113.983249 -308.106639) (xy 113.947558 -308.14783) (xy 113.906367 -308.183521) (xy 113.860517 -308.212987)
			(xy 113.81094 -308.235629) (xy 113.758645 -308.250984) (xy 113.704697 -308.25874) (xy 113.650195 -308.25874)
			(xy 113.596247 -308.250984) (xy 113.543952 -308.235629) (xy 113.494375 -308.212987) (xy 113.448525 -308.183521)
			(xy 113.407334 -308.14783) (xy 113.371643 -308.106639) (xy 113.342177 -308.060789) (xy 113.319535 -308.011212)
			(xy 113.30418 -307.958917) (xy 113.296424 -307.904969) (xy 113.295938 -307.877718) (xy 110.422444 -307.877718)
			(xy 110.418512 -307.905069) (xy 110.403157 -307.957364) (xy 110.380515 -308.006941) (xy 110.351049 -308.052791)
			(xy 110.315358 -308.093982) (xy 110.274167 -308.129673) (xy 110.228317 -308.159139) (xy 110.17874 -308.181781)
			(xy 110.126445 -308.197136) (xy 110.072497 -308.204892) (xy 110.017995 -308.204892) (xy 109.964047 -308.197136)
			(xy 109.911752 -308.181781) (xy 109.862175 -308.159139) (xy 109.816325 -308.129673) (xy 109.775134 -308.093982)
			(xy 109.739443 -308.052791) (xy 109.709977 -308.006941) (xy 109.687335 -307.957364) (xy 109.67198 -307.905069)
			(xy 109.664224 -307.851121) (xy 109.663738 -307.82387) (xy 107.214426 -307.82387) (xy 107.218256 -307.85035)
			(xy 107.218734 -307.877718) (xy 107.218248 -307.904969) (xy 107.210492 -307.958917) (xy 107.195137 -308.011212)
			(xy 107.172495 -308.060789) (xy 107.143029 -308.106639) (xy 107.107338 -308.14783) (xy 107.066147 -308.183521)
			(xy 107.020297 -308.212987) (xy 106.97072 -308.235629) (xy 106.918425 -308.250984) (xy 106.864477 -308.25874)
			(xy 106.809975 -308.25874) (xy 106.756027 -308.250984) (xy 106.703732 -308.235629) (xy 106.654155 -308.212987)
			(xy 106.608305 -308.183521) (xy 106.567114 -308.14783) (xy 106.531423 -308.106639) (xy 106.501957 -308.060789)
			(xy 106.479315 -308.011212) (xy 106.46396 -307.958917) (xy 106.456204 -307.904969) (xy 106.455718 -307.877718)
			(xy 103.582224 -307.877718) (xy 103.578292 -307.905069) (xy 103.562937 -307.957364) (xy 103.540295 -308.006941)
			(xy 103.510829 -308.052791) (xy 103.475138 -308.093982) (xy 103.433947 -308.129673) (xy 103.388097 -308.159139)
			(xy 103.33852 -308.181781) (xy 103.286225 -308.197136) (xy 103.232277 -308.204892) (xy 103.177775 -308.204892)
			(xy 103.123827 -308.197136) (xy 103.071532 -308.181781) (xy 103.021955 -308.159139) (xy 102.976105 -308.129673)
			(xy 102.934914 -308.093982) (xy 102.899223 -308.052791) (xy 102.869757 -308.006941) (xy 102.847115 -307.957364)
			(xy 102.83176 -307.905069) (xy 102.824004 -307.851121) (xy 102.823518 -307.82387) (xy 92.516033 -307.82387)
			(xy 92.515841 -307.835962) (xy 92.510498 -307.880656) (xy 92.50553 -307.90261) (xy 92.502482 -307.915818)
			(xy 92.509594 -307.940964) (xy 92.589858 -308.021228) (xy 92.615004 -308.02834) (xy 92.628212 -308.025292)
			(xy 92.650166 -308.020324) (xy 92.69486 -308.014981) (xy 92.717366 -308.014624) (xy 92.744621 -308.015018)
			(xy 92.798578 -308.022771) (xy 92.850882 -308.038124) (xy 92.900469 -308.060764) (xy 92.946328 -308.090231)
			(xy 92.987528 -308.125924) (xy 93.023229 -308.167118) (xy 93.052703 -308.212972) (xy 93.075352 -308.262555)
			(xy 93.090714 -308.314856) (xy 93.098477 -308.368811) (xy 93.098481 -308.423322) (xy 93.090728 -308.477279)
			(xy 93.075376 -308.529583) (xy 93.052735 -308.579169) (xy 93.023269 -308.625029) (xy 92.987575 -308.666229)
			(xy 92.946382 -308.701929) (xy 92.900527 -308.731404) (xy 92.850944 -308.754052) (xy 92.798643 -308.769414)
			(xy 92.744688 -308.777177) (xy 92.690177 -308.777181) (xy 92.636221 -308.769428) (xy 92.583917 -308.754075)
			(xy 92.53433 -308.731435) (xy 92.48847 -308.701968) (xy 92.447271 -308.666275) (xy 92.411571 -308.625081)
			(xy 92.382096 -308.579227) (xy 92.359447 -308.529644) (xy 92.344085 -308.477343) (xy 92.336323 -308.423387)
			(xy 92.335858 -308.396132) (xy 92.336212 -308.373626) (xy 92.341557 -308.328931) (xy 92.346526 -308.306978)
			(xy 92.349574 -308.29377) (xy 92.342462 -308.268624) (xy 92.262198 -308.18836) (xy 92.237052 -308.181248)
			(xy 92.223844 -308.184296) (xy 92.201888 -308.189254) (xy 92.157195 -308.194604) (xy 92.13469 -308.194964)
			(xy 92.107435 -308.194554) (xy 92.05348 -308.186795) (xy 92.001178 -308.171435) (xy 91.951595 -308.148788)
			(xy 91.90574 -308.119315) (xy 91.864546 -308.083616) (xy 91.828852 -308.042417) (xy 91.799386 -307.996558)
			(xy 91.776746 -307.946971) (xy 91.761394 -307.894667) (xy 91.753642 -307.840711) (xy 91.753182 -307.813456)
			(xy 91.75496 -307.77688) (xy 91.755976 -307.76545) (xy 91.748356 -307.744368) (xy 91.676728 -307.67274)
			(xy 91.655392 -307.66512) (xy 91.643962 -307.666136) (xy 91.607386 -307.667914) (xy 91.580136 -307.667407)
			(xy 91.526191 -307.659649) (xy 91.473899 -307.644292) (xy 91.424324 -307.62165) (xy 91.378477 -307.592184)
			(xy 91.33729 -307.556492) (xy 91.301601 -307.515303) (xy 91.272137 -307.469453) (xy 91.249499 -307.419877)
			(xy 91.234146 -307.367584) (xy 91.226391 -307.313639) (xy 82.754955 -307.313639) (xy 82.754737 -307.324475)
			(xy 82.746842 -307.373052) (xy 82.731258 -307.419733) (xy 82.708387 -307.46331) (xy 82.678822 -307.502654)
			(xy 82.643329 -307.536746) (xy 82.602826 -307.564702) (xy 82.558364 -307.5858) (xy 82.511093 -307.599492)
			(xy 82.462238 -307.605424) (xy 82.413063 -307.603443) (xy 82.364844 -307.593599) (xy 82.318828 -307.576147)
			(xy 82.276207 -307.55154) (xy 82.238086 -307.520415) (xy 82.205451 -307.483578) (xy 82.179148 -307.441982)
			(xy 82.159857 -307.396706) (xy 82.14808 -307.348922) (xy 82.14412 -307.299868) (xy 81.805272 -307.299868)
			(xy 81.804777 -307.324475) (xy 81.796882 -307.373052) (xy 81.781298 -307.419733) (xy 81.758427 -307.46331)
			(xy 81.728862 -307.502654) (xy 81.693369 -307.536746) (xy 81.652866 -307.564702) (xy 81.608404 -307.5858)
			(xy 81.561133 -307.599492) (xy 81.512278 -307.605424) (xy 81.463103 -307.603443) (xy 81.414884 -307.593599)
			(xy 81.368868 -307.576147) (xy 81.326247 -307.55154) (xy 81.288126 -307.520415) (xy 81.255491 -307.483578)
			(xy 81.229188 -307.441982) (xy 81.209897 -307.396706) (xy 81.19812 -307.348922) (xy 81.19416 -307.299868)
			(xy 80.855058 -307.299868) (xy 80.854563 -307.324475) (xy 80.846668 -307.373052) (xy 80.831084 -307.419733)
			(xy 80.808213 -307.46331) (xy 80.778648 -307.502654) (xy 80.743155 -307.536746) (xy 80.702652 -307.564702)
			(xy 80.65819 -307.5858) (xy 80.610919 -307.599492) (xy 80.562064 -307.605424) (xy 80.512889 -307.603443)
			(xy 80.46467 -307.593599) (xy 80.418654 -307.576147) (xy 80.376033 -307.55154) (xy 80.337912 -307.520415)
			(xy 80.305277 -307.483578) (xy 80.278974 -307.441982) (xy 80.259683 -307.396706) (xy 80.247906 -307.348922)
			(xy 80.243946 -307.299868) (xy 79.905098 -307.299868) (xy 79.904603 -307.324475) (xy 79.896708 -307.373052)
			(xy 79.881124 -307.419733) (xy 79.858253 -307.46331) (xy 79.828688 -307.502654) (xy 79.793195 -307.536746)
			(xy 79.752692 -307.564702) (xy 79.70823 -307.5858) (xy 79.660959 -307.599492) (xy 79.612104 -307.605424)
			(xy 79.562929 -307.603443) (xy 79.51471 -307.593599) (xy 79.468694 -307.576147) (xy 79.426073 -307.55154)
			(xy 79.387952 -307.520415) (xy 79.355317 -307.483578) (xy 79.329014 -307.441982) (xy 79.309723 -307.396706)
			(xy 79.297946 -307.348922) (xy 79.293986 -307.299868) (xy 78.955138 -307.299868) (xy 78.954643 -307.324475)
			(xy 78.946748 -307.373052) (xy 78.931164 -307.419733) (xy 78.908293 -307.46331) (xy 78.878728 -307.502654)
			(xy 78.843235 -307.536746) (xy 78.802732 -307.564702) (xy 78.75827 -307.5858) (xy 78.710999 -307.599492)
			(xy 78.662144 -307.605424) (xy 78.612969 -307.603443) (xy 78.56475 -307.593599) (xy 78.518734 -307.576147)
			(xy 78.476113 -307.55154) (xy 78.437992 -307.520415) (xy 78.405357 -307.483578) (xy 78.379054 -307.441982)
			(xy 78.359763 -307.396706) (xy 78.347986 -307.348922) (xy 78.344026 -307.299868) (xy 78.005178 -307.299868)
			(xy 78.004683 -307.324475) (xy 77.996788 -307.373052) (xy 77.981204 -307.419733) (xy 77.958333 -307.46331)
			(xy 77.928768 -307.502654) (xy 77.893275 -307.536746) (xy 77.852772 -307.564702) (xy 77.80831 -307.5858)
			(xy 77.761039 -307.599492) (xy 77.712184 -307.605424) (xy 77.663009 -307.603443) (xy 77.61479 -307.593599)
			(xy 77.568774 -307.576147) (xy 77.526153 -307.55154) (xy 77.488032 -307.520415) (xy 77.455397 -307.483578)
			(xy 77.429094 -307.441982) (xy 77.409803 -307.396706) (xy 77.398026 -307.348922) (xy 77.394066 -307.299868)
			(xy 77.055218 -307.299868) (xy 77.054723 -307.324475) (xy 77.046828 -307.373052) (xy 77.031244 -307.419733)
			(xy 77.008373 -307.46331) (xy 76.978808 -307.502654) (xy 76.943315 -307.536746) (xy 76.902812 -307.564702)
			(xy 76.85835 -307.5858) (xy 76.811079 -307.599492) (xy 76.762224 -307.605424) (xy 76.713049 -307.603443)
			(xy 76.66483 -307.593599) (xy 76.618814 -307.576147) (xy 76.576193 -307.55154) (xy 76.538072 -307.520415)
			(xy 76.505437 -307.483578) (xy 76.479134 -307.441982) (xy 76.459843 -307.396706) (xy 76.448066 -307.348922)
			(xy 76.444106 -307.299868) (xy 76.105258 -307.299868) (xy 76.104763 -307.324475) (xy 76.096868 -307.373052)
			(xy 76.081284 -307.419733) (xy 76.058413 -307.46331) (xy 76.028848 -307.502654) (xy 75.993355 -307.536746)
			(xy 75.952852 -307.564702) (xy 75.90839 -307.5858) (xy 75.861119 -307.599492) (xy 75.812264 -307.605424)
			(xy 75.763089 -307.603443) (xy 75.71487 -307.593599) (xy 75.668854 -307.576147) (xy 75.626233 -307.55154)
			(xy 75.588112 -307.520415) (xy 75.555477 -307.483578) (xy 75.529174 -307.441982) (xy 75.509883 -307.396706)
			(xy 75.498106 -307.348922) (xy 75.494146 -307.299868) (xy 75.155298 -307.299868) (xy 75.154803 -307.324475)
			(xy 75.146908 -307.373052) (xy 75.131324 -307.419733) (xy 75.108453 -307.46331) (xy 75.078888 -307.502654)
			(xy 75.043395 -307.536746) (xy 75.002892 -307.564702) (xy 74.95843 -307.5858) (xy 74.911159 -307.599492)
			(xy 74.862304 -307.605424) (xy 74.813129 -307.603443) (xy 74.76491 -307.593599) (xy 74.718894 -307.576147)
			(xy 74.676273 -307.55154) (xy 74.638152 -307.520415) (xy 74.605517 -307.483578) (xy 74.579214 -307.441982)
			(xy 74.559923 -307.396706) (xy 74.548146 -307.348922) (xy 74.544186 -307.299868) (xy 74.205084 -307.299868)
			(xy 74.204589 -307.324475) (xy 74.196694 -307.373052) (xy 74.18111 -307.419733) (xy 74.158239 -307.46331)
			(xy 74.128674 -307.502654) (xy 74.093181 -307.536746) (xy 74.052678 -307.564702) (xy 74.008216 -307.5858)
			(xy 73.960945 -307.599492) (xy 73.91209 -307.605424) (xy 73.862915 -307.603443) (xy 73.814696 -307.593599)
			(xy 73.76868 -307.576147) (xy 73.726059 -307.55154) (xy 73.687938 -307.520415) (xy 73.655303 -307.483578)
			(xy 73.629 -307.441982) (xy 73.609709 -307.396706) (xy 73.597932 -307.348922) (xy 73.593972 -307.299868)
			(xy 50.455068 -307.299868) (xy 50.454546 -307.325123) (xy 50.446233 -307.374945) (xy 50.429832 -307.422719)
			(xy 50.405791 -307.467142) (xy 50.374767 -307.507002) (xy 50.337605 -307.541212) (xy 50.295319 -307.568838)
			(xy 50.249063 -307.589128) (xy 50.200098 -307.601528) (xy 50.14976 -307.605699) (xy 50.099422 -307.601528)
			(xy 50.050457 -307.589128) (xy 50.004201 -307.568838) (xy 49.961915 -307.541212) (xy 49.924753 -307.507002)
			(xy 49.893729 -307.467142) (xy 49.869688 -307.422719) (xy 49.853287 -307.374945) (xy 49.844974 -307.325123)
			(xy 49.844452 -307.299868) (xy 49.844651 -307.285749) (xy 49.847322 -307.257637) (xy 49.849786 -307.243734)
			(xy 49.852072 -307.231288) (xy 49.844706 -307.207412) (xy 49.767236 -307.129942) (xy 49.74336 -307.122576)
			(xy 49.730914 -307.124862) (xy 49.717012 -307.12734) (xy 49.6889 -307.130014) (xy 49.67478 -307.130196)
			(xy 49.660661 -307.129997) (xy 49.632549 -307.127328) (xy 49.618646 -307.124862) (xy 49.6062 -307.122576)
			(xy 49.582324 -307.129942) (xy 49.504854 -307.207412) (xy 49.497488 -307.231288) (xy 49.499774 -307.243734)
			(xy 49.502249 -307.257636) (xy 49.504919 -307.285749) (xy 49.505108 -307.299868) (xy 49.504586 -307.325123)
			(xy 49.496273 -307.374945) (xy 49.479872 -307.422719) (xy 49.455831 -307.467142) (xy 49.424807 -307.507002)
			(xy 49.387645 -307.541212) (xy 49.345359 -307.568838) (xy 49.299103 -307.589128) (xy 49.250138 -307.601528)
			(xy 49.1998 -307.605699) (xy 49.149462 -307.601528) (xy 49.100497 -307.589128) (xy 49.054241 -307.568838)
			(xy 49.011955 -307.541212) (xy 48.974793 -307.507002) (xy 48.943769 -307.467142) (xy 48.919728 -307.422719)
			(xy 48.903327 -307.374945) (xy 48.895014 -307.325123) (xy 48.894492 -307.299868) (xy 48.894691 -307.285749)
			(xy 48.897361 -307.257637) (xy 48.899826 -307.243734) (xy 48.902112 -307.231288) (xy 48.894746 -307.207412)
			(xy 48.817276 -307.129942) (xy 48.7934 -307.122576) (xy 48.780954 -307.124862) (xy 48.767052 -307.127337)
			(xy 48.738939 -307.130006) (xy 48.72482 -307.130196) (xy 48.710701 -307.129995) (xy 48.68259 -307.12732)
			(xy 48.668686 -307.124862) (xy 48.65624 -307.122576) (xy 48.632364 -307.129942) (xy 48.554894 -307.207412)
			(xy 48.547528 -307.231288) (xy 48.549814 -307.243734) (xy 48.552289 -307.257636) (xy 48.554959 -307.285749)
			(xy 48.555148 -307.299868) (xy 48.55468 -307.323862) (xy 48.547178 -307.37126) (xy 48.532354 -307.416901)
			(xy 48.510573 -307.459661) (xy 48.482371 -307.498487) (xy 48.448442 -307.532424) (xy 48.409622 -307.560635)
			(xy 48.366867 -307.582426) (xy 48.32123 -307.597261) (xy 48.273834 -307.604774) (xy 48.24984 -307.605176)
			(xy 48.249586 -307.605176) (xy 48.220887 -307.604521) (xy 48.164504 -307.593776) (xy 48.137572 -307.58384)
			(xy 48.128682 -307.580284) (xy 48.11903 -307.580284) (xy 48.109004 -307.580698) (xy 48.090474 -307.588362)
			(xy 48.076288 -307.602535) (xy 48.068607 -307.621058) (xy 48.06823 -307.631084) (xy 48.06823 -307.683408)
			(xy 48.070008 -307.696616) (xy 48.07077 -307.699664) (xy 48.075157 -307.718085) (xy 48.079871 -307.75566)
			(xy 48.080168 -307.774594) (xy 48.080168 -307.775102) (xy 48.079914 -307.784246) (xy 48.079914 -307.791612)
			(xy 48.079914 -307.795168) (xy 48.07966 -307.796946) (xy 48.07966 -307.797962) (xy 48.078409 -307.812171)
			(xy 48.073571 -307.840284) (xy 48.070008 -307.854096) (xy 48.06823 -307.8607) (xy 48.06823 -307.918612)
			(xy 48.068652 -307.928629) (xy 48.076325 -307.947137) (xy 48.090498 -307.961298) (xy 48.109012 -307.968956)
			(xy 48.11903 -307.969412) (xy 48.128682 -307.969412) (xy 48.137572 -307.965856) (xy 48.164509 -307.955939)
			(xy 48.22089 -307.945205) (xy 48.249586 -307.94452) (xy 48.24984 -307.94452) (xy 48.275091 -307.945045)
			(xy 48.324903 -307.953363) (xy 48.372667 -307.969766) (xy 48.41708 -307.993806) (xy 48.45693 -308.024828)
			(xy 48.491132 -308.061985) (xy 48.518752 -308.104265) (xy 48.539036 -308.150514) (xy 48.551433 -308.199471)
			(xy 48.555603 -308.2498) (xy 48.551433 -308.300129) (xy 48.539036 -308.349086) (xy 48.518752 -308.395335)
			(xy 48.491132 -308.437615) (xy 48.45693 -308.474772) (xy 48.41708 -308.505794) (xy 48.372667 -308.529834)
			(xy 48.324903 -308.546237) (xy 48.275091 -308.554555) (xy 48.24984 -308.555136) (xy 48.249586 -308.555136)
			(xy 48.220887 -308.554482) (xy 48.164504 -308.543738) (xy 48.137572 -308.5338) (xy 48.128682 -308.530244)
			(xy 48.11903 -308.530244) (xy 48.109008 -308.530659) (xy 48.090488 -308.538325) (xy 48.076317 -308.5525)
			(xy 48.068656 -308.571022) (xy 48.06823 -308.581044) (xy 48.06823 -308.633368) (xy 48.070008 -308.646576)
			(xy 48.07077 -308.649624) (xy 48.07516 -308.668045) (xy 48.079879 -308.705619) (xy 48.080168 -308.724554)
			(xy 48.080168 -308.725062) (xy 48.079914 -308.734206) (xy 48.079914 -308.741572) (xy 48.079914 -308.745128)
			(xy 48.07966 -308.746906) (xy 48.07966 -308.747922) (xy 48.07841 -308.762131) (xy 48.073577 -308.790245)
			(xy 48.070008 -308.804056) (xy 48.06823 -308.81066) (xy 48.06823 -308.868572) (xy 48.068645 -308.878595)
			(xy 48.076311 -308.897116) (xy 48.090486 -308.91129) (xy 48.109007 -308.918955) (xy 48.11903 -308.919372)
			(xy 48.128682 -308.919372) (xy 48.137572 -308.915816) (xy 48.164509 -308.905901) (xy 48.22089 -308.895167)
			(xy 48.249586 -308.89448) (xy 48.24984 -308.89448) (xy 48.27383 -308.894954) (xy 48.321217 -308.902465)
			(xy 48.366847 -308.917295) (xy 48.409594 -308.939081) (xy 48.448409 -308.967285) (xy 48.482333 -309.001213)
			(xy 48.510534 -309.040029) (xy 48.532315 -309.082779) (xy 48.547142 -309.12841) (xy 48.554649 -309.175798)
			(xy 48.555148 -309.199788) (xy 48.554946 -309.213906) (xy 48.55227 -309.242017) (xy 48.549814 -309.255922)
			(xy 48.547528 -309.268368) (xy 48.55464 -309.29199) (xy 48.631856 -309.36946) (xy 48.655478 -309.376826)
			(xy 48.668178 -309.37454) (xy 48.68215 -309.372135) (xy 48.710389 -309.369593) (xy 48.724566 -309.36946)
			(xy 48.72482 -309.36946) (xy 48.748811 -309.369932) (xy 48.796202 -309.37744) (xy 48.841836 -309.392269)
			(xy 48.884588 -309.414053) (xy 48.923406 -309.442257) (xy 48.957336 -309.476184) (xy 48.98554 -309.515002)
			(xy 49.007326 -309.557753) (xy 49.022157 -309.603386) (xy 49.029667 -309.650777) (xy 49.030128 -309.674768)
			(xy 49.030128 -309.68188) (xy 49.029874 -309.69204) (xy 49.03724 -309.710836) (xy 49.076864 -309.75173)
			(xy 49.094898 -309.770272) (xy 49.102349 -309.777323) (xy 49.121225 -309.78531) (xy 49.131474 -309.785766)
			(xy 49.267618 -309.785766) (xy 49.277775 -309.785321) (xy 49.296509 -309.777464) (xy 49.30394 -309.770526)
			(xy 49.362106 -309.710836) (xy 49.369472 -309.69204) (xy 49.369218 -309.68188) (xy 49.369218 -309.674768)
			(xy 49.369691 -309.650779) (xy 49.377201 -309.603393) (xy 49.392032 -309.557765) (xy 49.413818 -309.515018)
			(xy 49.442022 -309.476206) (xy 49.475951 -309.442284) (xy 49.514768 -309.414087) (xy 49.557518 -309.39231)
			(xy 49.603149 -309.377488) (xy 49.650537 -309.369986) (xy 49.674526 -309.36946) (xy 49.67478 -309.36946)
			(xy 49.688899 -309.369661) (xy 49.71701 -309.372336) (xy 49.730914 -309.374794) (xy 49.74336 -309.37708)
			(xy 49.767236 -309.369714) (xy 49.844706 -309.292244) (xy 49.852072 -309.268368) (xy 49.849786 -309.255922)
			(xy 49.847308 -309.24202) (xy 49.844634 -309.213908) (xy 49.844452 -309.199788) (xy 49.84465 -309.185669)
			(xy 49.847319 -309.157557) (xy 49.849786 -309.143654) (xy 49.852072 -309.131208) (xy 49.844706 -309.107332)
			(xy 49.767236 -309.029862) (xy 49.74336 -309.022496) (xy 49.730914 -309.024782) (xy 49.717012 -309.027259)
			(xy 49.6889 -309.029934) (xy 49.67478 -309.030116) (xy 49.65079 -309.029644) (xy 49.6034 -309.022135)
			(xy 49.557768 -309.007306) (xy 49.515017 -308.985522) (xy 49.476201 -308.957318) (xy 49.442274 -308.92339)
			(xy 49.414072 -308.884572) (xy 49.392289 -308.841821) (xy 49.377462 -308.796188) (xy 49.369955 -308.748798)
			(xy 49.369472 -308.724808) (xy 49.369669 -308.710689) (xy 49.372336 -308.682576) (xy 49.374806 -308.668674)
			(xy 49.377092 -308.656228) (xy 49.369726 -308.632352) (xy 49.292256 -308.554882) (xy 49.26838 -308.547516)
			(xy 49.255934 -308.549802) (xy 49.242032 -308.55228) (xy 49.21392 -308.554956) (xy 49.1998 -308.555136)
			(xy 49.174976 -308.55465) (xy 49.125983 -308.546618) (xy 49.078935 -308.530765) (xy 49.035071 -308.507509)
			(xy 48.995548 -308.477464) (xy 48.961406 -308.44142) (xy 48.933545 -308.400327) (xy 48.9127 -308.355268)
			(xy 48.899419 -308.30743) (xy 48.894053 -308.258073) (xy 48.896742 -308.208499) (xy 48.907417 -308.160013)
			(xy 48.925795 -308.113892) (xy 48.951392 -308.071353) (xy 48.983535 -308.033515) (xy 49.021376 -308.001376)
			(xy 49.063918 -307.975782) (xy 49.11004 -307.957408) (xy 49.158527 -307.946739) (xy 49.208101 -307.944054)
			(xy 49.257457 -307.949425) (xy 49.305294 -307.96271) (xy 49.350351 -307.983559) (xy 49.391441 -308.011424)
			(xy 49.427483 -308.045569) (xy 49.457525 -308.085095) (xy 49.480776 -308.128961) (xy 49.496625 -308.17601)
			(xy 49.504652 -308.225004) (xy 49.505108 -308.249828) (xy 49.504909 -308.263947) (xy 49.502239 -308.292059)
			(xy 49.499774 -308.305962) (xy 49.497488 -308.318408) (xy 49.504854 -308.342284) (xy 49.582324 -308.419754)
			(xy 49.6062 -308.42712) (xy 49.618646 -308.424834) (xy 49.632548 -308.422359) (xy 49.660661 -308.41969)
			(xy 49.67478 -308.4195) (xy 49.698774 -308.419945) (xy 49.746171 -308.427449) (xy 49.791811 -308.442276)
			(xy 49.83457 -308.46406) (xy 49.873393 -308.492266) (xy 49.907326 -308.526198) (xy 49.935533 -308.56502)
			(xy 49.95732 -308.607778) (xy 49.972148 -308.653417) (xy 49.979654 -308.700814) (xy 49.980088 -308.724808)
			(xy 49.97989 -308.738927) (xy 49.977222 -308.767039) (xy 49.974754 -308.780942) (xy 49.972468 -308.793388)
			(xy 49.979834 -308.817264) (xy 50.057304 -308.894734) (xy 50.08118 -308.9021) (xy 50.093626 -308.899814)
			(xy 50.107528 -308.897338) (xy 50.135641 -308.894668) (xy 50.14976 -308.89448) (xy 50.173756 -308.894923)
			(xy 50.221157 -308.902425) (xy 50.2668 -308.91725) (xy 50.309563 -308.939033) (xy 50.348391 -308.967237)
			(xy 50.382329 -309.001169) (xy 50.41054 -309.039993) (xy 50.43233 -309.082752) (xy 50.447163 -309.128393)
			(xy 50.454673 -309.175793) (xy 50.455068 -309.199788) (xy 50.454866 -309.213906) (xy 50.452191 -309.242017)
			(xy 50.449734 -309.255922) (xy 50.447448 -309.268368) (xy 50.454814 -309.292244) (xy 50.532284 -309.369714)
			(xy 50.55616 -309.37708) (xy 50.568606 -309.374794) (xy 50.582508 -309.372318) (xy 50.610621 -309.369645)
			(xy 50.62474 -309.36946) (xy 50.624994 -309.36946) (xy 50.639113 -309.369657) (xy 50.667226 -309.372324)
			(xy 50.681128 -309.374794) (xy 50.693574 -309.37708) (xy 50.71745 -309.369714) (xy 50.79492 -309.292244)
			(xy 50.802286 -309.268368) (xy 50.8 -309.255922) (xy 50.797522 -309.24202) (xy 50.794848 -309.213908)
			(xy 50.794666 -309.199788) (xy 50.795137 -309.175797) (xy 50.802645 -309.128405) (xy 50.817473 -309.082771)
			(xy 50.839257 -309.040018) (xy 50.86746 -309.001199) (xy 50.901388 -308.967269) (xy 50.940206 -308.939064)
			(xy 50.982958 -308.917278) (xy 51.028591 -308.902448) (xy 51.075983 -308.894939) (xy 51.099974 -308.89448)
			(xy 51.114093 -308.894681) (xy 51.142204 -308.897355) (xy 51.156108 -308.899814) (xy 51.168554 -308.9021)
			(xy 51.19243 -308.894734) (xy 51.2699 -308.817264) (xy 51.277266 -308.793388) (xy 51.27498 -308.780942)
			(xy 51.272506 -308.76704) (xy 51.269839 -308.738927) (xy 51.269646 -308.724808) (xy 51.269843 -308.710689)
			(xy 51.27251 -308.682577) (xy 51.27498 -308.668674) (xy 51.277266 -308.656228) (xy 51.2699 -308.632352)
			(xy 51.19243 -308.554882) (xy 51.168554 -308.547516) (xy 51.156108 -308.549802) (xy 51.142206 -308.552279)
			(xy 51.114093 -308.554953) (xy 51.099974 -308.555136) (xy 51.075151 -308.554648) (xy 51.026159 -308.546612)
			(xy 50.979113 -308.530756) (xy 50.935252 -308.507497) (xy 50.895731 -308.477449) (xy 50.861593 -308.441403)
			(xy 50.833736 -308.400309) (xy 50.812893 -308.355249) (xy 50.799616 -308.307412) (xy 50.794252 -308.258056)
			(xy 50.796945 -308.208483) (xy 50.807621 -308.159998) (xy 50.826001 -308.113879) (xy 50.8516 -308.071342)
			(xy 50.883744 -308.033506) (xy 50.921586 -308.001369) (xy 50.964128 -307.975777) (xy 51.01025 -307.957405)
			(xy 51.058736 -307.946737) (xy 51.10831 -307.944054) (xy 51.157665 -307.949426) (xy 51.2055 -307.962712)
			(xy 51.250556 -307.983562) (xy 51.291645 -308.011427) (xy 51.327685 -308.045572) (xy 51.357726 -308.085098)
			(xy 51.380977 -308.128963) (xy 51.396825 -308.176012) (xy 51.404852 -308.225005) (xy 51.405282 -308.249828)
			(xy 51.405083 -308.263947) (xy 51.402413 -308.292059) (xy 51.399948 -308.305962) (xy 51.397662 -308.318408)
			(xy 51.405028 -308.342284) (xy 51.482498 -308.419754) (xy 51.506374 -308.42712) (xy 51.51882 -308.424834)
			(xy 51.532722 -308.422358) (xy 51.560835 -308.419687) (xy 51.574954 -308.4195) (xy 51.589073 -308.4197)
			(xy 51.617184 -308.422372) (xy 51.631088 -308.424834) (xy 51.643534 -308.42712) (xy 51.66741 -308.419754)
			(xy 51.74488 -308.342284) (xy 51.752246 -308.318408) (xy 51.74996 -308.305962) (xy 51.747485 -308.29206)
			(xy 51.744816 -308.263947) (xy 51.744626 -308.249828) (xy 51.745109 -308.22501) (xy 51.753135 -308.176027)
			(xy 51.76898 -308.128988) (xy 51.792225 -308.085132) (xy 51.82226 -308.045614) (xy 51.858292 -308.011476)
			(xy 51.899373 -307.983617) (xy 51.944419 -307.962771) (xy 51.992245 -307.949487) (xy 52.041589 -307.944116)
			(xy 52.091153 -307.946798) (xy 52.139629 -307.957464) (xy 52.185742 -307.975831) (xy 52.228275 -308.001417)
			(xy 52.266109 -308.033547) (xy 52.298247 -308.071374) (xy 52.323841 -308.113903) (xy 52.342218 -308.160011)
			(xy 52.352893 -308.208486) (xy 52.355586 -308.258049) (xy 52.350224 -308.307394) (xy 52.33695 -308.355222)
			(xy 52.316114 -308.400273) (xy 52.288263 -308.441359) (xy 52.254132 -308.477398) (xy 52.214621 -308.507441)
			(xy 52.170769 -308.530696) (xy 52.123733 -308.54655) (xy 52.074752 -308.554585) (xy 52.049934 -308.555136)
			(xy 52.035815 -308.554935) (xy 52.007704 -308.552262) (xy 51.9938 -308.549802) (xy 51.981354 -308.547516)
			(xy 51.957478 -308.554882) (xy 51.880008 -308.632352) (xy 51.872642 -308.656228) (xy 51.874928 -308.668674)
			(xy 51.877406 -308.682576) (xy 51.880081 -308.710688) (xy 51.880262 -308.724808) (xy 51.879815 -308.748799)
			(xy 51.872307 -308.796191) (xy 51.857477 -308.841825) (xy 51.835691 -308.884577) (xy 51.807484 -308.923393)
			(xy 51.773552 -308.957319) (xy 51.73473 -308.985519) (xy 51.691975 -309.007298) (xy 51.646339 -309.02212)
			(xy 51.598946 -309.029619) (xy 51.574954 -309.030116) (xy 51.560835 -309.029916) (xy 51.532724 -309.027245)
			(xy 51.51882 -309.024782) (xy 51.506374 -309.022496) (xy 51.482498 -309.029862) (xy 51.405028 -309.107332)
			(xy 51.397662 -309.131208) (xy 51.399948 -309.143654) (xy 51.402422 -309.157556) (xy 51.405089 -309.185669)
			(xy 51.405282 -309.199788) (xy 51.40508 -309.213906) (xy 51.402405 -309.242017) (xy 51.399948 -309.255922)
			(xy 51.397662 -309.268368) (xy 51.404774 -309.29199) (xy 51.48199 -309.36946) (xy 51.505612 -309.376826)
			(xy 51.518312 -309.37454) (xy 51.532284 -309.372132) (xy 51.560523 -309.369584) (xy 51.5747 -309.36946)
			(xy 51.574954 -309.36946) (xy 51.59895 -309.369903) (xy 51.646353 -309.377404) (xy 51.691999 -309.392228)
			(xy 51.734764 -309.41401) (xy 51.773595 -309.442214) (xy 51.807535 -309.476146) (xy 51.835749 -309.514969)
			(xy 51.857542 -309.557729) (xy 51.872378 -309.603371) (xy 51.879891 -309.650772) (xy 51.880262 -309.674768)
			(xy 51.880262 -309.68188) (xy 51.880008 -309.69204) (xy 51.887374 -309.710836) (xy 51.926998 -309.75173)
			(xy 51.945032 -309.770272) (xy 51.95248 -309.777334) (xy 51.971355 -309.785345) (xy 51.981608 -309.785766)
			(xy 52.117752 -309.785766) (xy 52.127906 -309.785315) (xy 52.146631 -309.777449) (xy 52.154074 -309.770526)
			(xy 52.21224 -309.710836) (xy 52.219606 -309.69204) (xy 52.219352 -309.68188) (xy 52.219352 -309.674768)
			(xy 52.219825 -309.650777) (xy 52.227335 -309.603387) (xy 52.242165 -309.557755) (xy 52.263949 -309.515004)
			(xy 52.292152 -309.476186) (xy 52.32608 -309.442258) (xy 52.364897 -309.414053) (xy 52.407647 -309.392268)
			(xy 52.453279 -309.377437) (xy 52.500669 -309.369926) (xy 52.52466 -309.36946) (xy 52.524914 -309.36946)
			(xy 52.539033 -309.369658) (xy 52.567145 -309.372327) (xy 52.581048 -309.374794) (xy 52.593494 -309.37708)
			(xy 52.61737 -309.369714) (xy 52.69484 -309.292244) (xy 52.702206 -309.268368) (xy 52.69992 -309.255922)
			(xy 52.697442 -309.24202) (xy 52.694767 -309.213908) (xy 52.694586 -309.199788) (xy 52.695058 -309.175797)
			(xy 52.702565 -309.128407) (xy 52.717393 -309.082774) (xy 52.739178 -309.040022) (xy 52.767381 -309.001205)
			(xy 52.801309 -308.967277) (xy 52.840128 -308.939074) (xy 52.882879 -308.917291) (xy 52.928512 -308.902464)
			(xy 52.975903 -308.894957) (xy 52.999894 -308.89448) (xy 53.014013 -308.894677) (xy 53.042126 -308.897344)
			(xy 53.056028 -308.899814) (xy 53.068474 -308.9021) (xy 53.09235 -308.894734) (xy 53.16982 -308.817264)
			(xy 53.177186 -308.793388) (xy 53.1749 -308.780942) (xy 53.172426 -308.76704) (xy 53.169759 -308.738927)
			(xy 53.169566 -308.724808) (xy 53.169763 -308.710689) (xy 53.17243 -308.682576) (xy 53.1749 -308.668674)
			(xy 53.177186 -308.656228) (xy 53.16982 -308.632352) (xy 53.09235 -308.554882) (xy 53.068474 -308.547516)
			(xy 53.056028 -308.549802) (xy 53.042126 -308.55228) (xy 53.014014 -308.554955) (xy 52.999894 -308.555136)
			(xy 52.974637 -308.554614) (xy 52.924811 -308.546299) (xy 52.877034 -308.529896) (xy 52.832608 -308.505853)
			(xy 52.792745 -308.474826) (xy 52.758533 -308.43766) (xy 52.730904 -308.395371) (xy 52.710613 -308.349111)
			(xy 52.698212 -308.300142) (xy 52.694041 -308.2498) (xy 52.698212 -308.199458) (xy 52.710613 -308.150489)
			(xy 52.730904 -308.104229) (xy 52.758533 -308.06194) (xy 52.792745 -308.024774) (xy 52.832608 -307.993747)
			(xy 52.877034 -307.969704) (xy 52.924811 -307.953301) (xy 52.974637 -307.944986) (xy 52.999894 -307.94452)
			(xy 53.014013 -307.944717) (xy 53.042125 -307.947384) (xy 53.056028 -307.949854) (xy 53.068474 -307.95214)
			(xy 53.09235 -307.944774) (xy 53.16982 -307.867304) (xy 53.177186 -307.843428) (xy 53.1749 -307.830982)
			(xy 53.172424 -307.81708) (xy 53.169753 -307.788967) (xy 53.169566 -307.774848) (xy 53.170048 -307.750024)
			(xy 53.178073 -307.701028) (xy 53.193919 -307.653976) (xy 53.217169 -307.610108) (xy 53.24721 -307.57058)
			(xy 53.283251 -307.536432) (xy 53.324342 -307.508566) (xy 53.369399 -307.487714) (xy 53.417237 -307.474428)
			(xy 53.466594 -307.469056) (xy 53.51617 -307.47174) (xy 53.564658 -307.48241) (xy 53.610781 -307.500784)
			(xy 53.653324 -307.526378) (xy 53.691166 -307.558519) (xy 53.723309 -307.596358) (xy 53.748906 -307.638899)
			(xy 53.767284 -307.685021) (xy 53.777957 -307.733509) (xy 53.780198 -307.774848) (xy 54.11903 -307.774848)
			(xy 54.12299 -307.725794) (xy 54.134767 -307.67801) (xy 54.154058 -307.632734) (xy 54.180361 -307.591138)
			(xy 54.212996 -307.554301) (xy 54.251117 -307.523176) (xy 54.293738 -307.498569) (xy 54.339754 -307.481117)
			(xy 54.387973 -307.471273) (xy 54.437148 -307.469292) (xy 54.486003 -307.475224) (xy 54.533274 -307.488916)
			(xy 54.577736 -307.510014) (xy 54.618239 -307.53797) (xy 54.653732 -307.572062) (xy 54.683297 -307.611406)
			(xy 54.706168 -307.654983) (xy 54.721752 -307.701664) (xy 54.729647 -307.750241) (xy 54.730142 -307.774848)
			(xy 55.06899 -307.774848) (xy 55.07295 -307.725794) (xy 55.084727 -307.67801) (xy 55.104018 -307.632734)
			(xy 55.130321 -307.591138) (xy 55.162956 -307.554301) (xy 55.201077 -307.523176) (xy 55.243698 -307.498569)
			(xy 55.289714 -307.481117) (xy 55.337933 -307.471273) (xy 55.387108 -307.469292) (xy 55.435963 -307.475224)
			(xy 55.483234 -307.488916) (xy 55.527696 -307.510014) (xy 55.568199 -307.53797) (xy 55.603692 -307.572062)
			(xy 55.633257 -307.611406) (xy 55.656128 -307.654983) (xy 55.671712 -307.701664) (xy 55.679607 -307.750241)
			(xy 55.680102 -307.774848) (xy 56.019204 -307.774848) (xy 56.023164 -307.725794) (xy 56.034941 -307.67801)
			(xy 56.054232 -307.632734) (xy 56.080535 -307.591138) (xy 56.11317 -307.554301) (xy 56.151291 -307.523176)
			(xy 56.193912 -307.498569) (xy 56.239928 -307.481117) (xy 56.288147 -307.471273) (xy 56.337322 -307.469292)
			(xy 56.386177 -307.475224) (xy 56.433448 -307.488916) (xy 56.47791 -307.510014) (xy 56.518413 -307.53797)
			(xy 56.553906 -307.572062) (xy 56.583471 -307.611406) (xy 56.606342 -307.654983) (xy 56.621926 -307.701664)
			(xy 56.629821 -307.750241) (xy 56.630316 -307.774848) (xy 56.969164 -307.774848) (xy 56.973124 -307.725794)
			(xy 56.984901 -307.67801) (xy 57.004192 -307.632734) (xy 57.030495 -307.591138) (xy 57.06313 -307.554301)
			(xy 57.101251 -307.523176) (xy 57.143872 -307.498569) (xy 57.189888 -307.481117) (xy 57.238107 -307.471273)
			(xy 57.287282 -307.469292) (xy 57.336137 -307.475224) (xy 57.383408 -307.488916) (xy 57.42787 -307.510014)
			(xy 57.468373 -307.53797) (xy 57.503866 -307.572062) (xy 57.533431 -307.611406) (xy 57.556302 -307.654983)
			(xy 57.571886 -307.701664) (xy 57.579781 -307.750241) (xy 57.580276 -307.774848) (xy 57.919124 -307.774848)
			(xy 57.923084 -307.725794) (xy 57.934861 -307.67801) (xy 57.954152 -307.632734) (xy 57.980455 -307.591138)
			(xy 58.01309 -307.554301) (xy 58.051211 -307.523176) (xy 58.093832 -307.498569) (xy 58.139848 -307.481117)
			(xy 58.188067 -307.471273) (xy 58.237242 -307.469292) (xy 58.286097 -307.475224) (xy 58.333368 -307.488916)
			(xy 58.37783 -307.510014) (xy 58.418333 -307.53797) (xy 58.453826 -307.572062) (xy 58.483391 -307.611406)
			(xy 58.506262 -307.654983) (xy 58.521846 -307.701664) (xy 58.529741 -307.750241) (xy 58.530236 -307.774848)
			(xy 59.819044 -307.774848) (xy 59.823004 -307.725794) (xy 59.834781 -307.67801) (xy 59.854072 -307.632734)
			(xy 59.880375 -307.591138) (xy 59.91301 -307.554301) (xy 59.951131 -307.523176) (xy 59.993752 -307.498569)
			(xy 60.039768 -307.481117) (xy 60.087987 -307.471273) (xy 60.137162 -307.469292) (xy 60.186017 -307.475224)
			(xy 60.233288 -307.488916) (xy 60.27775 -307.510014) (xy 60.318253 -307.53797) (xy 60.353746 -307.572062)
			(xy 60.383311 -307.611406) (xy 60.406182 -307.654983) (xy 60.421766 -307.701664) (xy 60.429661 -307.750241)
			(xy 60.430156 -307.774848) (xy 60.769004 -307.774848) (xy 60.772964 -307.725794) (xy 60.784741 -307.67801)
			(xy 60.804032 -307.632734) (xy 60.830335 -307.591138) (xy 60.86297 -307.554301) (xy 60.901091 -307.523176)
			(xy 60.943712 -307.498569) (xy 60.989728 -307.481117) (xy 61.037947 -307.471273) (xy 61.087122 -307.469292)
			(xy 61.135977 -307.475224) (xy 61.183248 -307.488916) (xy 61.22771 -307.510014) (xy 61.268213 -307.53797)
			(xy 61.303706 -307.572062) (xy 61.333271 -307.611406) (xy 61.356142 -307.654983) (xy 61.371726 -307.701664)
			(xy 61.379621 -307.750241) (xy 61.380116 -307.774848) (xy 61.718964 -307.774848) (xy 61.722924 -307.725794)
			(xy 61.734701 -307.67801) (xy 61.753992 -307.632734) (xy 61.780295 -307.591138) (xy 61.81293 -307.554301)
			(xy 61.851051 -307.523176) (xy 61.893672 -307.498569) (xy 61.939688 -307.481117) (xy 61.987907 -307.471273)
			(xy 62.037082 -307.469292) (xy 62.085937 -307.475224) (xy 62.133208 -307.488916) (xy 62.17767 -307.510014)
			(xy 62.218173 -307.53797) (xy 62.253666 -307.572062) (xy 62.283231 -307.611406) (xy 62.306102 -307.654983)
			(xy 62.321686 -307.701664) (xy 62.329581 -307.750241) (xy 62.330071 -307.774594) (xy 62.668924 -307.774594)
			(xy 62.672884 -307.72554) (xy 62.684661 -307.677756) (xy 62.703952 -307.63248) (xy 62.730255 -307.590884)
			(xy 62.76289 -307.554047) (xy 62.801011 -307.522922) (xy 62.843632 -307.498315) (xy 62.889648 -307.480863)
			(xy 62.937867 -307.471019) (xy 62.987042 -307.469038) (xy 63.035897 -307.47497) (xy 63.083168 -307.488662)
			(xy 63.12763 -307.50976) (xy 63.168133 -307.537716) (xy 63.203626 -307.571808) (xy 63.233191 -307.611152)
			(xy 63.256062 -307.654729) (xy 63.271646 -307.70141) (xy 63.279541 -307.749987) (xy 63.280036 -307.774594)
			(xy 63.619138 -307.774594) (xy 63.623098 -307.72554) (xy 63.634875 -307.677756) (xy 63.654166 -307.63248)
			(xy 63.680469 -307.590884) (xy 63.713104 -307.554047) (xy 63.751225 -307.522922) (xy 63.793846 -307.498315)
			(xy 63.839862 -307.480863) (xy 63.888081 -307.471019) (xy 63.937256 -307.469038) (xy 63.986111 -307.47497)
			(xy 64.033382 -307.488662) (xy 64.077844 -307.50976) (xy 64.118347 -307.537716) (xy 64.15384 -307.571808)
			(xy 64.183405 -307.611152) (xy 64.206276 -307.654729) (xy 64.22186 -307.70141) (xy 64.229755 -307.749987)
			(xy 64.23025 -307.774594) (xy 64.230245 -307.774848) (xy 64.569098 -307.774848) (xy 64.573058 -307.725794)
			(xy 64.584835 -307.67801) (xy 64.604126 -307.632734) (xy 64.630429 -307.591138) (xy 64.663064 -307.554301)
			(xy 64.701185 -307.523176) (xy 64.743806 -307.498569) (xy 64.789822 -307.481117) (xy 64.838041 -307.471273)
			(xy 64.887216 -307.469292) (xy 64.936071 -307.475224) (xy 64.983342 -307.488916) (xy 65.027804 -307.510014)
			(xy 65.068307 -307.53797) (xy 65.1038 -307.572062) (xy 65.133365 -307.611406) (xy 65.156236 -307.654983)
			(xy 65.17182 -307.701664) (xy 65.179715 -307.750241) (xy 65.18021 -307.774848) (xy 65.519058 -307.774848)
			(xy 65.523018 -307.725794) (xy 65.534795 -307.67801) (xy 65.554086 -307.632734) (xy 65.580389 -307.591138)
			(xy 65.613024 -307.554301) (xy 65.651145 -307.523176) (xy 65.693766 -307.498569) (xy 65.739782 -307.481117)
			(xy 65.788001 -307.471273) (xy 65.837176 -307.469292) (xy 65.886031 -307.475224) (xy 65.933302 -307.488916)
			(xy 65.977764 -307.510014) (xy 66.018267 -307.53797) (xy 66.05376 -307.572062) (xy 66.083325 -307.611406)
			(xy 66.106196 -307.654983) (xy 66.12178 -307.701664) (xy 66.129675 -307.750241) (xy 66.13017 -307.774848)
			(xy 66.469018 -307.774848) (xy 66.472978 -307.725794) (xy 66.484755 -307.67801) (xy 66.504046 -307.632734)
			(xy 66.530349 -307.591138) (xy 66.562984 -307.554301) (xy 66.601105 -307.523176) (xy 66.643726 -307.498569)
			(xy 66.689742 -307.481117) (xy 66.737961 -307.471273) (xy 66.787136 -307.469292) (xy 66.835991 -307.475224)
			(xy 66.883262 -307.488916) (xy 66.927724 -307.510014) (xy 66.968227 -307.53797) (xy 67.00372 -307.572062)
			(xy 67.033285 -307.611406) (xy 67.056156 -307.654983) (xy 67.07174 -307.701664) (xy 67.079635 -307.750241)
			(xy 67.08013 -307.774848) (xy 67.418978 -307.774848) (xy 67.422938 -307.725794) (xy 67.434715 -307.67801)
			(xy 67.454006 -307.632734) (xy 67.480309 -307.591138) (xy 67.512944 -307.554301) (xy 67.551065 -307.523176)
			(xy 67.593686 -307.498569) (xy 67.639702 -307.481117) (xy 67.687921 -307.471273) (xy 67.737096 -307.469292)
			(xy 67.785951 -307.475224) (xy 67.833222 -307.488916) (xy 67.877684 -307.510014) (xy 67.918187 -307.53797)
			(xy 67.95368 -307.572062) (xy 67.983245 -307.611406) (xy 68.006116 -307.654983) (xy 68.0217 -307.701664)
			(xy 68.029595 -307.750241) (xy 68.03009 -307.774848) (xy 68.368938 -307.774848) (xy 68.372898 -307.725794)
			(xy 68.384675 -307.67801) (xy 68.403966 -307.632734) (xy 68.430269 -307.591138) (xy 68.462904 -307.554301)
			(xy 68.501025 -307.523176) (xy 68.543646 -307.498569) (xy 68.589662 -307.481117) (xy 68.637881 -307.471273)
			(xy 68.687056 -307.469292) (xy 68.735911 -307.475224) (xy 68.783182 -307.488916) (xy 68.827644 -307.510014)
			(xy 68.868147 -307.53797) (xy 68.90364 -307.572062) (xy 68.933205 -307.611406) (xy 68.956076 -307.654983)
			(xy 68.97166 -307.701664) (xy 68.979555 -307.750241) (xy 68.98005 -307.774848) (xy 69.319152 -307.774848)
			(xy 69.323112 -307.725794) (xy 69.334889 -307.67801) (xy 69.35418 -307.632734) (xy 69.380483 -307.591138)
			(xy 69.413118 -307.554301) (xy 69.451239 -307.523176) (xy 69.49386 -307.498569) (xy 69.539876 -307.481117)
			(xy 69.588095 -307.471273) (xy 69.63727 -307.469292) (xy 69.686125 -307.475224) (xy 69.733396 -307.488916)
			(xy 69.777858 -307.510014) (xy 69.818361 -307.53797) (xy 69.853854 -307.572062) (xy 69.883419 -307.611406)
			(xy 69.90629 -307.654983) (xy 69.921874 -307.701664) (xy 69.929769 -307.750241) (xy 69.930264 -307.774848)
			(xy 70.269112 -307.774848) (xy 70.273072 -307.725794) (xy 70.284849 -307.67801) (xy 70.30414 -307.632734)
			(xy 70.330443 -307.591138) (xy 70.363078 -307.554301) (xy 70.401199 -307.523176) (xy 70.44382 -307.498569)
			(xy 70.489836 -307.481117) (xy 70.538055 -307.471273) (xy 70.58723 -307.469292) (xy 70.636085 -307.475224)
			(xy 70.683356 -307.488916) (xy 70.727818 -307.510014) (xy 70.768321 -307.53797) (xy 70.803814 -307.572062)
			(xy 70.833379 -307.611406) (xy 70.85625 -307.654983) (xy 70.871834 -307.701664) (xy 70.879729 -307.750241)
			(xy 70.880224 -307.774848) (xy 71.219072 -307.774848) (xy 71.223032 -307.725794) (xy 71.234809 -307.67801)
			(xy 71.2541 -307.632734) (xy 71.280403 -307.591138) (xy 71.313038 -307.554301) (xy 71.351159 -307.523176)
			(xy 71.39378 -307.498569) (xy 71.439796 -307.481117) (xy 71.488015 -307.471273) (xy 71.53719 -307.469292)
			(xy 71.586045 -307.475224) (xy 71.633316 -307.488916) (xy 71.677778 -307.510014) (xy 71.718281 -307.53797)
			(xy 71.753774 -307.572062) (xy 71.783339 -307.611406) (xy 71.80621 -307.654983) (xy 71.821794 -307.701664)
			(xy 71.829689 -307.750241) (xy 71.830184 -307.774848) (xy 72.169032 -307.774848) (xy 72.172992 -307.725794)
			(xy 72.184769 -307.67801) (xy 72.20406 -307.632734) (xy 72.230363 -307.591138) (xy 72.262998 -307.554301)
			(xy 72.301119 -307.523176) (xy 72.34374 -307.498569) (xy 72.389756 -307.481117) (xy 72.437975 -307.471273)
			(xy 72.48715 -307.469292) (xy 72.536005 -307.475224) (xy 72.583276 -307.488916) (xy 72.627738 -307.510014)
			(xy 72.668241 -307.53797) (xy 72.703734 -307.572062) (xy 72.733299 -307.611406) (xy 72.75617 -307.654983)
			(xy 72.771754 -307.701664) (xy 72.779649 -307.750241) (xy 72.780144 -307.774848) (xy 72.779649 -307.799455)
			(xy 72.771754 -307.848032) (xy 72.75617 -307.894713) (xy 72.733299 -307.93829) (xy 72.703734 -307.977634)
			(xy 72.668241 -308.011726) (xy 72.627738 -308.039682) (xy 72.583276 -308.06078) (xy 72.536005 -308.074472)
			(xy 72.48715 -308.080404) (xy 72.437975 -308.078423) (xy 72.389756 -308.068579) (xy 72.34374 -308.051127)
			(xy 72.301119 -308.02652) (xy 72.262998 -307.995395) (xy 72.230363 -307.958558) (xy 72.20406 -307.916962)
			(xy 72.184769 -307.871686) (xy 72.172992 -307.823902) (xy 72.169032 -307.774848) (xy 71.830184 -307.774848)
			(xy 71.829689 -307.799455) (xy 71.821794 -307.848032) (xy 71.80621 -307.894713) (xy 71.783339 -307.93829)
			(xy 71.753774 -307.977634) (xy 71.718281 -308.011726) (xy 71.677778 -308.039682) (xy 71.633316 -308.06078)
			(xy 71.586045 -308.074472) (xy 71.53719 -308.080404) (xy 71.488015 -308.078423) (xy 71.439796 -308.068579)
			(xy 71.39378 -308.051127) (xy 71.351159 -308.02652) (xy 71.313038 -307.995395) (xy 71.280403 -307.958558)
			(xy 71.2541 -307.916962) (xy 71.234809 -307.871686) (xy 71.223032 -307.823902) (xy 71.219072 -307.774848)
			(xy 70.880224 -307.774848) (xy 70.879729 -307.799455) (xy 70.871834 -307.848032) (xy 70.85625 -307.894713)
			(xy 70.833379 -307.93829) (xy 70.803814 -307.977634) (xy 70.768321 -308.011726) (xy 70.727818 -308.039682)
			(xy 70.683356 -308.06078) (xy 70.636085 -308.074472) (xy 70.58723 -308.080404) (xy 70.538055 -308.078423)
			(xy 70.489836 -308.068579) (xy 70.44382 -308.051127) (xy 70.401199 -308.02652) (xy 70.363078 -307.995395)
			(xy 70.330443 -307.958558) (xy 70.30414 -307.916962) (xy 70.284849 -307.871686) (xy 70.273072 -307.823902)
			(xy 70.269112 -307.774848) (xy 69.930264 -307.774848) (xy 69.929769 -307.799455) (xy 69.921874 -307.848032)
			(xy 69.90629 -307.894713) (xy 69.883419 -307.93829) (xy 69.853854 -307.977634) (xy 69.818361 -308.011726)
			(xy 69.777858 -308.039682) (xy 69.733396 -308.06078) (xy 69.686125 -308.074472) (xy 69.63727 -308.080404)
			(xy 69.588095 -308.078423) (xy 69.539876 -308.068579) (xy 69.49386 -308.051127) (xy 69.451239 -308.02652)
			(xy 69.413118 -307.995395) (xy 69.380483 -307.958558) (xy 69.35418 -307.916962) (xy 69.334889 -307.871686)
			(xy 69.323112 -307.823902) (xy 69.319152 -307.774848) (xy 68.98005 -307.774848) (xy 68.979555 -307.799455)
			(xy 68.97166 -307.848032) (xy 68.956076 -307.894713) (xy 68.933205 -307.93829) (xy 68.90364 -307.977634)
			(xy 68.868147 -308.011726) (xy 68.827644 -308.039682) (xy 68.783182 -308.06078) (xy 68.735911 -308.074472)
			(xy 68.687056 -308.080404) (xy 68.637881 -308.078423) (xy 68.589662 -308.068579) (xy 68.543646 -308.051127)
			(xy 68.501025 -308.02652) (xy 68.462904 -307.995395) (xy 68.430269 -307.958558) (xy 68.403966 -307.916962)
			(xy 68.384675 -307.871686) (xy 68.372898 -307.823902) (xy 68.368938 -307.774848) (xy 68.03009 -307.774848)
			(xy 68.029595 -307.799455) (xy 68.0217 -307.848032) (xy 68.006116 -307.894713) (xy 67.983245 -307.93829)
			(xy 67.95368 -307.977634) (xy 67.918187 -308.011726) (xy 67.877684 -308.039682) (xy 67.833222 -308.06078)
			(xy 67.785951 -308.074472) (xy 67.737096 -308.080404) (xy 67.687921 -308.078423) (xy 67.639702 -308.068579)
			(xy 67.593686 -308.051127) (xy 67.551065 -308.02652) (xy 67.512944 -307.995395) (xy 67.480309 -307.958558)
			(xy 67.454006 -307.916962) (xy 67.434715 -307.871686) (xy 67.422938 -307.823902) (xy 67.418978 -307.774848)
			(xy 67.08013 -307.774848) (xy 67.079635 -307.799455) (xy 67.07174 -307.848032) (xy 67.056156 -307.894713)
			(xy 67.033285 -307.93829) (xy 67.00372 -307.977634) (xy 66.968227 -308.011726) (xy 66.927724 -308.039682)
			(xy 66.883262 -308.06078) (xy 66.835991 -308.074472) (xy 66.787136 -308.080404) (xy 66.737961 -308.078423)
			(xy 66.689742 -308.068579) (xy 66.643726 -308.051127) (xy 66.601105 -308.02652) (xy 66.562984 -307.995395)
			(xy 66.530349 -307.958558) (xy 66.504046 -307.916962) (xy 66.484755 -307.871686) (xy 66.472978 -307.823902)
			(xy 66.469018 -307.774848) (xy 66.13017 -307.774848) (xy 66.129675 -307.799455) (xy 66.12178 -307.848032)
			(xy 66.106196 -307.894713) (xy 66.083325 -307.93829) (xy 66.05376 -307.977634) (xy 66.018267 -308.011726)
			(xy 65.977764 -308.039682) (xy 65.933302 -308.06078) (xy 65.886031 -308.074472) (xy 65.837176 -308.080404)
			(xy 65.788001 -308.078423) (xy 65.739782 -308.068579) (xy 65.693766 -308.051127) (xy 65.651145 -308.02652)
			(xy 65.613024 -307.995395) (xy 65.580389 -307.958558) (xy 65.554086 -307.916962) (xy 65.534795 -307.871686)
			(xy 65.523018 -307.823902) (xy 65.519058 -307.774848) (xy 65.18021 -307.774848) (xy 65.179715 -307.799455)
			(xy 65.17182 -307.848032) (xy 65.156236 -307.894713) (xy 65.133365 -307.93829) (xy 65.1038 -307.977634)
			(xy 65.068307 -308.011726) (xy 65.027804 -308.039682) (xy 64.983342 -308.06078) (xy 64.936071 -308.074472)
			(xy 64.887216 -308.080404) (xy 64.838041 -308.078423) (xy 64.789822 -308.068579) (xy 64.743806 -308.051127)
			(xy 64.701185 -308.02652) (xy 64.663064 -307.995395) (xy 64.630429 -307.958558) (xy 64.604126 -307.916962)
			(xy 64.584835 -307.871686) (xy 64.573058 -307.823902) (xy 64.569098 -307.774848) (xy 64.230245 -307.774848)
			(xy 64.229755 -307.799201) (xy 64.22186 -307.847778) (xy 64.206276 -307.894459) (xy 64.183405 -307.938036)
			(xy 64.15384 -307.97738) (xy 64.118347 -308.011472) (xy 64.077844 -308.039428) (xy 64.033382 -308.060526)
			(xy 63.986111 -308.074218) (xy 63.937256 -308.08015) (xy 63.888081 -308.078169) (xy 63.839862 -308.068325)
			(xy 63.793846 -308.050873) (xy 63.751225 -308.026266) (xy 63.713104 -307.995141) (xy 63.680469 -307.958304)
			(xy 63.654166 -307.916708) (xy 63.634875 -307.871432) (xy 63.623098 -307.823648) (xy 63.619138 -307.774594)
			(xy 63.280036 -307.774594) (xy 63.279541 -307.799201) (xy 63.271646 -307.847778) (xy 63.256062 -307.894459)
			(xy 63.233191 -307.938036) (xy 63.203626 -307.97738) (xy 63.168133 -308.011472) (xy 63.12763 -308.039428)
			(xy 63.083168 -308.060526) (xy 63.035897 -308.074218) (xy 62.987042 -308.08015) (xy 62.937867 -308.078169)
			(xy 62.889648 -308.068325) (xy 62.843632 -308.050873) (xy 62.801011 -308.026266) (xy 62.76289 -307.995141)
			(xy 62.730255 -307.958304) (xy 62.703952 -307.916708) (xy 62.684661 -307.871432) (xy 62.672884 -307.823648)
			(xy 62.668924 -307.774594) (xy 62.330071 -307.774594) (xy 62.330076 -307.774848) (xy 62.329581 -307.799455)
			(xy 62.321686 -307.848032) (xy 62.306102 -307.894713) (xy 62.283231 -307.93829) (xy 62.253666 -307.977634)
			(xy 62.218173 -308.011726) (xy 62.17767 -308.039682) (xy 62.133208 -308.06078) (xy 62.085937 -308.074472)
			(xy 62.037082 -308.080404) (xy 61.987907 -308.078423) (xy 61.939688 -308.068579) (xy 61.893672 -308.051127)
			(xy 61.851051 -308.02652) (xy 61.81293 -307.995395) (xy 61.780295 -307.958558) (xy 61.753992 -307.916962)
			(xy 61.734701 -307.871686) (xy 61.722924 -307.823902) (xy 61.718964 -307.774848) (xy 61.380116 -307.774848)
			(xy 61.379621 -307.799455) (xy 61.371726 -307.848032) (xy 61.356142 -307.894713) (xy 61.333271 -307.93829)
			(xy 61.303706 -307.977634) (xy 61.268213 -308.011726) (xy 61.22771 -308.039682) (xy 61.183248 -308.06078)
			(xy 61.135977 -308.074472) (xy 61.087122 -308.080404) (xy 61.037947 -308.078423) (xy 60.989728 -308.068579)
			(xy 60.943712 -308.051127) (xy 60.901091 -308.02652) (xy 60.86297 -307.995395) (xy 60.830335 -307.958558)
			(xy 60.804032 -307.916962) (xy 60.784741 -307.871686) (xy 60.772964 -307.823902) (xy 60.769004 -307.774848)
			(xy 60.430156 -307.774848) (xy 60.429661 -307.799455) (xy 60.421766 -307.848032) (xy 60.406182 -307.894713)
			(xy 60.383311 -307.93829) (xy 60.353746 -307.977634) (xy 60.318253 -308.011726) (xy 60.27775 -308.039682)
			(xy 60.233288 -308.06078) (xy 60.186017 -308.074472) (xy 60.137162 -308.080404) (xy 60.087987 -308.078423)
			(xy 60.039768 -308.068579) (xy 59.993752 -308.051127) (xy 59.951131 -308.02652) (xy 59.91301 -307.995395)
			(xy 59.880375 -307.958558) (xy 59.854072 -307.916962) (xy 59.834781 -307.871686) (xy 59.823004 -307.823902)
			(xy 59.819044 -307.774848) (xy 58.530236 -307.774848) (xy 58.529741 -307.799455) (xy 58.521846 -307.848032)
			(xy 58.506262 -307.894713) (xy 58.483391 -307.93829) (xy 58.453826 -307.977634) (xy 58.418333 -308.011726)
			(xy 58.37783 -308.039682) (xy 58.333368 -308.06078) (xy 58.286097 -308.074472) (xy 58.237242 -308.080404)
			(xy 58.188067 -308.078423) (xy 58.139848 -308.068579) (xy 58.093832 -308.051127) (xy 58.051211 -308.02652)
			(xy 58.01309 -307.995395) (xy 57.980455 -307.958558) (xy 57.954152 -307.916962) (xy 57.934861 -307.871686)
			(xy 57.923084 -307.823902) (xy 57.919124 -307.774848) (xy 57.580276 -307.774848) (xy 57.579781 -307.799455)
			(xy 57.571886 -307.848032) (xy 57.556302 -307.894713) (xy 57.533431 -307.93829) (xy 57.503866 -307.977634)
			(xy 57.468373 -308.011726) (xy 57.42787 -308.039682) (xy 57.383408 -308.06078) (xy 57.336137 -308.074472)
			(xy 57.287282 -308.080404) (xy 57.238107 -308.078423) (xy 57.189888 -308.068579) (xy 57.143872 -308.051127)
			(xy 57.101251 -308.02652) (xy 57.06313 -307.995395) (xy 57.030495 -307.958558) (xy 57.004192 -307.916962)
			(xy 56.984901 -307.871686) (xy 56.973124 -307.823902) (xy 56.969164 -307.774848) (xy 56.630316 -307.774848)
			(xy 56.629821 -307.799455) (xy 56.621926 -307.848032) (xy 56.606342 -307.894713) (xy 56.583471 -307.93829)
			(xy 56.553906 -307.977634) (xy 56.518413 -308.011726) (xy 56.47791 -308.039682) (xy 56.433448 -308.06078)
			(xy 56.386177 -308.074472) (xy 56.337322 -308.080404) (xy 56.288147 -308.078423) (xy 56.239928 -308.068579)
			(xy 56.193912 -308.051127) (xy 56.151291 -308.02652) (xy 56.11317 -307.995395) (xy 56.080535 -307.958558)
			(xy 56.054232 -307.916962) (xy 56.034941 -307.871686) (xy 56.023164 -307.823902) (xy 56.019204 -307.774848)
			(xy 55.680102 -307.774848) (xy 55.679607 -307.799455) (xy 55.671712 -307.848032) (xy 55.656128 -307.894713)
			(xy 55.633257 -307.93829) (xy 55.603692 -307.977634) (xy 55.568199 -308.011726) (xy 55.527696 -308.039682)
			(xy 55.483234 -308.06078) (xy 55.435963 -308.074472) (xy 55.387108 -308.080404) (xy 55.337933 -308.078423)
			(xy 55.289714 -308.068579) (xy 55.243698 -308.051127) (xy 55.201077 -308.02652) (xy 55.162956 -307.995395)
			(xy 55.130321 -307.958558) (xy 55.104018 -307.916962) (xy 55.084727 -307.871686) (xy 55.07295 -307.823902)
			(xy 55.06899 -307.774848) (xy 54.730142 -307.774848) (xy 54.729647 -307.799455) (xy 54.721752 -307.848032)
			(xy 54.706168 -307.894713) (xy 54.683297 -307.93829) (xy 54.653732 -307.977634) (xy 54.618239 -308.011726)
			(xy 54.577736 -308.039682) (xy 54.533274 -308.06078) (xy 54.486003 -308.074472) (xy 54.437148 -308.080404)
			(xy 54.387973 -308.078423) (xy 54.339754 -308.068579) (xy 54.293738 -308.051127) (xy 54.251117 -308.02652)
			(xy 54.212996 -307.995395) (xy 54.180361 -307.958558) (xy 54.154058 -307.916962) (xy 54.134767 -307.871686)
			(xy 54.12299 -307.823902) (xy 54.11903 -307.774848) (xy 53.780198 -307.774848) (xy 53.780645 -307.783084)
			(xy 53.775276 -307.832442) (xy 53.761993 -307.88028) (xy 53.741145 -307.925339) (xy 53.713282 -307.966432)
			(xy 53.679137 -308.002475) (xy 53.63961 -308.032519) (xy 53.595744 -308.055772) (xy 53.548693 -308.071622)
			(xy 53.499698 -308.07965) (xy 53.474874 -308.080156) (xy 53.460755 -308.079957) (xy 53.432643 -308.077287)
			(xy 53.41874 -308.074822) (xy 53.406294 -308.072536) (xy 53.382418 -308.079902) (xy 53.304948 -308.157372)
			(xy 53.297582 -308.181248) (xy 53.299868 -308.193694) (xy 53.302345 -308.207596) (xy 53.305019 -308.235709)
			(xy 53.305202 -308.249828) (xy 73.593972 -308.249828) (xy 73.597932 -308.200774) (xy 73.609709 -308.15299)
			(xy 73.629 -308.107714) (xy 73.655303 -308.066118) (xy 73.687938 -308.029281) (xy 73.726059 -307.998156)
			(xy 73.76868 -307.973549) (xy 73.814696 -307.956097) (xy 73.862915 -307.946253) (xy 73.91209 -307.944272)
			(xy 73.960945 -307.950204) (xy 74.008216 -307.963896) (xy 74.052678 -307.984994) (xy 74.093181 -308.01295)
			(xy 74.128674 -308.047042) (xy 74.158239 -308.086386) (xy 74.18111 -308.129963) (xy 74.196694 -308.176644)
			(xy 74.204589 -308.225221) (xy 74.205084 -308.249828) (xy 74.544186 -308.249828) (xy 74.548146 -308.200774)
			(xy 74.559923 -308.15299) (xy 74.579214 -308.107714) (xy 74.605517 -308.066118) (xy 74.638152 -308.029281)
			(xy 74.676273 -307.998156) (xy 74.718894 -307.973549) (xy 74.76491 -307.956097) (xy 74.813129 -307.946253)
			(xy 74.862304 -307.944272) (xy 74.911159 -307.950204) (xy 74.95843 -307.963896) (xy 75.002892 -307.984994)
			(xy 75.043395 -308.01295) (xy 75.078888 -308.047042) (xy 75.108453 -308.086386) (xy 75.131324 -308.129963)
			(xy 75.146908 -308.176644) (xy 75.154803 -308.225221) (xy 75.155298 -308.249828) (xy 75.494146 -308.249828)
			(xy 75.498106 -308.200774) (xy 75.509883 -308.15299) (xy 75.529174 -308.107714) (xy 75.555477 -308.066118)
			(xy 75.588112 -308.029281) (xy 75.626233 -307.998156) (xy 75.668854 -307.973549) (xy 75.71487 -307.956097)
			(xy 75.763089 -307.946253) (xy 75.812264 -307.944272) (xy 75.861119 -307.950204) (xy 75.90839 -307.963896)
			(xy 75.952852 -307.984994) (xy 75.993355 -308.01295) (xy 76.028848 -308.047042) (xy 76.058413 -308.086386)
			(xy 76.081284 -308.129963) (xy 76.096868 -308.176644) (xy 76.104763 -308.225221) (xy 76.105258 -308.249828)
			(xy 76.444106 -308.249828) (xy 76.448066 -308.200774) (xy 76.459843 -308.15299) (xy 76.479134 -308.107714)
			(xy 76.505437 -308.066118) (xy 76.538072 -308.029281) (xy 76.576193 -307.998156) (xy 76.618814 -307.973549)
			(xy 76.66483 -307.956097) (xy 76.713049 -307.946253) (xy 76.762224 -307.944272) (xy 76.811079 -307.950204)
			(xy 76.85835 -307.963896) (xy 76.902812 -307.984994) (xy 76.943315 -308.01295) (xy 76.978808 -308.047042)
			(xy 77.008373 -308.086386) (xy 77.031244 -308.129963) (xy 77.046828 -308.176644) (xy 77.054723 -308.225221)
			(xy 77.055218 -308.249828) (xy 77.394066 -308.249828) (xy 77.398026 -308.200774) (xy 77.409803 -308.15299)
			(xy 77.429094 -308.107714) (xy 77.455397 -308.066118) (xy 77.488032 -308.029281) (xy 77.526153 -307.998156)
			(xy 77.568774 -307.973549) (xy 77.61479 -307.956097) (xy 77.663009 -307.946253) (xy 77.712184 -307.944272)
			(xy 77.761039 -307.950204) (xy 77.80831 -307.963896) (xy 77.852772 -307.984994) (xy 77.893275 -308.01295)
			(xy 77.928768 -308.047042) (xy 77.958333 -308.086386) (xy 77.981204 -308.129963) (xy 77.996788 -308.176644)
			(xy 78.004683 -308.225221) (xy 78.005178 -308.249828) (xy 78.344026 -308.249828) (xy 78.347986 -308.200774)
			(xy 78.359763 -308.15299) (xy 78.379054 -308.107714) (xy 78.405357 -308.066118) (xy 78.437992 -308.029281)
			(xy 78.476113 -307.998156) (xy 78.518734 -307.973549) (xy 78.56475 -307.956097) (xy 78.612969 -307.946253)
			(xy 78.662144 -307.944272) (xy 78.710999 -307.950204) (xy 78.75827 -307.963896) (xy 78.802732 -307.984994)
			(xy 78.843235 -308.01295) (xy 78.878728 -308.047042) (xy 78.908293 -308.086386) (xy 78.931164 -308.129963)
			(xy 78.946748 -308.176644) (xy 78.954643 -308.225221) (xy 78.955138 -308.249828) (xy 79.293986 -308.249828)
			(xy 79.297946 -308.200774) (xy 79.309723 -308.15299) (xy 79.329014 -308.107714) (xy 79.355317 -308.066118)
			(xy 79.387952 -308.029281) (xy 79.426073 -307.998156) (xy 79.468694 -307.973549) (xy 79.51471 -307.956097)
			(xy 79.562929 -307.946253) (xy 79.612104 -307.944272) (xy 79.660959 -307.950204) (xy 79.70823 -307.963896)
			(xy 79.752692 -307.984994) (xy 79.793195 -308.01295) (xy 79.828688 -308.047042) (xy 79.858253 -308.086386)
			(xy 79.881124 -308.129963) (xy 79.896708 -308.176644) (xy 79.904603 -308.225221) (xy 79.905098 -308.249828)
			(xy 80.243946 -308.249828) (xy 80.247906 -308.200774) (xy 80.259683 -308.15299) (xy 80.278974 -308.107714)
			(xy 80.305277 -308.066118) (xy 80.337912 -308.029281) (xy 80.376033 -307.998156) (xy 80.418654 -307.973549)
			(xy 80.46467 -307.956097) (xy 80.512889 -307.946253) (xy 80.562064 -307.944272) (xy 80.610919 -307.950204)
			(xy 80.65819 -307.963896) (xy 80.702652 -307.984994) (xy 80.743155 -308.01295) (xy 80.778648 -308.047042)
			(xy 80.808213 -308.086386) (xy 80.831084 -308.129963) (xy 80.846668 -308.176644) (xy 80.854563 -308.225221)
			(xy 80.855058 -308.249828) (xy 81.19416 -308.249828) (xy 81.19812 -308.200774) (xy 81.209897 -308.15299)
			(xy 81.229188 -308.107714) (xy 81.255491 -308.066118) (xy 81.288126 -308.029281) (xy 81.326247 -307.998156)
			(xy 81.368868 -307.973549) (xy 81.414884 -307.956097) (xy 81.463103 -307.946253) (xy 81.512278 -307.944272)
			(xy 81.561133 -307.950204) (xy 81.608404 -307.963896) (xy 81.652866 -307.984994) (xy 81.693369 -308.01295)
			(xy 81.728862 -308.047042) (xy 81.758427 -308.086386) (xy 81.781298 -308.129963) (xy 81.796882 -308.176644)
			(xy 81.804777 -308.225221) (xy 81.805272 -308.249828) (xy 82.14412 -308.249828) (xy 82.14808 -308.200774)
			(xy 82.159857 -308.15299) (xy 82.179148 -308.107714) (xy 82.205451 -308.066118) (xy 82.238086 -308.029281)
			(xy 82.276207 -307.998156) (xy 82.318828 -307.973549) (xy 82.364844 -307.956097) (xy 82.413063 -307.946253)
			(xy 82.462238 -307.944272) (xy 82.511093 -307.950204) (xy 82.558364 -307.963896) (xy 82.602826 -307.984994)
			(xy 82.643329 -308.01295) (xy 82.678822 -308.047042) (xy 82.708387 -308.086386) (xy 82.731258 -308.129963)
			(xy 82.746842 -308.176644) (xy 82.754737 -308.225221) (xy 82.755232 -308.249828) (xy 83.094334 -308.249828)
			(xy 83.098294 -308.200774) (xy 83.110071 -308.15299) (xy 83.129362 -308.107714) (xy 83.155665 -308.066118)
			(xy 83.1883 -308.029281) (xy 83.226421 -307.998156) (xy 83.269042 -307.973549) (xy 83.315058 -307.956097)
			(xy 83.363277 -307.946253) (xy 83.412452 -307.944272) (xy 83.461307 -307.950204) (xy 83.508578 -307.963896)
			(xy 83.55304 -307.984994) (xy 83.593543 -308.01295) (xy 83.629036 -308.047042) (xy 83.658601 -308.086386)
			(xy 83.681472 -308.129963) (xy 83.697056 -308.176644) (xy 83.704951 -308.225221) (xy 83.705446 -308.249828)
			(xy 83.704951 -308.274435) (xy 83.697056 -308.323012) (xy 83.681472 -308.369693) (xy 83.658601 -308.41327)
			(xy 83.629036 -308.452614) (xy 83.593543 -308.486706) (xy 83.55304 -308.514662) (xy 83.508578 -308.53576)
			(xy 83.461307 -308.549452) (xy 83.412452 -308.555384) (xy 83.363277 -308.553403) (xy 83.315058 -308.543559)
			(xy 83.269042 -308.526107) (xy 83.226421 -308.5015) (xy 83.1883 -308.470375) (xy 83.155665 -308.433538)
			(xy 83.129362 -308.391942) (xy 83.110071 -308.346666) (xy 83.098294 -308.298882) (xy 83.094334 -308.249828)
			(xy 82.755232 -308.249828) (xy 82.754737 -308.274435) (xy 82.746842 -308.323012) (xy 82.731258 -308.369693)
			(xy 82.708387 -308.41327) (xy 82.678822 -308.452614) (xy 82.643329 -308.486706) (xy 82.602826 -308.514662)
			(xy 82.558364 -308.53576) (xy 82.511093 -308.549452) (xy 82.462238 -308.555384) (xy 82.413063 -308.553403)
			(xy 82.364844 -308.543559) (xy 82.318828 -308.526107) (xy 82.276207 -308.5015) (xy 82.238086 -308.470375)
			(xy 82.205451 -308.433538) (xy 82.179148 -308.391942) (xy 82.159857 -308.346666) (xy 82.14808 -308.298882)
			(xy 82.14412 -308.249828) (xy 81.805272 -308.249828) (xy 81.804777 -308.274435) (xy 81.796882 -308.323012)
			(xy 81.781298 -308.369693) (xy 81.758427 -308.41327) (xy 81.728862 -308.452614) (xy 81.693369 -308.486706)
			(xy 81.652866 -308.514662) (xy 81.608404 -308.53576) (xy 81.561133 -308.549452) (xy 81.512278 -308.555384)
			(xy 81.463103 -308.553403) (xy 81.414884 -308.543559) (xy 81.368868 -308.526107) (xy 81.326247 -308.5015)
			(xy 81.288126 -308.470375) (xy 81.255491 -308.433538) (xy 81.229188 -308.391942) (xy 81.209897 -308.346666)
			(xy 81.19812 -308.298882) (xy 81.19416 -308.249828) (xy 80.855058 -308.249828) (xy 80.854563 -308.274435)
			(xy 80.846668 -308.323012) (xy 80.831084 -308.369693) (xy 80.808213 -308.41327) (xy 80.778648 -308.452614)
			(xy 80.743155 -308.486706) (xy 80.702652 -308.514662) (xy 80.65819 -308.53576) (xy 80.610919 -308.549452)
			(xy 80.562064 -308.555384) (xy 80.512889 -308.553403) (xy 80.46467 -308.543559) (xy 80.418654 -308.526107)
			(xy 80.376033 -308.5015) (xy 80.337912 -308.470375) (xy 80.305277 -308.433538) (xy 80.278974 -308.391942)
			(xy 80.259683 -308.346666) (xy 80.247906 -308.298882) (xy 80.243946 -308.249828) (xy 79.905098 -308.249828)
			(xy 79.904603 -308.274435) (xy 79.896708 -308.323012) (xy 79.881124 -308.369693) (xy 79.858253 -308.41327)
			(xy 79.828688 -308.452614) (xy 79.793195 -308.486706) (xy 79.752692 -308.514662) (xy 79.70823 -308.53576)
			(xy 79.660959 -308.549452) (xy 79.612104 -308.555384) (xy 79.562929 -308.553403) (xy 79.51471 -308.543559)
			(xy 79.468694 -308.526107) (xy 79.426073 -308.5015) (xy 79.387952 -308.470375) (xy 79.355317 -308.433538)
			(xy 79.329014 -308.391942) (xy 79.309723 -308.346666) (xy 79.297946 -308.298882) (xy 79.293986 -308.249828)
			(xy 78.955138 -308.249828) (xy 78.954643 -308.274435) (xy 78.946748 -308.323012) (xy 78.931164 -308.369693)
			(xy 78.908293 -308.41327) (xy 78.878728 -308.452614) (xy 78.843235 -308.486706) (xy 78.802732 -308.514662)
			(xy 78.75827 -308.53576) (xy 78.710999 -308.549452) (xy 78.662144 -308.555384) (xy 78.612969 -308.553403)
			(xy 78.56475 -308.543559) (xy 78.518734 -308.526107) (xy 78.476113 -308.5015) (xy 78.437992 -308.470375)
			(xy 78.405357 -308.433538) (xy 78.379054 -308.391942) (xy 78.359763 -308.346666) (xy 78.347986 -308.298882)
			(xy 78.344026 -308.249828) (xy 78.005178 -308.249828) (xy 78.004683 -308.274435) (xy 77.996788 -308.323012)
			(xy 77.981204 -308.369693) (xy 77.958333 -308.41327) (xy 77.928768 -308.452614) (xy 77.893275 -308.486706)
			(xy 77.852772 -308.514662) (xy 77.80831 -308.53576) (xy 77.761039 -308.549452) (xy 77.712184 -308.555384)
			(xy 77.663009 -308.553403) (xy 77.61479 -308.543559) (xy 77.568774 -308.526107) (xy 77.526153 -308.5015)
			(xy 77.488032 -308.470375) (xy 77.455397 -308.433538) (xy 77.429094 -308.391942) (xy 77.409803 -308.346666)
			(xy 77.398026 -308.298882) (xy 77.394066 -308.249828) (xy 77.055218 -308.249828) (xy 77.054723 -308.274435)
			(xy 77.046828 -308.323012) (xy 77.031244 -308.369693) (xy 77.008373 -308.41327) (xy 76.978808 -308.452614)
			(xy 76.943315 -308.486706) (xy 76.902812 -308.514662) (xy 76.85835 -308.53576) (xy 76.811079 -308.549452)
			(xy 76.762224 -308.555384) (xy 76.713049 -308.553403) (xy 76.66483 -308.543559) (xy 76.618814 -308.526107)
			(xy 76.576193 -308.5015) (xy 76.538072 -308.470375) (xy 76.505437 -308.433538) (xy 76.479134 -308.391942)
			(xy 76.459843 -308.346666) (xy 76.448066 -308.298882) (xy 76.444106 -308.249828) (xy 76.105258 -308.249828)
			(xy 76.104763 -308.274435) (xy 76.096868 -308.323012) (xy 76.081284 -308.369693) (xy 76.058413 -308.41327)
			(xy 76.028848 -308.452614) (xy 75.993355 -308.486706) (xy 75.952852 -308.514662) (xy 75.90839 -308.53576)
			(xy 75.861119 -308.549452) (xy 75.812264 -308.555384) (xy 75.763089 -308.553403) (xy 75.71487 -308.543559)
			(xy 75.668854 -308.526107) (xy 75.626233 -308.5015) (xy 75.588112 -308.470375) (xy 75.555477 -308.433538)
			(xy 75.529174 -308.391942) (xy 75.509883 -308.346666) (xy 75.498106 -308.298882) (xy 75.494146 -308.249828)
			(xy 75.155298 -308.249828) (xy 75.154803 -308.274435) (xy 75.146908 -308.323012) (xy 75.131324 -308.369693)
			(xy 75.108453 -308.41327) (xy 75.078888 -308.452614) (xy 75.043395 -308.486706) (xy 75.002892 -308.514662)
			(xy 74.95843 -308.53576) (xy 74.911159 -308.549452) (xy 74.862304 -308.555384) (xy 74.813129 -308.553403)
			(xy 74.76491 -308.543559) (xy 74.718894 -308.526107) (xy 74.676273 -308.5015) (xy 74.638152 -308.470375)
			(xy 74.605517 -308.433538) (xy 74.579214 -308.391942) (xy 74.559923 -308.346666) (xy 74.548146 -308.298882)
			(xy 74.544186 -308.249828) (xy 74.205084 -308.249828) (xy 74.204589 -308.274435) (xy 74.196694 -308.323012)
			(xy 74.18111 -308.369693) (xy 74.158239 -308.41327) (xy 74.128674 -308.452614) (xy 74.093181 -308.486706)
			(xy 74.052678 -308.514662) (xy 74.008216 -308.53576) (xy 73.960945 -308.549452) (xy 73.91209 -308.555384)
			(xy 73.862915 -308.553403) (xy 73.814696 -308.543559) (xy 73.76868 -308.526107) (xy 73.726059 -308.5015)
			(xy 73.687938 -308.470375) (xy 73.655303 -308.433538) (xy 73.629 -308.391942) (xy 73.609709 -308.346666)
			(xy 73.597932 -308.298882) (xy 73.593972 -308.249828) (xy 53.305202 -308.249828) (xy 53.305003 -308.263947)
			(xy 53.302333 -308.292059) (xy 53.299868 -308.305962) (xy 53.297582 -308.318408) (xy 53.304948 -308.342284)
			(xy 53.382418 -308.419754) (xy 53.406294 -308.42712) (xy 53.41874 -308.424834) (xy 53.432642 -308.422359)
			(xy 53.460755 -308.41969) (xy 53.474874 -308.4195) (xy 53.500132 -308.419991) (xy 53.549961 -308.428302)
			(xy 53.597742 -308.444701) (xy 53.642171 -308.468742) (xy 53.682038 -308.499768) (xy 53.716253 -308.536933)
			(xy 53.743885 -308.579223) (xy 53.764178 -308.625485) (xy 53.77658 -308.674456) (xy 53.780752 -308.7248)
			(xy 53.780751 -308.724808) (xy 54.11903 -308.724808) (xy 54.12299 -308.675754) (xy 54.134767 -308.62797)
			(xy 54.154058 -308.582694) (xy 54.180361 -308.541098) (xy 54.212996 -308.504261) (xy 54.251117 -308.473136)
			(xy 54.293738 -308.448529) (xy 54.339754 -308.431077) (xy 54.387973 -308.421233) (xy 54.437148 -308.419252)
			(xy 54.486003 -308.425184) (xy 54.533274 -308.438876) (xy 54.577736 -308.459974) (xy 54.618239 -308.48793)
			(xy 54.653732 -308.522022) (xy 54.683297 -308.561366) (xy 54.706168 -308.604943) (xy 54.721752 -308.651624)
			(xy 54.729647 -308.700201) (xy 54.730142 -308.724808) (xy 54.729647 -308.749415) (xy 54.721752 -308.797992)
			(xy 54.706168 -308.844673) (xy 54.683297 -308.88825) (xy 54.653732 -308.927594) (xy 54.618239 -308.961686)
			(xy 54.577736 -308.989642) (xy 54.533274 -309.01074) (xy 54.486003 -309.024432) (xy 54.437148 -309.030364)
			(xy 54.387973 -309.028383) (xy 54.339754 -309.018539) (xy 54.293738 -309.001087) (xy 54.251117 -308.97648)
			(xy 54.212996 -308.945355) (xy 54.180361 -308.908518) (xy 54.154058 -308.866922) (xy 54.134767 -308.821646)
			(xy 54.12299 -308.773862) (xy 54.11903 -308.724808) (xy 53.780751 -308.724808) (xy 53.77658 -308.775144)
			(xy 53.764178 -308.824115) (xy 53.743885 -308.870377) (xy 53.716253 -308.912667) (xy 53.682038 -308.949832)
			(xy 53.642171 -308.980858) (xy 53.597742 -309.004899) (xy 53.549961 -309.021298) (xy 53.500132 -309.029609)
			(xy 53.474874 -309.030116) (xy 53.460755 -309.029917) (xy 53.432643 -309.027248) (xy 53.41874 -309.024782)
			(xy 53.406294 -309.022496) (xy 53.382418 -309.029862) (xy 53.304948 -309.107332) (xy 53.297582 -309.131208)
			(xy 53.299868 -309.143654) (xy 53.302342 -309.157556) (xy 53.305011 -309.185669) (xy 53.305202 -309.199788)
			(xy 53.305 -309.213906) (xy 53.302325 -309.242017) (xy 53.299868 -309.255922) (xy 53.297582 -309.268368)
			(xy 53.304694 -309.29199) (xy 53.38191 -309.36946) (xy 53.405532 -309.376826) (xy 53.418232 -309.37454)
			(xy 53.432204 -309.372132) (xy 53.460443 -309.369587) (xy 53.47462 -309.36946) (xy 53.474874 -309.36946)
			(xy 53.498867 -309.369929) (xy 53.546264 -309.377431) (xy 53.591904 -309.392256) (xy 53.634662 -309.414038)
			(xy 53.673487 -309.44224) (xy 53.707422 -309.476169) (xy 53.735632 -309.514988) (xy 53.757422 -309.557743)
			(xy 53.772255 -309.603379) (xy 53.779767 -309.650775) (xy 53.780182 -309.674768) (xy 53.780182 -309.68188)
			(xy 53.779928 -309.69204) (xy 53.787294 -309.710836) (xy 53.826918 -309.75173) (xy 53.844952 -309.770272)
			(xy 53.852401 -309.777331) (xy 53.871276 -309.785335) (xy 53.881528 -309.785766) (xy 54.017672 -309.785766)
			(xy 54.027825 -309.785311) (xy 54.046544 -309.77744) (xy 54.053994 -309.770526) (xy 54.11216 -309.710836)
			(xy 54.119526 -309.69204) (xy 54.119272 -309.68188) (xy 54.119272 -309.674768) (xy 54.119745 -309.650778)
			(xy 54.127255 -309.603389) (xy 54.142085 -309.557758) (xy 54.16387 -309.515008) (xy 54.192073 -309.476192)
			(xy 54.226001 -309.442266) (xy 54.264818 -309.414064) (xy 54.307569 -309.39228) (xy 54.353201 -309.377452)
			(xy 54.40059 -309.369944) (xy 54.42458 -309.36946) (xy 54.424834 -309.36946) (xy 54.448824 -309.369933)
			(xy 54.496214 -309.377443) (xy 54.541845 -309.392273) (xy 54.584596 -309.414058) (xy 54.623412 -309.442262)
			(xy 54.65734 -309.476189) (xy 54.685543 -309.515006) (xy 54.707328 -309.557756) (xy 54.722157 -309.603388)
			(xy 54.729667 -309.650778) (xy 54.730142 -309.674768) (xy 54.730142 -309.68188) (xy 54.729888 -309.69204)
			(xy 54.737254 -309.710836) (xy 54.776878 -309.75173) (xy 54.794912 -309.770272) (xy 54.802358 -309.777337)
			(xy 54.821233 -309.785356) (xy 54.831488 -309.785766) (xy 54.967632 -309.785766) (xy 54.977788 -309.785318)
			(xy 54.996518 -309.777458) (xy 55.003954 -309.770526) (xy 55.06212 -309.710836) (xy 55.069486 -309.69204)
			(xy 55.069232 -309.68188) (xy 55.069232 -309.674768) (xy 55.069681 -309.650778) (xy 55.077192 -309.603388)
			(xy 55.092023 -309.557758) (xy 55.113811 -309.515009) (xy 55.142018 -309.476195) (xy 55.17595 -309.442271)
			(xy 55.21477 -309.414073) (xy 55.257524 -309.392296) (xy 55.303158 -309.377475) (xy 55.35055 -309.369975)
			(xy 55.37454 -309.36946) (xy 55.374794 -309.36946) (xy 55.388913 -309.369657) (xy 55.417026 -309.372324)
			(xy 55.430928 -309.374794) (xy 55.443374 -309.37708) (xy 55.46725 -309.369714) (xy 55.54472 -309.292244)
			(xy 55.552086 -309.268368) (xy 55.5498 -309.255922) (xy 55.547322 -309.24202) (xy 55.544648 -309.213908)
			(xy 55.544466 -309.199788) (xy 55.544664 -309.185669) (xy 55.547332 -309.157557) (xy 55.5498 -309.143654)
			(xy 55.552086 -309.131208) (xy 55.54472 -309.107332) (xy 55.46725 -309.029862) (xy 55.443374 -309.022496)
			(xy 55.430928 -309.024782) (xy 55.417026 -309.02726) (xy 55.388914 -309.029936) (xy 55.374794 -309.030116)
			(xy 55.349972 -309.02963) (xy 55.300984 -309.021597) (xy 55.253939 -309.005745) (xy 55.21008 -308.982491)
			(xy 55.17056 -308.952448) (xy 55.136421 -308.916406) (xy 55.108563 -308.875317) (xy 55.087719 -308.830261)
			(xy 55.074439 -308.782427) (xy 55.069073 -308.733075) (xy 55.071762 -308.683505) (xy 55.082435 -308.635023)
			(xy 55.10081 -308.588906) (xy 55.126405 -308.54637) (xy 55.158544 -308.508534) (xy 55.196381 -308.476397)
			(xy 55.238919 -308.450804) (xy 55.285036 -308.43243) (xy 55.333519 -308.42176) (xy 55.383089 -308.419073)
			(xy 55.432441 -308.424442) (xy 55.480274 -308.437724) (xy 55.525329 -308.45857) (xy 55.566417 -308.48643)
			(xy 55.602457 -308.52057) (xy 55.632499 -308.560091) (xy 55.655751 -308.603952) (xy 55.671601 -308.650997)
			(xy 55.679631 -308.699986) (xy 55.680102 -308.724808) (xy 55.679904 -308.738927) (xy 55.677236 -308.767039)
			(xy 55.674768 -308.780942) (xy 55.672482 -308.793388) (xy 55.679848 -308.817264) (xy 55.757318 -308.894734)
			(xy 55.781194 -308.9021) (xy 55.79364 -308.899814) (xy 55.807542 -308.897339) (xy 55.835655 -308.89467)
			(xy 55.849774 -308.89448) (xy 55.863957 -308.894665) (xy 55.892196 -308.897336) (xy 55.906162 -308.899814)
			(xy 55.912257 -308.900816) (xy 55.924589 -308.900175) (xy 55.930546 -308.898544) (xy 55.936431 -308.896521)
			(xy 55.94709 -308.890103) (xy 55.951628 -308.885844) (xy 56.011064 -308.826408) (xy 56.019247 -308.817111)
			(xy 56.02655 -308.793487) (xy 56.025034 -308.781196) (xy 56.022548 -308.767231) (xy 56.019875 -308.738991)
			(xy 56.0197 -308.724808) (xy 56.020185 -308.699988) (xy 56.028215 -308.651001) (xy 56.044064 -308.603959)
			(xy 56.067315 -308.5601) (xy 56.097355 -308.520581) (xy 56.133393 -308.486442) (xy 56.174479 -308.458584)
			(xy 56.219531 -308.437739) (xy 56.267361 -308.424458) (xy 56.31671 -308.419089) (xy 56.366278 -308.421776)
			(xy 56.414758 -308.432445) (xy 56.460874 -308.450818) (xy 56.503409 -308.476409) (xy 56.541244 -308.508545)
			(xy 56.573381 -308.546378) (xy 56.598975 -308.588912) (xy 56.61735 -308.635026) (xy 56.628022 -308.683506)
			(xy 56.630263 -308.724808) (xy 57.919124 -308.724808) (xy 57.923084 -308.675754) (xy 57.934861 -308.62797)
			(xy 57.954152 -308.582694) (xy 57.980455 -308.541098) (xy 58.01309 -308.504261) (xy 58.051211 -308.473136)
			(xy 58.093832 -308.448529) (xy 58.139848 -308.431077) (xy 58.188067 -308.421233) (xy 58.237242 -308.419252)
			(xy 58.286097 -308.425184) (xy 58.333368 -308.438876) (xy 58.37783 -308.459974) (xy 58.418333 -308.48793)
			(xy 58.453826 -308.522022) (xy 58.483391 -308.561366) (xy 58.506262 -308.604943) (xy 58.521846 -308.651624)
			(xy 58.529741 -308.700201) (xy 58.530236 -308.724808) (xy 58.529741 -308.749415) (xy 58.521846 -308.797992)
			(xy 58.506262 -308.844673) (xy 58.483391 -308.88825) (xy 58.453826 -308.927594) (xy 58.418333 -308.961686)
			(xy 58.37783 -308.989642) (xy 58.333368 -309.01074) (xy 58.286097 -309.024432) (xy 58.237242 -309.030364)
			(xy 58.188067 -309.028383) (xy 58.139848 -309.018539) (xy 58.093832 -309.001087) (xy 58.051211 -308.97648)
			(xy 58.01309 -308.945355) (xy 57.980455 -308.908518) (xy 57.954152 -308.866922) (xy 57.934861 -308.821646)
			(xy 57.923084 -308.773862) (xy 57.919124 -308.724808) (xy 56.630263 -308.724808) (xy 56.630711 -308.733073)
			(xy 56.625345 -308.782423) (xy 56.612066 -308.830254) (xy 56.591224 -308.875307) (xy 56.563368 -308.916395)
			(xy 56.529231 -308.952435) (xy 56.489713 -308.982477) (xy 56.445856 -309.00573) (xy 56.398814 -309.021581)
			(xy 56.349828 -309.029613) (xy 56.325008 -309.030116) (xy 56.310826 -309.02993) (xy 56.282586 -309.027257)
			(xy 56.26862 -309.024782) (xy 56.262525 -309.023782) (xy 56.250195 -309.024427) (xy 56.244236 -309.026052)
			(xy 56.238352 -309.028077) (xy 56.227695 -309.034497) (xy 56.223154 -309.038752) (xy 56.163718 -309.098188)
			(xy 56.155537 -309.107485) (xy 56.148235 -309.131109) (xy 56.149748 -309.1434) (xy 56.152234 -309.157365)
			(xy 56.154907 -309.185605) (xy 56.155082 -309.199788) (xy 56.15488 -309.213906) (xy 56.152205 -309.242017)
			(xy 56.149748 -309.255922) (xy 56.147462 -309.268368) (xy 56.154574 -309.29199) (xy 56.23179 -309.36946)
			(xy 56.255412 -309.376826) (xy 56.268112 -309.37454) (xy 56.282084 -309.372132) (xy 56.310323 -309.369584)
			(xy 56.3245 -309.36946) (xy 56.324754 -309.36946) (xy 56.34875 -309.369903) (xy 56.396153 -309.377404)
			(xy 56.441799 -309.392228) (xy 56.484564 -309.41401) (xy 56.523395 -309.442214) (xy 56.557335 -309.476146)
			(xy 56.585549 -309.514969) (xy 56.607342 -309.557729) (xy 56.622178 -309.603371) (xy 56.629691 -309.650772)
			(xy 56.630062 -309.674768) (xy 56.630062 -309.68188) (xy 56.629808 -309.69204) (xy 56.637174 -309.710836)
			(xy 56.676798 -309.75173) (xy 56.694832 -309.770272) (xy 56.70228 -309.777334) (xy 56.721155 -309.785345)
			(xy 56.731408 -309.785766) (xy 56.867806 -309.785766) (xy 56.877964 -309.785323) (xy 56.896701 -309.777469)
			(xy 56.904128 -309.770526) (xy 56.962294 -309.710836) (xy 56.96966 -309.69204) (xy 56.969406 -309.68188)
			(xy 56.969406 -309.674768) (xy 56.969879 -309.650779) (xy 56.977389 -309.603392) (xy 56.99222 -309.557763)
			(xy 57.014005 -309.515016) (xy 57.042209 -309.476203) (xy 57.076138 -309.442279) (xy 57.114955 -309.414081)
			(xy 57.157706 -309.392302) (xy 57.203337 -309.377478) (xy 57.250725 -309.369975) (xy 57.274714 -309.36946)
			(xy 57.274968 -309.36946) (xy 57.298962 -309.369928) (xy 57.346359 -309.37743) (xy 57.392 -309.392254)
			(xy 57.434759 -309.414036) (xy 57.473585 -309.442238) (xy 57.50752 -309.476167) (xy 57.535731 -309.514986)
			(xy 57.557521 -309.557741) (xy 57.572355 -309.603378) (xy 57.579867 -309.650774) (xy 57.580276 -309.674768)
			(xy 57.580276 -309.68188) (xy 57.580022 -309.69204) (xy 57.587388 -309.710836) (xy 57.627012 -309.75173)
			(xy 57.645046 -309.770272) (xy 57.652494 -309.777332) (xy 57.671369 -309.785338) (xy 57.681622 -309.785766)
			(xy 57.735724 -309.785766) (xy 57.742018 -309.785576) (xy 57.754223 -309.78249) (xy 57.759854 -309.77967)
			(xy 57.777634 -309.770018) (xy 57.779158 -309.769256) (xy 57.792112 -309.762652) (xy 57.829958 -309.744872)
			(xy 57.831482 -309.744364) (xy 57.834276 -309.743094) (xy 57.843674 -309.738522) (xy 57.853072 -309.734458)
			(xy 57.872884 -309.72633) (xy 57.879996 -309.723536) (xy 57.891934 -309.714138) (xy 57.908444 -309.690008)
			(xy 57.912762 -309.676038) (xy 57.913016 -309.668418) (xy 57.914039 -309.642981) (xy 57.923332 -309.592932)
			(xy 57.940633 -309.545058) (xy 57.965482 -309.500631) (xy 57.99722 -309.460831) (xy 58.035003 -309.426718)
			(xy 58.077826 -309.399196) (xy 58.124552 -309.378998) (xy 58.173939 -309.366661) (xy 58.224674 -309.362511)
			(xy 58.275409 -309.366661) (xy 58.324796 -309.378998) (xy 58.371522 -309.399196) (xy 58.414345 -309.426718)
			(xy 58.452128 -309.460831) (xy 58.483866 -309.500631) (xy 58.508715 -309.545058) (xy 58.526016 -309.592932)
			(xy 58.535309 -309.642981) (xy 58.536332 -309.668418) (xy 58.536332 -309.677562) (xy 58.54065 -309.690262)
			(xy 58.543248 -309.697412) (xy 58.552042 -309.709818) (xy 58.557922 -309.714646) (xy 58.570876 -309.724552)
			(xy 58.57748 -309.727346) (xy 58.603458 -309.73773) (xy 58.65429 -309.761114) (xy 58.67908 -309.774082)
			(xy 58.679588 -309.774336) (xy 58.685176 -309.77713) (xy 58.69559 -309.781194) (xy 58.704988 -309.783988)
			(xy 58.708411 -309.784872) (xy 58.715423 -309.785762) (xy 58.718958 -309.785766) (xy 59.717686 -309.785766)
			(xy 59.727837 -309.785309) (xy 59.746553 -309.777434) (xy 59.754008 -309.770526) (xy 59.812174 -309.710836)
			(xy 59.81954 -309.69204) (xy 59.819286 -309.68188) (xy 59.819286 -309.674768) (xy 59.819759 -309.650778)
			(xy 59.827269 -309.60339) (xy 59.842099 -309.55776) (xy 59.863884 -309.515011) (xy 59.892088 -309.476197)
			(xy 59.926016 -309.442271) (xy 59.964833 -309.414071) (xy 60.007584 -309.392289) (xy 60.053215 -309.377463)
			(xy 60.100604 -309.369957) (xy 60.124594 -309.36946) (xy 60.124848 -309.36946) (xy 60.138967 -309.36966)
			(xy 60.167078 -309.372331) (xy 60.180982 -309.374794) (xy 60.193428 -309.37708) (xy 60.217304 -309.369714)
			(xy 60.294774 -309.292244) (xy 60.30214 -309.268368) (xy 60.299854 -309.255922) (xy 60.297377 -309.24202)
			(xy 60.294702 -309.213908) (xy 60.29452 -309.199788) (xy 60.294718 -309.185669) (xy 60.297387 -309.157557)
			(xy 60.299854 -309.143654) (xy 60.30214 -309.131208) (xy 60.294774 -309.107332) (xy 60.217304 -309.029862)
			(xy 60.193428 -309.022496) (xy 60.180982 -309.024782) (xy 60.16708 -309.027258) (xy 60.138967 -309.029929)
			(xy 60.124848 -309.030116) (xy 60.100025 -309.029634) (xy 60.051033 -309.02161) (xy 60.003985 -309.005765)
			(xy 59.96012 -308.982517) (xy 59.920594 -308.952478) (xy 59.886448 -308.91644) (xy 59.858583 -308.875353)
			(xy 59.837733 -308.830299) (xy 59.824446 -308.782465) (xy 59.819074 -308.733112) (xy 59.821757 -308.683539)
			(xy 59.832425 -308.635054) (xy 59.850797 -308.588934) (xy 59.876388 -308.546393) (xy 59.908525 -308.508553)
			(xy 59.94636 -308.476412) (xy 59.988898 -308.450815) (xy 60.035016 -308.432437) (xy 60.0835 -308.421762)
			(xy 60.133072 -308.419073) (xy 60.182426 -308.424439) (xy 60.230261 -308.437719) (xy 60.275318 -308.458564)
			(xy 60.316409 -308.486423) (xy 60.352451 -308.520564) (xy 60.382495 -308.560086) (xy 60.405749 -308.603948)
			(xy 60.4216 -308.650994) (xy 60.429631 -308.699986) (xy 60.430156 -308.724808) (xy 60.429958 -308.738927)
			(xy 60.427289 -308.767039) (xy 60.424822 -308.780942) (xy 60.422536 -308.793388) (xy 60.429902 -308.817264)
			(xy 60.507372 -308.894734) (xy 60.531248 -308.9021) (xy 60.543694 -308.899814) (xy 60.557596 -308.897337)
			(xy 60.585709 -308.894663) (xy 60.599828 -308.89448) (xy 60.613947 -308.894679) (xy 60.642059 -308.897349)
			(xy 60.655962 -308.899814) (xy 60.668408 -308.9021) (xy 60.692284 -308.894734) (xy 60.769754 -308.817264)
			(xy 60.77712 -308.793388) (xy 60.774834 -308.780942) (xy 60.77236 -308.76704) (xy 60.769692 -308.738927)
			(xy 60.7695 -308.724808) (xy 60.770022 -308.699553) (xy 60.778335 -308.649731) (xy 60.794736 -308.601957)
			(xy 60.818777 -308.557534) (xy 60.849801 -308.517674) (xy 60.886963 -308.483464) (xy 60.929249 -308.455838)
			(xy 60.975505 -308.435548) (xy 61.02447 -308.423148) (xy 61.074808 -308.418977) (xy 61.125146 -308.423148)
			(xy 61.174111 -308.435548) (xy 61.220367 -308.455838) (xy 61.262653 -308.483464) (xy 61.299815 -308.517674)
			(xy 61.330839 -308.557534) (xy 61.35488 -308.601957) (xy 61.371281 -308.649731) (xy 61.379594 -308.699553)
			(xy 61.380116 -308.724808) (xy 61.379918 -308.738927) (xy 61.37725 -308.767039) (xy 61.374782 -308.780942)
			(xy 61.372496 -308.793388) (xy 61.379862 -308.817264) (xy 61.457332 -308.894734) (xy 61.481208 -308.9021)
			(xy 61.493654 -308.899814) (xy 61.507556 -308.89734) (xy 61.535669 -308.894672) (xy 61.549788 -308.89448)
			(xy 61.563906 -308.894682) (xy 61.592017 -308.897357) (xy 61.605922 -308.899814) (xy 61.618368 -308.9021)
			(xy 61.642244 -308.894734) (xy 61.719714 -308.817264) (xy 61.72708 -308.793388) (xy 61.724794 -308.780942)
			(xy 61.72232 -308.76704) (xy 61.719653 -308.738927) (xy 61.71946 -308.724808) (xy 61.719945 -308.699984)
			(xy 61.727977 -308.650989) (xy 61.743828 -308.60394) (xy 61.767084 -308.560075) (xy 61.797129 -308.52055)
			(xy 61.833173 -308.486407) (xy 61.874267 -308.458545) (xy 61.919326 -308.437698) (xy 61.967165 -308.424416)
			(xy 62.016523 -308.419049) (xy 62.066098 -308.421738) (xy 62.114585 -308.432412) (xy 62.160707 -308.45079)
			(xy 62.203247 -308.476388) (xy 62.241086 -308.508531) (xy 62.273226 -308.546372) (xy 62.298821 -308.588915)
			(xy 62.317195 -308.635038) (xy 62.327865 -308.683526) (xy 62.330087 -308.724554) (xy 62.668924 -308.724554)
			(xy 62.672884 -308.6755) (xy 62.684661 -308.627716) (xy 62.703952 -308.58244) (xy 62.730255 -308.540844)
			(xy 62.76289 -308.504007) (xy 62.801011 -308.472882) (xy 62.843632 -308.448275) (xy 62.889648 -308.430823)
			(xy 62.937867 -308.420979) (xy 62.987042 -308.418998) (xy 63.035897 -308.42493) (xy 63.083168 -308.438622)
			(xy 63.12763 -308.45972) (xy 63.168133 -308.487676) (xy 63.203626 -308.521768) (xy 63.233191 -308.561112)
			(xy 63.256062 -308.604689) (xy 63.271646 -308.65137) (xy 63.279541 -308.699947) (xy 63.280036 -308.724554)
			(xy 63.280031 -308.724808) (xy 63.619138 -308.724808) (xy 63.623098 -308.675754) (xy 63.634875 -308.62797)
			(xy 63.654166 -308.582694) (xy 63.680469 -308.541098) (xy 63.713104 -308.504261) (xy 63.751225 -308.473136)
			(xy 63.793846 -308.448529) (xy 63.839862 -308.431077) (xy 63.888081 -308.421233) (xy 63.937256 -308.419252)
			(xy 63.986111 -308.425184) (xy 64.033382 -308.438876) (xy 64.077844 -308.459974) (xy 64.118347 -308.48793)
			(xy 64.15384 -308.522022) (xy 64.183405 -308.561366) (xy 64.206276 -308.604943) (xy 64.22186 -308.651624)
			(xy 64.229755 -308.700201) (xy 64.23025 -308.724808) (xy 64.569098 -308.724808) (xy 64.573058 -308.675754)
			(xy 64.584835 -308.62797) (xy 64.604126 -308.582694) (xy 64.630429 -308.541098) (xy 64.663064 -308.504261)
			(xy 64.701185 -308.473136) (xy 64.743806 -308.448529) (xy 64.789822 -308.431077) (xy 64.838041 -308.421233)
			(xy 64.887216 -308.419252) (xy 64.936071 -308.425184) (xy 64.983342 -308.438876) (xy 65.027804 -308.459974)
			(xy 65.068307 -308.48793) (xy 65.1038 -308.522022) (xy 65.133365 -308.561366) (xy 65.156236 -308.604943)
			(xy 65.17182 -308.651624) (xy 65.179715 -308.700201) (xy 65.18021 -308.724808) (xy 65.519058 -308.724808)
			(xy 65.523018 -308.675754) (xy 65.534795 -308.62797) (xy 65.554086 -308.582694) (xy 65.580389 -308.541098)
			(xy 65.613024 -308.504261) (xy 65.651145 -308.473136) (xy 65.693766 -308.448529) (xy 65.739782 -308.431077)
			(xy 65.788001 -308.421233) (xy 65.837176 -308.419252) (xy 65.886031 -308.425184) (xy 65.933302 -308.438876)
			(xy 65.977764 -308.459974) (xy 66.018267 -308.48793) (xy 66.05376 -308.522022) (xy 66.083325 -308.561366)
			(xy 66.106196 -308.604943) (xy 66.12178 -308.651624) (xy 66.129675 -308.700201) (xy 66.13017 -308.724808)
			(xy 66.469018 -308.724808) (xy 66.472978 -308.675754) (xy 66.484755 -308.62797) (xy 66.504046 -308.582694)
			(xy 66.530349 -308.541098) (xy 66.562984 -308.504261) (xy 66.601105 -308.473136) (xy 66.643726 -308.448529)
			(xy 66.689742 -308.431077) (xy 66.737961 -308.421233) (xy 66.787136 -308.419252) (xy 66.835991 -308.425184)
			(xy 66.883262 -308.438876) (xy 66.927724 -308.459974) (xy 66.968227 -308.48793) (xy 67.00372 -308.522022)
			(xy 67.033285 -308.561366) (xy 67.056156 -308.604943) (xy 67.07174 -308.651624) (xy 67.079635 -308.700201)
			(xy 67.08013 -308.724808) (xy 67.418978 -308.724808) (xy 67.422938 -308.675754) (xy 67.434715 -308.62797)
			(xy 67.454006 -308.582694) (xy 67.480309 -308.541098) (xy 67.512944 -308.504261) (xy 67.551065 -308.473136)
			(xy 67.593686 -308.448529) (xy 67.639702 -308.431077) (xy 67.687921 -308.421233) (xy 67.737096 -308.419252)
			(xy 67.785951 -308.425184) (xy 67.833222 -308.438876) (xy 67.877684 -308.459974) (xy 67.918187 -308.48793)
			(xy 67.95368 -308.522022) (xy 67.983245 -308.561366) (xy 68.006116 -308.604943) (xy 68.0217 -308.651624)
			(xy 68.029595 -308.700201) (xy 68.03009 -308.724808) (xy 68.369192 -308.724808) (xy 68.373152 -308.675754)
			(xy 68.384929 -308.62797) (xy 68.40422 -308.582694) (xy 68.430523 -308.541098) (xy 68.463158 -308.504261)
			(xy 68.501279 -308.473136) (xy 68.5439 -308.448529) (xy 68.589916 -308.431077) (xy 68.638135 -308.421233)
			(xy 68.68731 -308.419252) (xy 68.736165 -308.425184) (xy 68.783436 -308.438876) (xy 68.827898 -308.459974)
			(xy 68.868401 -308.48793) (xy 68.903894 -308.522022) (xy 68.933459 -308.561366) (xy 68.95633 -308.604943)
			(xy 68.971914 -308.651624) (xy 68.979809 -308.700201) (xy 68.980304 -308.724808) (xy 69.319152 -308.724808)
			(xy 69.323112 -308.675754) (xy 69.334889 -308.62797) (xy 69.35418 -308.582694) (xy 69.380483 -308.541098)
			(xy 69.413118 -308.504261) (xy 69.451239 -308.473136) (xy 69.49386 -308.448529) (xy 69.539876 -308.431077)
			(xy 69.588095 -308.421233) (xy 69.63727 -308.419252) (xy 69.686125 -308.425184) (xy 69.733396 -308.438876)
			(xy 69.777858 -308.459974) (xy 69.818361 -308.48793) (xy 69.853854 -308.522022) (xy 69.883419 -308.561366)
			(xy 69.90629 -308.604943) (xy 69.921874 -308.651624) (xy 69.929769 -308.700201) (xy 69.930264 -308.724808)
			(xy 70.269112 -308.724808) (xy 70.273072 -308.675754) (xy 70.284849 -308.62797) (xy 70.30414 -308.582694)
			(xy 70.330443 -308.541098) (xy 70.363078 -308.504261) (xy 70.401199 -308.473136) (xy 70.44382 -308.448529)
			(xy 70.489836 -308.431077) (xy 70.538055 -308.421233) (xy 70.58723 -308.419252) (xy 70.636085 -308.425184)
			(xy 70.683356 -308.438876) (xy 70.727818 -308.459974) (xy 70.768321 -308.48793) (xy 70.803814 -308.522022)
			(xy 70.833379 -308.561366) (xy 70.85625 -308.604943) (xy 70.871834 -308.651624) (xy 70.879729 -308.700201)
			(xy 70.880224 -308.724808) (xy 71.219072 -308.724808) (xy 71.223032 -308.675754) (xy 71.234809 -308.62797)
			(xy 71.2541 -308.582694) (xy 71.280403 -308.541098) (xy 71.313038 -308.504261) (xy 71.351159 -308.473136)
			(xy 71.39378 -308.448529) (xy 71.439796 -308.431077) (xy 71.488015 -308.421233) (xy 71.53719 -308.419252)
			(xy 71.586045 -308.425184) (xy 71.633316 -308.438876) (xy 71.677778 -308.459974) (xy 71.718281 -308.48793)
			(xy 71.753774 -308.522022) (xy 71.783339 -308.561366) (xy 71.80621 -308.604943) (xy 71.821794 -308.651624)
			(xy 71.829689 -308.700201) (xy 71.830184 -308.724808) (xy 72.169032 -308.724808) (xy 72.172992 -308.675754)
			(xy 72.184769 -308.62797) (xy 72.20406 -308.582694) (xy 72.230363 -308.541098) (xy 72.262998 -308.504261)
			(xy 72.301119 -308.473136) (xy 72.34374 -308.448529) (xy 72.389756 -308.431077) (xy 72.437975 -308.421233)
			(xy 72.48715 -308.419252) (xy 72.536005 -308.425184) (xy 72.583276 -308.438876) (xy 72.627738 -308.459974)
			(xy 72.668241 -308.48793) (xy 72.703734 -308.522022) (xy 72.733299 -308.561366) (xy 72.75617 -308.604943)
			(xy 72.771754 -308.651624) (xy 72.779649 -308.700201) (xy 72.780144 -308.724808) (xy 72.779649 -308.749415)
			(xy 72.771754 -308.797992) (xy 72.75617 -308.844673) (xy 72.733299 -308.88825) (xy 72.703734 -308.927594)
			(xy 72.668241 -308.961686) (xy 72.627738 -308.989642) (xy 72.583276 -309.01074) (xy 72.536005 -309.024432)
			(xy 72.48715 -309.030364) (xy 72.437975 -309.028383) (xy 72.389756 -309.018539) (xy 72.34374 -309.001087)
			(xy 72.301119 -308.97648) (xy 72.262998 -308.945355) (xy 72.230363 -308.908518) (xy 72.20406 -308.866922)
			(xy 72.184769 -308.821646) (xy 72.172992 -308.773862) (xy 72.169032 -308.724808) (xy 71.830184 -308.724808)
			(xy 71.829689 -308.749415) (xy 71.821794 -308.797992) (xy 71.80621 -308.844673) (xy 71.783339 -308.88825)
			(xy 71.753774 -308.927594) (xy 71.718281 -308.961686) (xy 71.677778 -308.989642) (xy 71.633316 -309.01074)
			(xy 71.586045 -309.024432) (xy 71.53719 -309.030364) (xy 71.488015 -309.028383) (xy 71.439796 -309.018539)
			(xy 71.39378 -309.001087) (xy 71.351159 -308.97648) (xy 71.313038 -308.945355) (xy 71.280403 -308.908518)
			(xy 71.2541 -308.866922) (xy 71.234809 -308.821646) (xy 71.223032 -308.773862) (xy 71.219072 -308.724808)
			(xy 70.880224 -308.724808) (xy 70.879729 -308.749415) (xy 70.871834 -308.797992) (xy 70.85625 -308.844673)
			(xy 70.833379 -308.88825) (xy 70.803814 -308.927594) (xy 70.768321 -308.961686) (xy 70.727818 -308.989642)
			(xy 70.683356 -309.01074) (xy 70.636085 -309.024432) (xy 70.58723 -309.030364) (xy 70.538055 -309.028383)
			(xy 70.489836 -309.018539) (xy 70.44382 -309.001087) (xy 70.401199 -308.97648) (xy 70.363078 -308.945355)
			(xy 70.330443 -308.908518) (xy 70.30414 -308.866922) (xy 70.284849 -308.821646) (xy 70.273072 -308.773862)
			(xy 70.269112 -308.724808) (xy 69.930264 -308.724808) (xy 69.929769 -308.749415) (xy 69.921874 -308.797992)
			(xy 69.90629 -308.844673) (xy 69.883419 -308.88825) (xy 69.853854 -308.927594) (xy 69.818361 -308.961686)
			(xy 69.777858 -308.989642) (xy 69.733396 -309.01074) (xy 69.686125 -309.024432) (xy 69.63727 -309.030364)
			(xy 69.588095 -309.028383) (xy 69.539876 -309.018539) (xy 69.49386 -309.001087) (xy 69.451239 -308.97648)
			(xy 69.413118 -308.945355) (xy 69.380483 -308.908518) (xy 69.35418 -308.866922) (xy 69.334889 -308.821646)
			(xy 69.323112 -308.773862) (xy 69.319152 -308.724808) (xy 68.980304 -308.724808) (xy 68.979809 -308.749415)
			(xy 68.971914 -308.797992) (xy 68.95633 -308.844673) (xy 68.933459 -308.88825) (xy 68.903894 -308.927594)
			(xy 68.868401 -308.961686) (xy 68.827898 -308.989642) (xy 68.783436 -309.01074) (xy 68.736165 -309.024432)
			(xy 68.68731 -309.030364) (xy 68.638135 -309.028383) (xy 68.589916 -309.018539) (xy 68.5439 -309.001087)
			(xy 68.501279 -308.97648) (xy 68.463158 -308.945355) (xy 68.430523 -308.908518) (xy 68.40422 -308.866922)
			(xy 68.384929 -308.821646) (xy 68.373152 -308.773862) (xy 68.369192 -308.724808) (xy 68.03009 -308.724808)
			(xy 68.029595 -308.749415) (xy 68.0217 -308.797992) (xy 68.006116 -308.844673) (xy 67.983245 -308.88825)
			(xy 67.95368 -308.927594) (xy 67.918187 -308.961686) (xy 67.877684 -308.989642) (xy 67.833222 -309.01074)
			(xy 67.785951 -309.024432) (xy 67.737096 -309.030364) (xy 67.687921 -309.028383) (xy 67.639702 -309.018539)
			(xy 67.593686 -309.001087) (xy 67.551065 -308.97648) (xy 67.512944 -308.945355) (xy 67.480309 -308.908518)
			(xy 67.454006 -308.866922) (xy 67.434715 -308.821646) (xy 67.422938 -308.773862) (xy 67.418978 -308.724808)
			(xy 67.08013 -308.724808) (xy 67.079635 -308.749415) (xy 67.07174 -308.797992) (xy 67.056156 -308.844673)
			(xy 67.033285 -308.88825) (xy 67.00372 -308.927594) (xy 66.968227 -308.961686) (xy 66.927724 -308.989642)
			(xy 66.883262 -309.01074) (xy 66.835991 -309.024432) (xy 66.787136 -309.030364) (xy 66.737961 -309.028383)
			(xy 66.689742 -309.018539) (xy 66.643726 -309.001087) (xy 66.601105 -308.97648) (xy 66.562984 -308.945355)
			(xy 66.530349 -308.908518) (xy 66.504046 -308.866922) (xy 66.484755 -308.821646) (xy 66.472978 -308.773862)
			(xy 66.469018 -308.724808) (xy 66.13017 -308.724808) (xy 66.129675 -308.749415) (xy 66.12178 -308.797992)
			(xy 66.106196 -308.844673) (xy 66.083325 -308.88825) (xy 66.05376 -308.927594) (xy 66.018267 -308.961686)
			(xy 65.977764 -308.989642) (xy 65.933302 -309.01074) (xy 65.886031 -309.024432) (xy 65.837176 -309.030364)
			(xy 65.788001 -309.028383) (xy 65.739782 -309.018539) (xy 65.693766 -309.001087) (xy 65.651145 -308.97648)
			(xy 65.613024 -308.945355) (xy 65.580389 -308.908518) (xy 65.554086 -308.866922) (xy 65.534795 -308.821646)
			(xy 65.523018 -308.773862) (xy 65.519058 -308.724808) (xy 65.18021 -308.724808) (xy 65.179715 -308.749415)
			(xy 65.17182 -308.797992) (xy 65.156236 -308.844673) (xy 65.133365 -308.88825) (xy 65.1038 -308.927594)
			(xy 65.068307 -308.961686) (xy 65.027804 -308.989642) (xy 64.983342 -309.01074) (xy 64.936071 -309.024432)
			(xy 64.887216 -309.030364) (xy 64.838041 -309.028383) (xy 64.789822 -309.018539) (xy 64.743806 -309.001087)
			(xy 64.701185 -308.97648) (xy 64.663064 -308.945355) (xy 64.630429 -308.908518) (xy 64.604126 -308.866922)
			(xy 64.584835 -308.821646) (xy 64.573058 -308.773862) (xy 64.569098 -308.724808) (xy 64.23025 -308.724808)
			(xy 64.229755 -308.749415) (xy 64.22186 -308.797992) (xy 64.206276 -308.844673) (xy 64.183405 -308.88825)
			(xy 64.15384 -308.927594) (xy 64.118347 -308.961686) (xy 64.077844 -308.989642) (xy 64.033382 -309.01074)
			(xy 63.986111 -309.024432) (xy 63.937256 -309.030364) (xy 63.888081 -309.028383) (xy 63.839862 -309.018539)
			(xy 63.793846 -309.001087) (xy 63.751225 -308.97648) (xy 63.713104 -308.945355) (xy 63.680469 -308.908518)
			(xy 63.654166 -308.866922) (xy 63.634875 -308.821646) (xy 63.623098 -308.773862) (xy 63.619138 -308.724808)
			(xy 63.280031 -308.724808) (xy 63.279541 -308.749161) (xy 63.271646 -308.797738) (xy 63.256062 -308.844419)
			(xy 63.233191 -308.887996) (xy 63.203626 -308.92734) (xy 63.168133 -308.961432) (xy 63.12763 -308.989388)
			(xy 63.083168 -309.010486) (xy 63.035897 -309.024178) (xy 62.987042 -309.03011) (xy 62.937867 -309.028129)
			(xy 62.889648 -309.018285) (xy 62.843632 -309.000833) (xy 62.801011 -308.976226) (xy 62.76289 -308.945101)
			(xy 62.730255 -308.908264) (xy 62.703952 -308.866668) (xy 62.684661 -308.821392) (xy 62.672884 -308.773608)
			(xy 62.668924 -308.724554) (xy 62.330087 -308.724554) (xy 62.33055 -308.733102) (xy 62.325179 -308.782458)
			(xy 62.311894 -308.830296) (xy 62.291044 -308.875354) (xy 62.263178 -308.916445) (xy 62.229032 -308.952487)
			(xy 62.189505 -308.982529) (xy 62.145638 -309.005781) (xy 62.098587 -309.021629) (xy 62.049592 -309.029657)
			(xy 62.024768 -309.030116) (xy 62.010649 -309.029917) (xy 61.982537 -309.027247) (xy 61.968634 -309.024782)
			(xy 61.956188 -309.022496) (xy 61.932312 -309.029862) (xy 61.854842 -309.107332) (xy 61.847476 -309.131208)
			(xy 61.849762 -309.143654) (xy 61.852236 -309.157556) (xy 61.854905 -309.185669) (xy 61.855096 -309.199788)
			(xy 61.854894 -309.213906) (xy 61.852219 -309.242017) (xy 61.849762 -309.255922) (xy 61.847476 -309.268368)
			(xy 61.854588 -309.29199) (xy 61.931804 -309.36946) (xy 61.955426 -309.376826) (xy 61.968126 -309.37454)
			(xy 61.982098 -309.372132) (xy 62.010337 -309.369586) (xy 62.024514 -309.36946) (xy 62.024768 -309.36946)
			(xy 62.048762 -309.369928) (xy 62.096159 -309.37743) (xy 62.1418 -309.392254) (xy 62.184559 -309.414036)
			(xy 62.223385 -309.442238) (xy 62.25732 -309.476167) (xy 62.285531 -309.514986) (xy 62.307321 -309.557741)
			(xy 62.322155 -309.603378) (xy 62.329667 -309.650774) (xy 62.330076 -309.674768) (xy 62.330076 -309.68188)
			(xy 62.329822 -309.69204) (xy 62.337188 -309.710836) (xy 62.376812 -309.75173) (xy 62.394846 -309.770272)
			(xy 62.402294 -309.777332) (xy 62.421169 -309.785338) (xy 62.431422 -309.785766) (xy 62.48527 -309.785766)
			(xy 62.497716 -309.784242) (xy 62.504828 -309.782464) (xy 62.510924 -309.779162) (xy 62.5221 -309.77332)
			(xy 62.522354 -309.77332) (xy 62.546656 -309.760531) (xy 62.59647 -309.737404) (xy 62.621922 -309.727092)
			(xy 62.622176 -309.726838) (xy 62.629057 -309.723859) (xy 62.640818 -309.714568) (xy 62.64529 -309.70855)
			(xy 62.660276 -309.68696) (xy 62.666626 -309.674768) (xy 62.669166 -309.667656) (xy 62.66942 -309.66029)
			(xy 62.671184 -309.634484) (xy 62.682298 -309.583972) (xy 62.701766 -309.536056) (xy 62.729032 -309.492107)
			(xy 62.763315 -309.453381) (xy 62.803634 -309.420988) (xy 62.848836 -309.395853) (xy 62.897628 -309.378696)
			(xy 62.948614 -309.370008) (xy 62.974474 -309.36946) (xy 62.974728 -309.36946) (xy 63.000638 -309.37001)
			(xy 63.051714 -309.378762) (xy 63.10058 -309.39601) (xy 63.145834 -309.421259) (xy 63.186176 -309.453784)
			(xy 63.220448 -309.492653) (xy 63.247668 -309.536749) (xy 63.267054 -309.584806) (xy 63.27805 -309.635447)
			(xy 63.279782 -309.661306) (xy 63.280036 -309.668672) (xy 63.284862 -309.682642) (xy 63.29934 -309.702708)
			(xy 63.300102 -309.703978) (xy 63.306452 -309.713376) (xy 63.313056 -309.71871) (xy 63.319914 -309.724044)
			(xy 63.327026 -309.726838) (xy 63.347642 -309.735096) (xy 63.388171 -309.753263) (xy 63.408052 -309.76316)
			(xy 63.43904 -309.779416) (xy 63.444703 -309.782357) (xy 63.457046 -309.785584) (xy 63.463424 -309.785766)
			(xy 63.51778 -309.785766) (xy 63.527932 -309.78531) (xy 63.546649 -309.777437) (xy 63.554102 -309.770526)
			(xy 63.612268 -309.710836) (xy 63.619634 -309.69204) (xy 63.61938 -309.68188) (xy 63.61938 -309.674768)
			(xy 63.619853 -309.650778) (xy 63.627363 -309.60339) (xy 63.642193 -309.557759) (xy 63.663978 -309.51501)
			(xy 63.692182 -309.476195) (xy 63.72611 -309.442269) (xy 63.764927 -309.414068) (xy 63.807678 -309.392285)
			(xy 63.853309 -309.377458) (xy 63.900698 -309.369951) (xy 63.924688 -309.36946) (xy 63.924942 -309.36946)
			(xy 63.948932 -309.369934) (xy 63.99632 -309.377445) (xy 64.041951 -309.392276) (xy 64.0847 -309.414061)
			(xy 64.123516 -309.442264) (xy 64.157442 -309.476192) (xy 64.185644 -309.515008) (xy 64.207428 -309.557758)
			(xy 64.222258 -309.603389) (xy 64.229767 -309.650778) (xy 64.23025 -309.674768) (xy 64.23025 -309.68188)
			(xy 64.229996 -309.69204) (xy 64.237362 -309.710836) (xy 64.276986 -309.75173) (xy 64.29502 -309.770272)
			(xy 64.302467 -309.777336) (xy 64.321342 -309.785352) (xy 64.331596 -309.785766) (xy 64.408812 -309.785766)
			(xy 64.417513 -309.785414) (xy 64.433916 -309.779599) (xy 64.447435 -309.768639) (xy 64.452246 -309.761382)
			(xy 64.4525 -309.760874) (xy 64.455294 -309.756302) (xy 64.495426 -309.738014) (xy 64.502538 -309.73522)
			(xy 64.5033 -309.734712) (xy 64.506856 -309.733188) (xy 64.50838 -309.73268) (xy 64.510158 -309.731918)
			(xy 64.511428 -309.731918) (xy 64.528192 -309.724298) (xy 64.534542 -309.720488) (xy 64.538606 -309.716932)
			(xy 64.541441 -309.714477) (xy 64.546414 -309.708865) (xy 64.548512 -309.705756) (xy 64.558926 -309.6895)
			(xy 64.56934 -309.681372) (xy 64.569293 -309.657396) (xy 64.575763 -309.609892) (xy 64.589576 -309.563983)
			(xy 64.610392 -309.520795) (xy 64.6377 -309.48139) (xy 64.67083 -309.446736) (xy 64.708967 -309.417683)
			(xy 64.751175 -309.394946) (xy 64.796417 -309.379083) (xy 64.843582 -309.370484) (xy 64.867536 -309.36946)
			(xy 64.875156 -309.36946) (xy 64.901042 -309.370027) (xy 64.952067 -309.378798) (xy 65.000882 -309.396046)
			(xy 65.046091 -309.421277) (xy 65.086399 -309.453768) (xy 65.120652 -309.49259) (xy 65.14787 -309.536631)
			(xy 65.167274 -309.58463) (xy 65.178308 -309.635214) (xy 65.179956 -309.661052) (xy 65.18021 -309.668418)
			(xy 65.184782 -309.681626) (xy 65.190116 -309.689246) (xy 65.20053 -309.705248) (xy 65.207134 -309.713376)
			(xy 65.216532 -309.722774) (xy 65.226438 -309.726584) (xy 65.264538 -309.742586) (xy 65.283613 -309.751081)
			(xy 65.321091 -309.769502) (xy 65.339468 -309.779416) (xy 65.339722 -309.77967) (xy 65.345409 -309.782525)
			(xy 65.357745 -309.785623) (xy 65.364106 -309.785766) (xy 65.4177 -309.785766) (xy 65.427859 -309.785324)
			(xy 65.446597 -309.777472) (xy 65.454022 -309.770526) (xy 65.512188 -309.710836) (xy 65.519554 -309.69204)
			(xy 65.5193 -309.68188) (xy 65.5193 -309.674768) (xy 65.519773 -309.650779) (xy 65.527283 -309.603391)
			(xy 65.542113 -309.557762) (xy 65.563899 -309.515014) (xy 65.592103 -309.476201) (xy 65.626031 -309.442277)
			(xy 65.664849 -309.414078) (xy 65.707599 -309.392298) (xy 65.75323 -309.377474) (xy 65.800619 -309.36997)
			(xy 65.824608 -309.36946) (xy 65.824862 -309.36946) (xy 65.848858 -309.369903) (xy 65.89626 -309.377405)
			(xy 65.941905 -309.39223) (xy 65.984668 -309.414013) (xy 66.023498 -309.442217) (xy 66.057437 -309.476149)
			(xy 66.085651 -309.514972) (xy 66.107443 -309.55773) (xy 66.122279 -309.603372) (xy 66.129791 -309.650772)
			(xy 66.13017 -309.674768) (xy 66.13017 -309.68188) (xy 66.129916 -309.69204) (xy 66.137282 -309.710836)
			(xy 66.176906 -309.75173) (xy 66.19494 -309.770272) (xy 66.202388 -309.777333) (xy 66.221263 -309.785341)
			(xy 66.231516 -309.785766) (xy 66.308732 -309.785766) (xy 66.317432 -309.785411) (xy 66.333829 -309.779591)
			(xy 66.347343 -309.76863) (xy 66.352166 -309.761382) (xy 66.35242 -309.760874) (xy 66.355214 -309.756302)
			(xy 66.395346 -309.738014) (xy 66.402458 -309.73522) (xy 66.40322 -309.734712) (xy 66.406776 -309.733188)
			(xy 66.4083 -309.73268) (xy 66.410078 -309.731918) (xy 66.411348 -309.731918) (xy 66.428112 -309.724298)
			(xy 66.434462 -309.720488) (xy 66.438526 -309.716932) (xy 66.441364 -309.71448) (xy 66.446345 -309.708872)
			(xy 66.448432 -309.705756) (xy 66.458846 -309.6895) (xy 66.46926 -309.681372) (xy 66.469213 -309.657397)
			(xy 66.475683 -309.609894) (xy 66.489496 -309.563985) (xy 66.510312 -309.520799) (xy 66.537621 -309.481396)
			(xy 66.570751 -309.446743) (xy 66.608888 -309.417693) (xy 66.651097 -309.394959) (xy 66.696339 -309.379098)
			(xy 66.743503 -309.370502) (xy 66.767456 -309.36946) (xy 66.775076 -309.36946) (xy 66.800961 -309.370028)
			(xy 66.851983 -309.378802) (xy 66.900795 -309.396052) (xy 66.946001 -309.421284) (xy 66.986306 -309.453775)
			(xy 67.020557 -309.492597) (xy 67.047773 -309.536636) (xy 67.067175 -309.584634) (xy 67.078208 -309.635216)
			(xy 67.079876 -309.661052) (xy 67.08013 -309.668418) (xy 67.084702 -309.681626) (xy 67.090036 -309.689246)
			(xy 67.10045 -309.705248) (xy 67.107054 -309.713376) (xy 67.116452 -309.722774) (xy 67.126358 -309.726584)
			(xy 67.164458 -309.742586) (xy 67.183532 -309.751081) (xy 67.22101 -309.769503) (xy 67.239388 -309.779416)
			(xy 67.239642 -309.77967) (xy 67.245329 -309.782523) (xy 67.257666 -309.785616) (xy 67.264026 -309.785766)
			(xy 67.31762 -309.785766) (xy 67.327777 -309.785321) (xy 67.34651 -309.777463) (xy 67.353942 -309.770526)
			(xy 67.412108 -309.710836) (xy 67.419474 -309.69204) (xy 67.41922 -309.68188) (xy 67.41922 -309.674768)
			(xy 67.419693 -309.650779) (xy 67.427203 -309.603393) (xy 67.442034 -309.557765) (xy 67.46382 -309.515019)
			(xy 67.492024 -309.476207) (xy 67.525953 -309.442285) (xy 67.56477 -309.414088) (xy 67.607521 -309.392311)
			(xy 67.653151 -309.377489) (xy 67.700539 -309.369988) (xy 67.724528 -309.36946) (xy 67.724782 -309.36946)
			(xy 67.748775 -309.369929) (xy 67.796171 -309.377433) (xy 67.841809 -309.392258) (xy 67.884567 -309.41404)
			(xy 67.92339 -309.442243) (xy 67.957325 -309.476171) (xy 67.985533 -309.514991) (xy 68.007323 -309.557744)
			(xy 68.022155 -309.60338) (xy 68.029667 -309.650775) (xy 68.03009 -309.674768) (xy 68.03009 -309.68188)
			(xy 68.029836 -309.69204) (xy 68.037202 -309.710836) (xy 68.076826 -309.75173) (xy 68.09486 -309.770272)
			(xy 68.102309 -309.77733) (xy 68.121184 -309.78533) (xy 68.131436 -309.785766) (xy 68.233544 -309.785766)
			(xy 68.258182 -309.769764) (xy 68.264532 -309.756048) (xy 68.267072 -309.750714) (xy 68.279518 -309.744872)
			(xy 68.280026 -309.744872) (xy 68.29044 -309.740046) (xy 68.293742 -309.738522) (xy 68.30314 -309.734458)
			(xy 68.322952 -309.72633) (xy 68.330064 -309.723536) (xy 68.342002 -309.714138) (xy 68.358512 -309.690008)
			(xy 68.36283 -309.676038) (xy 68.363084 -309.668672) (xy 68.364009 -309.644496) (xy 68.372411 -309.596851)
			(xy 68.388075 -309.551078) (xy 68.410627 -309.508276) (xy 68.439523 -309.469474) (xy 68.47407 -309.435605)
			(xy 68.513436 -309.407483) (xy 68.556676 -309.385783) (xy 68.602751 -309.371028) (xy 68.650552 -309.363572)
			(xy 68.674742 -309.36311) (xy 68.698917 -309.363568) (xy 68.746686 -309.371038) (xy 68.792729 -309.385793)
			(xy 68.835943 -309.407478) (xy 68.875292 -309.435574) (xy 68.909831 -309.469408) (xy 68.938734 -309.508167)
			(xy 68.961307 -309.550924) (xy 68.97701 -309.596653) (xy 68.985465 -309.644257) (xy 68.9864 -309.668418)
			(xy 68.986654 -309.676038) (xy 68.990972 -309.690008) (xy 68.99529 -309.696104) (xy 68.996306 -309.697628)
			(xy 69.004688 -309.709312) (xy 69.00804 -309.713835) (xy 69.016373 -309.721399) (xy 69.021198 -309.724298)
			(xy 69.0245 -309.726076) (xy 69.059806 -309.740554) (xy 69.080065 -309.749464) (xy 69.119833 -309.768901)
			(xy 69.139308 -309.779416) (xy 69.139816 -309.77967) (xy 69.145658 -309.782718) (xy 69.157596 -309.785766)
			(xy 69.217794 -309.785766) (xy 69.227953 -309.785325) (xy 69.246693 -309.777474) (xy 69.254116 -309.770526)
			(xy 69.312282 -309.710836) (xy 69.319648 -309.69204) (xy 69.319394 -309.68188) (xy 69.319394 -309.674768)
			(xy 69.319867 -309.650778) (xy 69.327377 -309.603391) (xy 69.342207 -309.557761) (xy 69.363993 -309.515013)
			(xy 69.392197 -309.476199) (xy 69.426125 -309.442275) (xy 69.464942 -309.414075) (xy 69.507693 -309.392294)
			(xy 69.553324 -309.377469) (xy 69.600712 -309.369964) (xy 69.624702 -309.36946) (xy 69.624956 -309.36946)
			(xy 69.648952 -309.369903) (xy 69.696355 -309.377404) (xy 69.742001 -309.392228) (xy 69.784765 -309.414011)
			(xy 69.823596 -309.442215) (xy 69.857536 -309.476147) (xy 69.88575 -309.51497) (xy 69.907543 -309.557729)
			(xy 69.922378 -309.603371) (xy 69.929891 -309.650772) (xy 69.930264 -309.674768) (xy 69.930264 -309.68188)
			(xy 69.93001 -309.69204) (xy 69.937376 -309.710836) (xy 69.977 -309.75173) (xy 69.995034 -309.770272)
			(xy 70.002482 -309.777334) (xy 70.021357 -309.785344) (xy 70.03161 -309.785766) (xy 70.108826 -309.785766)
			(xy 70.117526 -309.785412) (xy 70.133925 -309.779594) (xy 70.14744 -309.768633) (xy 70.15226 -309.761382)
			(xy 70.152514 -309.760874) (xy 70.155308 -309.756302) (xy 70.19544 -309.738014) (xy 70.202552 -309.73522)
			(xy 70.203314 -309.734712) (xy 70.20687 -309.733188) (xy 70.208394 -309.73268) (xy 70.210172 -309.731918)
			(xy 70.211442 -309.731918) (xy 70.228206 -309.724298) (xy 70.234556 -309.720488) (xy 70.23862 -309.716932)
			(xy 70.241458 -309.71448) (xy 70.246439 -309.708872) (xy 70.248526 -309.705756) (xy 70.25894 -309.6895)
			(xy 70.269354 -309.681372) (xy 70.269307 -309.657397) (xy 70.275777 -309.609893) (xy 70.28959 -309.563985)
			(xy 70.310406 -309.520798) (xy 70.337715 -309.481394) (xy 70.370845 -309.446741) (xy 70.408982 -309.41769)
			(xy 70.45119 -309.394955) (xy 70.496432 -309.379094) (xy 70.543597 -309.370497) (xy 70.56755 -309.36946)
			(xy 70.57517 -309.36946) (xy 70.601055 -309.370028) (xy 70.652078 -309.378801) (xy 70.700891 -309.39605)
			(xy 70.746098 -309.421281) (xy 70.786404 -309.453773) (xy 70.820656 -309.492595) (xy 70.847872 -309.536635)
			(xy 70.867275 -309.584633) (xy 70.878308 -309.635215) (xy 70.87997 -309.661052) (xy 70.880224 -309.668418)
			(xy 70.884796 -309.681626) (xy 70.89013 -309.689246) (xy 70.900544 -309.705248) (xy 70.907148 -309.713376)
			(xy 70.916546 -309.722774) (xy 70.926452 -309.726584) (xy 70.964552 -309.742586) (xy 70.983626 -309.751081)
			(xy 71.021104 -309.769503) (xy 71.039482 -309.779416) (xy 71.039736 -309.77967) (xy 71.045423 -309.782523)
			(xy 71.05776 -309.785618) (xy 71.06412 -309.785766) (xy 71.117714 -309.785766) (xy 71.127871 -309.785322)
			(xy 71.146606 -309.777466) (xy 71.154036 -309.770526) (xy 71.212202 -309.710836) (xy 71.219568 -309.69204)
			(xy 71.219314 -309.68188) (xy 71.219314 -309.674768) (xy 71.219787 -309.650779) (xy 71.227297 -309.603393)
			(xy 71.242128 -309.557764) (xy 71.263913 -309.515018) (xy 71.292118 -309.476205) (xy 71.326046 -309.442283)
			(xy 71.364864 -309.414085) (xy 71.407614 -309.392307) (xy 71.453245 -309.377485) (xy 71.500633 -309.369983)
			(xy 71.524622 -309.36946) (xy 71.524876 -309.36946) (xy 71.548869 -309.369929) (xy 71.596266 -309.377432)
			(xy 71.641905 -309.392257) (xy 71.684663 -309.414038) (xy 71.723488 -309.442241) (xy 71.757423 -309.476169)
			(xy 71.785632 -309.514989) (xy 71.807422 -309.557743) (xy 71.822255 -309.60338) (xy 71.829767 -309.650775)
			(xy 71.830184 -309.674768) (xy 71.830184 -309.68188) (xy 71.82993 -309.69204) (xy 71.837296 -309.710836)
			(xy 71.87692 -309.75173) (xy 71.894954 -309.770272) (xy 71.902403 -309.777331) (xy 71.921278 -309.785334)
			(xy 71.93153 -309.785766) (xy 72.008746 -309.785766) (xy 72.017445 -309.785409) (xy 72.033839 -309.779586)
			(xy 72.047348 -309.768624) (xy 72.05218 -309.761382) (xy 72.052434 -309.760874) (xy 72.055228 -309.756302)
			(xy 72.09536 -309.738014) (xy 72.102472 -309.73522) (xy 72.103234 -309.734712) (xy 72.10679 -309.733188)
			(xy 72.108314 -309.73268) (xy 72.110092 -309.731918) (xy 72.111362 -309.731918) (xy 72.128126 -309.724298)
			(xy 72.134476 -309.720488) (xy 72.13854 -309.716932) (xy 72.141377 -309.714479) (xy 72.146357 -309.708871)
			(xy 72.148446 -309.705756) (xy 72.15886 -309.6895) (xy 72.169274 -309.681372) (xy 72.169227 -309.657397)
			(xy 72.175697 -309.609895) (xy 72.18951 -309.563987) (xy 72.210327 -309.520802) (xy 72.237636 -309.4814)
			(xy 72.270766 -309.446749) (xy 72.308904 -309.4177) (xy 72.351112 -309.394967) (xy 72.396354 -309.379109)
			(xy 72.443518 -309.370515) (xy 72.46747 -309.36946) (xy 72.47509 -309.36946) (xy 72.500974 -309.370029)
			(xy 72.551994 -309.378805) (xy 72.600805 -309.396056) (xy 72.646009 -309.421288) (xy 72.686312 -309.45378)
			(xy 72.720561 -309.492601) (xy 72.747775 -309.53664) (xy 72.767176 -309.584637) (xy 72.778208 -309.635217)
			(xy 72.77989 -309.661052) (xy 72.780144 -309.668418) (xy 72.784716 -309.681626) (xy 72.79005 -309.689246)
			(xy 72.800464 -309.705248) (xy 72.807068 -309.713376) (xy 72.816466 -309.722774) (xy 72.826372 -309.726584)
			(xy 72.833738 -309.729632) (xy 72.843136 -309.733442) (xy 72.893174 -309.755794) (xy 72.893428 -309.756048)
			(xy 72.901048 -309.759604) (xy 72.939148 -309.779416) (xy 72.950578 -309.785766) (xy 72.964294 -309.785766)
			(xy 72.973438 -309.789576) (xy 72.978001 -309.791584) (xy 72.986315 -309.797084) (xy 72.989948 -309.800498)
			(xy 73.013062 -309.823612) (xy 73.020174 -309.829454) (xy 73.023222 -309.831486) (xy 73.04151 -309.84444)
			(xy 73.042018 -309.844948) (xy 73.04532 -309.847234) (xy 73.058274 -309.856886) (xy 73.05929 -309.857902)
			(xy 73.062338 -309.860188) (xy 73.064878 -309.861966) (xy 73.071228 -309.867046) (xy 73.083928 -309.871618)
			(xy 73.092551 -309.874203) (xy 73.110537 -309.873794) (xy 73.127267 -309.867178) (xy 73.13422 -309.861458)
			(xy 73.144634 -309.852314) (xy 73.15327 -309.826406) (xy 73.148698 -309.805324) (xy 73.146412 -309.800244)
			(xy 73.138155 -309.781106) (xy 73.126357 -309.74113) (xy 73.120114 -309.69992) (xy 73.119488 -309.679086)
			(xy 73.119488 -309.678578) (xy 73.119234 -309.669942) (xy 73.120056 -309.646197) (xy 73.128147 -309.59938)
			(xy 73.143392 -309.554381) (xy 73.165424 -309.512288) (xy 73.19371 -309.474115) (xy 73.227568 -309.440785)
			(xy 73.266181 -309.413102) (xy 73.308616 -309.391735) (xy 73.353848 -309.377199) (xy 73.400787 -309.369846)
			(xy 73.424542 -309.36946) (xy 73.424796 -309.36946) (xy 73.438915 -309.369657) (xy 73.467027 -309.372324)
			(xy 73.48093 -309.374794) (xy 73.493376 -309.37708) (xy 73.517252 -309.369714) (xy 73.594722 -309.292244)
			(xy 73.602088 -309.268368) (xy 73.599802 -309.255922) (xy 73.597324 -309.24202) (xy 73.594649 -309.213908)
			(xy 73.594468 -309.199788) (xy 73.594955 -309.174965) (xy 73.602989 -309.125973) (xy 73.618843 -309.078927)
			(xy 73.642099 -309.035065) (xy 73.672146 -308.995543) (xy 73.70819 -308.961404) (xy 73.749283 -308.933545)
			(xy 73.794341 -308.912701) (xy 73.842178 -308.899422) (xy 73.891534 -308.894057) (xy 73.941107 -308.896747)
			(xy 73.989591 -308.907422) (xy 74.03571 -308.925801) (xy 74.078248 -308.951398) (xy 74.116085 -308.983541)
			(xy 74.148223 -309.021381) (xy 74.173815 -309.063922) (xy 74.192188 -309.110043) (xy 74.202858 -309.158529)
			(xy 74.205092 -309.199788) (xy 74.544186 -309.199788) (xy 74.548146 -309.150734) (xy 74.559923 -309.10295)
			(xy 74.579214 -309.057674) (xy 74.605517 -309.016078) (xy 74.638152 -308.979241) (xy 74.676273 -308.948116)
			(xy 74.718894 -308.923509) (xy 74.76491 -308.906057) (xy 74.813129 -308.896213) (xy 74.862304 -308.894232)
			(xy 74.911159 -308.900164) (xy 74.95843 -308.913856) (xy 75.002892 -308.934954) (xy 75.043395 -308.96291)
			(xy 75.078888 -308.997002) (xy 75.108453 -309.036346) (xy 75.131324 -309.079923) (xy 75.146908 -309.126604)
			(xy 75.154803 -309.175181) (xy 75.155298 -309.199788) (xy 75.494146 -309.199788) (xy 75.498106 -309.150734)
			(xy 75.509883 -309.10295) (xy 75.529174 -309.057674) (xy 75.555477 -309.016078) (xy 75.588112 -308.979241)
			(xy 75.626233 -308.948116) (xy 75.668854 -308.923509) (xy 75.71487 -308.906057) (xy 75.763089 -308.896213)
			(xy 75.812264 -308.894232) (xy 75.861119 -308.900164) (xy 75.90839 -308.913856) (xy 75.952852 -308.934954)
			(xy 75.993355 -308.96291) (xy 76.028848 -308.997002) (xy 76.058413 -309.036346) (xy 76.081284 -309.079923)
			(xy 76.096868 -309.126604) (xy 76.104763 -309.175181) (xy 76.105258 -309.199788) (xy 76.444106 -309.199788)
			(xy 76.448066 -309.150734) (xy 76.459843 -309.10295) (xy 76.479134 -309.057674) (xy 76.505437 -309.016078)
			(xy 76.538072 -308.979241) (xy 76.576193 -308.948116) (xy 76.618814 -308.923509) (xy 76.66483 -308.906057)
			(xy 76.713049 -308.896213) (xy 76.762224 -308.894232) (xy 76.811079 -308.900164) (xy 76.85835 -308.913856)
			(xy 76.902812 -308.934954) (xy 76.943315 -308.96291) (xy 76.978808 -308.997002) (xy 77.008373 -309.036346)
			(xy 77.031244 -309.079923) (xy 77.046828 -309.126604) (xy 77.054723 -309.175181) (xy 77.055218 -309.199788)
			(xy 77.394066 -309.199788) (xy 77.398026 -309.150734) (xy 77.409803 -309.10295) (xy 77.429094 -309.057674)
			(xy 77.455397 -309.016078) (xy 77.488032 -308.979241) (xy 77.526153 -308.948116) (xy 77.568774 -308.923509)
			(xy 77.61479 -308.906057) (xy 77.663009 -308.896213) (xy 77.712184 -308.894232) (xy 77.761039 -308.900164)
			(xy 77.80831 -308.913856) (xy 77.852772 -308.934954) (xy 77.893275 -308.96291) (xy 77.928768 -308.997002)
			(xy 77.958333 -309.036346) (xy 77.981204 -309.079923) (xy 77.996788 -309.126604) (xy 78.004683 -309.175181)
			(xy 78.005178 -309.199788) (xy 78.344026 -309.199788) (xy 78.347986 -309.150734) (xy 78.359763 -309.10295)
			(xy 78.379054 -309.057674) (xy 78.405357 -309.016078) (xy 78.437992 -308.979241) (xy 78.476113 -308.948116)
			(xy 78.518734 -308.923509) (xy 78.56475 -308.906057) (xy 78.612969 -308.896213) (xy 78.662144 -308.894232)
			(xy 78.710999 -308.900164) (xy 78.75827 -308.913856) (xy 78.802732 -308.934954) (xy 78.843235 -308.96291)
			(xy 78.878728 -308.997002) (xy 78.908293 -309.036346) (xy 78.931164 -309.079923) (xy 78.946748 -309.126604)
			(xy 78.954643 -309.175181) (xy 78.955138 -309.199788) (xy 79.293986 -309.199788) (xy 79.297946 -309.150734)
			(xy 79.309723 -309.10295) (xy 79.329014 -309.057674) (xy 79.355317 -309.016078) (xy 79.387952 -308.979241)
			(xy 79.426073 -308.948116) (xy 79.468694 -308.923509) (xy 79.51471 -308.906057) (xy 79.562929 -308.896213)
			(xy 79.612104 -308.894232) (xy 79.660959 -308.900164) (xy 79.70823 -308.913856) (xy 79.752692 -308.934954)
			(xy 79.793195 -308.96291) (xy 79.828688 -308.997002) (xy 79.858253 -309.036346) (xy 79.881124 -309.079923)
			(xy 79.896708 -309.126604) (xy 79.904603 -309.175181) (xy 79.905098 -309.199788) (xy 80.243946 -309.199788)
			(xy 80.247906 -309.150734) (xy 80.259683 -309.10295) (xy 80.278974 -309.057674) (xy 80.305277 -309.016078)
			(xy 80.337912 -308.979241) (xy 80.376033 -308.948116) (xy 80.418654 -308.923509) (xy 80.46467 -308.906057)
			(xy 80.512889 -308.896213) (xy 80.562064 -308.894232) (xy 80.610919 -308.900164) (xy 80.65819 -308.913856)
			(xy 80.702652 -308.934954) (xy 80.743155 -308.96291) (xy 80.778648 -308.997002) (xy 80.808213 -309.036346)
			(xy 80.831084 -309.079923) (xy 80.846668 -309.126604) (xy 80.854563 -309.175181) (xy 80.855058 -309.199788)
			(xy 81.19416 -309.199788) (xy 81.19812 -309.150734) (xy 81.209897 -309.10295) (xy 81.229188 -309.057674)
			(xy 81.255491 -309.016078) (xy 81.288126 -308.979241) (xy 81.326247 -308.948116) (xy 81.368868 -308.923509)
			(xy 81.414884 -308.906057) (xy 81.463103 -308.896213) (xy 81.512278 -308.894232) (xy 81.561133 -308.900164)
			(xy 81.608404 -308.913856) (xy 81.652866 -308.934954) (xy 81.693369 -308.96291) (xy 81.728862 -308.997002)
			(xy 81.758427 -309.036346) (xy 81.781298 -309.079923) (xy 81.796882 -309.126604) (xy 81.804777 -309.175181)
			(xy 81.805272 -309.199788) (xy 82.14412 -309.199788) (xy 82.14808 -309.150734) (xy 82.159857 -309.10295)
			(xy 82.179148 -309.057674) (xy 82.205451 -309.016078) (xy 82.238086 -308.979241) (xy 82.276207 -308.948116)
			(xy 82.318828 -308.923509) (xy 82.364844 -308.906057) (xy 82.413063 -308.896213) (xy 82.462238 -308.894232)
			(xy 82.511093 -308.900164) (xy 82.558364 -308.913856) (xy 82.602826 -308.934954) (xy 82.643329 -308.96291)
			(xy 82.678822 -308.997002) (xy 82.708387 -309.036346) (xy 82.731258 -309.079923) (xy 82.746842 -309.126604)
			(xy 82.754737 -309.175181) (xy 82.754752 -309.175912) (xy 88.334086 -309.175912) (xy 88.338157 -309.12029)
			(xy 88.350283 -309.065853) (xy 88.370206 -309.013762) (xy 88.397502 -308.965127) (xy 88.431588 -308.920984)
			(xy 88.471737 -308.882275) (xy 88.517095 -308.849824) (xy 88.566695 -308.824323) (xy 88.619479 -308.806316)
			(xy 88.674322 -308.796186) (xy 88.730056 -308.794149) (xy 88.785493 -308.800249) (xy 88.83945 -308.814355)
			(xy 88.890779 -308.836167) (xy 88.938385 -308.865221) (xy 88.981253 -308.900896) (xy 89.01847 -308.942433)
			(xy 89.049243 -308.988946) (xy 89.072915 -309.039443) (xy 89.088983 -309.09285) (xy 89.097103 -309.148026)
			(xy 89.097612 -309.175912) (xy 89.097103 -309.203798) (xy 89.088983 -309.258974) (xy 89.072915 -309.312381)
			(xy 89.049243 -309.362878) (xy 89.01847 -309.409391) (xy 88.981253 -309.450928) (xy 88.938385 -309.486603)
			(xy 88.890779 -309.515657) (xy 88.83945 -309.537469) (xy 88.785493 -309.551575) (xy 88.730056 -309.557675)
			(xy 88.674322 -309.555638) (xy 88.619479 -309.545508) (xy 88.566695 -309.527501) (xy 88.517095 -309.502)
			(xy 88.471737 -309.469549) (xy 88.431588 -309.43084) (xy 88.397502 -309.386697) (xy 88.370206 -309.338062)
			(xy 88.350283 -309.285971) (xy 88.338157 -309.231534) (xy 88.334086 -309.175912) (xy 82.754752 -309.175912)
			(xy 82.755232 -309.199788) (xy 82.754737 -309.224395) (xy 82.746842 -309.272972) (xy 82.731258 -309.319653)
			(xy 82.708387 -309.36323) (xy 82.678822 -309.402574) (xy 82.643329 -309.436666) (xy 82.602826 -309.464622)
			(xy 82.558364 -309.48572) (xy 82.511093 -309.499412) (xy 82.462238 -309.505344) (xy 82.413063 -309.503363)
			(xy 82.364844 -309.493519) (xy 82.318828 -309.476067) (xy 82.276207 -309.45146) (xy 82.238086 -309.420335)
			(xy 82.205451 -309.383498) (xy 82.179148 -309.341902) (xy 82.159857 -309.296626) (xy 82.14808 -309.248842)
			(xy 82.14412 -309.199788) (xy 81.805272 -309.199788) (xy 81.804777 -309.224395) (xy 81.796882 -309.272972)
			(xy 81.781298 -309.319653) (xy 81.758427 -309.36323) (xy 81.728862 -309.402574) (xy 81.693369 -309.436666)
			(xy 81.652866 -309.464622) (xy 81.608404 -309.48572) (xy 81.561133 -309.499412) (xy 81.512278 -309.505344)
			(xy 81.463103 -309.503363) (xy 81.414884 -309.493519) (xy 81.368868 -309.476067) (xy 81.326247 -309.45146)
			(xy 81.288126 -309.420335) (xy 81.255491 -309.383498) (xy 81.229188 -309.341902) (xy 81.209897 -309.296626)
			(xy 81.19812 -309.248842) (xy 81.19416 -309.199788) (xy 80.855058 -309.199788) (xy 80.854563 -309.224395)
			(xy 80.846668 -309.272972) (xy 80.831084 -309.319653) (xy 80.808213 -309.36323) (xy 80.778648 -309.402574)
			(xy 80.743155 -309.436666) (xy 80.702652 -309.464622) (xy 80.65819 -309.48572) (xy 80.610919 -309.499412)
			(xy 80.562064 -309.505344) (xy 80.512889 -309.503363) (xy 80.46467 -309.493519) (xy 80.418654 -309.476067)
			(xy 80.376033 -309.45146) (xy 80.337912 -309.420335) (xy 80.305277 -309.383498) (xy 80.278974 -309.341902)
			(xy 80.259683 -309.296626) (xy 80.247906 -309.248842) (xy 80.243946 -309.199788) (xy 79.905098 -309.199788)
			(xy 79.904603 -309.224395) (xy 79.896708 -309.272972) (xy 79.881124 -309.319653) (xy 79.858253 -309.36323)
			(xy 79.828688 -309.402574) (xy 79.793195 -309.436666) (xy 79.752692 -309.464622) (xy 79.70823 -309.48572)
			(xy 79.660959 -309.499412) (xy 79.612104 -309.505344) (xy 79.562929 -309.503363) (xy 79.51471 -309.493519)
			(xy 79.468694 -309.476067) (xy 79.426073 -309.45146) (xy 79.387952 -309.420335) (xy 79.355317 -309.383498)
			(xy 79.329014 -309.341902) (xy 79.309723 -309.296626) (xy 79.297946 -309.248842) (xy 79.293986 -309.199788)
			(xy 78.955138 -309.199788) (xy 78.954643 -309.224395) (xy 78.946748 -309.272972) (xy 78.931164 -309.319653)
			(xy 78.908293 -309.36323) (xy 78.878728 -309.402574) (xy 78.843235 -309.436666) (xy 78.802732 -309.464622)
			(xy 78.75827 -309.48572) (xy 78.710999 -309.499412) (xy 78.662144 -309.505344) (xy 78.612969 -309.503363)
			(xy 78.56475 -309.493519) (xy 78.518734 -309.476067) (xy 78.476113 -309.45146) (xy 78.437992 -309.420335)
			(xy 78.405357 -309.383498) (xy 78.379054 -309.341902) (xy 78.359763 -309.296626) (xy 78.347986 -309.248842)
			(xy 78.344026 -309.199788) (xy 78.005178 -309.199788) (xy 78.004683 -309.224395) (xy 77.996788 -309.272972)
			(xy 77.981204 -309.319653) (xy 77.958333 -309.36323) (xy 77.928768 -309.402574) (xy 77.893275 -309.436666)
			(xy 77.852772 -309.464622) (xy 77.80831 -309.48572) (xy 77.761039 -309.499412) (xy 77.712184 -309.505344)
			(xy 77.663009 -309.503363) (xy 77.61479 -309.493519) (xy 77.568774 -309.476067) (xy 77.526153 -309.45146)
			(xy 77.488032 -309.420335) (xy 77.455397 -309.383498) (xy 77.429094 -309.341902) (xy 77.409803 -309.296626)
			(xy 77.398026 -309.248842) (xy 77.394066 -309.199788) (xy 77.055218 -309.199788) (xy 77.054723 -309.224395)
			(xy 77.046828 -309.272972) (xy 77.031244 -309.319653) (xy 77.008373 -309.36323) (xy 76.978808 -309.402574)
			(xy 76.943315 -309.436666) (xy 76.902812 -309.464622) (xy 76.85835 -309.48572) (xy 76.811079 -309.499412)
			(xy 76.762224 -309.505344) (xy 76.713049 -309.503363) (xy 76.66483 -309.493519) (xy 76.618814 -309.476067)
			(xy 76.576193 -309.45146) (xy 76.538072 -309.420335) (xy 76.505437 -309.383498) (xy 76.479134 -309.341902)
			(xy 76.459843 -309.296626) (xy 76.448066 -309.248842) (xy 76.444106 -309.199788) (xy 76.105258 -309.199788)
			(xy 76.104763 -309.224395) (xy 76.096868 -309.272972) (xy 76.081284 -309.319653) (xy 76.058413 -309.36323)
			(xy 76.028848 -309.402574) (xy 75.993355 -309.436666) (xy 75.952852 -309.464622) (xy 75.90839 -309.48572)
			(xy 75.861119 -309.499412) (xy 75.812264 -309.505344) (xy 75.763089 -309.503363) (xy 75.71487 -309.493519)
			(xy 75.668854 -309.476067) (xy 75.626233 -309.45146) (xy 75.588112 -309.420335) (xy 75.555477 -309.383498)
			(xy 75.529174 -309.341902) (xy 75.509883 -309.296626) (xy 75.498106 -309.248842) (xy 75.494146 -309.199788)
			(xy 75.155298 -309.199788) (xy 75.154803 -309.224395) (xy 75.146908 -309.272972) (xy 75.131324 -309.319653)
			(xy 75.108453 -309.36323) (xy 75.078888 -309.402574) (xy 75.043395 -309.436666) (xy 75.002892 -309.464622)
			(xy 74.95843 -309.48572) (xy 74.911159 -309.499412) (xy 74.862304 -309.505344) (xy 74.813129 -309.503363)
			(xy 74.76491 -309.493519) (xy 74.718894 -309.476067) (xy 74.676273 -309.45146) (xy 74.638152 -309.420335)
			(xy 74.605517 -309.383498) (xy 74.579214 -309.341902) (xy 74.559923 -309.296626) (xy 74.548146 -309.248842)
			(xy 74.544186 -309.199788) (xy 74.205092 -309.199788) (xy 74.205542 -309.208102) (xy 74.200171 -309.257457)
			(xy 74.186886 -309.305293) (xy 74.166037 -309.350349) (xy 74.138174 -309.391438) (xy 74.10403 -309.427479)
			(xy 74.064505 -309.45752) (xy 74.02064 -309.480771) (xy 73.973592 -309.49662) (xy 73.924599 -309.504648)
			(xy 73.899776 -309.505096) (xy 73.885657 -309.504897) (xy 73.857545 -309.502228) (xy 73.843642 -309.499762)
			(xy 73.831196 -309.497476) (xy 73.80732 -309.504842) (xy 73.72985 -309.582312) (xy 73.722484 -309.606188)
			(xy 73.72477 -309.618634) (xy 73.727236 -309.632473) (xy 73.729904 -309.660458) (xy 73.730104 -309.674514)
			(xy 73.730104 -309.675022) (xy 73.729888 -309.689014) (xy 73.727218 -309.716871) (xy 73.72477 -309.730648)
			(xy 73.722484 -309.743094) (xy 73.729596 -309.766716) (xy 73.79843 -309.835804) (xy 73.807671 -309.843946)
			(xy 73.831157 -309.851231) (xy 73.843388 -309.849774) (xy 73.843642 -309.849774) (xy 73.857544 -309.847299)
			(xy 73.885657 -309.844631) (xy 73.899776 -309.84444) (xy 73.923769 -309.844884) (xy 73.971165 -309.852388)
			(xy 74.016802 -309.867216) (xy 74.059558 -309.889) (xy 74.098379 -309.917206) (xy 74.132309 -309.951139)
			(xy 74.160512 -309.989962) (xy 74.182294 -310.03272) (xy 74.197117 -310.078359) (xy 74.204617 -310.125755)
			(xy 74.205084 -310.149748) (xy 74.205084 -310.150256) (xy 74.204513 -310.176311) (xy 74.195573 -310.227649)
			(xy 74.187304 -310.252364) (xy 74.184408 -310.261656) (xy 74.185094 -310.281091) (xy 74.192977 -310.298869)
			(xy 74.206919 -310.312426) (xy 74.22491 -310.319808) (xy 74.244357 -310.31995) (xy 74.253598 -310.31688)
			(xy 74.277728 -310.308498) (xy 74.302267 -310.301441) (xy 74.352795 -310.2941) (xy 74.403852 -310.294614)
			(xy 74.429112 -310.298338) (xy 74.44105 -310.30037) (xy 74.463656 -310.293512) (xy 74.54011 -310.220614)
			(xy 74.548238 -310.198262) (xy 74.546714 -310.186324) (xy 74.545718 -310.177213) (xy 74.544699 -310.158913)
			(xy 74.544682 -310.149748) (xy 74.545164 -310.124925) (xy 74.553188 -310.075933) (xy 74.569033 -310.028884)
			(xy 74.592282 -309.985018) (xy 74.622321 -309.945492) (xy 74.658359 -309.911347) (xy 74.699446 -309.883481)
			(xy 74.744501 -309.862631) (xy 74.792335 -309.849344) (xy 74.841689 -309.843972) (xy 74.891262 -309.846655)
			(xy 74.939747 -309.857323) (xy 74.985868 -309.875695) (xy 75.028409 -309.901287) (xy 75.066249 -309.933424)
			(xy 75.098391 -309.97126) (xy 75.123988 -310.013798) (xy 75.142366 -310.059916) (xy 75.15304 -310.108401)
			(xy 75.155283 -310.149748) (xy 75.494146 -310.149748) (xy 75.498106 -310.100694) (xy 75.509883 -310.05291)
			(xy 75.529174 -310.007634) (xy 75.555477 -309.966038) (xy 75.588112 -309.929201) (xy 75.626233 -309.898076)
			(xy 75.668854 -309.873469) (xy 75.71487 -309.856017) (xy 75.763089 -309.846173) (xy 75.812264 -309.844192)
			(xy 75.861119 -309.850124) (xy 75.90839 -309.863816) (xy 75.952852 -309.884914) (xy 75.993355 -309.91287)
			(xy 76.028848 -309.946962) (xy 76.058413 -309.986306) (xy 76.081284 -310.029883) (xy 76.096868 -310.076564)
			(xy 76.104763 -310.125141) (xy 76.105258 -310.149748) (xy 76.444106 -310.149748) (xy 76.448066 -310.100694)
			(xy 76.459843 -310.05291) (xy 76.479134 -310.007634) (xy 76.505437 -309.966038) (xy 76.538072 -309.929201)
			(xy 76.576193 -309.898076) (xy 76.618814 -309.873469) (xy 76.66483 -309.856017) (xy 76.713049 -309.846173)
			(xy 76.762224 -309.844192) (xy 76.811079 -309.850124) (xy 76.85835 -309.863816) (xy 76.902812 -309.884914)
			(xy 76.943315 -309.91287) (xy 76.978808 -309.946962) (xy 77.008373 -309.986306) (xy 77.031244 -310.029883)
			(xy 77.046828 -310.076564) (xy 77.054723 -310.125141) (xy 77.055218 -310.149748) (xy 77.394066 -310.149748)
			(xy 77.398026 -310.100694) (xy 77.409803 -310.05291) (xy 77.429094 -310.007634) (xy 77.455397 -309.966038)
			(xy 77.488032 -309.929201) (xy 77.526153 -309.898076) (xy 77.568774 -309.873469) (xy 77.61479 -309.856017)
			(xy 77.663009 -309.846173) (xy 77.712184 -309.844192) (xy 77.761039 -309.850124) (xy 77.80831 -309.863816)
			(xy 77.852772 -309.884914) (xy 77.893275 -309.91287) (xy 77.928768 -309.946962) (xy 77.958333 -309.986306)
			(xy 77.981204 -310.029883) (xy 77.996788 -310.076564) (xy 78.004683 -310.125141) (xy 78.005178 -310.149748)
			(xy 78.344026 -310.149748) (xy 78.347986 -310.100694) (xy 78.359763 -310.05291) (xy 78.379054 -310.007634)
			(xy 78.405357 -309.966038) (xy 78.437992 -309.929201) (xy 78.476113 -309.898076) (xy 78.518734 -309.873469)
			(xy 78.56475 -309.856017) (xy 78.612969 -309.846173) (xy 78.662144 -309.844192) (xy 78.710999 -309.850124)
			(xy 78.75827 -309.863816) (xy 78.802732 -309.884914) (xy 78.843235 -309.91287) (xy 78.878728 -309.946962)
			(xy 78.908293 -309.986306) (xy 78.931164 -310.029883) (xy 78.946748 -310.076564) (xy 78.954643 -310.125141)
			(xy 78.955138 -310.149748) (xy 79.293986 -310.149748) (xy 79.297946 -310.100694) (xy 79.309723 -310.05291)
			(xy 79.329014 -310.007634) (xy 79.355317 -309.966038) (xy 79.387952 -309.929201) (xy 79.426073 -309.898076)
			(xy 79.468694 -309.873469) (xy 79.51471 -309.856017) (xy 79.562929 -309.846173) (xy 79.612104 -309.844192)
			(xy 79.660959 -309.850124) (xy 79.70823 -309.863816) (xy 79.752692 -309.884914) (xy 79.793195 -309.91287)
			(xy 79.828688 -309.946962) (xy 79.858253 -309.986306) (xy 79.881124 -310.029883) (xy 79.896708 -310.076564)
			(xy 79.904603 -310.125141) (xy 79.905098 -310.149748) (xy 80.243946 -310.149748) (xy 80.247906 -310.100694)
			(xy 80.259683 -310.05291) (xy 80.278974 -310.007634) (xy 80.305277 -309.966038) (xy 80.337912 -309.929201)
			(xy 80.376033 -309.898076) (xy 80.418654 -309.873469) (xy 80.46467 -309.856017) (xy 80.512889 -309.846173)
			(xy 80.562064 -309.844192) (xy 80.610919 -309.850124) (xy 80.65819 -309.863816) (xy 80.702652 -309.884914)
			(xy 80.743155 -309.91287) (xy 80.778648 -309.946962) (xy 80.808213 -309.986306) (xy 80.831084 -310.029883)
			(xy 80.846668 -310.076564) (xy 80.854563 -310.125141) (xy 80.855058 -310.149748) (xy 81.19416 -310.149748)
			(xy 81.19812 -310.100694) (xy 81.209897 -310.05291) (xy 81.229188 -310.007634) (xy 81.255491 -309.966038)
			(xy 81.288126 -309.929201) (xy 81.326247 -309.898076) (xy 81.368868 -309.873469) (xy 81.414884 -309.856017)
			(xy 81.463103 -309.846173) (xy 81.512278 -309.844192) (xy 81.561133 -309.850124) (xy 81.608404 -309.863816)
			(xy 81.652866 -309.884914) (xy 81.693369 -309.91287) (xy 81.728862 -309.946962) (xy 81.758427 -309.986306)
			(xy 81.781298 -310.029883) (xy 81.796882 -310.076564) (xy 81.804777 -310.125141) (xy 81.805272 -310.149748)
			(xy 82.14412 -310.149748) (xy 82.14808 -310.100694) (xy 82.159857 -310.05291) (xy 82.179148 -310.007634)
			(xy 82.205451 -309.966038) (xy 82.238086 -309.929201) (xy 82.276207 -309.898076) (xy 82.318828 -309.873469)
			(xy 82.364844 -309.856017) (xy 82.413063 -309.846173) (xy 82.462238 -309.844192) (xy 82.511093 -309.850124)
			(xy 82.558364 -309.863816) (xy 82.602826 -309.884914) (xy 82.643329 -309.91287) (xy 82.678822 -309.946962)
			(xy 82.708387 -309.986306) (xy 82.731258 -310.029883) (xy 82.746842 -310.076564) (xy 82.754737 -310.125141)
			(xy 82.755232 -310.149748) (xy 83.094334 -310.149748) (xy 83.098294 -310.100694) (xy 83.110071 -310.05291)
			(xy 83.129362 -310.007634) (xy 83.155665 -309.966038) (xy 83.1883 -309.929201) (xy 83.226421 -309.898076)
			(xy 83.269042 -309.873469) (xy 83.315058 -309.856017) (xy 83.363277 -309.846173) (xy 83.412452 -309.844192)
			(xy 83.461307 -309.850124) (xy 83.472376 -309.85333) (xy 89.010742 -309.85333) (xy 89.014813 -309.797708)
			(xy 89.026939 -309.743271) (xy 89.046862 -309.69118) (xy 89.074158 -309.642545) (xy 89.108244 -309.598402)
			(xy 89.148393 -309.559693) (xy 89.193751 -309.527242) (xy 89.243351 -309.501741) (xy 89.296135 -309.483734)
			(xy 89.350978 -309.473604) (xy 89.406712 -309.471567) (xy 89.462149 -309.477667) (xy 89.516106 -309.491773)
			(xy 89.567435 -309.513585) (xy 89.615041 -309.542639) (xy 89.657909 -309.578314) (xy 89.68698 -309.61076)
			(xy 93.557088 -309.61076) (xy 93.561159 -309.555138) (xy 93.573285 -309.500701) (xy 93.593208 -309.44861)
			(xy 93.620504 -309.399975) (xy 93.65459 -309.355832) (xy 93.694739 -309.317123) (xy 93.740097 -309.284672)
			(xy 93.789697 -309.259171) (xy 93.842481 -309.241164) (xy 93.897324 -309.231034) (xy 93.953058 -309.228997)
			(xy 94.008495 -309.235097) (xy 94.062452 -309.249203) (xy 94.113781 -309.271015) (xy 94.161387 -309.300069)
			(xy 94.204255 -309.335744) (xy 94.241472 -309.377281) (xy 94.272245 -309.423794) (xy 94.295917 -309.474291)
			(xy 94.311985 -309.527698) (xy 94.320105 -309.582874) (xy 94.320614 -309.61076) (xy 94.320105 -309.638646)
			(xy 94.311985 -309.693822) (xy 94.295917 -309.747229) (xy 94.272245 -309.797726) (xy 94.241472 -309.844239)
			(xy 94.204255 -309.885776) (xy 94.161387 -309.921451) (xy 94.113781 -309.950505) (xy 94.062452 -309.972317)
			(xy 94.008495 -309.986423) (xy 93.953058 -309.992523) (xy 93.897324 -309.990486) (xy 93.842481 -309.980356)
			(xy 93.789697 -309.962349) (xy 93.740097 -309.936848) (xy 93.694739 -309.904397) (xy 93.65459 -309.865688)
			(xy 93.620504 -309.821545) (xy 93.593208 -309.77291) (xy 93.573285 -309.720819) (xy 93.561159 -309.666382)
			(xy 93.557088 -309.61076) (xy 89.68698 -309.61076) (xy 89.695126 -309.619851) (xy 89.725899 -309.666364)
			(xy 89.749571 -309.716861) (xy 89.765639 -309.770268) (xy 89.773759 -309.825444) (xy 89.774268 -309.85333)
			(xy 89.773759 -309.881216) (xy 89.765639 -309.936392) (xy 89.749571 -309.989799) (xy 89.725899 -310.040296)
			(xy 89.695126 -310.086809) (xy 89.657909 -310.128346) (xy 89.615041 -310.164021) (xy 89.567435 -310.193075)
			(xy 89.516106 -310.214887) (xy 89.462149 -310.228993) (xy 89.406712 -310.235093) (xy 89.350978 -310.233056)
			(xy 89.296135 -310.222926) (xy 89.243351 -310.204919) (xy 89.193751 -310.179418) (xy 89.148393 -310.146967)
			(xy 89.108244 -310.108258) (xy 89.074158 -310.064115) (xy 89.046862 -310.01548) (xy 89.026939 -309.963389)
			(xy 89.014813 -309.908952) (xy 89.010742 -309.85333) (xy 83.472376 -309.85333) (xy 83.508578 -309.863816)
			(xy 83.55304 -309.884914) (xy 83.593543 -309.91287) (xy 83.629036 -309.946962) (xy 83.658601 -309.986306)
			(xy 83.681472 -310.029883) (xy 83.697056 -310.076564) (xy 83.704951 -310.125141) (xy 83.705446 -310.149748)
			(xy 83.704951 -310.174355) (xy 83.697056 -310.222932) (xy 83.681472 -310.269613) (xy 83.658601 -310.31319)
			(xy 83.629036 -310.352534) (xy 83.593543 -310.386626) (xy 83.55304 -310.414582) (xy 83.508578 -310.43568)
			(xy 83.461307 -310.449372) (xy 83.412452 -310.455304) (xy 83.363277 -310.453323) (xy 83.315058 -310.443479)
			(xy 83.269042 -310.426027) (xy 83.226421 -310.40142) (xy 83.1883 -310.370295) (xy 83.155665 -310.333458)
			(xy 83.129362 -310.291862) (xy 83.110071 -310.246586) (xy 83.098294 -310.198802) (xy 83.094334 -310.149748)
			(xy 82.755232 -310.149748) (xy 82.754737 -310.174355) (xy 82.746842 -310.222932) (xy 82.731258 -310.269613)
			(xy 82.708387 -310.31319) (xy 82.678822 -310.352534) (xy 82.643329 -310.386626) (xy 82.602826 -310.414582)
			(xy 82.558364 -310.43568) (xy 82.511093 -310.449372) (xy 82.462238 -310.455304) (xy 82.413063 -310.453323)
			(xy 82.364844 -310.443479) (xy 82.318828 -310.426027) (xy 82.276207 -310.40142) (xy 82.238086 -310.370295)
			(xy 82.205451 -310.333458) (xy 82.179148 -310.291862) (xy 82.159857 -310.246586) (xy 82.14808 -310.198802)
			(xy 82.14412 -310.149748) (xy 81.805272 -310.149748) (xy 81.804777 -310.174355) (xy 81.796882 -310.222932)
			(xy 81.781298 -310.269613) (xy 81.758427 -310.31319) (xy 81.728862 -310.352534) (xy 81.693369 -310.386626)
			(xy 81.652866 -310.414582) (xy 81.608404 -310.43568) (xy 81.561133 -310.449372) (xy 81.512278 -310.455304)
			(xy 81.463103 -310.453323) (xy 81.414884 -310.443479) (xy 81.368868 -310.426027) (xy 81.326247 -310.40142)
			(xy 81.288126 -310.370295) (xy 81.255491 -310.333458) (xy 81.229188 -310.291862) (xy 81.209897 -310.246586)
			(xy 81.19812 -310.198802) (xy 81.19416 -310.149748) (xy 80.855058 -310.149748) (xy 80.854563 -310.174355)
			(xy 80.846668 -310.222932) (xy 80.831084 -310.269613) (xy 80.808213 -310.31319) (xy 80.778648 -310.352534)
			(xy 80.743155 -310.386626) (xy 80.702652 -310.414582) (xy 80.65819 -310.43568) (xy 80.610919 -310.449372)
			(xy 80.562064 -310.455304) (xy 80.512889 -310.453323) (xy 80.46467 -310.443479) (xy 80.418654 -310.426027)
			(xy 80.376033 -310.40142) (xy 80.337912 -310.370295) (xy 80.305277 -310.333458) (xy 80.278974 -310.291862)
			(xy 80.259683 -310.246586) (xy 80.247906 -310.198802) (xy 80.243946 -310.149748) (xy 79.905098 -310.149748)
			(xy 79.904603 -310.174355) (xy 79.896708 -310.222932) (xy 79.881124 -310.269613) (xy 79.858253 -310.31319)
			(xy 79.828688 -310.352534) (xy 79.793195 -310.386626) (xy 79.752692 -310.414582) (xy 79.70823 -310.43568)
			(xy 79.660959 -310.449372) (xy 79.612104 -310.455304) (xy 79.562929 -310.453323) (xy 79.51471 -310.443479)
			(xy 79.468694 -310.426027) (xy 79.426073 -310.40142) (xy 79.387952 -310.370295) (xy 79.355317 -310.333458)
			(xy 79.329014 -310.291862) (xy 79.309723 -310.246586) (xy 79.297946 -310.198802) (xy 79.293986 -310.149748)
			(xy 78.955138 -310.149748) (xy 78.954643 -310.174355) (xy 78.946748 -310.222932) (xy 78.931164 -310.269613)
			(xy 78.908293 -310.31319) (xy 78.878728 -310.352534) (xy 78.843235 -310.386626) (xy 78.802732 -310.414582)
			(xy 78.75827 -310.43568) (xy 78.710999 -310.449372) (xy 78.662144 -310.455304) (xy 78.612969 -310.453323)
			(xy 78.56475 -310.443479) (xy 78.518734 -310.426027) (xy 78.476113 -310.40142) (xy 78.437992 -310.370295)
			(xy 78.405357 -310.333458) (xy 78.379054 -310.291862) (xy 78.359763 -310.246586) (xy 78.347986 -310.198802)
			(xy 78.344026 -310.149748) (xy 78.005178 -310.149748) (xy 78.004683 -310.174355) (xy 77.996788 -310.222932)
			(xy 77.981204 -310.269613) (xy 77.958333 -310.31319) (xy 77.928768 -310.352534) (xy 77.893275 -310.386626)
			(xy 77.852772 -310.414582) (xy 77.80831 -310.43568) (xy 77.761039 -310.449372) (xy 77.712184 -310.455304)
			(xy 77.663009 -310.453323) (xy 77.61479 -310.443479) (xy 77.568774 -310.426027) (xy 77.526153 -310.40142)
			(xy 77.488032 -310.370295) (xy 77.455397 -310.333458) (xy 77.429094 -310.291862) (xy 77.409803 -310.246586)
			(xy 77.398026 -310.198802) (xy 77.394066 -310.149748) (xy 77.055218 -310.149748) (xy 77.054723 -310.174355)
			(xy 77.046828 -310.222932) (xy 77.031244 -310.269613) (xy 77.008373 -310.31319) (xy 76.978808 -310.352534)
			(xy 76.943315 -310.386626) (xy 76.902812 -310.414582) (xy 76.85835 -310.43568) (xy 76.811079 -310.449372)
			(xy 76.762224 -310.455304) (xy 76.713049 -310.453323) (xy 76.66483 -310.443479) (xy 76.618814 -310.426027)
			(xy 76.576193 -310.40142) (xy 76.538072 -310.370295) (xy 76.505437 -310.333458) (xy 76.479134 -310.291862)
			(xy 76.459843 -310.246586) (xy 76.448066 -310.198802) (xy 76.444106 -310.149748) (xy 76.105258 -310.149748)
			(xy 76.104763 -310.174355) (xy 76.096868 -310.222932) (xy 76.081284 -310.269613) (xy 76.058413 -310.31319)
			(xy 76.028848 -310.352534) (xy 75.993355 -310.386626) (xy 75.952852 -310.414582) (xy 75.90839 -310.43568)
			(xy 75.861119 -310.449372) (xy 75.812264 -310.455304) (xy 75.763089 -310.453323) (xy 75.71487 -310.443479)
			(xy 75.668854 -310.426027) (xy 75.626233 -310.40142) (xy 75.588112 -310.370295) (xy 75.555477 -310.333458)
			(xy 75.529174 -310.291862) (xy 75.509883 -310.246586) (xy 75.498106 -310.198802) (xy 75.494146 -310.149748)
			(xy 75.155283 -310.149748) (xy 75.155729 -310.157973) (xy 75.150363 -310.207327) (xy 75.137082 -310.255163)
			(xy 75.116237 -310.300221) (xy 75.088377 -310.341312) (xy 75.054236 -310.377354) (xy 75.014714 -310.407398)
			(xy 74.970851 -310.430651) (xy 74.923804 -310.446502) (xy 74.874813 -310.454533) (xy 74.84999 -310.455056)
			(xy 74.840826 -310.455023) (xy 74.822525 -310.454008) (xy 74.813414 -310.453024) (xy 74.801476 -310.4515)
			(xy 74.779124 -310.459628) (xy 74.70648 -310.536082) (xy 74.699368 -310.558434) (xy 74.7014 -310.570626)
			(xy 74.703511 -310.583989) (xy 74.705801 -310.610947) (xy 74.705972 -310.624474) (xy 74.705972 -310.68518)
			(xy 89.842592 -310.68518) (xy 89.846663 -310.629558) (xy 89.858789 -310.575121) (xy 89.878712 -310.52303)
			(xy 89.906008 -310.474395) (xy 89.940094 -310.430252) (xy 89.980243 -310.391543) (xy 90.025601 -310.359092)
			(xy 90.075201 -310.333591) (xy 90.127985 -310.315584) (xy 90.182828 -310.305454) (xy 90.238562 -310.303417)
			(xy 90.293999 -310.309517) (xy 90.347956 -310.323623) (xy 90.399285 -310.345435) (xy 90.446891 -310.374489)
			(xy 90.489759 -310.410164) (xy 90.526976 -310.451701) (xy 90.557749 -310.498214) (xy 90.581421 -310.548711)
			(xy 90.597489 -310.602118) (xy 90.605609 -310.657294) (xy 90.606118 -310.68518) (xy 90.605609 -310.713066)
			(xy 90.597489 -310.768242) (xy 90.581421 -310.821649) (xy 90.557749 -310.872146) (xy 90.526976 -310.918659)
			(xy 90.489759 -310.960196) (xy 90.446891 -310.995871) (xy 90.399285 -311.024925) (xy 90.347956 -311.046737)
			(xy 90.293999 -311.060843) (xy 90.238562 -311.066943) (xy 90.182828 -311.064906) (xy 90.127985 -311.054776)
			(xy 90.075201 -311.036769) (xy 90.025601 -311.011268) (xy 89.980243 -310.978817) (xy 89.940094 -310.940108)
			(xy 89.906008 -310.895965) (xy 89.878712 -310.84733) (xy 89.858789 -310.795239) (xy 89.846663 -310.740802)
			(xy 89.842592 -310.68518) (xy 74.705972 -310.68518) (xy 74.705972 -310.69534) (xy 74.706419 -310.706005)
			(xy 74.715083 -310.725494) (xy 74.722736 -310.732932) (xy 74.77887 -310.783732) (xy 74.782927 -310.787153)
			(xy 74.792143 -310.792411) (xy 74.797158 -310.794146) (xy 74.807318 -310.797448) (xy 74.81824 -310.796432)
			(xy 74.84999 -310.794654) (xy 74.875251 -310.795146) (xy 74.925085 -310.80346) (xy 74.972871 -310.819864)
			(xy 75.017305 -310.843909) (xy 75.057175 -310.87494) (xy 75.091394 -310.91211) (xy 75.119028 -310.954406)
			(xy 75.139323 -311.000673) (xy 75.151726 -311.04965) (xy 75.155895 -311.099962) (xy 75.494146 -311.099962)
			(xy 75.498106 -311.050908) (xy 75.509883 -311.003124) (xy 75.529174 -310.957848) (xy 75.555477 -310.916252)
			(xy 75.588112 -310.879415) (xy 75.626233 -310.84829) (xy 75.668854 -310.823683) (xy 75.71487 -310.806231)
			(xy 75.763089 -310.796387) (xy 75.812264 -310.794406) (xy 75.861119 -310.800338) (xy 75.90839 -310.81403)
			(xy 75.952852 -310.835128) (xy 75.993355 -310.863084) (xy 76.028848 -310.897176) (xy 76.058413 -310.93652)
			(xy 76.081284 -310.980097) (xy 76.096868 -311.026778) (xy 76.104763 -311.075355) (xy 76.105258 -311.099962)
			(xy 76.444106 -311.099962) (xy 76.448066 -311.050908) (xy 76.459843 -311.003124) (xy 76.479134 -310.957848)
			(xy 76.505437 -310.916252) (xy 76.538072 -310.879415) (xy 76.576193 -310.84829) (xy 76.618814 -310.823683)
			(xy 76.66483 -310.806231) (xy 76.713049 -310.796387) (xy 76.762224 -310.794406) (xy 76.811079 -310.800338)
			(xy 76.85835 -310.81403) (xy 76.902812 -310.835128) (xy 76.943315 -310.863084) (xy 76.978808 -310.897176)
			(xy 77.008373 -310.93652) (xy 77.031244 -310.980097) (xy 77.046828 -311.026778) (xy 77.054723 -311.075355)
			(xy 77.055218 -311.099962) (xy 77.394066 -311.099962) (xy 77.398026 -311.050908) (xy 77.409803 -311.003124)
			(xy 77.429094 -310.957848) (xy 77.455397 -310.916252) (xy 77.488032 -310.879415) (xy 77.526153 -310.84829)
			(xy 77.568774 -310.823683) (xy 77.61479 -310.806231) (xy 77.663009 -310.796387) (xy 77.712184 -310.794406)
			(xy 77.761039 -310.800338) (xy 77.80831 -310.81403) (xy 77.852772 -310.835128) (xy 77.893275 -310.863084)
			(xy 77.928768 -310.897176) (xy 77.958333 -310.93652) (xy 77.981204 -310.980097) (xy 77.996788 -311.026778)
			(xy 78.004683 -311.075355) (xy 78.005178 -311.099962) (xy 78.344026 -311.099962) (xy 78.347986 -311.050908)
			(xy 78.359763 -311.003124) (xy 78.379054 -310.957848) (xy 78.405357 -310.916252) (xy 78.437992 -310.879415)
			(xy 78.476113 -310.84829) (xy 78.518734 -310.823683) (xy 78.56475 -310.806231) (xy 78.612969 -310.796387)
			(xy 78.662144 -310.794406) (xy 78.710999 -310.800338) (xy 78.75827 -310.81403) (xy 78.802732 -310.835128)
			(xy 78.843235 -310.863084) (xy 78.878728 -310.897176) (xy 78.908293 -310.93652) (xy 78.931164 -310.980097)
			(xy 78.946748 -311.026778) (xy 78.954643 -311.075355) (xy 78.955138 -311.099962) (xy 79.293986 -311.099962)
			(xy 79.297946 -311.050908) (xy 79.309723 -311.003124) (xy 79.329014 -310.957848) (xy 79.355317 -310.916252)
			(xy 79.387952 -310.879415) (xy 79.426073 -310.84829) (xy 79.468694 -310.823683) (xy 79.51471 -310.806231)
			(xy 79.562929 -310.796387) (xy 79.612104 -310.794406) (xy 79.660959 -310.800338) (xy 79.70823 -310.81403)
			(xy 79.752692 -310.835128) (xy 79.793195 -310.863084) (xy 79.828688 -310.897176) (xy 79.858253 -310.93652)
			(xy 79.881124 -310.980097) (xy 79.896708 -311.026778) (xy 79.904603 -311.075355) (xy 79.905098 -311.099962)
			(xy 80.243946 -311.099962) (xy 80.247906 -311.050908) (xy 80.259683 -311.003124) (xy 80.278974 -310.957848)
			(xy 80.305277 -310.916252) (xy 80.337912 -310.879415) (xy 80.376033 -310.84829) (xy 80.418654 -310.823683)
			(xy 80.46467 -310.806231) (xy 80.512889 -310.796387) (xy 80.562064 -310.794406) (xy 80.610919 -310.800338)
			(xy 80.65819 -310.81403) (xy 80.702652 -310.835128) (xy 80.743155 -310.863084) (xy 80.778648 -310.897176)
			(xy 80.808213 -310.93652) (xy 80.831084 -310.980097) (xy 80.846668 -311.026778) (xy 80.854563 -311.075355)
			(xy 80.855058 -311.099962) (xy 81.19416 -311.099962) (xy 81.19812 -311.050908) (xy 81.209897 -311.003124)
			(xy 81.229188 -310.957848) (xy 81.255491 -310.916252) (xy 81.288126 -310.879415) (xy 81.326247 -310.84829)
			(xy 81.368868 -310.823683) (xy 81.414884 -310.806231) (xy 81.463103 -310.796387) (xy 81.512278 -310.794406)
			(xy 81.561133 -310.800338) (xy 81.608404 -310.81403) (xy 81.652866 -310.835128) (xy 81.693369 -310.863084)
			(xy 81.728862 -310.897176) (xy 81.758427 -310.93652) (xy 81.781298 -310.980097) (xy 81.796882 -311.026778)
			(xy 81.804777 -311.075355) (xy 81.805272 -311.099962) (xy 82.14412 -311.099962) (xy 82.14808 -311.050908)
			(xy 82.159857 -311.003124) (xy 82.179148 -310.957848) (xy 82.205451 -310.916252) (xy 82.238086 -310.879415)
			(xy 82.276207 -310.84829) (xy 82.318828 -310.823683) (xy 82.364844 -310.806231) (xy 82.413063 -310.796387)
			(xy 82.462238 -310.794406) (xy 82.511093 -310.800338) (xy 82.558364 -310.81403) (xy 82.602826 -310.835128)
			(xy 82.643329 -310.863084) (xy 82.678822 -310.897176) (xy 82.708387 -310.93652) (xy 82.731258 -310.980097)
			(xy 82.746842 -311.026778) (xy 82.754737 -311.075355) (xy 82.755232 -311.099962) (xy 82.754737 -311.124569)
			(xy 82.746842 -311.173146) (xy 82.731258 -311.219827) (xy 82.708387 -311.263404) (xy 82.678822 -311.302748)
			(xy 82.643329 -311.33684) (xy 82.602826 -311.364796) (xy 82.568916 -311.380887) (xy 90.566604 -311.380887)
			(xy 90.574356 -311.326928) (xy 90.589708 -311.274622) (xy 90.612348 -311.225033) (xy 90.641815 -311.17917)
			(xy 90.677508 -311.137968) (xy 90.718703 -311.102265) (xy 90.764559 -311.072788) (xy 90.814143 -311.050137)
			(xy 90.866446 -311.034774) (xy 90.920404 -311.02701) (xy 90.974917 -311.027004) (xy 91.028875 -311.034757)
			(xy 91.081182 -311.050109) (xy 91.130771 -311.07275) (xy 91.176633 -311.102217) (xy 91.217835 -311.137911)
			(xy 91.253537 -311.179106) (xy 91.283014 -311.224962) (xy 91.305664 -311.274547) (xy 91.321027 -311.32685)
			(xy 91.32879 -311.380808) (xy 91.329256 -311.408064) (xy 91.329059 -311.425112) (xy 91.326005 -311.459072)
			(xy 91.32316 -311.475882) (xy 91.320874 -311.488328) (xy 91.32824 -311.51195) (xy 91.405202 -311.588912)
			(xy 91.428824 -311.596278) (xy 91.44127 -311.593992) (xy 91.458141 -311.591124) (xy 91.49223 -311.58807)
			(xy 91.509342 -311.587896) (xy 91.536594 -311.588339) (xy 91.590544 -311.596101) (xy 91.64284 -311.611462)
			(xy 91.692417 -311.634108) (xy 91.738268 -311.663579) (xy 91.779458 -311.699275) (xy 91.815149 -311.740469)
			(xy 91.844614 -311.786323) (xy 91.867254 -311.835903) (xy 91.882609 -311.888201) (xy 91.890365 -311.942151)
			(xy 91.89085 -311.969404) (xy 91.889834 -311.99836) (xy 91.888818 -312.009536) (xy 91.896692 -312.030364)
			(xy 91.967558 -312.100722) (xy 91.988386 -312.108088) (xy 91.999816 -312.107072) (xy 92.032328 -312.105802)
			(xy 92.059577 -312.106308) (xy 92.113519 -312.114068) (xy 92.165807 -312.129425) (xy 92.215378 -312.152067)
			(xy 92.261223 -312.181533) (xy 92.302407 -312.217224) (xy 92.338093 -312.258412) (xy 92.367554 -312.30426)
			(xy 92.39019 -312.353833) (xy 92.405541 -312.406124) (xy 92.413295 -312.460067) (xy 92.413293 -312.514564)
			(xy 92.405535 -312.568506) (xy 92.39018 -312.620795) (xy 92.367539 -312.670367) (xy 92.338074 -312.716212)
			(xy 92.302385 -312.757398) (xy 92.261198 -312.793085) (xy 92.215351 -312.822548) (xy 92.165779 -312.845186)
			(xy 92.113489 -312.860539) (xy 92.059546 -312.868294) (xy 92.005049 -312.868294) (xy 91.951106 -312.860538)
			(xy 91.898816 -312.845184) (xy 91.849244 -312.822545) (xy 91.803398 -312.793082) (xy 91.762211 -312.757394)
			(xy 91.726523 -312.716208) (xy 91.697058 -312.670363) (xy 91.674419 -312.62079) (xy 91.659064 -312.568501)
			(xy 91.651307 -312.514559) (xy 91.65082 -312.48731) (xy 91.651836 -312.458354) (xy 91.652852 -312.447178)
			(xy 91.644978 -312.42635) (xy 91.574112 -312.355992) (xy 91.553284 -312.348626) (xy 91.541854 -312.349642)
			(xy 91.509342 -312.350912) (xy 91.48209 -312.350406) (xy 91.428141 -312.342654) (xy 91.375844 -312.327304)
			(xy 91.326265 -312.304667) (xy 91.280412 -312.275203) (xy 91.239218 -312.239514) (xy 91.203524 -312.198325)
			(xy 91.174055 -312.152476) (xy 91.151412 -312.102899) (xy 91.136055 -312.050604) (xy 91.128298 -311.996656)
			(xy 91.127834 -311.969404) (xy 91.12804 -311.952356) (xy 91.131088 -311.918397) (xy 91.13393 -311.901586)
			(xy 91.136216 -311.88914) (xy 91.12885 -311.865518) (xy 91.051888 -311.788556) (xy 91.028266 -311.78119)
			(xy 91.01582 -311.783476) (xy 90.998949 -311.786345) (xy 90.964861 -311.789398) (xy 90.947748 -311.789572)
			(xy 90.920491 -311.789196) (xy 90.866532 -311.781445) (xy 90.814226 -311.766094) (xy 90.764636 -311.743454)
			(xy 90.718773 -311.713988) (xy 90.677571 -311.678294) (xy 90.641867 -311.637101) (xy 90.61239 -311.591245)
			(xy 90.589739 -311.541661) (xy 90.574374 -311.489358) (xy 90.56661 -311.4354) (xy 90.566604 -311.380887)
			(xy 82.568916 -311.380887) (xy 82.558364 -311.385894) (xy 82.511093 -311.399586) (xy 82.462238 -311.405518)
			(xy 82.413063 -311.403537) (xy 82.364844 -311.393693) (xy 82.318828 -311.376241) (xy 82.276207 -311.351634)
			(xy 82.238086 -311.320509) (xy 82.205451 -311.283672) (xy 82.179148 -311.242076) (xy 82.159857 -311.1968)
			(xy 82.14808 -311.149016) (xy 82.14412 -311.099962) (xy 81.805272 -311.099962) (xy 81.804777 -311.124569)
			(xy 81.796882 -311.173146) (xy 81.781298 -311.219827) (xy 81.758427 -311.263404) (xy 81.728862 -311.302748)
			(xy 81.693369 -311.33684) (xy 81.652866 -311.364796) (xy 81.608404 -311.385894) (xy 81.561133 -311.399586)
			(xy 81.512278 -311.405518) (xy 81.463103 -311.403537) (xy 81.414884 -311.393693) (xy 81.368868 -311.376241)
			(xy 81.326247 -311.351634) (xy 81.288126 -311.320509) (xy 81.255491 -311.283672) (xy 81.229188 -311.242076)
			(xy 81.209897 -311.1968) (xy 81.19812 -311.149016) (xy 81.19416 -311.099962) (xy 80.855058 -311.099962)
			(xy 80.854563 -311.124569) (xy 80.846668 -311.173146) (xy 80.831084 -311.219827) (xy 80.808213 -311.263404)
			(xy 80.778648 -311.302748) (xy 80.743155 -311.33684) (xy 80.702652 -311.364796) (xy 80.65819 -311.385894)
			(xy 80.610919 -311.399586) (xy 80.562064 -311.405518) (xy 80.512889 -311.403537) (xy 80.46467 -311.393693)
			(xy 80.418654 -311.376241) (xy 80.376033 -311.351634) (xy 80.337912 -311.320509) (xy 80.305277 -311.283672)
			(xy 80.278974 -311.242076) (xy 80.259683 -311.1968) (xy 80.247906 -311.149016) (xy 80.243946 -311.099962)
			(xy 79.905098 -311.099962) (xy 79.904603 -311.124569) (xy 79.896708 -311.173146) (xy 79.881124 -311.219827)
			(xy 79.858253 -311.263404) (xy 79.828688 -311.302748) (xy 79.793195 -311.33684) (xy 79.752692 -311.364796)
			(xy 79.70823 -311.385894) (xy 79.660959 -311.399586) (xy 79.612104 -311.405518) (xy 79.562929 -311.403537)
			(xy 79.51471 -311.393693) (xy 79.468694 -311.376241) (xy 79.426073 -311.351634) (xy 79.387952 -311.320509)
			(xy 79.355317 -311.283672) (xy 79.329014 -311.242076) (xy 79.309723 -311.1968) (xy 79.297946 -311.149016)
			(xy 79.293986 -311.099962) (xy 78.955138 -311.099962) (xy 78.954643 -311.124569) (xy 78.946748 -311.173146)
			(xy 78.931164 -311.219827) (xy 78.908293 -311.263404) (xy 78.878728 -311.302748) (xy 78.843235 -311.33684)
			(xy 78.802732 -311.364796) (xy 78.75827 -311.385894) (xy 78.710999 -311.399586) (xy 78.662144 -311.405518)
			(xy 78.612969 -311.403537) (xy 78.56475 -311.393693) (xy 78.518734 -311.376241) (xy 78.476113 -311.351634)
			(xy 78.437992 -311.320509) (xy 78.405357 -311.283672) (xy 78.379054 -311.242076) (xy 78.359763 -311.1968)
			(xy 78.347986 -311.149016) (xy 78.344026 -311.099962) (xy 78.005178 -311.099962) (xy 78.004683 -311.124569)
			(xy 77.996788 -311.173146) (xy 77.981204 -311.219827) (xy 77.958333 -311.263404) (xy 77.928768 -311.302748)
			(xy 77.893275 -311.33684) (xy 77.852772 -311.364796) (xy 77.80831 -311.385894) (xy 77.761039 -311.399586)
			(xy 77.712184 -311.405518) (xy 77.663009 -311.403537) (xy 77.61479 -311.393693) (xy 77.568774 -311.376241)
			(xy 77.526153 -311.351634) (xy 77.488032 -311.320509) (xy 77.455397 -311.283672) (xy 77.429094 -311.242076)
			(xy 77.409803 -311.1968) (xy 77.398026 -311.149016) (xy 77.394066 -311.099962) (xy 77.055218 -311.099962)
			(xy 77.054723 -311.124569) (xy 77.046828 -311.173146) (xy 77.031244 -311.219827) (xy 77.008373 -311.263404)
			(xy 76.978808 -311.302748) (xy 76.943315 -311.33684) (xy 76.902812 -311.364796) (xy 76.85835 -311.385894)
			(xy 76.811079 -311.399586) (xy 76.762224 -311.405518) (xy 76.713049 -311.403537) (xy 76.66483 -311.393693)
			(xy 76.618814 -311.376241) (xy 76.576193 -311.351634) (xy 76.538072 -311.320509) (xy 76.505437 -311.283672)
			(xy 76.479134 -311.242076) (xy 76.459843 -311.1968) (xy 76.448066 -311.149016) (xy 76.444106 -311.099962)
			(xy 76.105258 -311.099962) (xy 76.104763 -311.124569) (xy 76.096868 -311.173146) (xy 76.081284 -311.219827)
			(xy 76.058413 -311.263404) (xy 76.028848 -311.302748) (xy 75.993355 -311.33684) (xy 75.952852 -311.364796)
			(xy 75.90839 -311.385894) (xy 75.861119 -311.399586) (xy 75.812264 -311.405518) (xy 75.763089 -311.403537)
			(xy 75.71487 -311.393693) (xy 75.668854 -311.376241) (xy 75.626233 -311.351634) (xy 75.588112 -311.320509)
			(xy 75.555477 -311.283672) (xy 75.529174 -311.242076) (xy 75.509883 -311.1968) (xy 75.498106 -311.149016)
			(xy 75.494146 -311.099962) (xy 75.155895 -311.099962) (xy 75.155898 -311.1) (xy 75.151726 -311.15035)
			(xy 75.139323 -311.199327) (xy 75.119028 -311.245594) (xy 75.091394 -311.28789) (xy 75.057175 -311.32506)
			(xy 75.017305 -311.356091) (xy 74.972871 -311.380136) (xy 74.925085 -311.39654) (xy 74.875251 -311.404854)
			(xy 74.84999 -311.40527) (xy 74.81824 -311.403492) (xy 74.807318 -311.402476) (xy 74.797158 -311.405778)
			(xy 74.792148 -311.407524) (xy 74.782932 -311.412778) (xy 74.77887 -311.416192) (xy 74.722736 -311.466992)
			(xy 74.715226 -311.474536) (xy 74.706564 -311.493956) (xy 74.705972 -311.504584) (xy 74.705972 -311.574688)
			(xy 74.705809 -311.588342) (xy 74.703518 -311.615554) (xy 74.7014 -311.629044) (xy 74.700059 -311.640813)
			(xy 74.706936 -311.663453) (xy 74.714608 -311.672478) (xy 74.770996 -311.731406) (xy 74.778416 -311.738536)
			(xy 74.797294 -311.746678) (xy 74.807572 -311.747154) (xy 74.811128 -311.747154) (xy 74.8208 -311.745971)
			(xy 74.840246 -311.744698) (xy 74.84999 -311.744614) (xy 74.875246 -311.745106) (xy 74.925071 -311.753418)
			(xy 74.972847 -311.769819) (xy 75.017272 -311.793859) (xy 75.057135 -311.824884) (xy 75.091347 -311.862047)
			(xy 75.118975 -311.904334) (xy 75.139266 -311.950593) (xy 75.151667 -311.99956) (xy 75.155838 -312.0499)
			(xy 75.155836 -312.049922) (xy 75.494146 -312.049922) (xy 75.498106 -312.000868) (xy 75.509883 -311.953084)
			(xy 75.529174 -311.907808) (xy 75.555477 -311.866212) (xy 75.588112 -311.829375) (xy 75.626233 -311.79825)
			(xy 75.668854 -311.773643) (xy 75.71487 -311.756191) (xy 75.763089 -311.746347) (xy 75.812264 -311.744366)
			(xy 75.861119 -311.750298) (xy 75.90839 -311.76399) (xy 75.952852 -311.785088) (xy 75.993355 -311.813044)
			(xy 76.028848 -311.847136) (xy 76.058413 -311.88648) (xy 76.081284 -311.930057) (xy 76.096868 -311.976738)
			(xy 76.104763 -312.025315) (xy 76.105258 -312.049922) (xy 76.444106 -312.049922) (xy 76.448066 -312.000868)
			(xy 76.459843 -311.953084) (xy 76.479134 -311.907808) (xy 76.505437 -311.866212) (xy 76.538072 -311.829375)
			(xy 76.576193 -311.79825) (xy 76.618814 -311.773643) (xy 76.66483 -311.756191) (xy 76.713049 -311.746347)
			(xy 76.762224 -311.744366) (xy 76.811079 -311.750298) (xy 76.85835 -311.76399) (xy 76.902812 -311.785088)
			(xy 76.943315 -311.813044) (xy 76.978808 -311.847136) (xy 77.008373 -311.88648) (xy 77.031244 -311.930057)
			(xy 77.046828 -311.976738) (xy 77.054723 -312.025315) (xy 77.055218 -312.049922) (xy 77.394066 -312.049922)
			(xy 77.398026 -312.000868) (xy 77.409803 -311.953084) (xy 77.429094 -311.907808) (xy 77.455397 -311.866212)
			(xy 77.488032 -311.829375) (xy 77.526153 -311.79825) (xy 77.568774 -311.773643) (xy 77.61479 -311.756191)
			(xy 77.663009 -311.746347) (xy 77.712184 -311.744366) (xy 77.761039 -311.750298) (xy 77.80831 -311.76399)
			(xy 77.852772 -311.785088) (xy 77.893275 -311.813044) (xy 77.928768 -311.847136) (xy 77.958333 -311.88648)
			(xy 77.981204 -311.930057) (xy 77.996788 -311.976738) (xy 78.004683 -312.025315) (xy 78.005178 -312.049922)
			(xy 78.344026 -312.049922) (xy 78.347986 -312.000868) (xy 78.359763 -311.953084) (xy 78.379054 -311.907808)
			(xy 78.405357 -311.866212) (xy 78.437992 -311.829375) (xy 78.476113 -311.79825) (xy 78.518734 -311.773643)
			(xy 78.56475 -311.756191) (xy 78.612969 -311.746347) (xy 78.662144 -311.744366) (xy 78.710999 -311.750298)
			(xy 78.75827 -311.76399) (xy 78.802732 -311.785088) (xy 78.843235 -311.813044) (xy 78.878728 -311.847136)
			(xy 78.908293 -311.88648) (xy 78.931164 -311.930057) (xy 78.946748 -311.976738) (xy 78.954643 -312.025315)
			(xy 78.955138 -312.049922) (xy 79.293986 -312.049922) (xy 79.297946 -312.000868) (xy 79.309723 -311.953084)
			(xy 79.329014 -311.907808) (xy 79.355317 -311.866212) (xy 79.387952 -311.829375) (xy 79.426073 -311.79825)
			(xy 79.468694 -311.773643) (xy 79.51471 -311.756191) (xy 79.562929 -311.746347) (xy 79.612104 -311.744366)
			(xy 79.660959 -311.750298) (xy 79.70823 -311.76399) (xy 79.752692 -311.785088) (xy 79.793195 -311.813044)
			(xy 79.828688 -311.847136) (xy 79.858253 -311.88648) (xy 79.881124 -311.930057) (xy 79.896708 -311.976738)
			(xy 79.904603 -312.025315) (xy 79.905098 -312.049922) (xy 80.243946 -312.049922) (xy 80.247906 -312.000868)
			(xy 80.259683 -311.953084) (xy 80.278974 -311.907808) (xy 80.305277 -311.866212) (xy 80.337912 -311.829375)
			(xy 80.376033 -311.79825) (xy 80.418654 -311.773643) (xy 80.46467 -311.756191) (xy 80.512889 -311.746347)
			(xy 80.562064 -311.744366) (xy 80.610919 -311.750298) (xy 80.65819 -311.76399) (xy 80.702652 -311.785088)
			(xy 80.743155 -311.813044) (xy 80.778648 -311.847136) (xy 80.808213 -311.88648) (xy 80.831084 -311.930057)
			(xy 80.846668 -311.976738) (xy 80.854563 -312.025315) (xy 80.855058 -312.049922) (xy 81.19416 -312.049922)
			(xy 81.19812 -312.000868) (xy 81.209897 -311.953084) (xy 81.229188 -311.907808) (xy 81.255491 -311.866212)
			(xy 81.288126 -311.829375) (xy 81.326247 -311.79825) (xy 81.368868 -311.773643) (xy 81.414884 -311.756191)
			(xy 81.463103 -311.746347) (xy 81.512278 -311.744366) (xy 81.561133 -311.750298) (xy 81.608404 -311.76399)
			(xy 81.652866 -311.785088) (xy 81.693369 -311.813044) (xy 81.728862 -311.847136) (xy 81.758427 -311.88648)
			(xy 81.781298 -311.930057) (xy 81.796882 -311.976738) (xy 81.804777 -312.025315) (xy 81.805272 -312.049922)
			(xy 82.14412 -312.049922) (xy 82.14808 -312.000868) (xy 82.159857 -311.953084) (xy 82.179148 -311.907808)
			(xy 82.205451 -311.866212) (xy 82.238086 -311.829375) (xy 82.276207 -311.79825) (xy 82.318828 -311.773643)
			(xy 82.364844 -311.756191) (xy 82.413063 -311.746347) (xy 82.462238 -311.744366) (xy 82.511093 -311.750298)
			(xy 82.558364 -311.76399) (xy 82.602826 -311.785088) (xy 82.643329 -311.813044) (xy 82.678822 -311.847136)
			(xy 82.708387 -311.88648) (xy 82.731258 -311.930057) (xy 82.746842 -311.976738) (xy 82.754737 -312.025315)
			(xy 82.755232 -312.049922) (xy 83.094334 -312.049922) (xy 83.098294 -312.000868) (xy 83.110071 -311.953084)
			(xy 83.129362 -311.907808) (xy 83.155665 -311.866212) (xy 83.1883 -311.829375) (xy 83.226421 -311.79825)
			(xy 83.269042 -311.773643) (xy 83.315058 -311.756191) (xy 83.363277 -311.746347) (xy 83.412452 -311.744366)
			(xy 83.461307 -311.750298) (xy 83.508578 -311.76399) (xy 83.55304 -311.785088) (xy 83.593543 -311.813044)
			(xy 83.629036 -311.847136) (xy 83.658601 -311.88648) (xy 83.681472 -311.930057) (xy 83.697056 -311.976738)
			(xy 83.704951 -312.025315) (xy 83.705446 -312.049922) (xy 83.704951 -312.074529) (xy 83.697056 -312.123106)
			(xy 83.681472 -312.169787) (xy 83.658601 -312.213364) (xy 83.629036 -312.252708) (xy 83.593543 -312.2868)
			(xy 83.55304 -312.314756) (xy 83.508578 -312.335854) (xy 83.461307 -312.349546) (xy 83.412452 -312.355478)
			(xy 83.363277 -312.353497) (xy 83.315058 -312.343653) (xy 83.269042 -312.326201) (xy 83.226421 -312.301594)
			(xy 83.1883 -312.270469) (xy 83.155665 -312.233632) (xy 83.129362 -312.192036) (xy 83.110071 -312.14676)
			(xy 83.098294 -312.098976) (xy 83.094334 -312.049922) (xy 82.755232 -312.049922) (xy 82.754737 -312.074529)
			(xy 82.746842 -312.123106) (xy 82.731258 -312.169787) (xy 82.708387 -312.213364) (xy 82.678822 -312.252708)
			(xy 82.643329 -312.2868) (xy 82.602826 -312.314756) (xy 82.558364 -312.335854) (xy 82.511093 -312.349546)
			(xy 82.462238 -312.355478) (xy 82.413063 -312.353497) (xy 82.364844 -312.343653) (xy 82.318828 -312.326201)
			(xy 82.276207 -312.301594) (xy 82.238086 -312.270469) (xy 82.205451 -312.233632) (xy 82.179148 -312.192036)
			(xy 82.159857 -312.14676) (xy 82.14808 -312.098976) (xy 82.14412 -312.049922) (xy 81.805272 -312.049922)
			(xy 81.804777 -312.074529) (xy 81.796882 -312.123106) (xy 81.781298 -312.169787) (xy 81.758427 -312.213364)
			(xy 81.728862 -312.252708) (xy 81.693369 -312.2868) (xy 81.652866 -312.314756) (xy 81.608404 -312.335854)
			(xy 81.561133 -312.349546) (xy 81.512278 -312.355478) (xy 81.463103 -312.353497) (xy 81.414884 -312.343653)
			(xy 81.368868 -312.326201) (xy 81.326247 -312.301594) (xy 81.288126 -312.270469) (xy 81.255491 -312.233632)
			(xy 81.229188 -312.192036) (xy 81.209897 -312.14676) (xy 81.19812 -312.098976) (xy 81.19416 -312.049922)
			(xy 80.855058 -312.049922) (xy 80.854563 -312.074529) (xy 80.846668 -312.123106) (xy 80.831084 -312.169787)
			(xy 80.808213 -312.213364) (xy 80.778648 -312.252708) (xy 80.743155 -312.2868) (xy 80.702652 -312.314756)
			(xy 80.65819 -312.335854) (xy 80.610919 -312.349546) (xy 80.562064 -312.355478) (xy 80.512889 -312.353497)
			(xy 80.46467 -312.343653) (xy 80.418654 -312.326201) (xy 80.376033 -312.301594) (xy 80.337912 -312.270469)
			(xy 80.305277 -312.233632) (xy 80.278974 -312.192036) (xy 80.259683 -312.14676) (xy 80.247906 -312.098976)
			(xy 80.243946 -312.049922) (xy 79.905098 -312.049922) (xy 79.904603 -312.074529) (xy 79.896708 -312.123106)
			(xy 79.881124 -312.169787) (xy 79.858253 -312.213364) (xy 79.828688 -312.252708) (xy 79.793195 -312.2868)
			(xy 79.752692 -312.314756) (xy 79.70823 -312.335854) (xy 79.660959 -312.349546) (xy 79.612104 -312.355478)
			(xy 79.562929 -312.353497) (xy 79.51471 -312.343653) (xy 79.468694 -312.326201) (xy 79.426073 -312.301594)
			(xy 79.387952 -312.270469) (xy 79.355317 -312.233632) (xy 79.329014 -312.192036) (xy 79.309723 -312.14676)
			(xy 79.297946 -312.098976) (xy 79.293986 -312.049922) (xy 78.955138 -312.049922) (xy 78.954643 -312.074529)
			(xy 78.946748 -312.123106) (xy 78.931164 -312.169787) (xy 78.908293 -312.213364) (xy 78.878728 -312.252708)
			(xy 78.843235 -312.2868) (xy 78.802732 -312.314756) (xy 78.75827 -312.335854) (xy 78.710999 -312.349546)
			(xy 78.662144 -312.355478) (xy 78.612969 -312.353497) (xy 78.56475 -312.343653) (xy 78.518734 -312.326201)
			(xy 78.476113 -312.301594) (xy 78.437992 -312.270469) (xy 78.405357 -312.233632) (xy 78.379054 -312.192036)
			(xy 78.359763 -312.14676) (xy 78.347986 -312.098976) (xy 78.344026 -312.049922) (xy 78.005178 -312.049922)
			(xy 78.004683 -312.074529) (xy 77.996788 -312.123106) (xy 77.981204 -312.169787) (xy 77.958333 -312.213364)
			(xy 77.928768 -312.252708) (xy 77.893275 -312.2868) (xy 77.852772 -312.314756) (xy 77.80831 -312.335854)
			(xy 77.761039 -312.349546) (xy 77.712184 -312.355478) (xy 77.663009 -312.353497) (xy 77.61479 -312.343653)
			(xy 77.568774 -312.326201) (xy 77.526153 -312.301594) (xy 77.488032 -312.270469) (xy 77.455397 -312.233632)
			(xy 77.429094 -312.192036) (xy 77.409803 -312.14676) (xy 77.398026 -312.098976) (xy 77.394066 -312.049922)
			(xy 77.055218 -312.049922) (xy 77.054723 -312.074529) (xy 77.046828 -312.123106) (xy 77.031244 -312.169787)
			(xy 77.008373 -312.213364) (xy 76.978808 -312.252708) (xy 76.943315 -312.2868) (xy 76.902812 -312.314756)
			(xy 76.85835 -312.335854) (xy 76.811079 -312.349546) (xy 76.762224 -312.355478) (xy 76.713049 -312.353497)
			(xy 76.66483 -312.343653) (xy 76.618814 -312.326201) (xy 76.576193 -312.301594) (xy 76.538072 -312.270469)
			(xy 76.505437 -312.233632) (xy 76.479134 -312.192036) (xy 76.459843 -312.14676) (xy 76.448066 -312.098976)
			(xy 76.444106 -312.049922) (xy 76.105258 -312.049922) (xy 76.104763 -312.074529) (xy 76.096868 -312.123106)
			(xy 76.081284 -312.169787) (xy 76.058413 -312.213364) (xy 76.028848 -312.252708) (xy 75.993355 -312.2868)
			(xy 75.952852 -312.314756) (xy 75.90839 -312.335854) (xy 75.861119 -312.349546) (xy 75.812264 -312.355478)
			(xy 75.763089 -312.353497) (xy 75.71487 -312.343653) (xy 75.668854 -312.326201) (xy 75.626233 -312.301594)
			(xy 75.588112 -312.270469) (xy 75.555477 -312.233632) (xy 75.529174 -312.192036) (xy 75.509883 -312.14676)
			(xy 75.498106 -312.098976) (xy 75.494146 -312.049922) (xy 75.155836 -312.049922) (xy 75.151667 -312.10024)
			(xy 75.139266 -312.149207) (xy 75.118975 -312.195466) (xy 75.091347 -312.237753) (xy 75.057135 -312.274916)
			(xy 75.017272 -312.305941) (xy 74.972847 -312.329981) (xy 74.925071 -312.346382) (xy 74.875246 -312.354694)
			(xy 74.84999 -312.35523) (xy 74.835808 -312.355043) (xy 74.807568 -312.352369) (xy 74.793602 -312.349896)
			(xy 74.787507 -312.348898) (xy 74.775178 -312.349547) (xy 74.769218 -312.351166) (xy 74.763335 -312.353193)
			(xy 74.752683 -312.359617) (xy 74.748136 -312.363866) (xy 74.6887 -312.423302) (xy 74.680524 -312.432601)
			(xy 74.673231 -312.456222) (xy 74.67473 -312.468514) (xy 74.677216 -312.482479) (xy 74.679888 -312.510719)
			(xy 74.680064 -312.524902) (xy 74.679877 -312.539084) (xy 74.677204 -312.567324) (xy 74.67473 -312.58129)
			(xy 74.673036 -312.593594) (xy 74.680363 -312.617296) (xy 74.6887 -312.626502) (xy 74.748136 -312.685938)
			(xy 74.752647 -312.690234) (xy 74.76331 -312.696665) (xy 74.769218 -312.698638) (xy 74.77518 -312.700243)
			(xy 74.787506 -312.700886) (xy 74.793602 -312.699908) (xy 74.807567 -312.697422) (xy 74.835807 -312.69475)
			(xy 74.84999 -312.694574) (xy 74.87525 -312.695066) (xy 74.92508 -312.70338) (xy 74.972863 -312.719782)
			(xy 75.017294 -312.743826) (xy 75.057162 -312.774855) (xy 75.091378 -312.812023) (xy 75.11901 -312.854315)
			(xy 75.139304 -312.90058) (xy 75.151706 -312.949553) (xy 75.155877 -312.999882) (xy 75.494146 -312.999882)
			(xy 75.498106 -312.950828) (xy 75.509883 -312.903044) (xy 75.529174 -312.857768) (xy 75.555477 -312.816172)
			(xy 75.588112 -312.779335) (xy 75.626233 -312.74821) (xy 75.668854 -312.723603) (xy 75.71487 -312.706151)
			(xy 75.763089 -312.696307) (xy 75.812264 -312.694326) (xy 75.861119 -312.700258) (xy 75.90839 -312.71395)
			(xy 75.952852 -312.735048) (xy 75.993355 -312.763004) (xy 76.028848 -312.797096) (xy 76.058413 -312.83644)
			(xy 76.081284 -312.880017) (xy 76.096868 -312.926698) (xy 76.104763 -312.975275) (xy 76.105258 -312.999882)
			(xy 76.444106 -312.999882) (xy 76.448066 -312.950828) (xy 76.459843 -312.903044) (xy 76.479134 -312.857768)
			(xy 76.505437 -312.816172) (xy 76.538072 -312.779335) (xy 76.576193 -312.74821) (xy 76.618814 -312.723603)
			(xy 76.66483 -312.706151) (xy 76.713049 -312.696307) (xy 76.762224 -312.694326) (xy 76.811079 -312.700258)
			(xy 76.85835 -312.71395) (xy 76.902812 -312.735048) (xy 76.943315 -312.763004) (xy 76.978808 -312.797096)
			(xy 77.008373 -312.83644) (xy 77.031244 -312.880017) (xy 77.046828 -312.926698) (xy 77.054723 -312.975275)
			(xy 77.055218 -312.999882) (xy 77.394066 -312.999882) (xy 77.398026 -312.950828) (xy 77.409803 -312.903044)
			(xy 77.429094 -312.857768) (xy 77.455397 -312.816172) (xy 77.488032 -312.779335) (xy 77.526153 -312.74821)
			(xy 77.568774 -312.723603) (xy 77.61479 -312.706151) (xy 77.663009 -312.696307) (xy 77.712184 -312.694326)
			(xy 77.761039 -312.700258) (xy 77.80831 -312.71395) (xy 77.852772 -312.735048) (xy 77.893275 -312.763004)
			(xy 77.928768 -312.797096) (xy 77.958333 -312.83644) (xy 77.981204 -312.880017) (xy 77.996788 -312.926698)
			(xy 78.004683 -312.975275) (xy 78.005178 -312.999882) (xy 78.344026 -312.999882) (xy 78.347986 -312.950828)
			(xy 78.359763 -312.903044) (xy 78.379054 -312.857768) (xy 78.405357 -312.816172) (xy 78.437992 -312.779335)
			(xy 78.476113 -312.74821) (xy 78.518734 -312.723603) (xy 78.56475 -312.706151) (xy 78.612969 -312.696307)
			(xy 78.662144 -312.694326) (xy 78.710999 -312.700258) (xy 78.75827 -312.71395) (xy 78.802732 -312.735048)
			(xy 78.843235 -312.763004) (xy 78.878728 -312.797096) (xy 78.908293 -312.83644) (xy 78.931164 -312.880017)
			(xy 78.946748 -312.926698) (xy 78.954643 -312.975275) (xy 78.955138 -312.999882) (xy 79.293986 -312.999882)
			(xy 79.297946 -312.950828) (xy 79.309723 -312.903044) (xy 79.329014 -312.857768) (xy 79.355317 -312.816172)
			(xy 79.387952 -312.779335) (xy 79.426073 -312.74821) (xy 79.468694 -312.723603) (xy 79.51471 -312.706151)
			(xy 79.562929 -312.696307) (xy 79.612104 -312.694326) (xy 79.660959 -312.700258) (xy 79.70823 -312.71395)
			(xy 79.752692 -312.735048) (xy 79.793195 -312.763004) (xy 79.828688 -312.797096) (xy 79.858253 -312.83644)
			(xy 79.881124 -312.880017) (xy 79.896708 -312.926698) (xy 79.904603 -312.975275) (xy 79.905098 -312.999882)
			(xy 80.243946 -312.999882) (xy 80.247906 -312.950828) (xy 80.259683 -312.903044) (xy 80.278974 -312.857768)
			(xy 80.305277 -312.816172) (xy 80.337912 -312.779335) (xy 80.376033 -312.74821) (xy 80.418654 -312.723603)
			(xy 80.46467 -312.706151) (xy 80.512889 -312.696307) (xy 80.562064 -312.694326) (xy 80.610919 -312.700258)
			(xy 80.65819 -312.71395) (xy 80.702652 -312.735048) (xy 80.743155 -312.763004) (xy 80.778648 -312.797096)
			(xy 80.808213 -312.83644) (xy 80.831084 -312.880017) (xy 80.846668 -312.926698) (xy 80.854563 -312.975275)
			(xy 80.855058 -312.999882) (xy 81.19416 -312.999882) (xy 81.19812 -312.950828) (xy 81.209897 -312.903044)
			(xy 81.229188 -312.857768) (xy 81.255491 -312.816172) (xy 81.288126 -312.779335) (xy 81.326247 -312.74821)
			(xy 81.368868 -312.723603) (xy 81.414884 -312.706151) (xy 81.463103 -312.696307) (xy 81.512278 -312.694326)
			(xy 81.561133 -312.700258) (xy 81.608404 -312.71395) (xy 81.652866 -312.735048) (xy 81.693369 -312.763004)
			(xy 81.728862 -312.797096) (xy 81.758427 -312.83644) (xy 81.781298 -312.880017) (xy 81.796882 -312.926698)
			(xy 81.804777 -312.975275) (xy 81.805272 -312.999882) (xy 82.14412 -312.999882) (xy 82.14808 -312.950828)
			(xy 82.159857 -312.903044) (xy 82.179148 -312.857768) (xy 82.205451 -312.816172) (xy 82.238086 -312.779335)
			(xy 82.276207 -312.74821) (xy 82.318828 -312.723603) (xy 82.364844 -312.706151) (xy 82.413063 -312.696307)
			(xy 82.462238 -312.694326) (xy 82.511093 -312.700258) (xy 82.558364 -312.71395) (xy 82.602826 -312.735048)
			(xy 82.643329 -312.763004) (xy 82.678822 -312.797096) (xy 82.708387 -312.83644) (xy 82.731258 -312.880017)
			(xy 82.746842 -312.926698) (xy 82.754737 -312.975275) (xy 82.755232 -312.999882) (xy 82.754737 -313.024489)
			(xy 82.746842 -313.073066) (xy 82.731258 -313.119747) (xy 82.708387 -313.163324) (xy 82.678822 -313.202668)
			(xy 82.643329 -313.23676) (xy 82.602826 -313.264716) (xy 82.558364 -313.285814) (xy 82.511093 -313.299506)
			(xy 82.462238 -313.305438) (xy 82.413063 -313.303457) (xy 82.364844 -313.293613) (xy 82.318828 -313.276161)
			(xy 82.276207 -313.251554) (xy 82.238086 -313.220429) (xy 82.205451 -313.183592) (xy 82.179148 -313.141996)
			(xy 82.159857 -313.09672) (xy 82.14808 -313.048936) (xy 82.14412 -312.999882) (xy 81.805272 -312.999882)
			(xy 81.804777 -313.024489) (xy 81.796882 -313.073066) (xy 81.781298 -313.119747) (xy 81.758427 -313.163324)
			(xy 81.728862 -313.202668) (xy 81.693369 -313.23676) (xy 81.652866 -313.264716) (xy 81.608404 -313.285814)
			(xy 81.561133 -313.299506) (xy 81.512278 -313.305438) (xy 81.463103 -313.303457) (xy 81.414884 -313.293613)
			(xy 81.368868 -313.276161) (xy 81.326247 -313.251554) (xy 81.288126 -313.220429) (xy 81.255491 -313.183592)
			(xy 81.229188 -313.141996) (xy 81.209897 -313.09672) (xy 81.19812 -313.048936) (xy 81.19416 -312.999882)
			(xy 80.855058 -312.999882) (xy 80.854563 -313.024489) (xy 80.846668 -313.073066) (xy 80.831084 -313.119747)
			(xy 80.808213 -313.163324) (xy 80.778648 -313.202668) (xy 80.743155 -313.23676) (xy 80.702652 -313.264716)
			(xy 80.65819 -313.285814) (xy 80.610919 -313.299506) (xy 80.562064 -313.305438) (xy 80.512889 -313.303457)
			(xy 80.46467 -313.293613) (xy 80.418654 -313.276161) (xy 80.376033 -313.251554) (xy 80.337912 -313.220429)
			(xy 80.305277 -313.183592) (xy 80.278974 -313.141996) (xy 80.259683 -313.09672) (xy 80.247906 -313.048936)
			(xy 80.243946 -312.999882) (xy 79.905098 -312.999882) (xy 79.904603 -313.024489) (xy 79.896708 -313.073066)
			(xy 79.881124 -313.119747) (xy 79.858253 -313.163324) (xy 79.828688 -313.202668) (xy 79.793195 -313.23676)
			(xy 79.752692 -313.264716) (xy 79.70823 -313.285814) (xy 79.660959 -313.299506) (xy 79.612104 -313.305438)
			(xy 79.562929 -313.303457) (xy 79.51471 -313.293613) (xy 79.468694 -313.276161) (xy 79.426073 -313.251554)
			(xy 79.387952 -313.220429) (xy 79.355317 -313.183592) (xy 79.329014 -313.141996) (xy 79.309723 -313.09672)
			(xy 79.297946 -313.048936) (xy 79.293986 -312.999882) (xy 78.955138 -312.999882) (xy 78.954643 -313.024489)
			(xy 78.946748 -313.073066) (xy 78.931164 -313.119747) (xy 78.908293 -313.163324) (xy 78.878728 -313.202668)
			(xy 78.843235 -313.23676) (xy 78.802732 -313.264716) (xy 78.75827 -313.285814) (xy 78.710999 -313.299506)
			(xy 78.662144 -313.305438) (xy 78.612969 -313.303457) (xy 78.56475 -313.293613) (xy 78.518734 -313.276161)
			(xy 78.476113 -313.251554) (xy 78.437992 -313.220429) (xy 78.405357 -313.183592) (xy 78.379054 -313.141996)
			(xy 78.359763 -313.09672) (xy 78.347986 -313.048936) (xy 78.344026 -312.999882) (xy 78.005178 -312.999882)
			(xy 78.004683 -313.024489) (xy 77.996788 -313.073066) (xy 77.981204 -313.119747) (xy 77.958333 -313.163324)
			(xy 77.928768 -313.202668) (xy 77.893275 -313.23676) (xy 77.852772 -313.264716) (xy 77.80831 -313.285814)
			(xy 77.761039 -313.299506) (xy 77.712184 -313.305438) (xy 77.663009 -313.303457) (xy 77.61479 -313.293613)
			(xy 77.568774 -313.276161) (xy 77.526153 -313.251554) (xy 77.488032 -313.220429) (xy 77.455397 -313.183592)
			(xy 77.429094 -313.141996) (xy 77.409803 -313.09672) (xy 77.398026 -313.048936) (xy 77.394066 -312.999882)
			(xy 77.055218 -312.999882) (xy 77.054723 -313.024489) (xy 77.046828 -313.073066) (xy 77.031244 -313.119747)
			(xy 77.008373 -313.163324) (xy 76.978808 -313.202668) (xy 76.943315 -313.23676) (xy 76.902812 -313.264716)
			(xy 76.85835 -313.285814) (xy 76.811079 -313.299506) (xy 76.762224 -313.305438) (xy 76.713049 -313.303457)
			(xy 76.66483 -313.293613) (xy 76.618814 -313.276161) (xy 76.576193 -313.251554) (xy 76.538072 -313.220429)
			(xy 76.505437 -313.183592) (xy 76.479134 -313.141996) (xy 76.459843 -313.09672) (xy 76.448066 -313.048936)
			(xy 76.444106 -312.999882) (xy 76.105258 -312.999882) (xy 76.104763 -313.024489) (xy 76.096868 -313.073066)
			(xy 76.081284 -313.119747) (xy 76.058413 -313.163324) (xy 76.028848 -313.202668) (xy 75.993355 -313.23676)
			(xy 75.952852 -313.264716) (xy 75.90839 -313.285814) (xy 75.861119 -313.299506) (xy 75.812264 -313.305438)
			(xy 75.763089 -313.303457) (xy 75.71487 -313.293613) (xy 75.668854 -313.276161) (xy 75.626233 -313.251554)
			(xy 75.588112 -313.220429) (xy 75.555477 -313.183592) (xy 75.529174 -313.141996) (xy 75.509883 -313.09672)
			(xy 75.498106 -313.048936) (xy 75.494146 -312.999882) (xy 75.155877 -312.999882) (xy 75.155878 -312.9999)
			(xy 75.151706 -313.050247) (xy 75.139304 -313.09922) (xy 75.11901 -313.145485) (xy 75.091378 -313.187777)
			(xy 75.057162 -313.224945) (xy 75.017294 -313.255974) (xy 74.972863 -313.280018) (xy 74.92508 -313.29642)
			(xy 74.87525 -313.304734) (xy 74.84999 -313.30519) (xy 74.835808 -313.305003) (xy 74.807569 -313.302328)
			(xy 74.793602 -313.299856) (xy 74.781156 -313.29757) (xy 74.769218 -313.301126) (xy 74.763334 -313.303152)
			(xy 74.752678 -313.309572) (xy 74.748136 -313.313826) (xy 74.680064 -313.382152) (xy 74.672698 -313.405774)
			(xy 74.674984 -313.41822) (xy 74.677016 -313.431174) (xy 74.677016 -313.431428) (xy 74.678794 -313.44362)
			(xy 74.680318 -313.474862) (xy 74.680117 -313.488981) (xy 74.677442 -313.517092) (xy 74.674984 -313.530996)
			(xy 74.672698 -313.543442) (xy 74.680064 -313.567318) (xy 74.757534 -313.644788) (xy 74.78141 -313.652154)
			(xy 74.793856 -313.649868) (xy 74.807758 -313.647394) (xy 74.835871 -313.644727) (xy 74.84999 -313.644534)
			(xy 74.875245 -313.645026) (xy 74.925066 -313.653338) (xy 74.972839 -313.669737) (xy 75.017261 -313.693776)
			(xy 75.057121 -313.724799) (xy 75.091331 -313.761959) (xy 75.118957 -313.804244) (xy 75.139247 -313.850499)
			(xy 75.151647 -313.899463) (xy 75.155818 -313.9498) (xy 75.155815 -313.949842) (xy 75.494146 -313.949842)
			(xy 75.498106 -313.900788) (xy 75.509883 -313.853004) (xy 75.529174 -313.807728) (xy 75.555477 -313.766132)
			(xy 75.588112 -313.729295) (xy 75.626233 -313.69817) (xy 75.668854 -313.673563) (xy 75.71487 -313.656111)
			(xy 75.763089 -313.646267) (xy 75.812264 -313.644286) (xy 75.861119 -313.650218) (xy 75.90839 -313.66391)
			(xy 75.952852 -313.685008) (xy 75.993355 -313.712964) (xy 76.028848 -313.747056) (xy 76.058413 -313.7864)
			(xy 76.081284 -313.829977) (xy 76.096868 -313.876658) (xy 76.104763 -313.925235) (xy 76.105258 -313.949842)
			(xy 76.444106 -313.949842) (xy 76.448066 -313.900788) (xy 76.459843 -313.853004) (xy 76.479134 -313.807728)
			(xy 76.505437 -313.766132) (xy 76.538072 -313.729295) (xy 76.576193 -313.69817) (xy 76.618814 -313.673563)
			(xy 76.66483 -313.656111) (xy 76.713049 -313.646267) (xy 76.762224 -313.644286) (xy 76.811079 -313.650218)
			(xy 76.85835 -313.66391) (xy 76.902812 -313.685008) (xy 76.943315 -313.712964) (xy 76.978808 -313.747056)
			(xy 77.008373 -313.7864) (xy 77.031244 -313.829977) (xy 77.046828 -313.876658) (xy 77.054723 -313.925235)
			(xy 77.055218 -313.949842) (xy 77.394066 -313.949842) (xy 77.398026 -313.900788) (xy 77.409803 -313.853004)
			(xy 77.429094 -313.807728) (xy 77.455397 -313.766132) (xy 77.488032 -313.729295) (xy 77.526153 -313.69817)
			(xy 77.568774 -313.673563) (xy 77.61479 -313.656111) (xy 77.663009 -313.646267) (xy 77.712184 -313.644286)
			(xy 77.761039 -313.650218) (xy 77.80831 -313.66391) (xy 77.852772 -313.685008) (xy 77.893275 -313.712964)
			(xy 77.928768 -313.747056) (xy 77.958333 -313.7864) (xy 77.981204 -313.829977) (xy 77.996788 -313.876658)
			(xy 78.004683 -313.925235) (xy 78.005178 -313.949842) (xy 78.344026 -313.949842) (xy 78.347986 -313.900788)
			(xy 78.359763 -313.853004) (xy 78.379054 -313.807728) (xy 78.405357 -313.766132) (xy 78.437992 -313.729295)
			(xy 78.476113 -313.69817) (xy 78.518734 -313.673563) (xy 78.56475 -313.656111) (xy 78.612969 -313.646267)
			(xy 78.662144 -313.644286) (xy 78.710999 -313.650218) (xy 78.75827 -313.66391) (xy 78.802732 -313.685008)
			(xy 78.843235 -313.712964) (xy 78.878728 -313.747056) (xy 78.908293 -313.7864) (xy 78.931164 -313.829977)
			(xy 78.946748 -313.876658) (xy 78.954643 -313.925235) (xy 78.955138 -313.949842) (xy 79.293986 -313.949842)
			(xy 79.297946 -313.900788) (xy 79.309723 -313.853004) (xy 79.329014 -313.807728) (xy 79.355317 -313.766132)
			(xy 79.387952 -313.729295) (xy 79.426073 -313.69817) (xy 79.468694 -313.673563) (xy 79.51471 -313.656111)
			(xy 79.562929 -313.646267) (xy 79.612104 -313.644286) (xy 79.660959 -313.650218) (xy 79.70823 -313.66391)
			(xy 79.752692 -313.685008) (xy 79.793195 -313.712964) (xy 79.828688 -313.747056) (xy 79.858253 -313.7864)
			(xy 79.881124 -313.829977) (xy 79.896708 -313.876658) (xy 79.904603 -313.925235) (xy 79.905098 -313.949842)
			(xy 80.243946 -313.949842) (xy 80.247906 -313.900788) (xy 80.259683 -313.853004) (xy 80.278974 -313.807728)
			(xy 80.305277 -313.766132) (xy 80.337912 -313.729295) (xy 80.376033 -313.69817) (xy 80.418654 -313.673563)
			(xy 80.46467 -313.656111) (xy 80.512889 -313.646267) (xy 80.562064 -313.644286) (xy 80.610919 -313.650218)
			(xy 80.65819 -313.66391) (xy 80.702652 -313.685008) (xy 80.743155 -313.712964) (xy 80.778648 -313.747056)
			(xy 80.808213 -313.7864) (xy 80.831084 -313.829977) (xy 80.846668 -313.876658) (xy 80.854563 -313.925235)
			(xy 80.855058 -313.949842) (xy 81.19416 -313.949842) (xy 81.19812 -313.900788) (xy 81.209897 -313.853004)
			(xy 81.229188 -313.807728) (xy 81.255491 -313.766132) (xy 81.288126 -313.729295) (xy 81.326247 -313.69817)
			(xy 81.368868 -313.673563) (xy 81.414884 -313.656111) (xy 81.463103 -313.646267) (xy 81.512278 -313.644286)
			(xy 81.561133 -313.650218) (xy 81.608404 -313.66391) (xy 81.652866 -313.685008) (xy 81.693369 -313.712964)
			(xy 81.728862 -313.747056) (xy 81.758427 -313.7864) (xy 81.781298 -313.829977) (xy 81.796882 -313.876658)
			(xy 81.804777 -313.925235) (xy 81.805272 -313.949842) (xy 82.14412 -313.949842) (xy 82.14808 -313.900788)
			(xy 82.159857 -313.853004) (xy 82.179148 -313.807728) (xy 82.205451 -313.766132) (xy 82.238086 -313.729295)
			(xy 82.276207 -313.69817) (xy 82.318828 -313.673563) (xy 82.364844 -313.656111) (xy 82.413063 -313.646267)
			(xy 82.462238 -313.644286) (xy 82.511093 -313.650218) (xy 82.558364 -313.66391) (xy 82.602826 -313.685008)
			(xy 82.643329 -313.712964) (xy 82.678822 -313.747056) (xy 82.708387 -313.7864) (xy 82.731258 -313.829977)
			(xy 82.746842 -313.876658) (xy 82.754737 -313.925235) (xy 82.755232 -313.949842) (xy 82.754737 -313.974449)
			(xy 82.746842 -314.023026) (xy 82.731258 -314.069707) (xy 82.708387 -314.113284) (xy 82.678822 -314.152628)
			(xy 82.643329 -314.18672) (xy 82.602826 -314.214676) (xy 82.558364 -314.235774) (xy 82.511093 -314.249466)
			(xy 82.462238 -314.255398) (xy 82.413063 -314.253417) (xy 82.364844 -314.243573) (xy 82.318828 -314.226121)
			(xy 82.276207 -314.201514) (xy 82.238086 -314.170389) (xy 82.205451 -314.133552) (xy 82.179148 -314.091956)
			(xy 82.159857 -314.04668) (xy 82.14808 -313.998896) (xy 82.14412 -313.949842) (xy 81.805272 -313.949842)
			(xy 81.804777 -313.974449) (xy 81.796882 -314.023026) (xy 81.781298 -314.069707) (xy 81.758427 -314.113284)
			(xy 81.728862 -314.152628) (xy 81.693369 -314.18672) (xy 81.652866 -314.214676) (xy 81.608404 -314.235774)
			(xy 81.561133 -314.249466) (xy 81.512278 -314.255398) (xy 81.463103 -314.253417) (xy 81.414884 -314.243573)
			(xy 81.368868 -314.226121) (xy 81.326247 -314.201514) (xy 81.288126 -314.170389) (xy 81.255491 -314.133552)
			(xy 81.229188 -314.091956) (xy 81.209897 -314.04668) (xy 81.19812 -313.998896) (xy 81.19416 -313.949842)
			(xy 80.855058 -313.949842) (xy 80.854563 -313.974449) (xy 80.846668 -314.023026) (xy 80.831084 -314.069707)
			(xy 80.808213 -314.113284) (xy 80.778648 -314.152628) (xy 80.743155 -314.18672) (xy 80.702652 -314.214676)
			(xy 80.65819 -314.235774) (xy 80.610919 -314.249466) (xy 80.562064 -314.255398) (xy 80.512889 -314.253417)
			(xy 80.46467 -314.243573) (xy 80.418654 -314.226121) (xy 80.376033 -314.201514) (xy 80.337912 -314.170389)
			(xy 80.305277 -314.133552) (xy 80.278974 -314.091956) (xy 80.259683 -314.04668) (xy 80.247906 -313.998896)
			(xy 80.243946 -313.949842) (xy 79.905098 -313.949842) (xy 79.904603 -313.974449) (xy 79.896708 -314.023026)
			(xy 79.881124 -314.069707) (xy 79.858253 -314.113284) (xy 79.828688 -314.152628) (xy 79.793195 -314.18672)
			(xy 79.752692 -314.214676) (xy 79.70823 -314.235774) (xy 79.660959 -314.249466) (xy 79.612104 -314.255398)
			(xy 79.562929 -314.253417) (xy 79.51471 -314.243573) (xy 79.468694 -314.226121) (xy 79.426073 -314.201514)
			(xy 79.387952 -314.170389) (xy 79.355317 -314.133552) (xy 79.329014 -314.091956) (xy 79.309723 -314.04668)
			(xy 79.297946 -313.998896) (xy 79.293986 -313.949842) (xy 78.955138 -313.949842) (xy 78.954643 -313.974449)
			(xy 78.946748 -314.023026) (xy 78.931164 -314.069707) (xy 78.908293 -314.113284) (xy 78.878728 -314.152628)
			(xy 78.843235 -314.18672) (xy 78.802732 -314.214676) (xy 78.75827 -314.235774) (xy 78.710999 -314.249466)
			(xy 78.662144 -314.255398) (xy 78.612969 -314.253417) (xy 78.56475 -314.243573) (xy 78.518734 -314.226121)
			(xy 78.476113 -314.201514) (xy 78.437992 -314.170389) (xy 78.405357 -314.133552) (xy 78.379054 -314.091956)
			(xy 78.359763 -314.04668) (xy 78.347986 -313.998896) (xy 78.344026 -313.949842) (xy 78.005178 -313.949842)
			(xy 78.004683 -313.974449) (xy 77.996788 -314.023026) (xy 77.981204 -314.069707) (xy 77.958333 -314.113284)
			(xy 77.928768 -314.152628) (xy 77.893275 -314.18672) (xy 77.852772 -314.214676) (xy 77.80831 -314.235774)
			(xy 77.761039 -314.249466) (xy 77.712184 -314.255398) (xy 77.663009 -314.253417) (xy 77.61479 -314.243573)
			(xy 77.568774 -314.226121) (xy 77.526153 -314.201514) (xy 77.488032 -314.170389) (xy 77.455397 -314.133552)
			(xy 77.429094 -314.091956) (xy 77.409803 -314.04668) (xy 77.398026 -313.998896) (xy 77.394066 -313.949842)
			(xy 77.055218 -313.949842) (xy 77.054723 -313.974449) (xy 77.046828 -314.023026) (xy 77.031244 -314.069707)
			(xy 77.008373 -314.113284) (xy 76.978808 -314.152628) (xy 76.943315 -314.18672) (xy 76.902812 -314.214676)
			(xy 76.85835 -314.235774) (xy 76.811079 -314.249466) (xy 76.762224 -314.255398) (xy 76.713049 -314.253417)
			(xy 76.66483 -314.243573) (xy 76.618814 -314.226121) (xy 76.576193 -314.201514) (xy 76.538072 -314.170389)
			(xy 76.505437 -314.133552) (xy 76.479134 -314.091956) (xy 76.459843 -314.04668) (xy 76.448066 -313.998896)
			(xy 76.444106 -313.949842) (xy 76.105258 -313.949842) (xy 76.104763 -313.974449) (xy 76.096868 -314.023026)
			(xy 76.081284 -314.069707) (xy 76.058413 -314.113284) (xy 76.028848 -314.152628) (xy 75.993355 -314.18672)
			(xy 75.952852 -314.214676) (xy 75.90839 -314.235774) (xy 75.861119 -314.249466) (xy 75.812264 -314.255398)
			(xy 75.763089 -314.253417) (xy 75.71487 -314.243573) (xy 75.668854 -314.226121) (xy 75.626233 -314.201514)
			(xy 75.588112 -314.170389) (xy 75.555477 -314.133552) (xy 75.529174 -314.091956) (xy 75.509883 -314.04668)
			(xy 75.498106 -313.998896) (xy 75.494146 -313.949842) (xy 75.155815 -313.949842) (xy 75.151647 -314.000137)
			(xy 75.139247 -314.049101) (xy 75.118957 -314.095356) (xy 75.091331 -314.137641) (xy 75.057121 -314.174801)
			(xy 75.017261 -314.205824) (xy 74.972839 -314.229863) (xy 74.925066 -314.246262) (xy 74.875245 -314.254574)
			(xy 74.84999 -314.25515) (xy 74.835808 -314.254963) (xy 74.807568 -314.252289) (xy 74.793602 -314.249816)
			(xy 74.787508 -314.248818) (xy 74.775178 -314.249467) (xy 74.769218 -314.251086) (xy 74.763336 -314.253114)
			(xy 74.752685 -314.25954) (xy 74.748136 -314.263786) (xy 74.6887 -314.323222) (xy 74.680528 -314.332522)
			(xy 74.673244 -314.356142) (xy 74.67473 -314.368434) (xy 74.677255 -314.38265) (xy 74.679925 -314.4114)
			(xy 74.680064 -314.425838) (xy 74.680064 -314.4266) (xy 74.679906 -314.437886) (xy 74.678127 -314.460388)
			(xy 74.676508 -314.471558) (xy 74.676 -314.474098) (xy 74.676 -314.474606) (xy 74.675746 -314.475622)
			(xy 74.674984 -314.478924) (xy 74.673738 -314.485513) (xy 74.674384 -314.498901) (xy 74.676254 -314.50534)
			(xy 74.676254 -314.505848) (xy 74.678299 -314.51151) (xy 74.684585 -314.521774) (xy 74.6887 -314.526168)
			(xy 74.748136 -314.585858) (xy 74.752647 -314.590153) (xy 74.763311 -314.596581) (xy 74.769218 -314.598558)
			(xy 74.781156 -314.602114) (xy 74.793602 -314.599828) (xy 74.807567 -314.597342) (xy 74.835807 -314.594669)
			(xy 74.84999 -314.594494) (xy 74.875248 -314.594986) (xy 74.925076 -314.603299) (xy 74.972855 -314.6197)
			(xy 75.017283 -314.643742) (xy 75.057148 -314.674769) (xy 75.091362 -314.711935) (xy 75.118993 -314.754225)
			(xy 75.139285 -314.800486) (xy 75.151686 -314.849456) (xy 75.155858 -314.8998) (xy 75.155858 -314.899802)
			(xy 75.494146 -314.899802) (xy 75.498106 -314.850748) (xy 75.509883 -314.802964) (xy 75.529174 -314.757688)
			(xy 75.555477 -314.716092) (xy 75.588112 -314.679255) (xy 75.626233 -314.64813) (xy 75.668854 -314.623523)
			(xy 75.71487 -314.606071) (xy 75.763089 -314.596227) (xy 75.812264 -314.594246) (xy 75.861119 -314.600178)
			(xy 75.90839 -314.61387) (xy 75.952852 -314.634968) (xy 75.993355 -314.662924) (xy 76.028848 -314.697016)
			(xy 76.058413 -314.73636) (xy 76.081284 -314.779937) (xy 76.096868 -314.826618) (xy 76.104763 -314.875195)
			(xy 76.105258 -314.899802) (xy 76.444106 -314.899802) (xy 76.448066 -314.850748) (xy 76.459843 -314.802964)
			(xy 76.479134 -314.757688) (xy 76.505437 -314.716092) (xy 76.538072 -314.679255) (xy 76.576193 -314.64813)
			(xy 76.618814 -314.623523) (xy 76.66483 -314.606071) (xy 76.713049 -314.596227) (xy 76.762224 -314.594246)
			(xy 76.811079 -314.600178) (xy 76.85835 -314.61387) (xy 76.902812 -314.634968) (xy 76.943315 -314.662924)
			(xy 76.978808 -314.697016) (xy 77.008373 -314.73636) (xy 77.031244 -314.779937) (xy 77.046828 -314.826618)
			(xy 77.054723 -314.875195) (xy 77.055218 -314.899802) (xy 77.394066 -314.899802) (xy 77.398026 -314.850748)
			(xy 77.409803 -314.802964) (xy 77.429094 -314.757688) (xy 77.455397 -314.716092) (xy 77.488032 -314.679255)
			(xy 77.526153 -314.64813) (xy 77.568774 -314.623523) (xy 77.61479 -314.606071) (xy 77.663009 -314.596227)
			(xy 77.712184 -314.594246) (xy 77.761039 -314.600178) (xy 77.80831 -314.61387) (xy 77.852772 -314.634968)
			(xy 77.893275 -314.662924) (xy 77.928768 -314.697016) (xy 77.958333 -314.73636) (xy 77.981204 -314.779937)
			(xy 77.996788 -314.826618) (xy 78.004683 -314.875195) (xy 78.005178 -314.899802) (xy 78.344026 -314.899802)
			(xy 78.347986 -314.850748) (xy 78.359763 -314.802964) (xy 78.379054 -314.757688) (xy 78.405357 -314.716092)
			(xy 78.437992 -314.679255) (xy 78.476113 -314.64813) (xy 78.518734 -314.623523) (xy 78.56475 -314.606071)
			(xy 78.612969 -314.596227) (xy 78.662144 -314.594246) (xy 78.710999 -314.600178) (xy 78.75827 -314.61387)
			(xy 78.802732 -314.634968) (xy 78.843235 -314.662924) (xy 78.878728 -314.697016) (xy 78.908293 -314.73636)
			(xy 78.931164 -314.779937) (xy 78.946748 -314.826618) (xy 78.954643 -314.875195) (xy 78.955138 -314.899802)
			(xy 79.293986 -314.899802) (xy 79.297946 -314.850748) (xy 79.309723 -314.802964) (xy 79.329014 -314.757688)
			(xy 79.355317 -314.716092) (xy 79.387952 -314.679255) (xy 79.426073 -314.64813) (xy 79.468694 -314.623523)
			(xy 79.51471 -314.606071) (xy 79.562929 -314.596227) (xy 79.612104 -314.594246) (xy 79.660959 -314.600178)
			(xy 79.70823 -314.61387) (xy 79.752692 -314.634968) (xy 79.793195 -314.662924) (xy 79.828688 -314.697016)
			(xy 79.858253 -314.73636) (xy 79.881124 -314.779937) (xy 79.896708 -314.826618) (xy 79.904603 -314.875195)
			(xy 79.905098 -314.899802) (xy 80.243946 -314.899802) (xy 80.247906 -314.850748) (xy 80.259683 -314.802964)
			(xy 80.278974 -314.757688) (xy 80.305277 -314.716092) (xy 80.337912 -314.679255) (xy 80.376033 -314.64813)
			(xy 80.418654 -314.623523) (xy 80.46467 -314.606071) (xy 80.512889 -314.596227) (xy 80.562064 -314.594246)
			(xy 80.610919 -314.600178) (xy 80.65819 -314.61387) (xy 80.702652 -314.634968) (xy 80.743155 -314.662924)
			(xy 80.778648 -314.697016) (xy 80.808213 -314.73636) (xy 80.831084 -314.779937) (xy 80.846668 -314.826618)
			(xy 80.854563 -314.875195) (xy 80.855058 -314.899802) (xy 81.19416 -314.899802) (xy 81.19812 -314.850748)
			(xy 81.209897 -314.802964) (xy 81.229188 -314.757688) (xy 81.255491 -314.716092) (xy 81.288126 -314.679255)
			(xy 81.326247 -314.64813) (xy 81.368868 -314.623523) (xy 81.414884 -314.606071) (xy 81.463103 -314.596227)
			(xy 81.512278 -314.594246) (xy 81.561133 -314.600178) (xy 81.608404 -314.61387) (xy 81.652866 -314.634968)
			(xy 81.693369 -314.662924) (xy 81.728862 -314.697016) (xy 81.758427 -314.73636) (xy 81.781298 -314.779937)
			(xy 81.796882 -314.826618) (xy 81.804777 -314.875195) (xy 81.805272 -314.899802) (xy 82.14412 -314.899802)
			(xy 82.14808 -314.850748) (xy 82.159857 -314.802964) (xy 82.179148 -314.757688) (xy 82.205451 -314.716092)
			(xy 82.238086 -314.679255) (xy 82.276207 -314.64813) (xy 82.318828 -314.623523) (xy 82.364844 -314.606071)
			(xy 82.413063 -314.596227) (xy 82.462238 -314.594246) (xy 82.511093 -314.600178) (xy 82.558364 -314.61387)
			(xy 82.602826 -314.634968) (xy 82.643329 -314.662924) (xy 82.678822 -314.697016) (xy 82.708387 -314.73636)
			(xy 82.731258 -314.779937) (xy 82.746842 -314.826618) (xy 82.754737 -314.875195) (xy 82.755227 -314.899548)
			(xy 83.094334 -314.899548) (xy 83.098294 -314.850494) (xy 83.110071 -314.80271) (xy 83.129362 -314.757434)
			(xy 83.155665 -314.715838) (xy 83.1883 -314.679001) (xy 83.226421 -314.647876) (xy 83.269042 -314.623269)
			(xy 83.315058 -314.605817) (xy 83.363277 -314.595973) (xy 83.412452 -314.593992) (xy 83.461307 -314.599924)
			(xy 83.508578 -314.613616) (xy 83.55304 -314.634714) (xy 83.593543 -314.66267) (xy 83.629036 -314.696762)
			(xy 83.658601 -314.736106) (xy 83.681472 -314.779683) (xy 83.697056 -314.826364) (xy 83.704951 -314.874941)
			(xy 83.705446 -314.899548) (xy 83.704951 -314.924155) (xy 83.697056 -314.972732) (xy 83.681472 -315.019413)
			(xy 83.658601 -315.06299) (xy 83.629036 -315.102334) (xy 83.593543 -315.136426) (xy 83.55304 -315.164382)
			(xy 83.508578 -315.18548) (xy 83.461307 -315.199172) (xy 83.412452 -315.205104) (xy 83.363277 -315.203123)
			(xy 83.315058 -315.193279) (xy 83.269042 -315.175827) (xy 83.226421 -315.15122) (xy 83.1883 -315.120095)
			(xy 83.155665 -315.083258) (xy 83.129362 -315.041662) (xy 83.110071 -314.996386) (xy 83.098294 -314.948602)
			(xy 83.094334 -314.899548) (xy 82.755227 -314.899548) (xy 82.755232 -314.899802) (xy 82.754737 -314.924409)
			(xy 82.746842 -314.972986) (xy 82.731258 -315.019667) (xy 82.708387 -315.063244) (xy 82.678822 -315.102588)
			(xy 82.643329 -315.13668) (xy 82.602826 -315.164636) (xy 82.558364 -315.185734) (xy 82.511093 -315.199426)
			(xy 82.462238 -315.205358) (xy 82.413063 -315.203377) (xy 82.364844 -315.193533) (xy 82.318828 -315.176081)
			(xy 82.276207 -315.151474) (xy 82.238086 -315.120349) (xy 82.205451 -315.083512) (xy 82.179148 -315.041916)
			(xy 82.159857 -314.99664) (xy 82.14808 -314.948856) (xy 82.14412 -314.899802) (xy 81.805272 -314.899802)
			(xy 81.804777 -314.924409) (xy 81.796882 -314.972986) (xy 81.781298 -315.019667) (xy 81.758427 -315.063244)
			(xy 81.728862 -315.102588) (xy 81.693369 -315.13668) (xy 81.652866 -315.164636) (xy 81.608404 -315.185734)
			(xy 81.561133 -315.199426) (xy 81.512278 -315.205358) (xy 81.463103 -315.203377) (xy 81.414884 -315.193533)
			(xy 81.368868 -315.176081) (xy 81.326247 -315.151474) (xy 81.288126 -315.120349) (xy 81.255491 -315.083512)
			(xy 81.229188 -315.041916) (xy 81.209897 -314.99664) (xy 81.19812 -314.948856) (xy 81.19416 -314.899802)
			(xy 80.855058 -314.899802) (xy 80.854563 -314.924409) (xy 80.846668 -314.972986) (xy 80.831084 -315.019667)
			(xy 80.808213 -315.063244) (xy 80.778648 -315.102588) (xy 80.743155 -315.13668) (xy 80.702652 -315.164636)
			(xy 80.65819 -315.185734) (xy 80.610919 -315.199426) (xy 80.562064 -315.205358) (xy 80.512889 -315.203377)
			(xy 80.46467 -315.193533) (xy 80.418654 -315.176081) (xy 80.376033 -315.151474) (xy 80.337912 -315.120349)
			(xy 80.305277 -315.083512) (xy 80.278974 -315.041916) (xy 80.259683 -314.99664) (xy 80.247906 -314.948856)
			(xy 80.243946 -314.899802) (xy 79.905098 -314.899802) (xy 79.904603 -314.924409) (xy 79.896708 -314.972986)
			(xy 79.881124 -315.019667) (xy 79.858253 -315.063244) (xy 79.828688 -315.102588) (xy 79.793195 -315.13668)
			(xy 79.752692 -315.164636) (xy 79.70823 -315.185734) (xy 79.660959 -315.199426) (xy 79.612104 -315.205358)
			(xy 79.562929 -315.203377) (xy 79.51471 -315.193533) (xy 79.468694 -315.176081) (xy 79.426073 -315.151474)
			(xy 79.387952 -315.120349) (xy 79.355317 -315.083512) (xy 79.329014 -315.041916) (xy 79.309723 -314.99664)
			(xy 79.297946 -314.948856) (xy 79.293986 -314.899802) (xy 78.955138 -314.899802) (xy 78.954643 -314.924409)
			(xy 78.946748 -314.972986) (xy 78.931164 -315.019667) (xy 78.908293 -315.063244) (xy 78.878728 -315.102588)
			(xy 78.843235 -315.13668) (xy 78.802732 -315.164636) (xy 78.75827 -315.185734) (xy 78.710999 -315.199426)
			(xy 78.662144 -315.205358) (xy 78.612969 -315.203377) (xy 78.56475 -315.193533) (xy 78.518734 -315.176081)
			(xy 78.476113 -315.151474) (xy 78.437992 -315.120349) (xy 78.405357 -315.083512) (xy 78.379054 -315.041916)
			(xy 78.359763 -314.99664) (xy 78.347986 -314.948856) (xy 78.344026 -314.899802) (xy 78.005178 -314.899802)
			(xy 78.004683 -314.924409) (xy 77.996788 -314.972986) (xy 77.981204 -315.019667) (xy 77.958333 -315.063244)
			(xy 77.928768 -315.102588) (xy 77.893275 -315.13668) (xy 77.852772 -315.164636) (xy 77.80831 -315.185734)
			(xy 77.761039 -315.199426) (xy 77.712184 -315.205358) (xy 77.663009 -315.203377) (xy 77.61479 -315.193533)
			(xy 77.568774 -315.176081) (xy 77.526153 -315.151474) (xy 77.488032 -315.120349) (xy 77.455397 -315.083512)
			(xy 77.429094 -315.041916) (xy 77.409803 -314.99664) (xy 77.398026 -314.948856) (xy 77.394066 -314.899802)
			(xy 77.055218 -314.899802) (xy 77.054723 -314.924409) (xy 77.046828 -314.972986) (xy 77.031244 -315.019667)
			(xy 77.008373 -315.063244) (xy 76.978808 -315.102588) (xy 76.943315 -315.13668) (xy 76.902812 -315.164636)
			(xy 76.85835 -315.185734) (xy 76.811079 -315.199426) (xy 76.762224 -315.205358) (xy 76.713049 -315.203377)
			(xy 76.66483 -315.193533) (xy 76.618814 -315.176081) (xy 76.576193 -315.151474) (xy 76.538072 -315.120349)
			(xy 76.505437 -315.083512) (xy 76.479134 -315.041916) (xy 76.459843 -314.99664) (xy 76.448066 -314.948856)
			(xy 76.444106 -314.899802) (xy 76.105258 -314.899802) (xy 76.104763 -314.924409) (xy 76.096868 -314.972986)
			(xy 76.081284 -315.019667) (xy 76.058413 -315.063244) (xy 76.028848 -315.102588) (xy 75.993355 -315.13668)
			(xy 75.952852 -315.164636) (xy 75.90839 -315.185734) (xy 75.861119 -315.199426) (xy 75.812264 -315.205358)
			(xy 75.763089 -315.203377) (xy 75.71487 -315.193533) (xy 75.668854 -315.176081) (xy 75.626233 -315.151474)
			(xy 75.588112 -315.120349) (xy 75.555477 -315.083512) (xy 75.529174 -315.041916) (xy 75.509883 -314.99664)
			(xy 75.498106 -314.948856) (xy 75.494146 -314.899802) (xy 75.155858 -314.899802) (xy 75.151686 -314.950144)
			(xy 75.139285 -314.999114) (xy 75.118993 -315.045375) (xy 75.091362 -315.087665) (xy 75.057148 -315.124831)
			(xy 75.017283 -315.155858) (xy 74.972855 -315.1799) (xy 74.925076 -315.196301) (xy 74.875248 -315.204614)
			(xy 74.84999 -315.20511) (xy 74.836258 -315.204924) (xy 74.808911 -315.202376) (xy 74.79538 -315.20003)
			(xy 74.782934 -315.197744) (xy 74.759312 -315.20511) (xy 74.682096 -315.28258) (xy 74.67473 -315.306202)
			(xy 74.677016 -315.318648) (xy 74.678658 -315.327915) (xy 74.680945 -315.346597) (xy 74.681588 -315.355986)
			(xy 74.682378 -315.374668) (xy 74.679956 -315.411984) (xy 74.676762 -315.430408) (xy 74.676762 -315.43117)
			(xy 74.675313 -315.443341) (xy 74.6826 -315.466705) (xy 74.690732 -315.475874) (xy 74.749914 -315.53531)
			(xy 74.759116 -315.543542) (xy 74.782613 -315.550988) (xy 74.794872 -315.549534) (xy 74.795126 -315.549534)
			(xy 74.808721 -315.547187) (xy 74.836195 -315.544642) (xy 74.84999 -315.544454) (xy 74.875251 -315.544946)
			(xy 74.925085 -315.55326) (xy 74.972871 -315.569664) (xy 75.017305 -315.593709) (xy 75.057175 -315.62474)
			(xy 75.091394 -315.66191) (xy 75.119028 -315.704206) (xy 75.139323 -315.750473) (xy 75.151726 -315.79945)
			(xy 75.155895 -315.849762) (xy 75.494146 -315.849762) (xy 75.498106 -315.800708) (xy 75.509883 -315.752924)
			(xy 75.529174 -315.707648) (xy 75.555477 -315.666052) (xy 75.588112 -315.629215) (xy 75.626233 -315.59809)
			(xy 75.668854 -315.573483) (xy 75.71487 -315.556031) (xy 75.763089 -315.546187) (xy 75.812264 -315.544206)
			(xy 75.861119 -315.550138) (xy 75.90839 -315.56383) (xy 75.952852 -315.584928) (xy 75.993355 -315.612884)
			(xy 76.028848 -315.646976) (xy 76.058413 -315.68632) (xy 76.081284 -315.729897) (xy 76.096868 -315.776578)
			(xy 76.104763 -315.825155) (xy 76.105258 -315.849762) (xy 76.444106 -315.849762) (xy 76.448066 -315.800708)
			(xy 76.459843 -315.752924) (xy 76.479134 -315.707648) (xy 76.505437 -315.666052) (xy 76.538072 -315.629215)
			(xy 76.576193 -315.59809) (xy 76.618814 -315.573483) (xy 76.66483 -315.556031) (xy 76.713049 -315.546187)
			(xy 76.762224 -315.544206) (xy 76.811079 -315.550138) (xy 76.85835 -315.56383) (xy 76.902812 -315.584928)
			(xy 76.943315 -315.612884) (xy 76.978808 -315.646976) (xy 77.008373 -315.68632) (xy 77.031244 -315.729897)
			(xy 77.046828 -315.776578) (xy 77.054723 -315.825155) (xy 77.055218 -315.849762) (xy 77.394066 -315.849762)
			(xy 77.398026 -315.800708) (xy 77.409803 -315.752924) (xy 77.429094 -315.707648) (xy 77.455397 -315.666052)
			(xy 77.488032 -315.629215) (xy 77.526153 -315.59809) (xy 77.568774 -315.573483) (xy 77.61479 -315.556031)
			(xy 77.663009 -315.546187) (xy 77.712184 -315.544206) (xy 77.761039 -315.550138) (xy 77.80831 -315.56383)
			(xy 77.852772 -315.584928) (xy 77.893275 -315.612884) (xy 77.928768 -315.646976) (xy 77.958333 -315.68632)
			(xy 77.981204 -315.729897) (xy 77.996788 -315.776578) (xy 78.004683 -315.825155) (xy 78.005178 -315.849762)
			(xy 78.344026 -315.849762) (xy 78.347986 -315.800708) (xy 78.359763 -315.752924) (xy 78.379054 -315.707648)
			(xy 78.405357 -315.666052) (xy 78.437992 -315.629215) (xy 78.476113 -315.59809) (xy 78.518734 -315.573483)
			(xy 78.56475 -315.556031) (xy 78.612969 -315.546187) (xy 78.662144 -315.544206) (xy 78.710999 -315.550138)
			(xy 78.75827 -315.56383) (xy 78.802732 -315.584928) (xy 78.843235 -315.612884) (xy 78.878728 -315.646976)
			(xy 78.908293 -315.68632) (xy 78.931164 -315.729897) (xy 78.946748 -315.776578) (xy 78.954643 -315.825155)
			(xy 78.955138 -315.849762) (xy 79.293986 -315.849762) (xy 79.297946 -315.800708) (xy 79.309723 -315.752924)
			(xy 79.329014 -315.707648) (xy 79.355317 -315.666052) (xy 79.387952 -315.629215) (xy 79.426073 -315.59809)
			(xy 79.468694 -315.573483) (xy 79.51471 -315.556031) (xy 79.562929 -315.546187) (xy 79.612104 -315.544206)
			(xy 79.660959 -315.550138) (xy 79.70823 -315.56383) (xy 79.752692 -315.584928) (xy 79.793195 -315.612884)
			(xy 79.828688 -315.646976) (xy 79.858253 -315.68632) (xy 79.881124 -315.729897) (xy 79.896708 -315.776578)
			(xy 79.904603 -315.825155) (xy 79.905098 -315.849762) (xy 80.243946 -315.849762) (xy 80.247906 -315.800708)
			(xy 80.259683 -315.752924) (xy 80.278974 -315.707648) (xy 80.305277 -315.666052) (xy 80.337912 -315.629215)
			(xy 80.376033 -315.59809) (xy 80.418654 -315.573483) (xy 80.46467 -315.556031) (xy 80.512889 -315.546187)
			(xy 80.562064 -315.544206) (xy 80.610919 -315.550138) (xy 80.65819 -315.56383) (xy 80.702652 -315.584928)
			(xy 80.743155 -315.612884) (xy 80.778648 -315.646976) (xy 80.808213 -315.68632) (xy 80.831084 -315.729897)
			(xy 80.846668 -315.776578) (xy 80.854563 -315.825155) (xy 80.855058 -315.849762) (xy 81.19416 -315.849762)
			(xy 81.19812 -315.800708) (xy 81.209897 -315.752924) (xy 81.229188 -315.707648) (xy 81.255491 -315.666052)
			(xy 81.288126 -315.629215) (xy 81.326247 -315.59809) (xy 81.368868 -315.573483) (xy 81.414884 -315.556031)
			(xy 81.463103 -315.546187) (xy 81.512278 -315.544206) (xy 81.561133 -315.550138) (xy 81.608404 -315.56383)
			(xy 81.652866 -315.584928) (xy 81.693369 -315.612884) (xy 81.728862 -315.646976) (xy 81.758427 -315.68632)
			(xy 81.781298 -315.729897) (xy 81.796882 -315.776578) (xy 81.804777 -315.825155) (xy 81.805272 -315.849762)
			(xy 82.14412 -315.849762) (xy 82.14808 -315.800708) (xy 82.159857 -315.752924) (xy 82.179148 -315.707648)
			(xy 82.205451 -315.666052) (xy 82.238086 -315.629215) (xy 82.276207 -315.59809) (xy 82.318828 -315.573483)
			(xy 82.364844 -315.556031) (xy 82.413063 -315.546187) (xy 82.462238 -315.544206) (xy 82.511093 -315.550138)
			(xy 82.558364 -315.56383) (xy 82.602826 -315.584928) (xy 82.643329 -315.612884) (xy 82.678822 -315.646976)
			(xy 82.708387 -315.68632) (xy 82.731258 -315.729897) (xy 82.746842 -315.776578) (xy 82.754737 -315.825155)
			(xy 82.755232 -315.849762) (xy 82.754737 -315.874369) (xy 82.746842 -315.922946) (xy 82.731258 -315.969627)
			(xy 82.708387 -316.013204) (xy 82.678822 -316.052548) (xy 82.643329 -316.08664) (xy 82.602826 -316.114596)
			(xy 82.558364 -316.135694) (xy 82.511093 -316.149386) (xy 82.462238 -316.155318) (xy 82.413063 -316.153337)
			(xy 82.364844 -316.143493) (xy 82.318828 -316.126041) (xy 82.276207 -316.101434) (xy 82.238086 -316.070309)
			(xy 82.205451 -316.033472) (xy 82.179148 -315.991876) (xy 82.159857 -315.9466) (xy 82.14808 -315.898816)
			(xy 82.14412 -315.849762) (xy 81.805272 -315.849762) (xy 81.804777 -315.874369) (xy 81.796882 -315.922946)
			(xy 81.781298 -315.969627) (xy 81.758427 -316.013204) (xy 81.728862 -316.052548) (xy 81.693369 -316.08664)
			(xy 81.652866 -316.114596) (xy 81.608404 -316.135694) (xy 81.561133 -316.149386) (xy 81.512278 -316.155318)
			(xy 81.463103 -316.153337) (xy 81.414884 -316.143493) (xy 81.368868 -316.126041) (xy 81.326247 -316.101434)
			(xy 81.288126 -316.070309) (xy 81.255491 -316.033472) (xy 81.229188 -315.991876) (xy 81.209897 -315.9466)
			(xy 81.19812 -315.898816) (xy 81.19416 -315.849762) (xy 80.855058 -315.849762) (xy 80.854563 -315.874369)
			(xy 80.846668 -315.922946) (xy 80.831084 -315.969627) (xy 80.808213 -316.013204) (xy 80.778648 -316.052548)
			(xy 80.743155 -316.08664) (xy 80.702652 -316.114596) (xy 80.65819 -316.135694) (xy 80.610919 -316.149386)
			(xy 80.562064 -316.155318) (xy 80.512889 -316.153337) (xy 80.46467 -316.143493) (xy 80.418654 -316.126041)
			(xy 80.376033 -316.101434) (xy 80.337912 -316.070309) (xy 80.305277 -316.033472) (xy 80.278974 -315.991876)
			(xy 80.259683 -315.9466) (xy 80.247906 -315.898816) (xy 80.243946 -315.849762) (xy 79.905098 -315.849762)
			(xy 79.904603 -315.874369) (xy 79.896708 -315.922946) (xy 79.881124 -315.969627) (xy 79.858253 -316.013204)
			(xy 79.828688 -316.052548) (xy 79.793195 -316.08664) (xy 79.752692 -316.114596) (xy 79.70823 -316.135694)
			(xy 79.660959 -316.149386) (xy 79.612104 -316.155318) (xy 79.562929 -316.153337) (xy 79.51471 -316.143493)
			(xy 79.468694 -316.126041) (xy 79.426073 -316.101434) (xy 79.387952 -316.070309) (xy 79.355317 -316.033472)
			(xy 79.329014 -315.991876) (xy 79.309723 -315.9466) (xy 79.297946 -315.898816) (xy 79.293986 -315.849762)
			(xy 78.955138 -315.849762) (xy 78.954643 -315.874369) (xy 78.946748 -315.922946) (xy 78.931164 -315.969627)
			(xy 78.908293 -316.013204) (xy 78.878728 -316.052548) (xy 78.843235 -316.08664) (xy 78.802732 -316.114596)
			(xy 78.75827 -316.135694) (xy 78.710999 -316.149386) (xy 78.662144 -316.155318) (xy 78.612969 -316.153337)
			(xy 78.56475 -316.143493) (xy 78.518734 -316.126041) (xy 78.476113 -316.101434) (xy 78.437992 -316.070309)
			(xy 78.405357 -316.033472) (xy 78.379054 -315.991876) (xy 78.359763 -315.9466) (xy 78.347986 -315.898816)
			(xy 78.344026 -315.849762) (xy 78.005178 -315.849762) (xy 78.004683 -315.874369) (xy 77.996788 -315.922946)
			(xy 77.981204 -315.969627) (xy 77.958333 -316.013204) (xy 77.928768 -316.052548) (xy 77.893275 -316.08664)
			(xy 77.852772 -316.114596) (xy 77.80831 -316.135694) (xy 77.761039 -316.149386) (xy 77.712184 -316.155318)
			(xy 77.663009 -316.153337) (xy 77.61479 -316.143493) (xy 77.568774 -316.126041) (xy 77.526153 -316.101434)
			(xy 77.488032 -316.070309) (xy 77.455397 -316.033472) (xy 77.429094 -315.991876) (xy 77.409803 -315.9466)
			(xy 77.398026 -315.898816) (xy 77.394066 -315.849762) (xy 77.055218 -315.849762) (xy 77.054723 -315.874369)
			(xy 77.046828 -315.922946) (xy 77.031244 -315.969627) (xy 77.008373 -316.013204) (xy 76.978808 -316.052548)
			(xy 76.943315 -316.08664) (xy 76.902812 -316.114596) (xy 76.85835 -316.135694) (xy 76.811079 -316.149386)
			(xy 76.762224 -316.155318) (xy 76.713049 -316.153337) (xy 76.66483 -316.143493) (xy 76.618814 -316.126041)
			(xy 76.576193 -316.101434) (xy 76.538072 -316.070309) (xy 76.505437 -316.033472) (xy 76.479134 -315.991876)
			(xy 76.459843 -315.9466) (xy 76.448066 -315.898816) (xy 76.444106 -315.849762) (xy 76.105258 -315.849762)
			(xy 76.104763 -315.874369) (xy 76.096868 -315.922946) (xy 76.081284 -315.969627) (xy 76.058413 -316.013204)
			(xy 76.028848 -316.052548) (xy 75.993355 -316.08664) (xy 75.952852 -316.114596) (xy 75.90839 -316.135694)
			(xy 75.861119 -316.149386) (xy 75.812264 -316.155318) (xy 75.763089 -316.153337) (xy 75.71487 -316.143493)
			(xy 75.668854 -316.126041) (xy 75.626233 -316.101434) (xy 75.588112 -316.070309) (xy 75.555477 -316.033472)
			(xy 75.529174 -315.991876) (xy 75.509883 -315.9466) (xy 75.498106 -315.898816) (xy 75.494146 -315.849762)
			(xy 75.155895 -315.849762) (xy 75.155898 -315.8498) (xy 75.151726 -315.90015) (xy 75.139323 -315.949127)
			(xy 75.119028 -315.995394) (xy 75.091394 -316.03769) (xy 75.057175 -316.07486) (xy 75.017305 -316.105891)
			(xy 74.972871 -316.129936) (xy 74.925085 -316.14634) (xy 74.875251 -316.154654) (xy 74.84999 -316.15507)
			(xy 74.849482 -316.15507) (xy 74.823426 -316.154503) (xy 74.772085 -316.145571) (xy 74.747374 -316.13729)
			(xy 74.738076 -316.134387) (xy 74.718626 -316.135063) (xy 74.700831 -316.142945) (xy 74.687259 -316.156894)
			(xy 74.679868 -316.174898) (xy 74.679724 -316.19436) (xy 74.682858 -316.203584) (xy 74.685144 -316.20968)
			(xy 74.686414 -316.213236) (xy 74.695492 -316.240217) (xy 74.705331 -316.296282) (xy 74.705972 -316.324742)
			(xy 74.705972 -316.3951) (xy 74.706431 -316.40576) (xy 74.71511 -316.42523) (xy 74.722736 -316.432692)
			(xy 74.77887 -316.483492) (xy 74.782929 -316.48691) (xy 74.792147 -316.492162) (xy 74.797158 -316.493906)
			(xy 74.807318 -316.497208) (xy 74.81824 -316.496192) (xy 74.84999 -316.494414) (xy 74.875246 -316.494906)
			(xy 74.925071 -316.503218) (xy 74.972847 -316.519619) (xy 75.017272 -316.543659) (xy 75.057135 -316.574684)
			(xy 75.091347 -316.611847) (xy 75.118975 -316.654134) (xy 75.139266 -316.700393) (xy 75.151667 -316.74936)
			(xy 75.155838 -316.7997) (xy 75.155836 -316.799722) (xy 75.494146 -316.799722) (xy 75.498106 -316.750668)
			(xy 75.509883 -316.702884) (xy 75.529174 -316.657608) (xy 75.555477 -316.616012) (xy 75.588112 -316.579175)
			(xy 75.626233 -316.54805) (xy 75.668854 -316.523443) (xy 75.71487 -316.505991) (xy 75.763089 -316.496147)
			(xy 75.812264 -316.494166) (xy 75.861119 -316.500098) (xy 75.90839 -316.51379) (xy 75.952852 -316.534888)
			(xy 75.993355 -316.562844) (xy 76.028848 -316.596936) (xy 76.058413 -316.63628) (xy 76.081284 -316.679857)
			(xy 76.096868 -316.726538) (xy 76.104763 -316.775115) (xy 76.105258 -316.799722) (xy 76.444106 -316.799722)
			(xy 76.448066 -316.750668) (xy 76.459843 -316.702884) (xy 76.479134 -316.657608) (xy 76.505437 -316.616012)
			(xy 76.538072 -316.579175) (xy 76.576193 -316.54805) (xy 76.618814 -316.523443) (xy 76.66483 -316.505991)
			(xy 76.713049 -316.496147) (xy 76.762224 -316.494166) (xy 76.811079 -316.500098) (xy 76.85835 -316.51379)
			(xy 76.902812 -316.534888) (xy 76.943315 -316.562844) (xy 76.978808 -316.596936) (xy 77.008373 -316.63628)
			(xy 77.031244 -316.679857) (xy 77.046828 -316.726538) (xy 77.054723 -316.775115) (xy 77.055218 -316.799722)
			(xy 77.394066 -316.799722) (xy 77.398026 -316.750668) (xy 77.409803 -316.702884) (xy 77.429094 -316.657608)
			(xy 77.455397 -316.616012) (xy 77.488032 -316.579175) (xy 77.526153 -316.54805) (xy 77.568774 -316.523443)
			(xy 77.61479 -316.505991) (xy 77.663009 -316.496147) (xy 77.712184 -316.494166) (xy 77.761039 -316.500098)
			(xy 77.80831 -316.51379) (xy 77.852772 -316.534888) (xy 77.893275 -316.562844) (xy 77.928768 -316.596936)
			(xy 77.958333 -316.63628) (xy 77.981204 -316.679857) (xy 77.996788 -316.726538) (xy 78.004683 -316.775115)
			(xy 78.005178 -316.799722) (xy 78.344026 -316.799722) (xy 78.347986 -316.750668) (xy 78.359763 -316.702884)
			(xy 78.379054 -316.657608) (xy 78.405357 -316.616012) (xy 78.437992 -316.579175) (xy 78.476113 -316.54805)
			(xy 78.518734 -316.523443) (xy 78.56475 -316.505991) (xy 78.612969 -316.496147) (xy 78.662144 -316.494166)
			(xy 78.710999 -316.500098) (xy 78.75827 -316.51379) (xy 78.802732 -316.534888) (xy 78.843235 -316.562844)
			(xy 78.878728 -316.596936) (xy 78.908293 -316.63628) (xy 78.931164 -316.679857) (xy 78.946748 -316.726538)
			(xy 78.954643 -316.775115) (xy 78.955138 -316.799722) (xy 79.293986 -316.799722) (xy 79.297946 -316.750668)
			(xy 79.309723 -316.702884) (xy 79.329014 -316.657608) (xy 79.355317 -316.616012) (xy 79.387952 -316.579175)
			(xy 79.426073 -316.54805) (xy 79.468694 -316.523443) (xy 79.51471 -316.505991) (xy 79.562929 -316.496147)
			(xy 79.612104 -316.494166) (xy 79.660959 -316.500098) (xy 79.70823 -316.51379) (xy 79.752692 -316.534888)
			(xy 79.793195 -316.562844) (xy 79.828688 -316.596936) (xy 79.858253 -316.63628) (xy 79.881124 -316.679857)
			(xy 79.896708 -316.726538) (xy 79.904603 -316.775115) (xy 79.905098 -316.799722) (xy 80.243946 -316.799722)
			(xy 80.247906 -316.750668) (xy 80.259683 -316.702884) (xy 80.278974 -316.657608) (xy 80.305277 -316.616012)
			(xy 80.337912 -316.579175) (xy 80.376033 -316.54805) (xy 80.418654 -316.523443) (xy 80.46467 -316.505991)
			(xy 80.512889 -316.496147) (xy 80.562064 -316.494166) (xy 80.610919 -316.500098) (xy 80.65819 -316.51379)
			(xy 80.702652 -316.534888) (xy 80.743155 -316.562844) (xy 80.778648 -316.596936) (xy 80.808213 -316.63628)
			(xy 80.831084 -316.679857) (xy 80.846668 -316.726538) (xy 80.854563 -316.775115) (xy 80.855058 -316.799722)
			(xy 81.19416 -316.799722) (xy 81.19812 -316.750668) (xy 81.209897 -316.702884) (xy 81.229188 -316.657608)
			(xy 81.255491 -316.616012) (xy 81.288126 -316.579175) (xy 81.326247 -316.54805) (xy 81.368868 -316.523443)
			(xy 81.414884 -316.505991) (xy 81.463103 -316.496147) (xy 81.512278 -316.494166) (xy 81.561133 -316.500098)
			(xy 81.608404 -316.51379) (xy 81.652866 -316.534888) (xy 81.693369 -316.562844) (xy 81.728862 -316.596936)
			(xy 81.758427 -316.63628) (xy 81.781298 -316.679857) (xy 81.796882 -316.726538) (xy 81.804777 -316.775115)
			(xy 81.805272 -316.799722) (xy 82.14412 -316.799722) (xy 82.14808 -316.750668) (xy 82.159857 -316.702884)
			(xy 82.179148 -316.657608) (xy 82.205451 -316.616012) (xy 82.238086 -316.579175) (xy 82.276207 -316.54805)
			(xy 82.318828 -316.523443) (xy 82.364844 -316.505991) (xy 82.413063 -316.496147) (xy 82.462238 -316.494166)
			(xy 82.511093 -316.500098) (xy 82.558364 -316.51379) (xy 82.602826 -316.534888) (xy 82.643329 -316.562844)
			(xy 82.678822 -316.596936) (xy 82.708387 -316.63628) (xy 82.731258 -316.679857) (xy 82.746842 -316.726538)
			(xy 82.754737 -316.775115) (xy 82.755232 -316.799722) (xy 83.094334 -316.799722) (xy 83.098294 -316.750668)
			(xy 83.110071 -316.702884) (xy 83.129362 -316.657608) (xy 83.155665 -316.616012) (xy 83.1883 -316.579175)
			(xy 83.226421 -316.54805) (xy 83.269042 -316.523443) (xy 83.315058 -316.505991) (xy 83.363277 -316.496147)
			(xy 83.412452 -316.494166) (xy 83.461307 -316.500098) (xy 83.508578 -316.51379) (xy 83.55304 -316.534888)
			(xy 83.593543 -316.562844) (xy 83.629036 -316.596936) (xy 83.658601 -316.63628) (xy 83.681472 -316.679857)
			(xy 83.697056 -316.726538) (xy 83.704951 -316.775115) (xy 83.705446 -316.799722) (xy 83.704951 -316.824329)
			(xy 83.697056 -316.872906) (xy 83.681472 -316.919587) (xy 83.658601 -316.963164) (xy 83.629036 -317.002508)
			(xy 83.593543 -317.0366) (xy 83.55304 -317.064556) (xy 83.508578 -317.085654) (xy 83.461307 -317.099346)
			(xy 83.412452 -317.105278) (xy 83.363277 -317.103297) (xy 83.315058 -317.093453) (xy 83.269042 -317.076001)
			(xy 83.226421 -317.051394) (xy 83.1883 -317.020269) (xy 83.155665 -316.983432) (xy 83.129362 -316.941836)
			(xy 83.110071 -316.89656) (xy 83.098294 -316.848776) (xy 83.094334 -316.799722) (xy 82.755232 -316.799722)
			(xy 82.754737 -316.824329) (xy 82.746842 -316.872906) (xy 82.731258 -316.919587) (xy 82.708387 -316.963164)
			(xy 82.678822 -317.002508) (xy 82.643329 -317.0366) (xy 82.602826 -317.064556) (xy 82.558364 -317.085654)
			(xy 82.511093 -317.099346) (xy 82.462238 -317.105278) (xy 82.413063 -317.103297) (xy 82.364844 -317.093453)
			(xy 82.318828 -317.076001) (xy 82.276207 -317.051394) (xy 82.238086 -317.020269) (xy 82.205451 -316.983432)
			(xy 82.179148 -316.941836) (xy 82.159857 -316.89656) (xy 82.14808 -316.848776) (xy 82.14412 -316.799722)
			(xy 81.805272 -316.799722) (xy 81.804777 -316.824329) (xy 81.796882 -316.872906) (xy 81.781298 -316.919587)
			(xy 81.758427 -316.963164) (xy 81.728862 -317.002508) (xy 81.693369 -317.0366) (xy 81.652866 -317.064556)
			(xy 81.608404 -317.085654) (xy 81.561133 -317.099346) (xy 81.512278 -317.105278) (xy 81.463103 -317.103297)
			(xy 81.414884 -317.093453) (xy 81.368868 -317.076001) (xy 81.326247 -317.051394) (xy 81.288126 -317.020269)
			(xy 81.255491 -316.983432) (xy 81.229188 -316.941836) (xy 81.209897 -316.89656) (xy 81.19812 -316.848776)
			(xy 81.19416 -316.799722) (xy 80.855058 -316.799722) (xy 80.854563 -316.824329) (xy 80.846668 -316.872906)
			(xy 80.831084 -316.919587) (xy 80.808213 -316.963164) (xy 80.778648 -317.002508) (xy 80.743155 -317.0366)
			(xy 80.702652 -317.064556) (xy 80.65819 -317.085654) (xy 80.610919 -317.099346) (xy 80.562064 -317.105278)
			(xy 80.512889 -317.103297) (xy 80.46467 -317.093453) (xy 80.418654 -317.076001) (xy 80.376033 -317.051394)
			(xy 80.337912 -317.020269) (xy 80.305277 -316.983432) (xy 80.278974 -316.941836) (xy 80.259683 -316.89656)
			(xy 80.247906 -316.848776) (xy 80.243946 -316.799722) (xy 79.905098 -316.799722) (xy 79.904603 -316.824329)
			(xy 79.896708 -316.872906) (xy 79.881124 -316.919587) (xy 79.858253 -316.963164) (xy 79.828688 -317.002508)
			(xy 79.793195 -317.0366) (xy 79.752692 -317.064556) (xy 79.70823 -317.085654) (xy 79.660959 -317.099346)
			(xy 79.612104 -317.105278) (xy 79.562929 -317.103297) (xy 79.51471 -317.093453) (xy 79.468694 -317.076001)
			(xy 79.426073 -317.051394) (xy 79.387952 -317.020269) (xy 79.355317 -316.983432) (xy 79.329014 -316.941836)
			(xy 79.309723 -316.89656) (xy 79.297946 -316.848776) (xy 79.293986 -316.799722) (xy 78.955138 -316.799722)
			(xy 78.954643 -316.824329) (xy 78.946748 -316.872906) (xy 78.931164 -316.919587) (xy 78.908293 -316.963164)
			(xy 78.878728 -317.002508) (xy 78.843235 -317.0366) (xy 78.802732 -317.064556) (xy 78.75827 -317.085654)
			(xy 78.710999 -317.099346) (xy 78.662144 -317.105278) (xy 78.612969 -317.103297) (xy 78.56475 -317.093453)
			(xy 78.518734 -317.076001) (xy 78.476113 -317.051394) (xy 78.437992 -317.020269) (xy 78.405357 -316.983432)
			(xy 78.379054 -316.941836) (xy 78.359763 -316.89656) (xy 78.347986 -316.848776) (xy 78.344026 -316.799722)
			(xy 78.005178 -316.799722) (xy 78.004683 -316.824329) (xy 77.996788 -316.872906) (xy 77.981204 -316.919587)
			(xy 77.958333 -316.963164) (xy 77.928768 -317.002508) (xy 77.893275 -317.0366) (xy 77.852772 -317.064556)
			(xy 77.80831 -317.085654) (xy 77.761039 -317.099346) (xy 77.712184 -317.105278) (xy 77.663009 -317.103297)
			(xy 77.61479 -317.093453) (xy 77.568774 -317.076001) (xy 77.526153 -317.051394) (xy 77.488032 -317.020269)
			(xy 77.455397 -316.983432) (xy 77.429094 -316.941836) (xy 77.409803 -316.89656) (xy 77.398026 -316.848776)
			(xy 77.394066 -316.799722) (xy 77.055218 -316.799722) (xy 77.054723 -316.824329) (xy 77.046828 -316.872906)
			(xy 77.031244 -316.919587) (xy 77.008373 -316.963164) (xy 76.978808 -317.002508) (xy 76.943315 -317.0366)
			(xy 76.902812 -317.064556) (xy 76.85835 -317.085654) (xy 76.811079 -317.099346) (xy 76.762224 -317.105278)
			(xy 76.713049 -317.103297) (xy 76.66483 -317.093453) (xy 76.618814 -317.076001) (xy 76.576193 -317.051394)
			(xy 76.538072 -317.020269) (xy 76.505437 -316.983432) (xy 76.479134 -316.941836) (xy 76.459843 -316.89656)
			(xy 76.448066 -316.848776) (xy 76.444106 -316.799722) (xy 76.105258 -316.799722) (xy 76.104763 -316.824329)
			(xy 76.096868 -316.872906) (xy 76.081284 -316.919587) (xy 76.058413 -316.963164) (xy 76.028848 -317.002508)
			(xy 75.993355 -317.0366) (xy 75.952852 -317.064556) (xy 75.90839 -317.085654) (xy 75.861119 -317.099346)
			(xy 75.812264 -317.105278) (xy 75.763089 -317.103297) (xy 75.71487 -317.093453) (xy 75.668854 -317.076001)
			(xy 75.626233 -317.051394) (xy 75.588112 -317.020269) (xy 75.555477 -316.983432) (xy 75.529174 -316.941836)
			(xy 75.509883 -316.89656) (xy 75.498106 -316.848776) (xy 75.494146 -316.799722) (xy 75.155836 -316.799722)
			(xy 75.151667 -316.85004) (xy 75.139266 -316.899007) (xy 75.118975 -316.945266) (xy 75.091347 -316.987553)
			(xy 75.057135 -317.024716) (xy 75.017272 -317.055741) (xy 74.972847 -317.079781) (xy 74.925071 -317.096182)
			(xy 74.875246 -317.104494) (xy 74.84999 -317.10503) (xy 74.81824 -317.103252) (xy 74.807318 -317.102236)
			(xy 74.797158 -317.105538) (xy 74.792147 -317.107282) (xy 74.782929 -317.112534) (xy 74.77887 -317.115952)
			(xy 74.722736 -317.166752) (xy 74.71522 -317.174294) (xy 74.706543 -317.193713) (xy 74.705972 -317.204344)
			(xy 74.705972 -317.274702) (xy 74.705809 -317.288356) (xy 74.703516 -317.315568) (xy 74.7014 -317.329058)
			(xy 74.699368 -317.34125) (xy 74.70648 -317.363602) (xy 74.770996 -317.43142) (xy 74.778417 -317.438548)
			(xy 74.797294 -317.446688) (xy 74.807572 -317.447168) (xy 74.811128 -317.447168) (xy 74.8208 -317.445985)
			(xy 74.840246 -317.444712) (xy 74.84999 -317.444628) (xy 74.873983 -317.445073) (xy 74.921377 -317.452579)
			(xy 74.967014 -317.467407) (xy 75.009769 -317.489193) (xy 75.048589 -317.517399) (xy 75.082518 -317.551331)
			(xy 75.110721 -317.590153) (xy 75.132503 -317.63291) (xy 75.147327 -317.678548) (xy 75.154829 -317.725943)
			(xy 75.155298 -317.749936) (xy 75.154753 -317.776117) (xy 75.145805 -317.82771) (xy 75.137518 -317.852552)
			(xy 75.131676 -317.868554) (xy 75.141328 -317.900304) (xy 75.15479 -317.910464) (xy 75.161946 -317.915387)
			(xy 75.178514 -317.920559) (xy 75.195858 -317.919912) (xy 75.204066 -317.917068) (xy 75.227688 -317.908686)
			(xy 75.252227 -317.901634) (xy 75.302755 -317.894302) (xy 75.353809 -317.894825) (xy 75.379072 -317.898526)
			(xy 75.39101 -317.900558) (xy 75.413616 -317.8937) (xy 75.49007 -317.820802) (xy 75.498198 -317.79845)
			(xy 75.496674 -317.786512) (xy 75.495678 -317.777401) (xy 75.49466 -317.759101) (xy 75.494642 -317.749936)
			(xy 75.495164 -317.724681) (xy 75.503477 -317.674859) (xy 75.519878 -317.627085) (xy 75.543919 -317.582662)
			(xy 75.574943 -317.542802) (xy 75.612105 -317.508592) (xy 75.654391 -317.480966) (xy 75.700647 -317.460676)
			(xy 75.749612 -317.448276) (xy 75.79995 -317.444105) (xy 75.850288 -317.448276) (xy 75.899253 -317.460676)
			(xy 75.945509 -317.480966) (xy 75.987795 -317.508592) (xy 76.024957 -317.542802) (xy 76.055981 -317.582662)
			(xy 76.080022 -317.627085) (xy 76.096423 -317.674859) (xy 76.104736 -317.724681) (xy 76.105258 -317.749936)
			(xy 76.105059 -317.764055) (xy 76.102388 -317.792166) (xy 76.099924 -317.80607) (xy 76.097638 -317.818516)
			(xy 76.10475 -317.842138) (xy 76.181966 -317.919608) (xy 76.205588 -317.926974) (xy 76.218288 -317.924688)
			(xy 76.23226 -317.922283) (xy 76.260499 -317.91974) (xy 76.274676 -317.919608) (xy 76.27493 -317.919608)
			(xy 76.289049 -317.919807) (xy 76.317161 -317.922477) (xy 76.331064 -317.924942) (xy 76.34351 -317.927228)
			(xy 76.367386 -317.919862) (xy 76.444856 -317.842392) (xy 76.452222 -317.818516) (xy 76.449936 -317.80607)
			(xy 76.44746 -317.792168) (xy 76.44479 -317.764055) (xy 76.444602 -317.749936) (xy 76.445124 -317.724681)
			(xy 76.453437 -317.674859) (xy 76.469838 -317.627085) (xy 76.493879 -317.582662) (xy 76.524903 -317.542802)
			(xy 76.562065 -317.508592) (xy 76.604351 -317.480966) (xy 76.650607 -317.460676) (xy 76.699572 -317.448276)
			(xy 76.74991 -317.444105) (xy 76.800248 -317.448276) (xy 76.849213 -317.460676) (xy 76.895469 -317.480966)
			(xy 76.937755 -317.508592) (xy 76.974917 -317.542802) (xy 77.005941 -317.582662) (xy 77.029982 -317.627085)
			(xy 77.046383 -317.674859) (xy 77.054696 -317.724681) (xy 77.055218 -317.749936) (xy 77.054673 -317.776117)
			(xy 77.045725 -317.82771) (xy 77.037438 -317.852552) (xy 77.031596 -317.868554) (xy 77.041248 -317.900304)
			(xy 77.05471 -317.910464) (xy 77.061864 -317.915399) (xy 77.078438 -317.920598) (xy 77.095796 -317.919974)
			(xy 77.103986 -317.917068) (xy 77.127608 -317.908686) (xy 77.152147 -317.901635) (xy 77.202675 -317.894307)
			(xy 77.253728 -317.894833) (xy 77.278992 -317.898526) (xy 77.29093 -317.900558) (xy 77.313536 -317.8937)
			(xy 77.38999 -317.820802) (xy 77.398118 -317.79845) (xy 77.396594 -317.786512) (xy 77.395599 -317.777401)
			(xy 77.39458 -317.759101) (xy 77.394562 -317.749936) (xy 77.395084 -317.724681) (xy 77.403397 -317.674859)
			(xy 77.419798 -317.627085) (xy 77.443839 -317.582662) (xy 77.474863 -317.542802) (xy 77.512025 -317.508592)
			(xy 77.554311 -317.480966) (xy 77.600567 -317.460676) (xy 77.649532 -317.448276) (xy 77.69987 -317.444105)
			(xy 77.750208 -317.448276) (xy 77.799173 -317.460676) (xy 77.845429 -317.480966) (xy 77.887715 -317.508592)
			(xy 77.924877 -317.542802) (xy 77.955901 -317.582662) (xy 77.979942 -317.627085) (xy 77.996343 -317.674859)
			(xy 78.004656 -317.724681) (xy 78.005178 -317.749936) (xy 78.004979 -317.764055) (xy 78.002308 -317.792167)
			(xy 77.999844 -317.80607) (xy 77.997558 -317.818516) (xy 78.00467 -317.842138) (xy 78.081886 -317.919608)
			(xy 78.105508 -317.926974) (xy 78.118208 -317.924688) (xy 78.13218 -317.922284) (xy 78.160419 -317.919743)
			(xy 78.174596 -317.919608) (xy 78.17485 -317.919608) (xy 78.188969 -317.919808) (xy 78.21708 -317.92248)
			(xy 78.230984 -317.924942) (xy 78.24343 -317.927228) (xy 78.267306 -317.919862) (xy 78.344776 -317.842392)
			(xy 78.352142 -317.818516) (xy 78.349856 -317.80607) (xy 78.347381 -317.792168) (xy 78.344711 -317.764055)
			(xy 78.344522 -317.749936) (xy 78.345044 -317.724681) (xy 78.353357 -317.674859) (xy 78.369758 -317.627085)
			(xy 78.393799 -317.582662) (xy 78.424823 -317.542802) (xy 78.461985 -317.508592) (xy 78.504271 -317.480966)
			(xy 78.550527 -317.460676) (xy 78.599492 -317.448276) (xy 78.64983 -317.444105) (xy 78.700168 -317.448276)
			(xy 78.749133 -317.460676) (xy 78.795389 -317.480966) (xy 78.837675 -317.508592) (xy 78.874837 -317.542802)
			(xy 78.905861 -317.582662) (xy 78.929902 -317.627085) (xy 78.946303 -317.674859) (xy 78.954616 -317.724681)
			(xy 78.955138 -317.749936) (xy 78.954594 -317.776118) (xy 78.945646 -317.827711) (xy 78.937358 -317.852552)
			(xy 78.931516 -317.868554) (xy 78.941168 -317.900304) (xy 78.95463 -317.910464) (xy 78.961785 -317.915396)
			(xy 78.978357 -317.920588) (xy 78.995712 -317.919959) (xy 79.003906 -317.917068) (xy 79.027528 -317.908686)
			(xy 79.052067 -317.901629) (xy 79.102595 -317.894288) (xy 79.153651 -317.894802) (xy 79.178912 -317.898526)
			(xy 79.19085 -317.900558) (xy 79.213456 -317.8937) (xy 79.28991 -317.820802) (xy 79.298038 -317.79845)
			(xy 79.296514 -317.786512) (xy 79.295519 -317.777401) (xy 79.2945 -317.759101) (xy 79.294482 -317.749936)
			(xy 79.295004 -317.724681) (xy 79.303317 -317.674859) (xy 79.319718 -317.627085) (xy 79.343759 -317.582662)
			(xy 79.374783 -317.542802) (xy 79.411945 -317.508592) (xy 79.454231 -317.480966) (xy 79.500487 -317.460676)
			(xy 79.549452 -317.448276) (xy 79.59979 -317.444105) (xy 79.650128 -317.448276) (xy 79.699093 -317.460676)
			(xy 79.745349 -317.480966) (xy 79.787635 -317.508592) (xy 79.824797 -317.542802) (xy 79.855821 -317.582662)
			(xy 79.879862 -317.627085) (xy 79.896263 -317.674859) (xy 79.904576 -317.724681) (xy 79.905098 -317.749936)
			(xy 79.904899 -317.764055) (xy 79.902228 -317.792167) (xy 79.899764 -317.80607) (xy 79.897478 -317.818516)
			(xy 79.90459 -317.842138) (xy 79.981806 -317.919608) (xy 80.005428 -317.926974) (xy 80.018128 -317.924688)
			(xy 80.0321 -317.922285) (xy 80.060339 -317.919746) (xy 80.074516 -317.919608) (xy 80.07477 -317.919608)
			(xy 80.088889 -317.919809) (xy 80.117 -317.922483) (xy 80.130904 -317.924942) (xy 80.14335 -317.927228)
			(xy 80.167226 -317.919862) (xy 80.244696 -317.842392) (xy 80.252062 -317.818516) (xy 80.249776 -317.80607)
			(xy 80.247301 -317.792168) (xy 80.244631 -317.764055) (xy 80.244442 -317.749936) (xy 80.244964 -317.724681)
			(xy 80.253277 -317.674859) (xy 80.269678 -317.627085) (xy 80.293719 -317.582662) (xy 80.324743 -317.542802)
			(xy 80.361905 -317.508592) (xy 80.404191 -317.480966) (xy 80.450447 -317.460676) (xy 80.499412 -317.448276)
			(xy 80.54975 -317.444105) (xy 80.600088 -317.448276) (xy 80.649053 -317.460676) (xy 80.695309 -317.480966)
			(xy 80.737595 -317.508592) (xy 80.774757 -317.542802) (xy 80.805781 -317.582662) (xy 80.829822 -317.627085)
			(xy 80.846223 -317.674859) (xy 80.854536 -317.724681) (xy 80.855058 -317.749936) (xy 80.854514 -317.776118)
			(xy 80.845567 -317.827711) (xy 80.837278 -317.852552) (xy 80.831436 -317.868554) (xy 80.841088 -317.900304)
			(xy 80.85455 -317.910464) (xy 80.861705 -317.915393) (xy 80.878276 -317.920579) (xy 80.895627 -317.919943)
			(xy 80.903826 -317.917068) (xy 80.927448 -317.908686) (xy 80.940743 -317.904784) (xy 80.967829 -317.898933)
			(xy 80.98155 -317.897002) (xy 81.026254 -317.893954) (xy 81.039526 -317.894168) (xy 81.065974 -317.896457)
			(xy 81.079086 -317.898526) (xy 81.091278 -317.900558) (xy 81.11363 -317.893446) (xy 81.181448 -317.82893)
			(xy 81.188561 -317.821503) (xy 81.196669 -317.802626) (xy 81.197196 -317.792354) (xy 81.197196 -317.789052)
			(xy 81.196942 -317.786004) (xy 81.195902 -317.777023) (xy 81.194761 -317.758977) (xy 81.194656 -317.749936)
			(xy 81.195178 -317.724681) (xy 81.203491 -317.674859) (xy 81.219892 -317.627085) (xy 81.243933 -317.582662)
			(xy 81.274957 -317.542802) (xy 81.312119 -317.508592) (xy 81.354405 -317.480966) (xy 81.400661 -317.460676)
			(xy 81.449626 -317.448276) (xy 81.499964 -317.444105) (xy 81.550302 -317.448276) (xy 81.599267 -317.460676)
			(xy 81.645523 -317.480966) (xy 81.687809 -317.508592) (xy 81.724971 -317.542802) (xy 81.755995 -317.582662)
			(xy 81.780036 -317.627085) (xy 81.796437 -317.674859) (xy 81.80475 -317.724681) (xy 81.805272 -317.749936)
			(xy 81.805073 -317.764055) (xy 81.802402 -317.792167) (xy 81.799938 -317.80607) (xy 81.797652 -317.818516)
			(xy 81.804764 -317.842138) (xy 81.88198 -317.919608) (xy 81.905602 -317.926974) (xy 81.918302 -317.924688)
			(xy 81.932274 -317.922284) (xy 81.960513 -317.919742) (xy 81.97469 -317.919608) (xy 81.974944 -317.919608)
			(xy 81.989063 -317.919808) (xy 82.017174 -317.922479) (xy 82.031078 -317.924942) (xy 82.043524 -317.927228)
			(xy 82.0674 -317.919862) (xy 82.14487 -317.842392) (xy 82.152236 -317.818516) (xy 82.14995 -317.80607)
			(xy 82.147475 -317.792168) (xy 82.144806 -317.764055) (xy 82.144616 -317.749936) (xy 82.145138 -317.724681)
			(xy 82.153451 -317.674859) (xy 82.169852 -317.627085) (xy 82.193893 -317.582662) (xy 82.224917 -317.542802)
			(xy 82.262079 -317.508592) (xy 82.304365 -317.480966) (xy 82.350621 -317.460676) (xy 82.399586 -317.448276)
			(xy 82.449924 -317.444105) (xy 82.500262 -317.448276) (xy 82.549227 -317.460676) (xy 82.595483 -317.480966)
			(xy 82.637769 -317.508592) (xy 82.674931 -317.542802) (xy 82.705955 -317.582662) (xy 82.729996 -317.627085)
			(xy 82.746397 -317.674859) (xy 82.75471 -317.724681) (xy 82.755232 -317.749936) (xy 82.755122 -317.758913)
			(xy 82.753978 -317.776832) (xy 82.752946 -317.78575) (xy 82.752946 -317.78702) (xy 82.752299 -317.798623)
			(xy 82.760256 -317.820432) (xy 82.768186 -317.82893) (xy 82.83575 -317.893446) (xy 82.858356 -317.900558)
			(xy 82.870548 -317.898526) (xy 82.887879 -317.895885) (xy 82.922878 -317.893849) (xy 82.940398 -317.894462)
			(xy 82.964835 -317.896028) (xy 83.012883 -317.905464) (xy 83.059015 -317.92188) (xy 83.102223 -317.944917)
			(xy 83.141563 -317.974073) (xy 83.176176 -318.008709) (xy 83.205304 -318.048069) (xy 83.228311 -318.091293)
			(xy 83.244696 -318.137436) (xy 83.254099 -318.18549) (xy 83.255612 -318.20993) (xy 83.25612 -318.219836)
			(xy 83.263994 -318.237362) (xy 83.314032 -318.285622) (xy 83.315048 -318.286384) (xy 83.322922 -318.293496)
			(xy 83.330094 -318.29955) (xy 83.34758 -318.306336) (xy 83.356958 -318.306704) (xy 84.465922 -318.306704)
		)
		(stroke
			(width 0)
			(type solid)
		)
		(fill yes)
		(layer "In7.Cu")
		(net "P0V8_PEX0")
	)
	(gr_poly
		(pts
			(xy 316.671452 -318.30645) (xy 316.671706 -318.30645) (xy 316.680272 -318.305162) (xy 316.695862 -318.297637)
			(xy 316.702186 -318.291718) (xy 319.070482 -315.923422) (xy 319.077884 -315.916586) (xy 319.096482 -315.908878)
			(xy 319.10655 -315.908436) (xy 325.482966 -315.908436) (xy 325.49303 -315.908872) (xy 325.511614 -315.916607)
			(xy 325.519034 -315.923422) (xy 326.002396 -316.406784) (xy 331.6384 -316.406784) (xy 331.642471 -316.351162)
			(xy 331.654597 -316.296725) (xy 331.67452 -316.244634) (xy 331.701816 -316.195999) (xy 331.735902 -316.151856)
			(xy 331.776051 -316.113147) (xy 331.821409 -316.080696) (xy 331.871009 -316.055195) (xy 331.923793 -316.037188)
			(xy 331.978636 -316.027058) (xy 332.03437 -316.025021) (xy 332.089807 -316.031121) (xy 332.143764 -316.045227)
			(xy 332.195093 -316.067039) (xy 332.242699 -316.096093) (xy 332.285567 -316.131768) (xy 332.322784 -316.173305)
			(xy 332.353557 -316.219818) (xy 332.377229 -316.270315) (xy 332.393297 -316.323722) (xy 332.401417 -316.378898)
			(xy 332.401926 -316.406784) (xy 332.401417 -316.43467) (xy 332.393297 -316.489846) (xy 332.377229 -316.543253)
			(xy 332.353557 -316.59375) (xy 332.322784 -316.640263) (xy 332.285567 -316.6818) (xy 332.242699 -316.717475)
			(xy 332.195093 -316.746529) (xy 332.143764 -316.768341) (xy 332.089807 -316.782447) (xy 332.03437 -316.788547)
			(xy 331.978636 -316.78651) (xy 331.923793 -316.77638) (xy 331.871009 -316.758373) (xy 331.821409 -316.732872)
			(xy 331.776051 -316.700421) (xy 331.735902 -316.661712) (xy 331.701816 -316.617569) (xy 331.67452 -316.568934)
			(xy 331.654597 -316.516843) (xy 331.642471 -316.462406) (xy 331.6384 -316.406784) (xy 326.002396 -316.406784)
			(xy 327.261728 -317.666116) (xy 327.268192 -317.672162) (xy 327.284194 -317.6797) (xy 327.29297 -317.680848)
			(xy 327.29551 -317.681102) (xy 349.448374 -317.681102) (xy 349.476822 -317.656464) (xy 349.479616 -317.637668)
			(xy 349.484043 -317.610833) (xy 349.499507 -317.55869) (xy 349.522218 -317.509271) (xy 349.551717 -317.463579)
			(xy 349.587405 -317.422538) (xy 349.62856 -317.386981) (xy 349.674347 -317.357629) (xy 349.723838 -317.335077)
			(xy 349.776031 -317.319781) (xy 349.829866 -317.312052) (xy 349.85706 -317.311532) (xy 349.881318 -317.311909)
			(xy 349.929442 -317.318062) (xy 349.976395 -317.330273) (xy 349.999046 -317.338964) (xy 350.010984 -317.34379)
			(xy 350.035876 -317.340996) (xy 350.11614 -317.28664) (xy 350.126112 -317.279158) (xy 350.137817 -317.25718)
			(xy 350.138492 -317.24473) (xy 350.138492 -316.43828) (xy 350.137803 -316.425837) (xy 350.126093 -316.403869)
			(xy 350.11614 -316.39637) (xy 350.035876 -316.342014) (xy 350.010984 -316.33922) (xy 349.999046 -316.344046)
			(xy 349.976393 -316.352729) (xy 349.92944 -316.364942) (xy 349.881318 -316.371103) (xy 349.85706 -316.371478)
			(xy 349.829813 -316.370989) (xy 349.775874 -316.363229) (xy 349.723588 -316.347871) (xy 349.67402 -316.32523)
			(xy 349.628178 -316.295765) (xy 349.586996 -316.260076) (xy 349.551311 -316.21889) (xy 349.521851 -316.173045)
			(xy 349.499215 -316.123475) (xy 349.483863 -316.071187) (xy 349.476108 -316.017247) (xy 349.476108 -315.962753)
			(xy 349.483863 -315.908813) (xy 349.499215 -315.856525) (xy 349.521851 -315.806955) (xy 349.551311 -315.76111)
			(xy 349.586996 -315.719924) (xy 349.628178 -315.684235) (xy 349.67402 -315.65477) (xy 349.723588 -315.632129)
			(xy 349.775874 -315.616771) (xy 349.829813 -315.609011) (xy 349.85706 -315.608462) (xy 349.881318 -315.60884)
			(xy 349.929441 -315.614993) (xy 349.976395 -315.627205) (xy 349.999046 -315.635894) (xy 350.010984 -315.64072)
			(xy 350.035876 -315.637926) (xy 350.11614 -315.58357) (xy 350.126116 -315.57609) (xy 350.137835 -315.554112)
			(xy 350.138492 -315.54166) (xy 350.138492 -305.96078) (xy 350.138065 -305.950712) (xy 350.130345 -305.932113)
			(xy 350.123506 -305.924712) (xy 348.908116 -304.709322) (xy 348.90128 -304.70192) (xy 348.893572 -304.683322)
			(xy 348.89313 -304.673254) (xy 348.89313 -302.42002) (xy 348.893568 -302.409957) (xy 348.901307 -302.391376)
			(xy 348.908116 -302.383952) (xy 350.123506 -301.168562) (xy 350.129396 -301.162219) (xy 350.136914 -301.146638)
			(xy 350.138238 -301.138082) (xy 350.138492 -301.135288) (xy 350.138492 -294.43553) (xy 350.138056 -294.425466)
			(xy 350.130323 -294.40688) (xy 350.123506 -294.399462) (xy 349.705422 -293.981378) (xy 349.698023 -293.974535)
			(xy 349.679424 -293.966817) (xy 349.669354 -293.966392) (xy 349.152718 -293.966392) (xy 349.147763 -293.966275)
			(xy 349.138041 -293.964359) (xy 349.133414 -293.962582) (xy 349.116396 -293.95547) (xy 349.111709 -293.953673)
			(xy 349.101857 -293.951757) (xy 349.096838 -293.95166) (xy 333.145384 -293.95166) (xy 333.140973 -293.951745)
			(xy 333.132284 -293.953274) (xy 333.128112 -293.954708) (xy 333.104744 -293.96309) (xy 333.097632 -293.968678)
			(xy 333.071506 -293.989646) (xy 333.014563 -294.024929) (xy 332.953289 -294.052002) (xy 332.888861 -294.070346)
			(xy 332.822516 -294.079609) (xy 332.789022 -294.080184) (xy 329.948286 -294.080184) (xy 329.919039 -294.079787)
			(xy 329.860966 -294.072781) (xy 329.832462 -294.066214) (xy 329.819583 -294.062953) (xy 329.794168 -294.055203)
			(xy 329.781662 -294.05072) (xy 329.764644 -294.04437) (xy 329.760326 -294.042846) (xy 329.743054 -294.034464)
			(xy 329.718 -294.022264) (xy 329.670612 -293.992941) (xy 329.626901 -293.958373) (xy 329.60691 -293.93896)
			(xy 327.309988 -291.642038) (xy 327.289866 -291.621338) (xy 327.254184 -291.575955) (xy 327.22417 -291.52664)
			(xy 327.200254 -291.474096) (xy 327.191116 -291.446712) (xy 327.182734 -291.416486) (xy 327.176164 -291.387983)
			(xy 327.169161 -291.32991) (xy 327.168764 -291.300662) (xy 327.168764 -288.264854) (xy 327.169163 -288.235607)
			(xy 327.176174 -288.177535) (xy 327.182734 -288.14903) (xy 327.188191 -288.127858) (xy 327.202436 -288.086519)
			(xy 327.211182 -288.06648) (xy 327.214484 -288.059622) (xy 327.226686 -288.03457) (xy 327.256014 -287.987185)
			(xy 327.290586 -287.943479) (xy 327.309988 -287.923478) (xy 328.9935 -286.239966) (xy 329.001634 -286.230938)
			(xy 329.009074 -286.207846) (xy 329.007724 -286.19577) (xy 328.992484 -286.102298) (xy 328.978006 -286.082486)
			(xy 328.967084 -286.077152) (xy 328.941678 -286.063944) (xy 328.894794 -286.031072) (xy 328.853349 -285.991563)
			(xy 328.818272 -285.946305) (xy 328.790352 -285.896314) (xy 328.770214 -285.842712) (xy 328.758312 -285.786704)
			(xy 328.754912 -285.729545) (xy 328.760092 -285.67252) (xy 328.773733 -285.616909) (xy 328.795531 -285.563961)
			(xy 328.824996 -285.514865) (xy 328.861466 -285.470722) (xy 328.882502 -285.451296) (xy 328.89063 -285.444184)
			(xy 328.899266 -285.425388) (xy 328.90206 -285.3309) (xy 328.89444 -285.311342) (xy 328.887074 -285.303976)
			(xy 328.866294 -285.282361) (xy 328.831053 -285.233856) (xy 328.80383 -285.180438) (xy 328.785293 -285.12342)
			(xy 328.7759 -285.064205) (xy 328.775314 -285.034228) (xy 328.7758 -285.006977) (xy 328.783556 -284.953029)
			(xy 328.798911 -284.900734) (xy 328.821553 -284.851157) (xy 328.851019 -284.805307) (xy 328.88671 -284.764116)
			(xy 328.927901 -284.728425) (xy 328.973751 -284.698959) (xy 329.023328 -284.676317) (xy 329.075623 -284.660962)
			(xy 329.129571 -284.653206) (xy 329.184073 -284.653206) (xy 329.238021 -284.660962) (xy 329.290316 -284.676317)
			(xy 329.339893 -284.698959) (xy 329.385743 -284.728425) (xy 329.426934 -284.764116) (xy 329.462625 -284.805307)
			(xy 329.492091 -284.851157) (xy 329.514733 -284.900734) (xy 329.530088 -284.953029) (xy 329.537844 -285.006977)
			(xy 329.53833 -285.034228) (xy 329.537899 -285.060985) (xy 329.530461 -285.113978) (xy 329.515692 -285.165413)
			(xy 329.493884 -285.214281) (xy 329.465462 -285.259622) (xy 329.430985 -285.300548) (xy 329.41133 -285.318708)
			(xy 329.403202 -285.325566) (xy 329.394566 -285.344362) (xy 329.391772 -285.43885) (xy 329.399392 -285.458408)
			(xy 329.406758 -285.465774) (xy 329.428212 -285.48803) (xy 329.464332 -285.538193) (xy 329.47864 -285.565596)
			(xy 329.484637 -285.576123) (xy 329.504141 -285.590435) (xy 329.515978 -285.593028) (xy 329.597258 -285.606236)
			(xy 329.60932 -285.607482) (xy 329.632366 -285.600045) (xy 329.641454 -285.592012) (xy 330.177902 -285.055564)
			(xy 330.184707 -285.048217) (xy 330.192426 -285.029754) (xy 330.192888 -285.01975) (xy 330.192888 -276.076664)
			(xy 330.191761 -276.067159) (xy 330.183449 -276.049934) (xy 330.169438 -276.036915) (xy 330.151649 -276.029888)
			(xy 330.142088 -276.02942) (xy 319.476374 -276.02942) (xy 319.466305 -276.028993) (xy 319.447706 -276.021274)
			(xy 319.440306 -276.014434) (xy 314.479686 -271.053814) (xy 314.472287 -271.046968) (xy 314.453689 -271.039237)
			(xy 314.443618 -271.038828) (xy 292.081712 -271.038828) (xy 292.071641 -271.03925) (xy 292.053036 -271.046964)
			(xy 292.045644 -271.053814) (xy 291.55644 -271.543018) (xy 291.549328 -271.556734) (xy 291.548058 -271.564354)
			(xy 291.538985 -271.612846) (xy 291.512521 -271.707889) (xy 291.495226 -271.754092) (xy 291.491924 -271.762982)
			(xy 291.491924 -271.833086) (xy 291.492269 -271.84266) (xy 291.49918 -271.860512) (xy 291.512158 -271.874585)
			(xy 291.520626 -271.87906) (xy 291.616892 -271.92478) (xy 291.645848 -271.921478) (xy 291.657278 -271.91208)
			(xy 291.677825 -271.896118) (xy 291.723221 -271.870702) (xy 291.772266 -271.853342) (xy 291.823543 -271.84454)
			(xy 291.849556 -271.844008) (xy 291.874815 -271.844497) (xy 291.924644 -271.852806) (xy 291.972426 -271.869203)
			(xy 292.016858 -271.893242) (xy 292.056725 -271.924268) (xy 292.090942 -271.961432) (xy 292.118575 -272.003722)
			(xy 292.13887 -272.049984) (xy 292.151272 -272.098955) (xy 292.155444 -272.1493) (xy 292.155422 -272.14957)
			(xy 293.443672 -272.14957) (xy 293.447632 -272.100516) (xy 293.459409 -272.052732) (xy 293.4787 -272.007456)
			(xy 293.505003 -271.96586) (xy 293.537638 -271.929023) (xy 293.575759 -271.897898) (xy 293.61838 -271.873291)
			(xy 293.664396 -271.855839) (xy 293.712615 -271.845995) (xy 293.76179 -271.844014) (xy 293.810645 -271.849946)
			(xy 293.857916 -271.863638) (xy 293.902378 -271.884736) (xy 293.942881 -271.912692) (xy 293.978374 -271.946784)
			(xy 294.007939 -271.986128) (xy 294.03081 -272.029705) (xy 294.046394 -272.076386) (xy 294.054289 -272.124963)
			(xy 294.054784 -272.14957) (xy 295.343846 -272.14957) (xy 295.347806 -272.100516) (xy 295.359583 -272.052732)
			(xy 295.378874 -272.007456) (xy 295.405177 -271.96586) (xy 295.437812 -271.929023) (xy 295.475933 -271.897898)
			(xy 295.518554 -271.873291) (xy 295.56457 -271.855839) (xy 295.612789 -271.845995) (xy 295.661964 -271.844014)
			(xy 295.710819 -271.849946) (xy 295.75809 -271.863638) (xy 295.802552 -271.884736) (xy 295.843055 -271.912692)
			(xy 295.878548 -271.946784) (xy 295.908113 -271.986128) (xy 295.930984 -272.029705) (xy 295.946568 -272.076386)
			(xy 295.954463 -272.124963) (xy 295.954958 -272.14957) (xy 297.243766 -272.14957) (xy 297.247726 -272.100516)
			(xy 297.259503 -272.052732) (xy 297.278794 -272.007456) (xy 297.305097 -271.96586) (xy 297.337732 -271.929023)
			(xy 297.375853 -271.897898) (xy 297.418474 -271.873291) (xy 297.46449 -271.855839) (xy 297.512709 -271.845995)
			(xy 297.561884 -271.844014) (xy 297.610739 -271.849946) (xy 297.65801 -271.863638) (xy 297.702472 -271.884736)
			(xy 297.742975 -271.912692) (xy 297.778468 -271.946784) (xy 297.808033 -271.986128) (xy 297.830904 -272.029705)
			(xy 297.846488 -272.076386) (xy 297.854383 -272.124963) (xy 297.854878 -272.14957) (xy 299.143686 -272.14957)
			(xy 299.147646 -272.100516) (xy 299.159423 -272.052732) (xy 299.178714 -272.007456) (xy 299.205017 -271.96586)
			(xy 299.237652 -271.929023) (xy 299.275773 -271.897898) (xy 299.318394 -271.873291) (xy 299.36441 -271.855839)
			(xy 299.412629 -271.845995) (xy 299.461804 -271.844014) (xy 299.510659 -271.849946) (xy 299.55793 -271.863638)
			(xy 299.602392 -271.884736) (xy 299.642895 -271.912692) (xy 299.678388 -271.946784) (xy 299.707953 -271.986128)
			(xy 299.730824 -272.029705) (xy 299.746408 -272.076386) (xy 299.754303 -272.124963) (xy 299.754798 -272.14957)
			(xy 301.04386 -272.14957) (xy 301.04782 -272.100516) (xy 301.059597 -272.052732) (xy 301.078888 -272.007456)
			(xy 301.105191 -271.96586) (xy 301.137826 -271.929023) (xy 301.175947 -271.897898) (xy 301.218568 -271.873291)
			(xy 301.264584 -271.855839) (xy 301.312803 -271.845995) (xy 301.361978 -271.844014) (xy 301.410833 -271.849946)
			(xy 301.458104 -271.863638) (xy 301.502566 -271.884736) (xy 301.543069 -271.912692) (xy 301.578562 -271.946784)
			(xy 301.608127 -271.986128) (xy 301.630998 -272.029705) (xy 301.646582 -272.076386) (xy 301.654477 -272.124963)
			(xy 301.654972 -272.14957) (xy 302.94378 -272.14957) (xy 302.94774 -272.100516) (xy 302.959517 -272.052732)
			(xy 302.978808 -272.007456) (xy 303.005111 -271.96586) (xy 303.037746 -271.929023) (xy 303.075867 -271.897898)
			(xy 303.118488 -271.873291) (xy 303.164504 -271.855839) (xy 303.212723 -271.845995) (xy 303.261898 -271.844014)
			(xy 303.310753 -271.849946) (xy 303.358024 -271.863638) (xy 303.402486 -271.884736) (xy 303.442989 -271.912692)
			(xy 303.478482 -271.946784) (xy 303.508047 -271.986128) (xy 303.530918 -272.029705) (xy 303.546502 -272.076386)
			(xy 303.554397 -272.124963) (xy 303.554892 -272.14957) (xy 304.8437 -272.14957) (xy 304.84766 -272.100516)
			(xy 304.859437 -272.052732) (xy 304.878728 -272.007456) (xy 304.905031 -271.96586) (xy 304.937666 -271.929023)
			(xy 304.975787 -271.897898) (xy 305.018408 -271.873291) (xy 305.064424 -271.855839) (xy 305.112643 -271.845995)
			(xy 305.161818 -271.844014) (xy 305.210673 -271.849946) (xy 305.257944 -271.863638) (xy 305.302406 -271.884736)
			(xy 305.342909 -271.912692) (xy 305.378402 -271.946784) (xy 305.407967 -271.986128) (xy 305.430838 -272.029705)
			(xy 305.446422 -272.076386) (xy 305.454317 -272.124963) (xy 305.454812 -272.14957) (xy 306.743874 -272.14957)
			(xy 306.747834 -272.100516) (xy 306.759611 -272.052732) (xy 306.778902 -272.007456) (xy 306.805205 -271.96586)
			(xy 306.83784 -271.929023) (xy 306.875961 -271.897898) (xy 306.918582 -271.873291) (xy 306.964598 -271.855839)
			(xy 307.012817 -271.845995) (xy 307.061992 -271.844014) (xy 307.110847 -271.849946) (xy 307.158118 -271.863638)
			(xy 307.20258 -271.884736) (xy 307.243083 -271.912692) (xy 307.278576 -271.946784) (xy 307.308141 -271.986128)
			(xy 307.331012 -272.029705) (xy 307.346596 -272.076386) (xy 307.354491 -272.124963) (xy 307.354986 -272.14957)
			(xy 308.644048 -272.14957) (xy 308.648008 -272.100516) (xy 308.659785 -272.052732) (xy 308.679076 -272.007456)
			(xy 308.705379 -271.96586) (xy 308.738014 -271.929023) (xy 308.776135 -271.897898) (xy 308.818756 -271.873291)
			(xy 308.864772 -271.855839) (xy 308.912991 -271.845995) (xy 308.962166 -271.844014) (xy 309.011021 -271.849946)
			(xy 309.058292 -271.863638) (xy 309.102754 -271.884736) (xy 309.143257 -271.912692) (xy 309.17875 -271.946784)
			(xy 309.208315 -271.986128) (xy 309.231186 -272.029705) (xy 309.24677 -272.076386) (xy 309.254665 -272.124963)
			(xy 309.25516 -272.14957) (xy 310.543968 -272.14957) (xy 310.547928 -272.100516) (xy 310.559705 -272.052732)
			(xy 310.578996 -272.007456) (xy 310.605299 -271.96586) (xy 310.637934 -271.929023) (xy 310.676055 -271.897898)
			(xy 310.718676 -271.873291) (xy 310.764692 -271.855839) (xy 310.812911 -271.845995) (xy 310.862086 -271.844014)
			(xy 310.910941 -271.849946) (xy 310.958212 -271.863638) (xy 311.002674 -271.884736) (xy 311.043177 -271.912692)
			(xy 311.07867 -271.946784) (xy 311.108235 -271.986128) (xy 311.131106 -272.029705) (xy 311.14669 -272.076386)
			(xy 311.154585 -272.124963) (xy 311.15508 -272.14957) (xy 312.443888 -272.14957) (xy 312.447848 -272.100516)
			(xy 312.459625 -272.052732) (xy 312.478916 -272.007456) (xy 312.505219 -271.96586) (xy 312.537854 -271.929023)
			(xy 312.575975 -271.897898) (xy 312.618596 -271.873291) (xy 312.664612 -271.855839) (xy 312.712831 -271.845995)
			(xy 312.762006 -271.844014) (xy 312.810861 -271.849946) (xy 312.858132 -271.863638) (xy 312.902594 -271.884736)
			(xy 312.943097 -271.912692) (xy 312.97859 -271.946784) (xy 313.008155 -271.986128) (xy 313.031026 -272.029705)
			(xy 313.04661 -272.076386) (xy 313.054505 -272.124963) (xy 313.055 -272.14957) (xy 313.054505 -272.174177)
			(xy 313.04661 -272.222754) (xy 313.031026 -272.269435) (xy 313.008155 -272.313012) (xy 312.97859 -272.352356)
			(xy 312.943097 -272.386448) (xy 312.902594 -272.414404) (xy 312.858132 -272.435502) (xy 312.810861 -272.449194)
			(xy 312.762006 -272.455126) (xy 312.712831 -272.453145) (xy 312.664612 -272.443301) (xy 312.618596 -272.425849)
			(xy 312.575975 -272.401242) (xy 312.537854 -272.370117) (xy 312.505219 -272.33328) (xy 312.478916 -272.291684)
			(xy 312.459625 -272.246408) (xy 312.447848 -272.198624) (xy 312.443888 -272.14957) (xy 311.15508 -272.14957)
			(xy 311.154585 -272.174177) (xy 311.14669 -272.222754) (xy 311.131106 -272.269435) (xy 311.108235 -272.313012)
			(xy 311.07867 -272.352356) (xy 311.043177 -272.386448) (xy 311.002674 -272.414404) (xy 310.958212 -272.435502)
			(xy 310.910941 -272.449194) (xy 310.862086 -272.455126) (xy 310.812911 -272.453145) (xy 310.764692 -272.443301)
			(xy 310.718676 -272.425849) (xy 310.676055 -272.401242) (xy 310.637934 -272.370117) (xy 310.605299 -272.33328)
			(xy 310.578996 -272.291684) (xy 310.559705 -272.246408) (xy 310.547928 -272.198624) (xy 310.543968 -272.14957)
			(xy 309.25516 -272.14957) (xy 309.254665 -272.174177) (xy 309.24677 -272.222754) (xy 309.231186 -272.269435)
			(xy 309.208315 -272.313012) (xy 309.17875 -272.352356) (xy 309.143257 -272.386448) (xy 309.102754 -272.414404)
			(xy 309.058292 -272.435502) (xy 309.011021 -272.449194) (xy 308.962166 -272.455126) (xy 308.912991 -272.453145)
			(xy 308.864772 -272.443301) (xy 308.818756 -272.425849) (xy 308.776135 -272.401242) (xy 308.738014 -272.370117)
			(xy 308.705379 -272.33328) (xy 308.679076 -272.291684) (xy 308.659785 -272.246408) (xy 308.648008 -272.198624)
			(xy 308.644048 -272.14957) (xy 307.354986 -272.14957) (xy 307.354491 -272.174177) (xy 307.346596 -272.222754)
			(xy 307.331012 -272.269435) (xy 307.308141 -272.313012) (xy 307.278576 -272.352356) (xy 307.243083 -272.386448)
			(xy 307.20258 -272.414404) (xy 307.158118 -272.435502) (xy 307.110847 -272.449194) (xy 307.061992 -272.455126)
			(xy 307.012817 -272.453145) (xy 306.964598 -272.443301) (xy 306.918582 -272.425849) (xy 306.875961 -272.401242)
			(xy 306.83784 -272.370117) (xy 306.805205 -272.33328) (xy 306.778902 -272.291684) (xy 306.759611 -272.246408)
			(xy 306.747834 -272.198624) (xy 306.743874 -272.14957) (xy 305.454812 -272.14957) (xy 305.454317 -272.174177)
			(xy 305.446422 -272.222754) (xy 305.430838 -272.269435) (xy 305.407967 -272.313012) (xy 305.378402 -272.352356)
			(xy 305.342909 -272.386448) (xy 305.302406 -272.414404) (xy 305.257944 -272.435502) (xy 305.210673 -272.449194)
			(xy 305.161818 -272.455126) (xy 305.112643 -272.453145) (xy 305.064424 -272.443301) (xy 305.018408 -272.425849)
			(xy 304.975787 -272.401242) (xy 304.937666 -272.370117) (xy 304.905031 -272.33328) (xy 304.878728 -272.291684)
			(xy 304.859437 -272.246408) (xy 304.84766 -272.198624) (xy 304.8437 -272.14957) (xy 303.554892 -272.14957)
			(xy 303.554397 -272.174177) (xy 303.546502 -272.222754) (xy 303.530918 -272.269435) (xy 303.508047 -272.313012)
			(xy 303.478482 -272.352356) (xy 303.442989 -272.386448) (xy 303.402486 -272.414404) (xy 303.358024 -272.435502)
			(xy 303.310753 -272.449194) (xy 303.261898 -272.455126) (xy 303.212723 -272.453145) (xy 303.164504 -272.443301)
			(xy 303.118488 -272.425849) (xy 303.075867 -272.401242) (xy 303.037746 -272.370117) (xy 303.005111 -272.33328)
			(xy 302.978808 -272.291684) (xy 302.959517 -272.246408) (xy 302.94774 -272.198624) (xy 302.94378 -272.14957)
			(xy 301.654972 -272.14957) (xy 301.654477 -272.174177) (xy 301.646582 -272.222754) (xy 301.630998 -272.269435)
			(xy 301.608127 -272.313012) (xy 301.578562 -272.352356) (xy 301.543069 -272.386448) (xy 301.502566 -272.414404)
			(xy 301.458104 -272.435502) (xy 301.410833 -272.449194) (xy 301.361978 -272.455126) (xy 301.312803 -272.453145)
			(xy 301.264584 -272.443301) (xy 301.218568 -272.425849) (xy 301.175947 -272.401242) (xy 301.137826 -272.370117)
			(xy 301.105191 -272.33328) (xy 301.078888 -272.291684) (xy 301.059597 -272.246408) (xy 301.04782 -272.198624)
			(xy 301.04386 -272.14957) (xy 299.754798 -272.14957) (xy 299.754303 -272.174177) (xy 299.746408 -272.222754)
			(xy 299.730824 -272.269435) (xy 299.707953 -272.313012) (xy 299.678388 -272.352356) (xy 299.642895 -272.386448)
			(xy 299.602392 -272.414404) (xy 299.55793 -272.435502) (xy 299.510659 -272.449194) (xy 299.461804 -272.455126)
			(xy 299.412629 -272.453145) (xy 299.36441 -272.443301) (xy 299.318394 -272.425849) (xy 299.275773 -272.401242)
			(xy 299.237652 -272.370117) (xy 299.205017 -272.33328) (xy 299.178714 -272.291684) (xy 299.159423 -272.246408)
			(xy 299.147646 -272.198624) (xy 299.143686 -272.14957) (xy 297.854878 -272.14957) (xy 297.854383 -272.174177)
			(xy 297.846488 -272.222754) (xy 297.830904 -272.269435) (xy 297.808033 -272.313012) (xy 297.778468 -272.352356)
			(xy 297.742975 -272.386448) (xy 297.702472 -272.414404) (xy 297.65801 -272.435502) (xy 297.610739 -272.449194)
			(xy 297.561884 -272.455126) (xy 297.512709 -272.453145) (xy 297.46449 -272.443301) (xy 297.418474 -272.425849)
			(xy 297.375853 -272.401242) (xy 297.337732 -272.370117) (xy 297.305097 -272.33328) (xy 297.278794 -272.291684)
			(xy 297.259503 -272.246408) (xy 297.247726 -272.198624) (xy 297.243766 -272.14957) (xy 295.954958 -272.14957)
			(xy 295.954463 -272.174177) (xy 295.946568 -272.222754) (xy 295.930984 -272.269435) (xy 295.908113 -272.313012)
			(xy 295.878548 -272.352356) (xy 295.843055 -272.386448) (xy 295.802552 -272.414404) (xy 295.75809 -272.435502)
			(xy 295.710819 -272.449194) (xy 295.661964 -272.455126) (xy 295.612789 -272.453145) (xy 295.56457 -272.443301)
			(xy 295.518554 -272.425849) (xy 295.475933 -272.401242) (xy 295.437812 -272.370117) (xy 295.405177 -272.33328)
			(xy 295.378874 -272.291684) (xy 295.359583 -272.246408) (xy 295.347806 -272.198624) (xy 295.343846 -272.14957)
			(xy 294.054784 -272.14957) (xy 294.054289 -272.174177) (xy 294.046394 -272.222754) (xy 294.03081 -272.269435)
			(xy 294.007939 -272.313012) (xy 293.978374 -272.352356) (xy 293.942881 -272.386448) (xy 293.902378 -272.414404)
			(xy 293.857916 -272.435502) (xy 293.810645 -272.449194) (xy 293.76179 -272.455126) (xy 293.712615 -272.453145)
			(xy 293.664396 -272.443301) (xy 293.61838 -272.425849) (xy 293.575759 -272.401242) (xy 293.537638 -272.370117)
			(xy 293.505003 -272.33328) (xy 293.4787 -272.291684) (xy 293.459409 -272.246408) (xy 293.447632 -272.198624)
			(xy 293.443672 -272.14957) (xy 292.155422 -272.14957) (xy 292.151272 -272.199645) (xy 292.13887 -272.248616)
			(xy 292.118575 -272.294878) (xy 292.090942 -272.337168) (xy 292.056725 -272.374332) (xy 292.016858 -272.405358)
			(xy 291.972426 -272.429397) (xy 291.924644 -272.445794) (xy 291.874815 -272.454103) (xy 291.849556 -272.454624)
			(xy 291.823544 -272.454097) (xy 291.772271 -272.445282) (xy 291.72323 -272.427915) (xy 291.677838 -272.402497)
			(xy 291.657278 -272.386552) (xy 291.645848 -272.377154) (xy 291.616892 -272.373852) (xy 291.520626 -272.419572)
			(xy 291.5122 -272.424103) (xy 291.499245 -272.438161) (xy 291.492334 -272.455985) (xy 291.491924 -272.465546)
			(xy 291.491924 -272.755868) (xy 291.492356 -272.765254) (xy 291.499106 -272.782772) (xy 291.511685 -272.796709)
			(xy 291.519864 -272.801334) (xy 291.614098 -272.848578) (xy 291.642292 -272.846038) (xy 291.65423 -272.837402)
			(xy 291.675532 -272.822168) (xy 291.721971 -272.797965) (xy 291.771675 -272.781474) (xy 291.823372 -272.773119)
			(xy 291.849556 -272.772632) (xy 291.875246 -272.773106) (xy 291.925993 -272.781138) (xy 291.97486 -272.79701)
			(xy 292.020641 -272.820331) (xy 292.062211 -272.850528) (xy 292.098544 -272.886856) (xy 292.128746 -272.928421)
			(xy 292.152073 -272.974199) (xy 292.167952 -273.023064) (xy 292.17599 -273.07381) (xy 292.17599 -273.099784)
			(xy 292.493966 -273.099784) (xy 292.497926 -273.05073) (xy 292.509703 -273.002946) (xy 292.528994 -272.95767)
			(xy 292.555297 -272.916074) (xy 292.587932 -272.879237) (xy 292.626053 -272.848112) (xy 292.668674 -272.823505)
			(xy 292.71469 -272.806053) (xy 292.762909 -272.796209) (xy 292.812084 -272.794228) (xy 292.860939 -272.80016)
			(xy 292.90821 -272.813852) (xy 292.952672 -272.83495) (xy 292.993175 -272.862906) (xy 293.028668 -272.896998)
			(xy 293.058233 -272.936342) (xy 293.081104 -272.979919) (xy 293.096688 -273.0266) (xy 293.104583 -273.075177)
			(xy 293.105078 -273.099784) (xy 293.104583 -273.124391) (xy 293.104404 -273.125492) (xy 293.422828 -273.125492)
			(xy 293.422828 -273.074076) (xy 293.430871 -273.023294) (xy 293.446759 -272.974395) (xy 293.470102 -272.928583)
			(xy 293.500323 -272.886987) (xy 293.536679 -272.850631) (xy 293.578275 -272.82041) (xy 293.624087 -272.797067)
			(xy 293.672986 -272.781179) (xy 293.723768 -272.773136) (xy 293.775184 -272.773136) (xy 293.825966 -272.781179)
			(xy 293.874865 -272.797067) (xy 293.920677 -272.82041) (xy 293.962273 -272.850631) (xy 293.998629 -272.886987)
			(xy 294.02885 -272.928583) (xy 294.052193 -272.974395) (xy 294.068081 -273.023294) (xy 294.076124 -273.074076)
			(xy 294.076628 -273.099784) (xy 294.393886 -273.099784) (xy 294.397846 -273.05073) (xy 294.409623 -273.002946)
			(xy 294.428914 -272.95767) (xy 294.455217 -272.916074) (xy 294.487852 -272.879237) (xy 294.525973 -272.848112)
			(xy 294.568594 -272.823505) (xy 294.61461 -272.806053) (xy 294.662829 -272.796209) (xy 294.712004 -272.794228)
			(xy 294.760859 -272.80016) (xy 294.80813 -272.813852) (xy 294.852592 -272.83495) (xy 294.893095 -272.862906)
			(xy 294.928588 -272.896998) (xy 294.958153 -272.936342) (xy 294.981024 -272.979919) (xy 294.996608 -273.0266)
			(xy 295.004503 -273.075177) (xy 295.004998 -273.099784) (xy 295.004503 -273.124391) (xy 295.004324 -273.125492)
			(xy 295.323002 -273.125492) (xy 295.323002 -273.074076) (xy 295.331045 -273.023294) (xy 295.346933 -272.974395)
			(xy 295.370276 -272.928583) (xy 295.400497 -272.886987) (xy 295.436853 -272.850631) (xy 295.478449 -272.82041)
			(xy 295.524261 -272.797067) (xy 295.57316 -272.781179) (xy 295.623942 -272.773136) (xy 295.675358 -272.773136)
			(xy 295.72614 -272.781179) (xy 295.775039 -272.797067) (xy 295.820851 -272.82041) (xy 295.862447 -272.850631)
			(xy 295.898803 -272.886987) (xy 295.929024 -272.928583) (xy 295.952367 -272.974395) (xy 295.968255 -273.023294)
			(xy 295.976298 -273.074076) (xy 295.976802 -273.099784) (xy 296.29406 -273.099784) (xy 296.29802 -273.05073)
			(xy 296.309797 -273.002946) (xy 296.329088 -272.95767) (xy 296.355391 -272.916074) (xy 296.388026 -272.879237)
			(xy 296.426147 -272.848112) (xy 296.468768 -272.823505) (xy 296.514784 -272.806053) (xy 296.563003 -272.796209)
			(xy 296.612178 -272.794228) (xy 296.661033 -272.80016) (xy 296.708304 -272.813852) (xy 296.752766 -272.83495)
			(xy 296.793269 -272.862906) (xy 296.828762 -272.896998) (xy 296.858327 -272.936342) (xy 296.881198 -272.979919)
			(xy 296.896782 -273.0266) (xy 296.904677 -273.075177) (xy 296.905172 -273.099784) (xy 296.904677 -273.124391)
			(xy 296.904498 -273.125492) (xy 297.222922 -273.125492) (xy 297.222922 -273.074076) (xy 297.230965 -273.023294)
			(xy 297.246853 -272.974395) (xy 297.270196 -272.928583) (xy 297.300417 -272.886987) (xy 297.336773 -272.850631)
			(xy 297.378369 -272.82041) (xy 297.424181 -272.797067) (xy 297.47308 -272.781179) (xy 297.523862 -272.773136)
			(xy 297.575278 -272.773136) (xy 297.62606 -272.781179) (xy 297.674959 -272.797067) (xy 297.720771 -272.82041)
			(xy 297.762367 -272.850631) (xy 297.798723 -272.886987) (xy 297.828944 -272.928583) (xy 297.852287 -272.974395)
			(xy 297.868175 -273.023294) (xy 297.876218 -273.074076) (xy 297.876722 -273.099784) (xy 298.19398 -273.099784)
			(xy 298.19794 -273.05073) (xy 298.209717 -273.002946) (xy 298.229008 -272.95767) (xy 298.255311 -272.916074)
			(xy 298.287946 -272.879237) (xy 298.326067 -272.848112) (xy 298.368688 -272.823505) (xy 298.414704 -272.806053)
			(xy 298.462923 -272.796209) (xy 298.512098 -272.794228) (xy 298.560953 -272.80016) (xy 298.608224 -272.813852)
			(xy 298.652686 -272.83495) (xy 298.693189 -272.862906) (xy 298.728682 -272.896998) (xy 298.758247 -272.936342)
			(xy 298.781118 -272.979919) (xy 298.796702 -273.0266) (xy 298.804597 -273.075177) (xy 298.805092 -273.099784)
			(xy 298.804597 -273.124391) (xy 298.804418 -273.125492) (xy 299.122842 -273.125492) (xy 299.122842 -273.074076)
			(xy 299.130885 -273.023294) (xy 299.146773 -272.974395) (xy 299.170116 -272.928583) (xy 299.200337 -272.886987)
			(xy 299.236693 -272.850631) (xy 299.278289 -272.82041) (xy 299.324101 -272.797067) (xy 299.373 -272.781179)
			(xy 299.423782 -272.773136) (xy 299.475198 -272.773136) (xy 299.52598 -272.781179) (xy 299.574879 -272.797067)
			(xy 299.620691 -272.82041) (xy 299.662287 -272.850631) (xy 299.698643 -272.886987) (xy 299.728864 -272.928583)
			(xy 299.752207 -272.974395) (xy 299.768095 -273.023294) (xy 299.776138 -273.074076) (xy 299.776642 -273.099784)
			(xy 300.0939 -273.099784) (xy 300.09786 -273.05073) (xy 300.109637 -273.002946) (xy 300.128928 -272.95767)
			(xy 300.155231 -272.916074) (xy 300.187866 -272.879237) (xy 300.225987 -272.848112) (xy 300.268608 -272.823505)
			(xy 300.314624 -272.806053) (xy 300.362843 -272.796209) (xy 300.412018 -272.794228) (xy 300.460873 -272.80016)
			(xy 300.508144 -272.813852) (xy 300.552606 -272.83495) (xy 300.593109 -272.862906) (xy 300.628602 -272.896998)
			(xy 300.658167 -272.936342) (xy 300.681038 -272.979919) (xy 300.696622 -273.0266) (xy 300.704517 -273.075177)
			(xy 300.705012 -273.099784) (xy 300.704517 -273.124391) (xy 300.704338 -273.125492) (xy 301.023016 -273.125492)
			(xy 301.023016 -273.074076) (xy 301.031059 -273.023294) (xy 301.046947 -272.974395) (xy 301.07029 -272.928583)
			(xy 301.100511 -272.886987) (xy 301.136867 -272.850631) (xy 301.178463 -272.82041) (xy 301.224275 -272.797067)
			(xy 301.273174 -272.781179) (xy 301.323956 -272.773136) (xy 301.375372 -272.773136) (xy 301.426154 -272.781179)
			(xy 301.475053 -272.797067) (xy 301.520865 -272.82041) (xy 301.562461 -272.850631) (xy 301.598817 -272.886987)
			(xy 301.629038 -272.928583) (xy 301.652381 -272.974395) (xy 301.668269 -273.023294) (xy 301.676312 -273.074076)
			(xy 301.676816 -273.099784) (xy 301.994074 -273.099784) (xy 301.998034 -273.05073) (xy 302.009811 -273.002946)
			(xy 302.029102 -272.95767) (xy 302.055405 -272.916074) (xy 302.08804 -272.879237) (xy 302.126161 -272.848112)
			(xy 302.168782 -272.823505) (xy 302.214798 -272.806053) (xy 302.263017 -272.796209) (xy 302.312192 -272.794228)
			(xy 302.361047 -272.80016) (xy 302.408318 -272.813852) (xy 302.45278 -272.83495) (xy 302.493283 -272.862906)
			(xy 302.528776 -272.896998) (xy 302.558341 -272.936342) (xy 302.581212 -272.979919) (xy 302.596796 -273.0266)
			(xy 302.604691 -273.075177) (xy 302.605186 -273.099784) (xy 302.604691 -273.124391) (xy 302.604512 -273.125492)
			(xy 302.922936 -273.125492) (xy 302.922936 -273.074076) (xy 302.930979 -273.023294) (xy 302.946867 -272.974395)
			(xy 302.97021 -272.928583) (xy 303.000431 -272.886987) (xy 303.036787 -272.850631) (xy 303.078383 -272.82041)
			(xy 303.124195 -272.797067) (xy 303.173094 -272.781179) (xy 303.223876 -272.773136) (xy 303.275292 -272.773136)
			(xy 303.326074 -272.781179) (xy 303.374973 -272.797067) (xy 303.420785 -272.82041) (xy 303.462381 -272.850631)
			(xy 303.498737 -272.886987) (xy 303.528958 -272.928583) (xy 303.552301 -272.974395) (xy 303.568189 -273.023294)
			(xy 303.576232 -273.074076) (xy 303.576736 -273.099784) (xy 303.893994 -273.099784) (xy 303.897954 -273.05073)
			(xy 303.909731 -273.002946) (xy 303.929022 -272.95767) (xy 303.955325 -272.916074) (xy 303.98796 -272.879237)
			(xy 304.026081 -272.848112) (xy 304.068702 -272.823505) (xy 304.114718 -272.806053) (xy 304.162937 -272.796209)
			(xy 304.212112 -272.794228) (xy 304.260967 -272.80016) (xy 304.308238 -272.813852) (xy 304.3527 -272.83495)
			(xy 304.393203 -272.862906) (xy 304.428696 -272.896998) (xy 304.458261 -272.936342) (xy 304.481132 -272.979919)
			(xy 304.496716 -273.0266) (xy 304.504611 -273.075177) (xy 304.505106 -273.099784) (xy 304.504611 -273.124391)
			(xy 304.504432 -273.125492) (xy 304.822856 -273.125492) (xy 304.822856 -273.074076) (xy 304.830899 -273.023294)
			(xy 304.846787 -272.974395) (xy 304.87013 -272.928583) (xy 304.900351 -272.886987) (xy 304.936707 -272.850631)
			(xy 304.978303 -272.82041) (xy 305.024115 -272.797067) (xy 305.073014 -272.781179) (xy 305.123796 -272.773136)
			(xy 305.175212 -272.773136) (xy 305.225994 -272.781179) (xy 305.274893 -272.797067) (xy 305.320705 -272.82041)
			(xy 305.362301 -272.850631) (xy 305.398657 -272.886987) (xy 305.428878 -272.928583) (xy 305.452221 -272.974395)
			(xy 305.468109 -273.023294) (xy 305.476152 -273.074076) (xy 305.476656 -273.099784) (xy 305.793914 -273.099784)
			(xy 305.797874 -273.05073) (xy 305.809651 -273.002946) (xy 305.828942 -272.95767) (xy 305.855245 -272.916074)
			(xy 305.88788 -272.879237) (xy 305.926001 -272.848112) (xy 305.968622 -272.823505) (xy 306.014638 -272.806053)
			(xy 306.062857 -272.796209) (xy 306.112032 -272.794228) (xy 306.160887 -272.80016) (xy 306.208158 -272.813852)
			(xy 306.25262 -272.83495) (xy 306.293123 -272.862906) (xy 306.328616 -272.896998) (xy 306.358181 -272.936342)
			(xy 306.381052 -272.979919) (xy 306.396636 -273.0266) (xy 306.404531 -273.075177) (xy 306.405026 -273.099784)
			(xy 306.404531 -273.124391) (xy 306.404352 -273.125492) (xy 306.72303 -273.125492) (xy 306.72303 -273.074076)
			(xy 306.731073 -273.023294) (xy 306.746961 -272.974395) (xy 306.770304 -272.928583) (xy 306.800525 -272.886987)
			(xy 306.836881 -272.850631) (xy 306.878477 -272.82041) (xy 306.924289 -272.797067) (xy 306.973188 -272.781179)
			(xy 307.02397 -272.773136) (xy 307.075386 -272.773136) (xy 307.126168 -272.781179) (xy 307.175067 -272.797067)
			(xy 307.220879 -272.82041) (xy 307.262475 -272.850631) (xy 307.298831 -272.886987) (xy 307.329052 -272.928583)
			(xy 307.352395 -272.974395) (xy 307.368283 -273.023294) (xy 307.376326 -273.074076) (xy 307.37683 -273.099784)
			(xy 307.694088 -273.099784) (xy 307.698048 -273.05073) (xy 307.709825 -273.002946) (xy 307.729116 -272.95767)
			(xy 307.755419 -272.916074) (xy 307.788054 -272.879237) (xy 307.826175 -272.848112) (xy 307.868796 -272.823505)
			(xy 307.914812 -272.806053) (xy 307.963031 -272.796209) (xy 308.012206 -272.794228) (xy 308.061061 -272.80016)
			(xy 308.108332 -272.813852) (xy 308.152794 -272.83495) (xy 308.193297 -272.862906) (xy 308.22879 -272.896998)
			(xy 308.258355 -272.936342) (xy 308.281226 -272.979919) (xy 308.29681 -273.0266) (xy 308.304705 -273.075177)
			(xy 308.3052 -273.099784) (xy 308.304705 -273.124391) (xy 308.304526 -273.125492) (xy 308.62295 -273.125492)
			(xy 308.62295 -273.074076) (xy 308.630993 -273.023294) (xy 308.646881 -272.974395) (xy 308.670224 -272.928583)
			(xy 308.700445 -272.886987) (xy 308.736801 -272.850631) (xy 308.778397 -272.82041) (xy 308.824209 -272.797067)
			(xy 308.873108 -272.781179) (xy 308.92389 -272.773136) (xy 308.975306 -272.773136) (xy 309.026088 -272.781179)
			(xy 309.074987 -272.797067) (xy 309.120799 -272.82041) (xy 309.162395 -272.850631) (xy 309.198751 -272.886987)
			(xy 309.228972 -272.928583) (xy 309.252315 -272.974395) (xy 309.268203 -273.023294) (xy 309.276246 -273.074076)
			(xy 309.27675 -273.099784) (xy 309.594262 -273.099784) (xy 309.598222 -273.05073) (xy 309.609999 -273.002946)
			(xy 309.62929 -272.95767) (xy 309.655593 -272.916074) (xy 309.688228 -272.879237) (xy 309.726349 -272.848112)
			(xy 309.76897 -272.823505) (xy 309.814986 -272.806053) (xy 309.863205 -272.796209) (xy 309.91238 -272.794228)
			(xy 309.961235 -272.80016) (xy 310.008506 -272.813852) (xy 310.052968 -272.83495) (xy 310.093471 -272.862906)
			(xy 310.128964 -272.896998) (xy 310.158529 -272.936342) (xy 310.1814 -272.979919) (xy 310.196984 -273.0266)
			(xy 310.204879 -273.075177) (xy 310.205374 -273.099784) (xy 310.204879 -273.124391) (xy 310.2047 -273.125492)
			(xy 310.52287 -273.125492) (xy 310.52287 -273.074076) (xy 310.530913 -273.023294) (xy 310.546801 -272.974395)
			(xy 310.570144 -272.928583) (xy 310.600365 -272.886987) (xy 310.636721 -272.850631) (xy 310.678317 -272.82041)
			(xy 310.724129 -272.797067) (xy 310.773028 -272.781179) (xy 310.82381 -272.773136) (xy 310.875226 -272.773136)
			(xy 310.926008 -272.781179) (xy 310.974907 -272.797067) (xy 311.020719 -272.82041) (xy 311.062315 -272.850631)
			(xy 311.098671 -272.886987) (xy 311.128892 -272.928583) (xy 311.152235 -272.974395) (xy 311.168123 -273.023294)
			(xy 311.176166 -273.074076) (xy 311.17667 -273.099784) (xy 311.494182 -273.099784) (xy 311.498142 -273.05073)
			(xy 311.509919 -273.002946) (xy 311.52921 -272.95767) (xy 311.555513 -272.916074) (xy 311.588148 -272.879237)
			(xy 311.626269 -272.848112) (xy 311.66889 -272.823505) (xy 311.714906 -272.806053) (xy 311.763125 -272.796209)
			(xy 311.8123 -272.794228) (xy 311.861155 -272.80016) (xy 311.908426 -272.813852) (xy 311.952888 -272.83495)
			(xy 311.993391 -272.862906) (xy 312.028884 -272.896998) (xy 312.058449 -272.936342) (xy 312.08132 -272.979919)
			(xy 312.096904 -273.0266) (xy 312.104799 -273.075177) (xy 312.105294 -273.099784) (xy 312.104799 -273.124391)
			(xy 312.10462 -273.125492) (xy 312.42279 -273.125492) (xy 312.42279 -273.074076) (xy 312.430833 -273.023294)
			(xy 312.446721 -272.974395) (xy 312.470064 -272.928583) (xy 312.500285 -272.886987) (xy 312.536641 -272.850631)
			(xy 312.578237 -272.82041) (xy 312.624049 -272.797067) (xy 312.672948 -272.781179) (xy 312.72373 -272.773136)
			(xy 312.775146 -272.773136) (xy 312.825928 -272.781179) (xy 312.874827 -272.797067) (xy 312.920639 -272.82041)
			(xy 312.962235 -272.850631) (xy 312.998591 -272.886987) (xy 313.028812 -272.928583) (xy 313.052155 -272.974395)
			(xy 313.068043 -273.023294) (xy 313.076086 -273.074076) (xy 313.07659 -273.099784) (xy 313.394102 -273.099784)
			(xy 313.398062 -273.05073) (xy 313.409839 -273.002946) (xy 313.42913 -272.95767) (xy 313.455433 -272.916074)
			(xy 313.488068 -272.879237) (xy 313.526189 -272.848112) (xy 313.56881 -272.823505) (xy 313.614826 -272.806053)
			(xy 313.663045 -272.796209) (xy 313.71222 -272.794228) (xy 313.761075 -272.80016) (xy 313.808346 -272.813852)
			(xy 313.852808 -272.83495) (xy 313.893311 -272.862906) (xy 313.928804 -272.896998) (xy 313.958369 -272.936342)
			(xy 313.98124 -272.979919) (xy 313.996824 -273.0266) (xy 314.004719 -273.075177) (xy 314.005214 -273.099784)
			(xy 314.004719 -273.124391) (xy 313.996824 -273.172968) (xy 313.98124 -273.219649) (xy 313.958369 -273.263226)
			(xy 313.928804 -273.30257) (xy 313.893311 -273.336662) (xy 313.852808 -273.364618) (xy 313.808346 -273.385716)
			(xy 313.761075 -273.399408) (xy 313.71222 -273.40534) (xy 313.663045 -273.403359) (xy 313.614826 -273.393515)
			(xy 313.56881 -273.376063) (xy 313.526189 -273.351456) (xy 313.488068 -273.320331) (xy 313.455433 -273.283494)
			(xy 313.42913 -273.241898) (xy 313.409839 -273.196622) (xy 313.398062 -273.148838) (xy 313.394102 -273.099784)
			(xy 313.07659 -273.099784) (xy 313.076086 -273.125492) (xy 313.068043 -273.176274) (xy 313.052155 -273.225173)
			(xy 313.028812 -273.270985) (xy 312.998591 -273.312581) (xy 312.962235 -273.348937) (xy 312.920639 -273.379158)
			(xy 312.874827 -273.402501) (xy 312.825928 -273.418389) (xy 312.775146 -273.426432) (xy 312.72373 -273.426432)
			(xy 312.672948 -273.418389) (xy 312.624049 -273.402501) (xy 312.578237 -273.379158) (xy 312.536641 -273.348937)
			(xy 312.500285 -273.312581) (xy 312.470064 -273.270985) (xy 312.446721 -273.225173) (xy 312.430833 -273.176274)
			(xy 312.42279 -273.125492) (xy 312.10462 -273.125492) (xy 312.096904 -273.172968) (xy 312.08132 -273.219649)
			(xy 312.058449 -273.263226) (xy 312.028884 -273.30257) (xy 311.993391 -273.336662) (xy 311.952888 -273.364618)
			(xy 311.908426 -273.385716) (xy 311.861155 -273.399408) (xy 311.8123 -273.40534) (xy 311.763125 -273.403359)
			(xy 311.714906 -273.393515) (xy 311.66889 -273.376063) (xy 311.626269 -273.351456) (xy 311.588148 -273.320331)
			(xy 311.555513 -273.283494) (xy 311.52921 -273.241898) (xy 311.509919 -273.196622) (xy 311.498142 -273.148838)
			(xy 311.494182 -273.099784) (xy 311.17667 -273.099784) (xy 311.176166 -273.125492) (xy 311.168123 -273.176274)
			(xy 311.152235 -273.225173) (xy 311.128892 -273.270985) (xy 311.098671 -273.312581) (xy 311.062315 -273.348937)
			(xy 311.020719 -273.379158) (xy 310.974907 -273.402501) (xy 310.926008 -273.418389) (xy 310.875226 -273.426432)
			(xy 310.82381 -273.426432) (xy 310.773028 -273.418389) (xy 310.724129 -273.402501) (xy 310.678317 -273.379158)
			(xy 310.636721 -273.348937) (xy 310.600365 -273.312581) (xy 310.570144 -273.270985) (xy 310.546801 -273.225173)
			(xy 310.530913 -273.176274) (xy 310.52287 -273.125492) (xy 310.2047 -273.125492) (xy 310.196984 -273.172968)
			(xy 310.1814 -273.219649) (xy 310.158529 -273.263226) (xy 310.128964 -273.30257) (xy 310.093471 -273.336662)
			(xy 310.052968 -273.364618) (xy 310.008506 -273.385716) (xy 309.961235 -273.399408) (xy 309.91238 -273.40534)
			(xy 309.863205 -273.403359) (xy 309.814986 -273.393515) (xy 309.76897 -273.376063) (xy 309.726349 -273.351456)
			(xy 309.688228 -273.320331) (xy 309.655593 -273.283494) (xy 309.62929 -273.241898) (xy 309.609999 -273.196622)
			(xy 309.598222 -273.148838) (xy 309.594262 -273.099784) (xy 309.27675 -273.099784) (xy 309.276246 -273.125492)
			(xy 309.268203 -273.176274) (xy 309.252315 -273.225173) (xy 309.228972 -273.270985) (xy 309.198751 -273.312581)
			(xy 309.162395 -273.348937) (xy 309.120799 -273.379158) (xy 309.074987 -273.402501) (xy 309.026088 -273.418389)
			(xy 308.975306 -273.426432) (xy 308.92389 -273.426432) (xy 308.873108 -273.418389) (xy 308.824209 -273.402501)
			(xy 308.778397 -273.379158) (xy 308.736801 -273.348937) (xy 308.700445 -273.312581) (xy 308.670224 -273.270985)
			(xy 308.646881 -273.225173) (xy 308.630993 -273.176274) (xy 308.62295 -273.125492) (xy 308.304526 -273.125492)
			(xy 308.29681 -273.172968) (xy 308.281226 -273.219649) (xy 308.258355 -273.263226) (xy 308.22879 -273.30257)
			(xy 308.193297 -273.336662) (xy 308.152794 -273.364618) (xy 308.108332 -273.385716) (xy 308.061061 -273.399408)
			(xy 308.012206 -273.40534) (xy 307.963031 -273.403359) (xy 307.914812 -273.393515) (xy 307.868796 -273.376063)
			(xy 307.826175 -273.351456) (xy 307.788054 -273.320331) (xy 307.755419 -273.283494) (xy 307.729116 -273.241898)
			(xy 307.709825 -273.196622) (xy 307.698048 -273.148838) (xy 307.694088 -273.099784) (xy 307.37683 -273.099784)
			(xy 307.376326 -273.125492) (xy 307.368283 -273.176274) (xy 307.352395 -273.225173) (xy 307.329052 -273.270985)
			(xy 307.298831 -273.312581) (xy 307.262475 -273.348937) (xy 307.220879 -273.379158) (xy 307.175067 -273.402501)
			(xy 307.126168 -273.418389) (xy 307.075386 -273.426432) (xy 307.02397 -273.426432) (xy 306.973188 -273.418389)
			(xy 306.924289 -273.402501) (xy 306.878477 -273.379158) (xy 306.836881 -273.348937) (xy 306.800525 -273.312581)
			(xy 306.770304 -273.270985) (xy 306.746961 -273.225173) (xy 306.731073 -273.176274) (xy 306.72303 -273.125492)
			(xy 306.404352 -273.125492) (xy 306.396636 -273.172968) (xy 306.381052 -273.219649) (xy 306.358181 -273.263226)
			(xy 306.328616 -273.30257) (xy 306.293123 -273.336662) (xy 306.25262 -273.364618) (xy 306.208158 -273.385716)
			(xy 306.160887 -273.399408) (xy 306.112032 -273.40534) (xy 306.062857 -273.403359) (xy 306.014638 -273.393515)
			(xy 305.968622 -273.376063) (xy 305.926001 -273.351456) (xy 305.88788 -273.320331) (xy 305.855245 -273.283494)
			(xy 305.828942 -273.241898) (xy 305.809651 -273.196622) (xy 305.797874 -273.148838) (xy 305.793914 -273.099784)
			(xy 305.476656 -273.099784) (xy 305.476152 -273.125492) (xy 305.468109 -273.176274) (xy 305.452221 -273.225173)
			(xy 305.428878 -273.270985) (xy 305.398657 -273.312581) (xy 305.362301 -273.348937) (xy 305.320705 -273.379158)
			(xy 305.274893 -273.402501) (xy 305.225994 -273.418389) (xy 305.175212 -273.426432) (xy 305.123796 -273.426432)
			(xy 305.073014 -273.418389) (xy 305.024115 -273.402501) (xy 304.978303 -273.379158) (xy 304.936707 -273.348937)
			(xy 304.900351 -273.312581) (xy 304.87013 -273.270985) (xy 304.846787 -273.225173) (xy 304.830899 -273.176274)
			(xy 304.822856 -273.125492) (xy 304.504432 -273.125492) (xy 304.496716 -273.172968) (xy 304.481132 -273.219649)
			(xy 304.458261 -273.263226) (xy 304.428696 -273.30257) (xy 304.393203 -273.336662) (xy 304.3527 -273.364618)
			(xy 304.308238 -273.385716) (xy 304.260967 -273.399408) (xy 304.212112 -273.40534) (xy 304.162937 -273.403359)
			(xy 304.114718 -273.393515) (xy 304.068702 -273.376063) (xy 304.026081 -273.351456) (xy 303.98796 -273.320331)
			(xy 303.955325 -273.283494) (xy 303.929022 -273.241898) (xy 303.909731 -273.196622) (xy 303.897954 -273.148838)
			(xy 303.893994 -273.099784) (xy 303.576736 -273.099784) (xy 303.576232 -273.125492) (xy 303.568189 -273.176274)
			(xy 303.552301 -273.225173) (xy 303.528958 -273.270985) (xy 303.498737 -273.312581) (xy 303.462381 -273.348937)
			(xy 303.420785 -273.379158) (xy 303.374973 -273.402501) (xy 303.326074 -273.418389) (xy 303.275292 -273.426432)
			(xy 303.223876 -273.426432) (xy 303.173094 -273.418389) (xy 303.124195 -273.402501) (xy 303.078383 -273.379158)
			(xy 303.036787 -273.348937) (xy 303.000431 -273.312581) (xy 302.97021 -273.270985) (xy 302.946867 -273.225173)
			(xy 302.930979 -273.176274) (xy 302.922936 -273.125492) (xy 302.604512 -273.125492) (xy 302.596796 -273.172968)
			(xy 302.581212 -273.219649) (xy 302.558341 -273.263226) (xy 302.528776 -273.30257) (xy 302.493283 -273.336662)
			(xy 302.45278 -273.364618) (xy 302.408318 -273.385716) (xy 302.361047 -273.399408) (xy 302.312192 -273.40534)
			(xy 302.263017 -273.403359) (xy 302.214798 -273.393515) (xy 302.168782 -273.376063) (xy 302.126161 -273.351456)
			(xy 302.08804 -273.320331) (xy 302.055405 -273.283494) (xy 302.029102 -273.241898) (xy 302.009811 -273.196622)
			(xy 301.998034 -273.148838) (xy 301.994074 -273.099784) (xy 301.676816 -273.099784) (xy 301.676312 -273.125492)
			(xy 301.668269 -273.176274) (xy 301.652381 -273.225173) (xy 301.629038 -273.270985) (xy 301.598817 -273.312581)
			(xy 301.562461 -273.348937) (xy 301.520865 -273.379158) (xy 301.475053 -273.402501) (xy 301.426154 -273.418389)
			(xy 301.375372 -273.426432) (xy 301.323956 -273.426432) (xy 301.273174 -273.418389) (xy 301.224275 -273.402501)
			(xy 301.178463 -273.379158) (xy 301.136867 -273.348937) (xy 301.100511 -273.312581) (xy 301.07029 -273.270985)
			(xy 301.046947 -273.225173) (xy 301.031059 -273.176274) (xy 301.023016 -273.125492) (xy 300.704338 -273.125492)
			(xy 300.696622 -273.172968) (xy 300.681038 -273.219649) (xy 300.658167 -273.263226) (xy 300.628602 -273.30257)
			(xy 300.593109 -273.336662) (xy 300.552606 -273.364618) (xy 300.508144 -273.385716) (xy 300.460873 -273.399408)
			(xy 300.412018 -273.40534) (xy 300.362843 -273.403359) (xy 300.314624 -273.393515) (xy 300.268608 -273.376063)
			(xy 300.225987 -273.351456) (xy 300.187866 -273.320331) (xy 300.155231 -273.283494) (xy 300.128928 -273.241898)
			(xy 300.109637 -273.196622) (xy 300.09786 -273.148838) (xy 300.0939 -273.099784) (xy 299.776642 -273.099784)
			(xy 299.776138 -273.125492) (xy 299.768095 -273.176274) (xy 299.752207 -273.225173) (xy 299.728864 -273.270985)
			(xy 299.698643 -273.312581) (xy 299.662287 -273.348937) (xy 299.620691 -273.379158) (xy 299.574879 -273.402501)
			(xy 299.52598 -273.418389) (xy 299.475198 -273.426432) (xy 299.423782 -273.426432) (xy 299.373 -273.418389)
			(xy 299.324101 -273.402501) (xy 299.278289 -273.379158) (xy 299.236693 -273.348937) (xy 299.200337 -273.312581)
			(xy 299.170116 -273.270985) (xy 299.146773 -273.225173) (xy 299.130885 -273.176274) (xy 299.122842 -273.125492)
			(xy 298.804418 -273.125492) (xy 298.796702 -273.172968) (xy 298.781118 -273.219649) (xy 298.758247 -273.263226)
			(xy 298.728682 -273.30257) (xy 298.693189 -273.336662) (xy 298.652686 -273.364618) (xy 298.608224 -273.385716)
			(xy 298.560953 -273.399408) (xy 298.512098 -273.40534) (xy 298.462923 -273.403359) (xy 298.414704 -273.393515)
			(xy 298.368688 -273.376063) (xy 298.326067 -273.351456) (xy 298.287946 -273.320331) (xy 298.255311 -273.283494)
			(xy 298.229008 -273.241898) (xy 298.209717 -273.196622) (xy 298.19794 -273.148838) (xy 298.19398 -273.099784)
			(xy 297.876722 -273.099784) (xy 297.876218 -273.125492) (xy 297.868175 -273.176274) (xy 297.852287 -273.225173)
			(xy 297.828944 -273.270985) (xy 297.798723 -273.312581) (xy 297.762367 -273.348937) (xy 297.720771 -273.379158)
			(xy 297.674959 -273.402501) (xy 297.62606 -273.418389) (xy 297.575278 -273.426432) (xy 297.523862 -273.426432)
			(xy 297.47308 -273.418389) (xy 297.424181 -273.402501) (xy 297.378369 -273.379158) (xy 297.336773 -273.348937)
			(xy 297.300417 -273.312581) (xy 297.270196 -273.270985) (xy 297.246853 -273.225173) (xy 297.230965 -273.176274)
			(xy 297.222922 -273.125492) (xy 296.904498 -273.125492) (xy 296.896782 -273.172968) (xy 296.881198 -273.219649)
			(xy 296.858327 -273.263226) (xy 296.828762 -273.30257) (xy 296.793269 -273.336662) (xy 296.752766 -273.364618)
			(xy 296.708304 -273.385716) (xy 296.661033 -273.399408) (xy 296.612178 -273.40534) (xy 296.563003 -273.403359)
			(xy 296.514784 -273.393515) (xy 296.468768 -273.376063) (xy 296.426147 -273.351456) (xy 296.388026 -273.320331)
			(xy 296.355391 -273.283494) (xy 296.329088 -273.241898) (xy 296.309797 -273.196622) (xy 296.29802 -273.148838)
			(xy 296.29406 -273.099784) (xy 295.976802 -273.099784) (xy 295.976298 -273.125492) (xy 295.968255 -273.176274)
			(xy 295.952367 -273.225173) (xy 295.929024 -273.270985) (xy 295.898803 -273.312581) (xy 295.862447 -273.348937)
			(xy 295.820851 -273.379158) (xy 295.775039 -273.402501) (xy 295.72614 -273.418389) (xy 295.675358 -273.426432)
			(xy 295.623942 -273.426432) (xy 295.57316 -273.418389) (xy 295.524261 -273.402501) (xy 295.478449 -273.379158)
			(xy 295.436853 -273.348937) (xy 295.400497 -273.312581) (xy 295.370276 -273.270985) (xy 295.346933 -273.225173)
			(xy 295.331045 -273.176274) (xy 295.323002 -273.125492) (xy 295.004324 -273.125492) (xy 294.996608 -273.172968)
			(xy 294.981024 -273.219649) (xy 294.958153 -273.263226) (xy 294.928588 -273.30257) (xy 294.893095 -273.336662)
			(xy 294.852592 -273.364618) (xy 294.80813 -273.385716) (xy 294.760859 -273.399408) (xy 294.712004 -273.40534)
			(xy 294.662829 -273.403359) (xy 294.61461 -273.393515) (xy 294.568594 -273.376063) (xy 294.525973 -273.351456)
			(xy 294.487852 -273.320331) (xy 294.455217 -273.283494) (xy 294.428914 -273.241898) (xy 294.409623 -273.196622)
			(xy 294.397846 -273.148838) (xy 294.393886 -273.099784) (xy 294.076628 -273.099784) (xy 294.076124 -273.125492)
			(xy 294.068081 -273.176274) (xy 294.052193 -273.225173) (xy 294.02885 -273.270985) (xy 293.998629 -273.312581)
			(xy 293.962273 -273.348937) (xy 293.920677 -273.379158) (xy 293.874865 -273.402501) (xy 293.825966 -273.418389)
			(xy 293.775184 -273.426432) (xy 293.723768 -273.426432) (xy 293.672986 -273.418389) (xy 293.624087 -273.402501)
			(xy 293.578275 -273.379158) (xy 293.536679 -273.348937) (xy 293.500323 -273.312581) (xy 293.470102 -273.270985)
			(xy 293.446759 -273.225173) (xy 293.430871 -273.176274) (xy 293.422828 -273.125492) (xy 293.104404 -273.125492)
			(xy 293.096688 -273.172968) (xy 293.081104 -273.219649) (xy 293.058233 -273.263226) (xy 293.028668 -273.30257)
			(xy 292.993175 -273.336662) (xy 292.952672 -273.364618) (xy 292.90821 -273.385716) (xy 292.860939 -273.399408)
			(xy 292.812084 -273.40534) (xy 292.762909 -273.403359) (xy 292.71469 -273.393515) (xy 292.668674 -273.376063)
			(xy 292.626053 -273.351456) (xy 292.587932 -273.320331) (xy 292.555297 -273.283494) (xy 292.528994 -273.241898)
			(xy 292.509703 -273.196622) (xy 292.497926 -273.148838) (xy 292.493966 -273.099784) (xy 292.17599 -273.099784)
			(xy 292.17599 -273.12519) (xy 292.167952 -273.175936) (xy 292.152073 -273.224801) (xy 292.128746 -273.270579)
			(xy 292.098544 -273.312144) (xy 292.062211 -273.348472) (xy 292.020641 -273.378669) (xy 291.97486 -273.40199)
			(xy 291.925993 -273.417862) (xy 291.875246 -273.425894) (xy 291.849556 -273.426428) (xy 291.823374 -273.425908)
			(xy 291.771682 -273.417555) (xy 291.721982 -273.401069) (xy 291.675545 -273.376871) (xy 291.65423 -273.361658)
			(xy 291.642292 -273.353022) (xy 291.614098 -273.350482) (xy 291.519864 -273.397726) (xy 291.511616 -273.402272)
			(xy 291.49897 -273.41621) (xy 291.492225 -273.433781) (xy 291.491924 -273.443192) (xy 291.491924 -273.705828)
			(xy 291.492366 -273.715208) (xy 291.499129 -273.73271) (xy 291.511711 -273.746629) (xy 291.519864 -273.751294)
			(xy 291.614098 -273.798538) (xy 291.642292 -273.795998) (xy 291.65423 -273.787362) (xy 291.675533 -273.772129)
			(xy 291.721973 -273.747929) (xy 291.771676 -273.731441) (xy 291.823373 -273.723086) (xy 291.849556 -273.722592)
			(xy 291.875249 -273.723066) (xy 291.926003 -273.731098) (xy 291.974875 -273.746972) (xy 292.020663 -273.770297)
			(xy 292.062237 -273.800497) (xy 292.098574 -273.83683) (xy 292.12878 -273.8784) (xy 292.152111 -273.924184)
			(xy 292.167991 -273.973054) (xy 292.17603 -274.023807) (xy 292.17603 -274.049744) (xy 292.493966 -274.049744)
			(xy 292.497926 -274.00069) (xy 292.509703 -273.952906) (xy 292.528994 -273.90763) (xy 292.555297 -273.866034)
			(xy 292.587932 -273.829197) (xy 292.626053 -273.798072) (xy 292.668674 -273.773465) (xy 292.71469 -273.756013)
			(xy 292.762909 -273.746169) (xy 292.812084 -273.744188) (xy 292.860939 -273.75012) (xy 292.90821 -273.763812)
			(xy 292.952672 -273.78491) (xy 292.993175 -273.812866) (xy 293.028668 -273.846958) (xy 293.058233 -273.886302)
			(xy 293.081104 -273.929879) (xy 293.096688 -273.97656) (xy 293.104583 -274.025137) (xy 293.105078 -274.049744)
			(xy 293.104583 -274.074351) (xy 293.104404 -274.075452) (xy 293.422828 -274.075452) (xy 293.422828 -274.024036)
			(xy 293.430871 -273.973254) (xy 293.446759 -273.924355) (xy 293.470102 -273.878543) (xy 293.500323 -273.836947)
			(xy 293.536679 -273.800591) (xy 293.578275 -273.77037) (xy 293.624087 -273.747027) (xy 293.672986 -273.731139)
			(xy 293.723768 -273.723096) (xy 293.775184 -273.723096) (xy 293.825966 -273.731139) (xy 293.874865 -273.747027)
			(xy 293.920677 -273.77037) (xy 293.962273 -273.800591) (xy 293.998629 -273.836947) (xy 294.02885 -273.878543)
			(xy 294.052193 -273.924355) (xy 294.068081 -273.973254) (xy 294.076124 -274.024036) (xy 294.076628 -274.049744)
			(xy 294.393886 -274.049744) (xy 294.397846 -274.00069) (xy 294.409623 -273.952906) (xy 294.428914 -273.90763)
			(xy 294.455217 -273.866034) (xy 294.487852 -273.829197) (xy 294.525973 -273.798072) (xy 294.568594 -273.773465)
			(xy 294.61461 -273.756013) (xy 294.662829 -273.746169) (xy 294.712004 -273.744188) (xy 294.760859 -273.75012)
			(xy 294.80813 -273.763812) (xy 294.852592 -273.78491) (xy 294.893095 -273.812866) (xy 294.928588 -273.846958)
			(xy 294.958153 -273.886302) (xy 294.981024 -273.929879) (xy 294.996608 -273.97656) (xy 295.004503 -274.025137)
			(xy 295.004998 -274.049744) (xy 295.004503 -274.074351) (xy 295.004324 -274.075452) (xy 295.323002 -274.075452)
			(xy 295.323002 -274.024036) (xy 295.331045 -273.973254) (xy 295.346933 -273.924355) (xy 295.370276 -273.878543)
			(xy 295.400497 -273.836947) (xy 295.436853 -273.800591) (xy 295.478449 -273.77037) (xy 295.524261 -273.747027)
			(xy 295.57316 -273.731139) (xy 295.623942 -273.723096) (xy 295.675358 -273.723096) (xy 295.72614 -273.731139)
			(xy 295.775039 -273.747027) (xy 295.820851 -273.77037) (xy 295.862447 -273.800591) (xy 295.898803 -273.836947)
			(xy 295.929024 -273.878543) (xy 295.952367 -273.924355) (xy 295.968255 -273.973254) (xy 295.976298 -274.024036)
			(xy 295.976802 -274.049744) (xy 296.29406 -274.049744) (xy 296.29802 -274.00069) (xy 296.309797 -273.952906)
			(xy 296.329088 -273.90763) (xy 296.355391 -273.866034) (xy 296.388026 -273.829197) (xy 296.426147 -273.798072)
			(xy 296.468768 -273.773465) (xy 296.514784 -273.756013) (xy 296.563003 -273.746169) (xy 296.612178 -273.744188)
			(xy 296.661033 -273.75012) (xy 296.708304 -273.763812) (xy 296.752766 -273.78491) (xy 296.793269 -273.812866)
			(xy 296.828762 -273.846958) (xy 296.858327 -273.886302) (xy 296.881198 -273.929879) (xy 296.896782 -273.97656)
			(xy 296.904677 -274.025137) (xy 296.905172 -274.049744) (xy 296.904677 -274.074351) (xy 296.904498 -274.075452)
			(xy 297.222922 -274.075452) (xy 297.222922 -274.024036) (xy 297.230965 -273.973254) (xy 297.246853 -273.924355)
			(xy 297.270196 -273.878543) (xy 297.300417 -273.836947) (xy 297.336773 -273.800591) (xy 297.378369 -273.77037)
			(xy 297.424181 -273.747027) (xy 297.47308 -273.731139) (xy 297.523862 -273.723096) (xy 297.575278 -273.723096)
			(xy 297.62606 -273.731139) (xy 297.674959 -273.747027) (xy 297.720771 -273.77037) (xy 297.762367 -273.800591)
			(xy 297.798723 -273.836947) (xy 297.828944 -273.878543) (xy 297.852287 -273.924355) (xy 297.868175 -273.973254)
			(xy 297.876218 -274.024036) (xy 297.876722 -274.049744) (xy 298.19398 -274.049744) (xy 298.19794 -274.00069)
			(xy 298.209717 -273.952906) (xy 298.229008 -273.90763) (xy 298.255311 -273.866034) (xy 298.287946 -273.829197)
			(xy 298.326067 -273.798072) (xy 298.368688 -273.773465) (xy 298.414704 -273.756013) (xy 298.462923 -273.746169)
			(xy 298.512098 -273.744188) (xy 298.560953 -273.75012) (xy 298.608224 -273.763812) (xy 298.652686 -273.78491)
			(xy 298.693189 -273.812866) (xy 298.728682 -273.846958) (xy 298.758247 -273.886302) (xy 298.781118 -273.929879)
			(xy 298.796702 -273.97656) (xy 298.804597 -274.025137) (xy 298.805092 -274.049744) (xy 298.804597 -274.074351)
			(xy 298.804418 -274.075452) (xy 299.122842 -274.075452) (xy 299.122842 -274.024036) (xy 299.130885 -273.973254)
			(xy 299.146773 -273.924355) (xy 299.170116 -273.878543) (xy 299.200337 -273.836947) (xy 299.236693 -273.800591)
			(xy 299.278289 -273.77037) (xy 299.324101 -273.747027) (xy 299.373 -273.731139) (xy 299.423782 -273.723096)
			(xy 299.475198 -273.723096) (xy 299.52598 -273.731139) (xy 299.574879 -273.747027) (xy 299.620691 -273.77037)
			(xy 299.662287 -273.800591) (xy 299.698643 -273.836947) (xy 299.728864 -273.878543) (xy 299.752207 -273.924355)
			(xy 299.768095 -273.973254) (xy 299.776138 -274.024036) (xy 299.776642 -274.049744) (xy 300.0939 -274.049744)
			(xy 300.09786 -274.00069) (xy 300.109637 -273.952906) (xy 300.128928 -273.90763) (xy 300.155231 -273.866034)
			(xy 300.187866 -273.829197) (xy 300.225987 -273.798072) (xy 300.268608 -273.773465) (xy 300.314624 -273.756013)
			(xy 300.362843 -273.746169) (xy 300.412018 -273.744188) (xy 300.460873 -273.75012) (xy 300.508144 -273.763812)
			(xy 300.552606 -273.78491) (xy 300.593109 -273.812866) (xy 300.628602 -273.846958) (xy 300.658167 -273.886302)
			(xy 300.681038 -273.929879) (xy 300.696622 -273.97656) (xy 300.704517 -274.025137) (xy 300.705012 -274.049744)
			(xy 300.704517 -274.074351) (xy 300.704338 -274.075452) (xy 301.023016 -274.075452) (xy 301.023016 -274.024036)
			(xy 301.031059 -273.973254) (xy 301.046947 -273.924355) (xy 301.07029 -273.878543) (xy 301.100511 -273.836947)
			(xy 301.136867 -273.800591) (xy 301.178463 -273.77037) (xy 301.224275 -273.747027) (xy 301.273174 -273.731139)
			(xy 301.323956 -273.723096) (xy 301.375372 -273.723096) (xy 301.426154 -273.731139) (xy 301.475053 -273.747027)
			(xy 301.520865 -273.77037) (xy 301.562461 -273.800591) (xy 301.598817 -273.836947) (xy 301.629038 -273.878543)
			(xy 301.652381 -273.924355) (xy 301.668269 -273.973254) (xy 301.676312 -274.024036) (xy 301.676816 -274.049744)
			(xy 301.994074 -274.049744) (xy 301.998034 -274.00069) (xy 302.009811 -273.952906) (xy 302.029102 -273.90763)
			(xy 302.055405 -273.866034) (xy 302.08804 -273.829197) (xy 302.126161 -273.798072) (xy 302.168782 -273.773465)
			(xy 302.214798 -273.756013) (xy 302.263017 -273.746169) (xy 302.312192 -273.744188) (xy 302.361047 -273.75012)
			(xy 302.408318 -273.763812) (xy 302.45278 -273.78491) (xy 302.493283 -273.812866) (xy 302.528776 -273.846958)
			(xy 302.558341 -273.886302) (xy 302.581212 -273.929879) (xy 302.596796 -273.97656) (xy 302.604691 -274.025137)
			(xy 302.605186 -274.049744) (xy 302.604691 -274.074351) (xy 302.604512 -274.075452) (xy 302.922936 -274.075452)
			(xy 302.922936 -274.024036) (xy 302.930979 -273.973254) (xy 302.946867 -273.924355) (xy 302.97021 -273.878543)
			(xy 303.000431 -273.836947) (xy 303.036787 -273.800591) (xy 303.078383 -273.77037) (xy 303.124195 -273.747027)
			(xy 303.173094 -273.731139) (xy 303.223876 -273.723096) (xy 303.275292 -273.723096) (xy 303.326074 -273.731139)
			(xy 303.374973 -273.747027) (xy 303.420785 -273.77037) (xy 303.462381 -273.800591) (xy 303.498737 -273.836947)
			(xy 303.528958 -273.878543) (xy 303.552301 -273.924355) (xy 303.568189 -273.973254) (xy 303.576232 -274.024036)
			(xy 303.576736 -274.049744) (xy 303.893994 -274.049744) (xy 303.897954 -274.00069) (xy 303.909731 -273.952906)
			(xy 303.929022 -273.90763) (xy 303.955325 -273.866034) (xy 303.98796 -273.829197) (xy 304.026081 -273.798072)
			(xy 304.068702 -273.773465) (xy 304.114718 -273.756013) (xy 304.162937 -273.746169) (xy 304.212112 -273.744188)
			(xy 304.260967 -273.75012) (xy 304.308238 -273.763812) (xy 304.3527 -273.78491) (xy 304.393203 -273.812866)
			(xy 304.428696 -273.846958) (xy 304.458261 -273.886302) (xy 304.481132 -273.929879) (xy 304.496716 -273.97656)
			(xy 304.504611 -274.025137) (xy 304.505106 -274.049744) (xy 304.504611 -274.074351) (xy 304.504432 -274.075452)
			(xy 304.822856 -274.075452) (xy 304.822856 -274.024036) (xy 304.830899 -273.973254) (xy 304.846787 -273.924355)
			(xy 304.87013 -273.878543) (xy 304.900351 -273.836947) (xy 304.936707 -273.800591) (xy 304.978303 -273.77037)
			(xy 305.024115 -273.747027) (xy 305.073014 -273.731139) (xy 305.123796 -273.723096) (xy 305.175212 -273.723096)
			(xy 305.225994 -273.731139) (xy 305.274893 -273.747027) (xy 305.320705 -273.77037) (xy 305.362301 -273.800591)
			(xy 305.398657 -273.836947) (xy 305.428878 -273.878543) (xy 305.452221 -273.924355) (xy 305.468109 -273.973254)
			(xy 305.476152 -274.024036) (xy 305.476656 -274.049744) (xy 305.793914 -274.049744) (xy 305.797874 -274.00069)
			(xy 305.809651 -273.952906) (xy 305.828942 -273.90763) (xy 305.855245 -273.866034) (xy 305.88788 -273.829197)
			(xy 305.926001 -273.798072) (xy 305.968622 -273.773465) (xy 306.014638 -273.756013) (xy 306.062857 -273.746169)
			(xy 306.112032 -273.744188) (xy 306.160887 -273.75012) (xy 306.208158 -273.763812) (xy 306.25262 -273.78491)
			(xy 306.293123 -273.812866) (xy 306.328616 -273.846958) (xy 306.358181 -273.886302) (xy 306.381052 -273.929879)
			(xy 306.396636 -273.97656) (xy 306.404531 -274.025137) (xy 306.405026 -274.049744) (xy 306.404531 -274.074351)
			(xy 306.404352 -274.075452) (xy 306.72303 -274.075452) (xy 306.72303 -274.024036) (xy 306.731073 -273.973254)
			(xy 306.746961 -273.924355) (xy 306.770304 -273.878543) (xy 306.800525 -273.836947) (xy 306.836881 -273.800591)
			(xy 306.878477 -273.77037) (xy 306.924289 -273.747027) (xy 306.973188 -273.731139) (xy 307.02397 -273.723096)
			(xy 307.075386 -273.723096) (xy 307.126168 -273.731139) (xy 307.175067 -273.747027) (xy 307.220879 -273.77037)
			(xy 307.262475 -273.800591) (xy 307.298831 -273.836947) (xy 307.329052 -273.878543) (xy 307.352395 -273.924355)
			(xy 307.368283 -273.973254) (xy 307.376326 -274.024036) (xy 307.37683 -274.049744) (xy 307.694342 -274.049744)
			(xy 307.698302 -274.00069) (xy 307.710079 -273.952906) (xy 307.72937 -273.90763) (xy 307.755673 -273.866034)
			(xy 307.788308 -273.829197) (xy 307.826429 -273.798072) (xy 307.86905 -273.773465) (xy 307.915066 -273.756013)
			(xy 307.963285 -273.746169) (xy 308.01246 -273.744188) (xy 308.061315 -273.75012) (xy 308.108586 -273.763812)
			(xy 308.153048 -273.78491) (xy 308.193551 -273.812866) (xy 308.229044 -273.846958) (xy 308.258609 -273.886302)
			(xy 308.28148 -273.929879) (xy 308.297064 -273.97656) (xy 308.304959 -274.025137) (xy 308.305454 -274.049744)
			(xy 308.304959 -274.074351) (xy 308.30478 -274.075452) (xy 308.62295 -274.075452) (xy 308.62295 -274.024036)
			(xy 308.630993 -273.973254) (xy 308.646881 -273.924355) (xy 308.670224 -273.878543) (xy 308.700445 -273.836947)
			(xy 308.736801 -273.800591) (xy 308.778397 -273.77037) (xy 308.824209 -273.747027) (xy 308.873108 -273.731139)
			(xy 308.92389 -273.723096) (xy 308.975306 -273.723096) (xy 309.026088 -273.731139) (xy 309.074987 -273.747027)
			(xy 309.120799 -273.77037) (xy 309.162395 -273.800591) (xy 309.198751 -273.836947) (xy 309.228972 -273.878543)
			(xy 309.252315 -273.924355) (xy 309.268203 -273.973254) (xy 309.276246 -274.024036) (xy 309.27675 -274.049744)
			(xy 309.594262 -274.049744) (xy 309.598222 -274.00069) (xy 309.609999 -273.952906) (xy 309.62929 -273.90763)
			(xy 309.655593 -273.866034) (xy 309.688228 -273.829197) (xy 309.726349 -273.798072) (xy 309.76897 -273.773465)
			(xy 309.814986 -273.756013) (xy 309.863205 -273.746169) (xy 309.91238 -273.744188) (xy 309.961235 -273.75012)
			(xy 310.008506 -273.763812) (xy 310.052968 -273.78491) (xy 310.093471 -273.812866) (xy 310.128964 -273.846958)
			(xy 310.158529 -273.886302) (xy 310.1814 -273.929879) (xy 310.196984 -273.97656) (xy 310.204879 -274.025137)
			(xy 310.205374 -274.049744) (xy 310.204879 -274.074351) (xy 310.2047 -274.075452) (xy 310.52287 -274.075452)
			(xy 310.52287 -274.024036) (xy 310.530913 -273.973254) (xy 310.546801 -273.924355) (xy 310.570144 -273.878543)
			(xy 310.600365 -273.836947) (xy 310.636721 -273.800591) (xy 310.678317 -273.77037) (xy 310.724129 -273.747027)
			(xy 310.773028 -273.731139) (xy 310.82381 -273.723096) (xy 310.875226 -273.723096) (xy 310.926008 -273.731139)
			(xy 310.974907 -273.747027) (xy 311.020719 -273.77037) (xy 311.062315 -273.800591) (xy 311.098671 -273.836947)
			(xy 311.128892 -273.878543) (xy 311.152235 -273.924355) (xy 311.168123 -273.973254) (xy 311.176166 -274.024036)
			(xy 311.17667 -274.049744) (xy 311.494182 -274.049744) (xy 311.498142 -274.00069) (xy 311.509919 -273.952906)
			(xy 311.52921 -273.90763) (xy 311.555513 -273.866034) (xy 311.588148 -273.829197) (xy 311.626269 -273.798072)
			(xy 311.66889 -273.773465) (xy 311.714906 -273.756013) (xy 311.763125 -273.746169) (xy 311.8123 -273.744188)
			(xy 311.861155 -273.75012) (xy 311.908426 -273.763812) (xy 311.952888 -273.78491) (xy 311.993391 -273.812866)
			(xy 312.028884 -273.846958) (xy 312.058449 -273.886302) (xy 312.08132 -273.929879) (xy 312.096904 -273.97656)
			(xy 312.104799 -274.025137) (xy 312.105294 -274.049744) (xy 312.104799 -274.074351) (xy 312.10462 -274.075452)
			(xy 312.42279 -274.075452) (xy 312.42279 -274.024036) (xy 312.430833 -273.973254) (xy 312.446721 -273.924355)
			(xy 312.470064 -273.878543) (xy 312.500285 -273.836947) (xy 312.536641 -273.800591) (xy 312.578237 -273.77037)
			(xy 312.624049 -273.747027) (xy 312.672948 -273.731139) (xy 312.72373 -273.723096) (xy 312.775146 -273.723096)
			(xy 312.825928 -273.731139) (xy 312.874827 -273.747027) (xy 312.920639 -273.77037) (xy 312.962235 -273.800591)
			(xy 312.998591 -273.836947) (xy 313.028812 -273.878543) (xy 313.052155 -273.924355) (xy 313.068043 -273.973254)
			(xy 313.076086 -274.024036) (xy 313.07659 -274.049744) (xy 313.394102 -274.049744) (xy 313.398062 -274.00069)
			(xy 313.409839 -273.952906) (xy 313.42913 -273.90763) (xy 313.455433 -273.866034) (xy 313.488068 -273.829197)
			(xy 313.526189 -273.798072) (xy 313.56881 -273.773465) (xy 313.614826 -273.756013) (xy 313.663045 -273.746169)
			(xy 313.71222 -273.744188) (xy 313.761075 -273.75012) (xy 313.808346 -273.763812) (xy 313.852808 -273.78491)
			(xy 313.893311 -273.812866) (xy 313.928804 -273.846958) (xy 313.958369 -273.886302) (xy 313.98124 -273.929879)
			(xy 313.996824 -273.97656) (xy 314.004719 -274.025137) (xy 314.005214 -274.049744) (xy 314.344062 -274.049744)
			(xy 314.348022 -274.00069) (xy 314.359799 -273.952906) (xy 314.37909 -273.90763) (xy 314.405393 -273.866034)
			(xy 314.438028 -273.829197) (xy 314.476149 -273.798072) (xy 314.51877 -273.773465) (xy 314.564786 -273.756013)
			(xy 314.613005 -273.746169) (xy 314.66218 -273.744188) (xy 314.711035 -273.75012) (xy 314.758306 -273.763812)
			(xy 314.802768 -273.78491) (xy 314.843271 -273.812866) (xy 314.878764 -273.846958) (xy 314.908329 -273.886302)
			(xy 314.9312 -273.929879) (xy 314.946784 -273.97656) (xy 314.954679 -274.025137) (xy 314.955174 -274.049744)
			(xy 314.954679 -274.074351) (xy 314.946784 -274.122928) (xy 314.9312 -274.169609) (xy 314.908329 -274.213186)
			(xy 314.878764 -274.25253) (xy 314.843271 -274.286622) (xy 314.802768 -274.314578) (xy 314.758306 -274.335676)
			(xy 314.711035 -274.349368) (xy 314.66218 -274.3553) (xy 314.613005 -274.353319) (xy 314.564786 -274.343475)
			(xy 314.51877 -274.326023) (xy 314.476149 -274.301416) (xy 314.438028 -274.270291) (xy 314.405393 -274.233454)
			(xy 314.37909 -274.191858) (xy 314.359799 -274.146582) (xy 314.348022 -274.098798) (xy 314.344062 -274.049744)
			(xy 314.005214 -274.049744) (xy 314.004719 -274.074351) (xy 313.996824 -274.122928) (xy 313.98124 -274.169609)
			(xy 313.958369 -274.213186) (xy 313.928804 -274.25253) (xy 313.893311 -274.286622) (xy 313.852808 -274.314578)
			(xy 313.808346 -274.335676) (xy 313.761075 -274.349368) (xy 313.71222 -274.3553) (xy 313.663045 -274.353319)
			(xy 313.614826 -274.343475) (xy 313.56881 -274.326023) (xy 313.526189 -274.301416) (xy 313.488068 -274.270291)
			(xy 313.455433 -274.233454) (xy 313.42913 -274.191858) (xy 313.409839 -274.146582) (xy 313.398062 -274.098798)
			(xy 313.394102 -274.049744) (xy 313.07659 -274.049744) (xy 313.076086 -274.075452) (xy 313.068043 -274.126234)
			(xy 313.052155 -274.175133) (xy 313.028812 -274.220945) (xy 312.998591 -274.262541) (xy 312.962235 -274.298897)
			(xy 312.920639 -274.329118) (xy 312.874827 -274.352461) (xy 312.825928 -274.368349) (xy 312.775146 -274.376392)
			(xy 312.72373 -274.376392) (xy 312.672948 -274.368349) (xy 312.624049 -274.352461) (xy 312.578237 -274.329118)
			(xy 312.536641 -274.298897) (xy 312.500285 -274.262541) (xy 312.470064 -274.220945) (xy 312.446721 -274.175133)
			(xy 312.430833 -274.126234) (xy 312.42279 -274.075452) (xy 312.10462 -274.075452) (xy 312.096904 -274.122928)
			(xy 312.08132 -274.169609) (xy 312.058449 -274.213186) (xy 312.028884 -274.25253) (xy 311.993391 -274.286622)
			(xy 311.952888 -274.314578) (xy 311.908426 -274.335676) (xy 311.861155 -274.349368) (xy 311.8123 -274.3553)
			(xy 311.763125 -274.353319) (xy 311.714906 -274.343475) (xy 311.66889 -274.326023) (xy 311.626269 -274.301416)
			(xy 311.588148 -274.270291) (xy 311.555513 -274.233454) (xy 311.52921 -274.191858) (xy 311.509919 -274.146582)
			(xy 311.498142 -274.098798) (xy 311.494182 -274.049744) (xy 311.17667 -274.049744) (xy 311.176166 -274.075452)
			(xy 311.168123 -274.126234) (xy 311.152235 -274.175133) (xy 311.128892 -274.220945) (xy 311.098671 -274.262541)
			(xy 311.062315 -274.298897) (xy 311.020719 -274.329118) (xy 310.974907 -274.352461) (xy 310.926008 -274.368349)
			(xy 310.875226 -274.376392) (xy 310.82381 -274.376392) (xy 310.773028 -274.368349) (xy 310.724129 -274.352461)
			(xy 310.678317 -274.329118) (xy 310.636721 -274.298897) (xy 310.600365 -274.262541) (xy 310.570144 -274.220945)
			(xy 310.546801 -274.175133) (xy 310.530913 -274.126234) (xy 310.52287 -274.075452) (xy 310.2047 -274.075452)
			(xy 310.196984 -274.122928) (xy 310.1814 -274.169609) (xy 310.158529 -274.213186) (xy 310.128964 -274.25253)
			(xy 310.093471 -274.286622) (xy 310.052968 -274.314578) (xy 310.008506 -274.335676) (xy 309.961235 -274.349368)
			(xy 309.91238 -274.3553) (xy 309.863205 -274.353319) (xy 309.814986 -274.343475) (xy 309.76897 -274.326023)
			(xy 309.726349 -274.301416) (xy 309.688228 -274.270291) (xy 309.655593 -274.233454) (xy 309.62929 -274.191858)
			(xy 309.609999 -274.146582) (xy 309.598222 -274.098798) (xy 309.594262 -274.049744) (xy 309.27675 -274.049744)
			(xy 309.276246 -274.075452) (xy 309.268203 -274.126234) (xy 309.252315 -274.175133) (xy 309.228972 -274.220945)
			(xy 309.198751 -274.262541) (xy 309.162395 -274.298897) (xy 309.120799 -274.329118) (xy 309.074987 -274.352461)
			(xy 309.026088 -274.368349) (xy 308.975306 -274.376392) (xy 308.92389 -274.376392) (xy 308.873108 -274.368349)
			(xy 308.824209 -274.352461) (xy 308.778397 -274.329118) (xy 308.736801 -274.298897) (xy 308.700445 -274.262541)
			(xy 308.670224 -274.220945) (xy 308.646881 -274.175133) (xy 308.630993 -274.126234) (xy 308.62295 -274.075452)
			(xy 308.30478 -274.075452) (xy 308.297064 -274.122928) (xy 308.28148 -274.169609) (xy 308.258609 -274.213186)
			(xy 308.229044 -274.25253) (xy 308.193551 -274.286622) (xy 308.153048 -274.314578) (xy 308.108586 -274.335676)
			(xy 308.061315 -274.349368) (xy 308.01246 -274.3553) (xy 307.963285 -274.353319) (xy 307.915066 -274.343475)
			(xy 307.86905 -274.326023) (xy 307.826429 -274.301416) (xy 307.788308 -274.270291) (xy 307.755673 -274.233454)
			(xy 307.72937 -274.191858) (xy 307.710079 -274.146582) (xy 307.698302 -274.098798) (xy 307.694342 -274.049744)
			(xy 307.37683 -274.049744) (xy 307.376326 -274.075452) (xy 307.368283 -274.126234) (xy 307.352395 -274.175133)
			(xy 307.329052 -274.220945) (xy 307.298831 -274.262541) (xy 307.262475 -274.298897) (xy 307.220879 -274.329118)
			(xy 307.175067 -274.352461) (xy 307.126168 -274.368349) (xy 307.075386 -274.376392) (xy 307.02397 -274.376392)
			(xy 306.973188 -274.368349) (xy 306.924289 -274.352461) (xy 306.878477 -274.329118) (xy 306.836881 -274.298897)
			(xy 306.800525 -274.262541) (xy 306.770304 -274.220945) (xy 306.746961 -274.175133) (xy 306.731073 -274.126234)
			(xy 306.72303 -274.075452) (xy 306.404352 -274.075452) (xy 306.396636 -274.122928) (xy 306.381052 -274.169609)
			(xy 306.358181 -274.213186) (xy 306.328616 -274.25253) (xy 306.293123 -274.286622) (xy 306.25262 -274.314578)
			(xy 306.208158 -274.335676) (xy 306.160887 -274.349368) (xy 306.112032 -274.3553) (xy 306.062857 -274.353319)
			(xy 306.014638 -274.343475) (xy 305.968622 -274.326023) (xy 305.926001 -274.301416) (xy 305.88788 -274.270291)
			(xy 305.855245 -274.233454) (xy 305.828942 -274.191858) (xy 305.809651 -274.146582) (xy 305.797874 -274.098798)
			(xy 305.793914 -274.049744) (xy 305.476656 -274.049744) (xy 305.476152 -274.075452) (xy 305.468109 -274.126234)
			(xy 305.452221 -274.175133) (xy 305.428878 -274.220945) (xy 305.398657 -274.262541) (xy 305.362301 -274.298897)
			(xy 305.320705 -274.329118) (xy 305.274893 -274.352461) (xy 305.225994 -274.368349) (xy 305.175212 -274.376392)
			(xy 305.123796 -274.376392) (xy 305.073014 -274.368349) (xy 305.024115 -274.352461) (xy 304.978303 -274.329118)
			(xy 304.936707 -274.298897) (xy 304.900351 -274.262541) (xy 304.87013 -274.220945) (xy 304.846787 -274.175133)
			(xy 304.830899 -274.126234) (xy 304.822856 -274.075452) (xy 304.504432 -274.075452) (xy 304.496716 -274.122928)
			(xy 304.481132 -274.169609) (xy 304.458261 -274.213186) (xy 304.428696 -274.25253) (xy 304.393203 -274.286622)
			(xy 304.3527 -274.314578) (xy 304.308238 -274.335676) (xy 304.260967 -274.349368) (xy 304.212112 -274.3553)
			(xy 304.162937 -274.353319) (xy 304.114718 -274.343475) (xy 304.068702 -274.326023) (xy 304.026081 -274.301416)
			(xy 303.98796 -274.270291) (xy 303.955325 -274.233454) (xy 303.929022 -274.191858) (xy 303.909731 -274.146582)
			(xy 303.897954 -274.098798) (xy 303.893994 -274.049744) (xy 303.576736 -274.049744) (xy 303.576232 -274.075452)
			(xy 303.568189 -274.126234) (xy 303.552301 -274.175133) (xy 303.528958 -274.220945) (xy 303.498737 -274.262541)
			(xy 303.462381 -274.298897) (xy 303.420785 -274.329118) (xy 303.374973 -274.352461) (xy 303.326074 -274.368349)
			(xy 303.275292 -274.376392) (xy 303.223876 -274.376392) (xy 303.173094 -274.368349) (xy 303.124195 -274.352461)
			(xy 303.078383 -274.329118) (xy 303.036787 -274.298897) (xy 303.000431 -274.262541) (xy 302.97021 -274.220945)
			(xy 302.946867 -274.175133) (xy 302.930979 -274.126234) (xy 302.922936 -274.075452) (xy 302.604512 -274.075452)
			(xy 302.596796 -274.122928) (xy 302.581212 -274.169609) (xy 302.558341 -274.213186) (xy 302.528776 -274.25253)
			(xy 302.493283 -274.286622) (xy 302.45278 -274.314578) (xy 302.408318 -274.335676) (xy 302.361047 -274.349368)
			(xy 302.312192 -274.3553) (xy 302.263017 -274.353319) (xy 302.214798 -274.343475) (xy 302.168782 -274.326023)
			(xy 302.126161 -274.301416) (xy 302.08804 -274.270291) (xy 302.055405 -274.233454) (xy 302.029102 -274.191858)
			(xy 302.009811 -274.146582) (xy 301.998034 -274.098798) (xy 301.994074 -274.049744) (xy 301.676816 -274.049744)
			(xy 301.676312 -274.075452) (xy 301.668269 -274.126234) (xy 301.652381 -274.175133) (xy 301.629038 -274.220945)
			(xy 301.598817 -274.262541) (xy 301.562461 -274.298897) (xy 301.520865 -274.329118) (xy 301.475053 -274.352461)
			(xy 301.426154 -274.368349) (xy 301.375372 -274.376392) (xy 301.323956 -274.376392) (xy 301.273174 -274.368349)
			(xy 301.224275 -274.352461) (xy 301.178463 -274.329118) (xy 301.136867 -274.298897) (xy 301.100511 -274.262541)
			(xy 301.07029 -274.220945) (xy 301.046947 -274.175133) (xy 301.031059 -274.126234) (xy 301.023016 -274.075452)
			(xy 300.704338 -274.075452) (xy 300.696622 -274.122928) (xy 300.681038 -274.169609) (xy 300.658167 -274.213186)
			(xy 300.628602 -274.25253) (xy 300.593109 -274.286622) (xy 300.552606 -274.314578) (xy 300.508144 -274.335676)
			(xy 300.460873 -274.349368) (xy 300.412018 -274.3553) (xy 300.362843 -274.353319) (xy 300.314624 -274.343475)
			(xy 300.268608 -274.326023) (xy 300.225987 -274.301416) (xy 300.187866 -274.270291) (xy 300.155231 -274.233454)
			(xy 300.128928 -274.191858) (xy 300.109637 -274.146582) (xy 300.09786 -274.098798) (xy 300.0939 -274.049744)
			(xy 299.776642 -274.049744) (xy 299.776138 -274.075452) (xy 299.768095 -274.126234) (xy 299.752207 -274.175133)
			(xy 299.728864 -274.220945) (xy 299.698643 -274.262541) (xy 299.662287 -274.298897) (xy 299.620691 -274.329118)
			(xy 299.574879 -274.352461) (xy 299.52598 -274.368349) (xy 299.475198 -274.376392) (xy 299.423782 -274.376392)
			(xy 299.373 -274.368349) (xy 299.324101 -274.352461) (xy 299.278289 -274.329118) (xy 299.236693 -274.298897)
			(xy 299.200337 -274.262541) (xy 299.170116 -274.220945) (xy 299.146773 -274.175133) (xy 299.130885 -274.126234)
			(xy 299.122842 -274.075452) (xy 298.804418 -274.075452) (xy 298.796702 -274.122928) (xy 298.781118 -274.169609)
			(xy 298.758247 -274.213186) (xy 298.728682 -274.25253) (xy 298.693189 -274.286622) (xy 298.652686 -274.314578)
			(xy 298.608224 -274.335676) (xy 298.560953 -274.349368) (xy 298.512098 -274.3553) (xy 298.462923 -274.353319)
			(xy 298.414704 -274.343475) (xy 298.368688 -274.326023) (xy 298.326067 -274.301416) (xy 298.287946 -274.270291)
			(xy 298.255311 -274.233454) (xy 298.229008 -274.191858) (xy 298.209717 -274.146582) (xy 298.19794 -274.098798)
			(xy 298.19398 -274.049744) (xy 297.876722 -274.049744) (xy 297.876218 -274.075452) (xy 297.868175 -274.126234)
			(xy 297.852287 -274.175133) (xy 297.828944 -274.220945) (xy 297.798723 -274.262541) (xy 297.762367 -274.298897)
			(xy 297.720771 -274.329118) (xy 297.674959 -274.352461) (xy 297.62606 -274.368349) (xy 297.575278 -274.376392)
			(xy 297.523862 -274.376392) (xy 297.47308 -274.368349) (xy 297.424181 -274.352461) (xy 297.378369 -274.329118)
			(xy 297.336773 -274.298897) (xy 297.300417 -274.262541) (xy 297.270196 -274.220945) (xy 297.246853 -274.175133)
			(xy 297.230965 -274.126234) (xy 297.222922 -274.075452) (xy 296.904498 -274.075452) (xy 296.896782 -274.122928)
			(xy 296.881198 -274.169609) (xy 296.858327 -274.213186) (xy 296.828762 -274.25253) (xy 296.793269 -274.286622)
			(xy 296.752766 -274.314578) (xy 296.708304 -274.335676) (xy 296.661033 -274.349368) (xy 296.612178 -274.3553)
			(xy 296.563003 -274.353319) (xy 296.514784 -274.343475) (xy 296.468768 -274.326023) (xy 296.426147 -274.301416)
			(xy 296.388026 -274.270291) (xy 296.355391 -274.233454) (xy 296.329088 -274.191858) (xy 296.309797 -274.146582)
			(xy 296.29802 -274.098798) (xy 296.29406 -274.049744) (xy 295.976802 -274.049744) (xy 295.976298 -274.075452)
			(xy 295.968255 -274.126234) (xy 295.952367 -274.175133) (xy 295.929024 -274.220945) (xy 295.898803 -274.262541)
			(xy 295.862447 -274.298897) (xy 295.820851 -274.329118) (xy 295.775039 -274.352461) (xy 295.72614 -274.368349)
			(xy 295.675358 -274.376392) (xy 295.623942 -274.376392) (xy 295.57316 -274.368349) (xy 295.524261 -274.352461)
			(xy 295.478449 -274.329118) (xy 295.436853 -274.298897) (xy 295.400497 -274.262541) (xy 295.370276 -274.220945)
			(xy 295.346933 -274.175133) (xy 295.331045 -274.126234) (xy 295.323002 -274.075452) (xy 295.004324 -274.075452)
			(xy 294.996608 -274.122928) (xy 294.981024 -274.169609) (xy 294.958153 -274.213186) (xy 294.928588 -274.25253)
			(xy 294.893095 -274.286622) (xy 294.852592 -274.314578) (xy 294.80813 -274.335676) (xy 294.760859 -274.349368)
			(xy 294.712004 -274.3553) (xy 294.662829 -274.353319) (xy 294.61461 -274.343475) (xy 294.568594 -274.326023)
			(xy 294.525973 -274.301416) (xy 294.487852 -274.270291) (xy 294.455217 -274.233454) (xy 294.428914 -274.191858)
			(xy 294.409623 -274.146582) (xy 294.397846 -274.098798) (xy 294.393886 -274.049744) (xy 294.076628 -274.049744)
			(xy 294.076124 -274.075452) (xy 294.068081 -274.126234) (xy 294.052193 -274.175133) (xy 294.02885 -274.220945)
			(xy 293.998629 -274.262541) (xy 293.962273 -274.298897) (xy 293.920677 -274.329118) (xy 293.874865 -274.352461)
			(xy 293.825966 -274.368349) (xy 293.775184 -274.376392) (xy 293.723768 -274.376392) (xy 293.672986 -274.368349)
			(xy 293.624087 -274.352461) (xy 293.578275 -274.329118) (xy 293.536679 -274.298897) (xy 293.500323 -274.262541)
			(xy 293.470102 -274.220945) (xy 293.446759 -274.175133) (xy 293.430871 -274.126234) (xy 293.422828 -274.075452)
			(xy 293.104404 -274.075452) (xy 293.096688 -274.122928) (xy 293.081104 -274.169609) (xy 293.058233 -274.213186)
			(xy 293.028668 -274.25253) (xy 292.993175 -274.286622) (xy 292.952672 -274.314578) (xy 292.90821 -274.335676)
			(xy 292.860939 -274.349368) (xy 292.812084 -274.3553) (xy 292.762909 -274.353319) (xy 292.71469 -274.343475)
			(xy 292.668674 -274.326023) (xy 292.626053 -274.301416) (xy 292.587932 -274.270291) (xy 292.555297 -274.233454)
			(xy 292.528994 -274.191858) (xy 292.509703 -274.146582) (xy 292.497926 -274.098798) (xy 292.493966 -274.049744)
			(xy 292.17603 -274.049744) (xy 292.17603 -274.075193) (xy 292.167991 -274.125946) (xy 292.152111 -274.174816)
			(xy 292.12878 -274.2206) (xy 292.098574 -274.26217) (xy 292.062237 -274.298503) (xy 292.020663 -274.328703)
			(xy 291.974875 -274.352028) (xy 291.926003 -274.367902) (xy 291.875249 -274.375934) (xy 291.849556 -274.376388)
			(xy 291.840666 -274.376388) (xy 291.82695 -274.376134) (xy 291.803074 -274.389088) (xy 291.742876 -274.488148)
			(xy 291.742368 -274.515326) (xy 291.749226 -274.527264) (xy 291.76688 -274.55979) (xy 291.797776 -274.627045)
			(xy 291.810948 -274.66163) (xy 291.814918 -274.670965) (xy 291.828805 -274.68573) (xy 291.847308 -274.694004)
			(xy 291.85743 -274.69465) (xy 291.88103 -274.695674) (xy 291.927508 -274.7041) (xy 291.972134 -274.719585)
			(xy 292.013842 -274.74176) (xy 292.051635 -274.770095) (xy 292.084613 -274.803914) (xy 292.111987 -274.842409)
			(xy 292.133105 -274.884662) (xy 292.147461 -274.929664) (xy 292.154713 -274.97634) (xy 292.155118 -274.999958)
			(xy 292.154593 -275.025412) (xy 292.472868 -275.025412) (xy 292.472868 -274.973996) (xy 292.480911 -274.923214)
			(xy 292.496799 -274.874315) (xy 292.520142 -274.828503) (xy 292.550363 -274.786907) (xy 292.586719 -274.750551)
			(xy 292.628315 -274.72033) (xy 292.674127 -274.696987) (xy 292.723026 -274.681099) (xy 292.773808 -274.673056)
			(xy 292.825224 -274.673056) (xy 292.876006 -274.681099) (xy 292.924905 -274.696987) (xy 292.970717 -274.72033)
			(xy 293.012313 -274.750551) (xy 293.048669 -274.786907) (xy 293.07889 -274.828503) (xy 293.102233 -274.874315)
			(xy 293.118121 -274.923214) (xy 293.126164 -274.973996) (xy 293.126668 -274.999704) (xy 293.126663 -274.999958)
			(xy 293.443926 -274.999958) (xy 293.447886 -274.950904) (xy 293.459663 -274.90312) (xy 293.478954 -274.857844)
			(xy 293.505257 -274.816248) (xy 293.537892 -274.779411) (xy 293.576013 -274.748286) (xy 293.618634 -274.723679)
			(xy 293.66465 -274.706227) (xy 293.712869 -274.696383) (xy 293.762044 -274.694402) (xy 293.810899 -274.700334)
			(xy 293.85817 -274.714026) (xy 293.902632 -274.735124) (xy 293.943135 -274.76308) (xy 293.978628 -274.797172)
			(xy 294.008193 -274.836516) (xy 294.031064 -274.880093) (xy 294.046648 -274.926774) (xy 294.054543 -274.975351)
			(xy 294.055038 -274.999958) (xy 294.054543 -275.024565) (xy 294.054364 -275.025666) (xy 294.372788 -275.025666)
			(xy 294.372788 -274.97425) (xy 294.380831 -274.923468) (xy 294.396719 -274.874569) (xy 294.420062 -274.828757)
			(xy 294.450283 -274.787161) (xy 294.486639 -274.750805) (xy 294.528235 -274.720584) (xy 294.574047 -274.697241)
			(xy 294.622946 -274.681353) (xy 294.673728 -274.67331) (xy 294.725144 -274.67331) (xy 294.775926 -274.681353)
			(xy 294.824825 -274.697241) (xy 294.870637 -274.720584) (xy 294.912233 -274.750805) (xy 294.948589 -274.787161)
			(xy 294.97881 -274.828757) (xy 295.002153 -274.874569) (xy 295.018041 -274.923468) (xy 295.026084 -274.97425)
			(xy 295.026588 -274.999958) (xy 295.3441 -274.999958) (xy 295.34806 -274.950904) (xy 295.359837 -274.90312)
			(xy 295.379128 -274.857844) (xy 295.405431 -274.816248) (xy 295.438066 -274.779411) (xy 295.476187 -274.748286)
			(xy 295.518808 -274.723679) (xy 295.564824 -274.706227) (xy 295.613043 -274.696383) (xy 295.662218 -274.694402)
			(xy 295.711073 -274.700334) (xy 295.758344 -274.714026) (xy 295.802806 -274.735124) (xy 295.843309 -274.76308)
			(xy 295.878802 -274.797172) (xy 295.908367 -274.836516) (xy 295.931238 -274.880093) (xy 295.946822 -274.926774)
			(xy 295.954717 -274.975351) (xy 295.955212 -274.999958) (xy 295.954717 -275.024565) (xy 295.954579 -275.025412)
			(xy 296.272962 -275.025412) (xy 296.272962 -274.973996) (xy 296.281005 -274.923214) (xy 296.296893 -274.874315)
			(xy 296.320236 -274.828503) (xy 296.350457 -274.786907) (xy 296.386813 -274.750551) (xy 296.428409 -274.72033)
			(xy 296.474221 -274.696987) (xy 296.52312 -274.681099) (xy 296.573902 -274.673056) (xy 296.625318 -274.673056)
			(xy 296.6761 -274.681099) (xy 296.724999 -274.696987) (xy 296.770811 -274.72033) (xy 296.812407 -274.750551)
			(xy 296.848763 -274.786907) (xy 296.878984 -274.828503) (xy 296.902327 -274.874315) (xy 296.918215 -274.923214)
			(xy 296.926258 -274.973996) (xy 296.926762 -274.999704) (xy 296.926757 -274.999958) (xy 297.24402 -274.999958)
			(xy 297.24798 -274.950904) (xy 297.259757 -274.90312) (xy 297.279048 -274.857844) (xy 297.305351 -274.816248)
			(xy 297.337986 -274.779411) (xy 297.376107 -274.748286) (xy 297.418728 -274.723679) (xy 297.464744 -274.706227)
			(xy 297.512963 -274.696383) (xy 297.562138 -274.694402) (xy 297.610993 -274.700334) (xy 297.658264 -274.714026)
			(xy 297.702726 -274.735124) (xy 297.743229 -274.76308) (xy 297.778722 -274.797172) (xy 297.808287 -274.836516)
			(xy 297.831158 -274.880093) (xy 297.846742 -274.926774) (xy 297.854637 -274.975351) (xy 297.855132 -274.999958)
			(xy 297.854637 -275.024565) (xy 297.854458 -275.025666) (xy 298.172882 -275.025666) (xy 298.172882 -274.97425)
			(xy 298.180925 -274.923468) (xy 298.196813 -274.874569) (xy 298.220156 -274.828757) (xy 298.250377 -274.787161)
			(xy 298.286733 -274.750805) (xy 298.328329 -274.720584) (xy 298.374141 -274.697241) (xy 298.42304 -274.681353)
			(xy 298.473822 -274.67331) (xy 298.525238 -274.67331) (xy 298.57602 -274.681353) (xy 298.624919 -274.697241)
			(xy 298.670731 -274.720584) (xy 298.712327 -274.750805) (xy 298.748683 -274.787161) (xy 298.778904 -274.828757)
			(xy 298.802247 -274.874569) (xy 298.818135 -274.923468) (xy 298.826178 -274.97425) (xy 298.826682 -274.999958)
			(xy 299.14394 -274.999958) (xy 299.1479 -274.950904) (xy 299.159677 -274.90312) (xy 299.178968 -274.857844)
			(xy 299.205271 -274.816248) (xy 299.237906 -274.779411) (xy 299.276027 -274.748286) (xy 299.318648 -274.723679)
			(xy 299.364664 -274.706227) (xy 299.412883 -274.696383) (xy 299.462058 -274.694402) (xy 299.510913 -274.700334)
			(xy 299.558184 -274.714026) (xy 299.602646 -274.735124) (xy 299.643149 -274.76308) (xy 299.678642 -274.797172)
			(xy 299.708207 -274.836516) (xy 299.731078 -274.880093) (xy 299.746662 -274.926774) (xy 299.754557 -274.975351)
			(xy 299.755052 -274.999958) (xy 299.754557 -275.024565) (xy 299.754419 -275.025412) (xy 300.072802 -275.025412)
			(xy 300.072802 -274.973996) (xy 300.080845 -274.923214) (xy 300.096733 -274.874315) (xy 300.120076 -274.828503)
			(xy 300.150297 -274.786907) (xy 300.186653 -274.750551) (xy 300.228249 -274.72033) (xy 300.274061 -274.696987)
			(xy 300.32296 -274.681099) (xy 300.373742 -274.673056) (xy 300.425158 -274.673056) (xy 300.47594 -274.681099)
			(xy 300.524839 -274.696987) (xy 300.570651 -274.72033) (xy 300.612247 -274.750551) (xy 300.648603 -274.786907)
			(xy 300.678824 -274.828503) (xy 300.702167 -274.874315) (xy 300.718055 -274.923214) (xy 300.726098 -274.973996)
			(xy 300.726602 -274.999704) (xy 300.726597 -274.999958) (xy 301.044114 -274.999958) (xy 301.048074 -274.950904)
			(xy 301.059851 -274.90312) (xy 301.079142 -274.857844) (xy 301.105445 -274.816248) (xy 301.13808 -274.779411)
			(xy 301.176201 -274.748286) (xy 301.218822 -274.723679) (xy 301.264838 -274.706227) (xy 301.313057 -274.696383)
			(xy 301.362232 -274.694402) (xy 301.411087 -274.700334) (xy 301.458358 -274.714026) (xy 301.50282 -274.735124)
			(xy 301.543323 -274.76308) (xy 301.578816 -274.797172) (xy 301.608381 -274.836516) (xy 301.631252 -274.880093)
			(xy 301.646836 -274.926774) (xy 301.654731 -274.975351) (xy 301.655226 -274.999958) (xy 301.654731 -275.024565)
			(xy 301.654552 -275.025666) (xy 301.972722 -275.025666) (xy 301.972722 -274.97425) (xy 301.980765 -274.923468)
			(xy 301.996653 -274.874569) (xy 302.019996 -274.828757) (xy 302.050217 -274.787161) (xy 302.086573 -274.750805)
			(xy 302.128169 -274.720584) (xy 302.173981 -274.697241) (xy 302.22288 -274.681353) (xy 302.273662 -274.67331)
			(xy 302.325078 -274.67331) (xy 302.37586 -274.681353) (xy 302.424759 -274.697241) (xy 302.470571 -274.720584)
			(xy 302.512167 -274.750805) (xy 302.548523 -274.787161) (xy 302.578744 -274.828757) (xy 302.602087 -274.874569)
			(xy 302.617975 -274.923468) (xy 302.626018 -274.97425) (xy 302.626522 -274.999958) (xy 302.944034 -274.999958)
			(xy 302.947994 -274.950904) (xy 302.959771 -274.90312) (xy 302.979062 -274.857844) (xy 303.005365 -274.816248)
			(xy 303.038 -274.779411) (xy 303.076121 -274.748286) (xy 303.118742 -274.723679) (xy 303.164758 -274.706227)
			(xy 303.212977 -274.696383) (xy 303.262152 -274.694402) (xy 303.311007 -274.700334) (xy 303.358278 -274.714026)
			(xy 303.40274 -274.735124) (xy 303.443243 -274.76308) (xy 303.478736 -274.797172) (xy 303.508301 -274.836516)
			(xy 303.531172 -274.880093) (xy 303.546756 -274.926774) (xy 303.554651 -274.975351) (xy 303.555146 -274.999958)
			(xy 303.554651 -275.024565) (xy 303.554513 -275.025412) (xy 303.872896 -275.025412) (xy 303.872896 -274.973996)
			(xy 303.880939 -274.923214) (xy 303.896827 -274.874315) (xy 303.92017 -274.828503) (xy 303.950391 -274.786907)
			(xy 303.986747 -274.750551) (xy 304.028343 -274.72033) (xy 304.074155 -274.696987) (xy 304.123054 -274.681099)
			(xy 304.173836 -274.673056) (xy 304.225252 -274.673056) (xy 304.276034 -274.681099) (xy 304.324933 -274.696987)
			(xy 304.370745 -274.72033) (xy 304.412341 -274.750551) (xy 304.448697 -274.786907) (xy 304.478918 -274.828503)
			(xy 304.502261 -274.874315) (xy 304.518149 -274.923214) (xy 304.526192 -274.973996) (xy 304.526696 -274.999704)
			(xy 304.526691 -274.999958) (xy 304.843954 -274.999958) (xy 304.847914 -274.950904) (xy 304.859691 -274.90312)
			(xy 304.878982 -274.857844) (xy 304.905285 -274.816248) (xy 304.93792 -274.779411) (xy 304.976041 -274.748286)
			(xy 305.018662 -274.723679) (xy 305.064678 -274.706227) (xy 305.112897 -274.696383) (xy 305.162072 -274.694402)
			(xy 305.210927 -274.700334) (xy 305.258198 -274.714026) (xy 305.30266 -274.735124) (xy 305.343163 -274.76308)
			(xy 305.378656 -274.797172) (xy 305.408221 -274.836516) (xy 305.431092 -274.880093) (xy 305.446676 -274.926774)
			(xy 305.454571 -274.975351) (xy 305.455066 -274.999958) (xy 305.454571 -275.024565) (xy 305.454392 -275.025666)
			(xy 305.772816 -275.025666) (xy 305.772816 -274.97425) (xy 305.780859 -274.923468) (xy 305.796747 -274.874569)
			(xy 305.82009 -274.828757) (xy 305.850311 -274.787161) (xy 305.886667 -274.750805) (xy 305.928263 -274.720584)
			(xy 305.974075 -274.697241) (xy 306.022974 -274.681353) (xy 306.073756 -274.67331) (xy 306.125172 -274.67331)
			(xy 306.175954 -274.681353) (xy 306.224853 -274.697241) (xy 306.270665 -274.720584) (xy 306.312261 -274.750805)
			(xy 306.348617 -274.787161) (xy 306.378838 -274.828757) (xy 306.402181 -274.874569) (xy 306.418069 -274.923468)
			(xy 306.426112 -274.97425) (xy 306.426616 -274.999958) (xy 306.743874 -274.999958) (xy 306.747834 -274.950904)
			(xy 306.759611 -274.90312) (xy 306.778902 -274.857844) (xy 306.805205 -274.816248) (xy 306.83784 -274.779411)
			(xy 306.875961 -274.748286) (xy 306.918582 -274.723679) (xy 306.964598 -274.706227) (xy 307.012817 -274.696383)
			(xy 307.061992 -274.694402) (xy 307.110847 -274.700334) (xy 307.158118 -274.714026) (xy 307.20258 -274.735124)
			(xy 307.243083 -274.76308) (xy 307.278576 -274.797172) (xy 307.308141 -274.836516) (xy 307.331012 -274.880093)
			(xy 307.346596 -274.926774) (xy 307.354491 -274.975351) (xy 307.354986 -274.999958) (xy 307.354491 -275.024565)
			(xy 307.354353 -275.025412) (xy 307.67299 -275.025412) (xy 307.67299 -274.973996) (xy 307.681033 -274.923214)
			(xy 307.696921 -274.874315) (xy 307.720264 -274.828503) (xy 307.750485 -274.786907) (xy 307.786841 -274.750551)
			(xy 307.828437 -274.72033) (xy 307.874249 -274.696987) (xy 307.923148 -274.681099) (xy 307.97393 -274.673056)
			(xy 308.025346 -274.673056) (xy 308.076128 -274.681099) (xy 308.125027 -274.696987) (xy 308.170839 -274.72033)
			(xy 308.212435 -274.750551) (xy 308.248791 -274.786907) (xy 308.279012 -274.828503) (xy 308.302355 -274.874315)
			(xy 308.318243 -274.923214) (xy 308.326286 -274.973996) (xy 308.32679 -274.999704) (xy 308.326785 -274.999958)
			(xy 308.643794 -274.999958) (xy 308.647754 -274.950904) (xy 308.659531 -274.90312) (xy 308.678822 -274.857844)
			(xy 308.705125 -274.816248) (xy 308.73776 -274.779411) (xy 308.775881 -274.748286) (xy 308.818502 -274.723679)
			(xy 308.864518 -274.706227) (xy 308.912737 -274.696383) (xy 308.961912 -274.694402) (xy 309.010767 -274.700334)
			(xy 309.058038 -274.714026) (xy 309.1025 -274.735124) (xy 309.143003 -274.76308) (xy 309.178496 -274.797172)
			(xy 309.208061 -274.836516) (xy 309.230932 -274.880093) (xy 309.246516 -274.926774) (xy 309.254411 -274.975351)
			(xy 309.254906 -274.999958) (xy 309.254411 -275.024565) (xy 309.254232 -275.025666) (xy 309.57291 -275.025666)
			(xy 309.57291 -274.97425) (xy 309.580953 -274.923468) (xy 309.596841 -274.874569) (xy 309.620184 -274.828757)
			(xy 309.650405 -274.787161) (xy 309.686761 -274.750805) (xy 309.728357 -274.720584) (xy 309.774169 -274.697241)
			(xy 309.823068 -274.681353) (xy 309.87385 -274.67331) (xy 309.925266 -274.67331) (xy 309.976048 -274.681353)
			(xy 310.024947 -274.697241) (xy 310.070759 -274.720584) (xy 310.112355 -274.750805) (xy 310.148711 -274.787161)
			(xy 310.178932 -274.828757) (xy 310.202275 -274.874569) (xy 310.218163 -274.923468) (xy 310.226206 -274.97425)
			(xy 310.22671 -274.999958) (xy 310.543714 -274.999958) (xy 310.547674 -274.950904) (xy 310.559451 -274.90312)
			(xy 310.578742 -274.857844) (xy 310.605045 -274.816248) (xy 310.63768 -274.779411) (xy 310.675801 -274.748286)
			(xy 310.718422 -274.723679) (xy 310.764438 -274.706227) (xy 310.812657 -274.696383) (xy 310.861832 -274.694402)
			(xy 310.910687 -274.700334) (xy 310.957958 -274.714026) (xy 311.00242 -274.735124) (xy 311.042923 -274.76308)
			(xy 311.078416 -274.797172) (xy 311.107981 -274.836516) (xy 311.130852 -274.880093) (xy 311.146436 -274.926774)
			(xy 311.154331 -274.975351) (xy 311.154826 -274.999958) (xy 311.154331 -275.024565) (xy 311.154152 -275.025666)
			(xy 311.47283 -275.025666) (xy 311.47283 -274.97425) (xy 311.480873 -274.923468) (xy 311.496761 -274.874569)
			(xy 311.520104 -274.828757) (xy 311.550325 -274.787161) (xy 311.586681 -274.750805) (xy 311.628277 -274.720584)
			(xy 311.674089 -274.697241) (xy 311.722988 -274.681353) (xy 311.77377 -274.67331) (xy 311.825186 -274.67331)
			(xy 311.875968 -274.681353) (xy 311.924867 -274.697241) (xy 311.970679 -274.720584) (xy 312.012275 -274.750805)
			(xy 312.048631 -274.787161) (xy 312.078852 -274.828757) (xy 312.102195 -274.874569) (xy 312.118083 -274.923468)
			(xy 312.126126 -274.97425) (xy 312.12663 -274.999958) (xy 312.443888 -274.999958) (xy 312.447848 -274.950904)
			(xy 312.459625 -274.90312) (xy 312.478916 -274.857844) (xy 312.505219 -274.816248) (xy 312.537854 -274.779411)
			(xy 312.575975 -274.748286) (xy 312.618596 -274.723679) (xy 312.664612 -274.706227) (xy 312.712831 -274.696383)
			(xy 312.762006 -274.694402) (xy 312.810861 -274.700334) (xy 312.858132 -274.714026) (xy 312.902594 -274.735124)
			(xy 312.943097 -274.76308) (xy 312.97859 -274.797172) (xy 313.008155 -274.836516) (xy 313.031026 -274.880093)
			(xy 313.04661 -274.926774) (xy 313.054505 -274.975351) (xy 313.055 -274.999958) (xy 313.054505 -275.024565)
			(xy 313.054367 -275.025412) (xy 313.373258 -275.025412) (xy 313.373258 -274.973996) (xy 313.381301 -274.923214)
			(xy 313.397189 -274.874315) (xy 313.420532 -274.828503) (xy 313.450753 -274.786907) (xy 313.487109 -274.750551)
			(xy 313.528705 -274.72033) (xy 313.574517 -274.696987) (xy 313.623416 -274.681099) (xy 313.674198 -274.673056)
			(xy 313.725614 -274.673056) (xy 313.776396 -274.681099) (xy 313.825295 -274.696987) (xy 313.871107 -274.72033)
			(xy 313.912703 -274.750551) (xy 313.949059 -274.786907) (xy 313.97928 -274.828503) (xy 314.002623 -274.874315)
			(xy 314.018511 -274.923214) (xy 314.026554 -274.973996) (xy 314.027058 -274.999704) (xy 314.026554 -275.025412)
			(xy 314.323218 -275.025412) (xy 314.323218 -274.973996) (xy 314.331261 -274.923214) (xy 314.347149 -274.874315)
			(xy 314.370492 -274.828503) (xy 314.400713 -274.786907) (xy 314.437069 -274.750551) (xy 314.478665 -274.72033)
			(xy 314.524477 -274.696987) (xy 314.573376 -274.681099) (xy 314.624158 -274.673056) (xy 314.675574 -274.673056)
			(xy 314.726356 -274.681099) (xy 314.775255 -274.696987) (xy 314.821067 -274.72033) (xy 314.862663 -274.750551)
			(xy 314.899019 -274.786907) (xy 314.92924 -274.828503) (xy 314.952583 -274.874315) (xy 314.968471 -274.923214)
			(xy 314.976514 -274.973996) (xy 314.977018 -274.999704) (xy 314.977013 -274.999958) (xy 315.294276 -274.999958)
			(xy 315.298236 -274.950904) (xy 315.310013 -274.90312) (xy 315.329304 -274.857844) (xy 315.355607 -274.816248)
			(xy 315.388242 -274.779411) (xy 315.426363 -274.748286) (xy 315.468984 -274.723679) (xy 315.515 -274.706227)
			(xy 315.563219 -274.696383) (xy 315.612394 -274.694402) (xy 315.661249 -274.700334) (xy 315.70852 -274.714026)
			(xy 315.752982 -274.735124) (xy 315.793485 -274.76308) (xy 315.828978 -274.797172) (xy 315.858543 -274.836516)
			(xy 315.881414 -274.880093) (xy 315.896998 -274.926774) (xy 315.904893 -274.975351) (xy 315.905388 -274.999958)
			(xy 315.904893 -275.024565) (xy 315.896998 -275.073142) (xy 315.881414 -275.119823) (xy 315.858543 -275.1634)
			(xy 315.828978 -275.202744) (xy 315.793485 -275.236836) (xy 315.752982 -275.264792) (xy 315.70852 -275.28589)
			(xy 315.661249 -275.299582) (xy 315.612394 -275.305514) (xy 315.563219 -275.303533) (xy 315.515 -275.293689)
			(xy 315.468984 -275.276237) (xy 315.426363 -275.25163) (xy 315.388242 -275.220505) (xy 315.355607 -275.183668)
			(xy 315.329304 -275.142072) (xy 315.310013 -275.096796) (xy 315.298236 -275.049012) (xy 315.294276 -274.999958)
			(xy 314.977013 -274.999958) (xy 314.976514 -275.025412) (xy 314.968471 -275.076194) (xy 314.952583 -275.125093)
			(xy 314.92924 -275.170905) (xy 314.899019 -275.212501) (xy 314.862663 -275.248857) (xy 314.821067 -275.279078)
			(xy 314.775255 -275.302421) (xy 314.726356 -275.318309) (xy 314.675574 -275.326352) (xy 314.624158 -275.326352)
			(xy 314.573376 -275.318309) (xy 314.524477 -275.302421) (xy 314.478665 -275.279078) (xy 314.437069 -275.248857)
			(xy 314.400713 -275.212501) (xy 314.370492 -275.170905) (xy 314.347149 -275.125093) (xy 314.331261 -275.076194)
			(xy 314.323218 -275.025412) (xy 314.026554 -275.025412) (xy 314.018511 -275.076194) (xy 314.002623 -275.125093)
			(xy 313.97928 -275.170905) (xy 313.949059 -275.212501) (xy 313.912703 -275.248857) (xy 313.871107 -275.279078)
			(xy 313.825295 -275.302421) (xy 313.776396 -275.318309) (xy 313.725614 -275.326352) (xy 313.674198 -275.326352)
			(xy 313.623416 -275.318309) (xy 313.574517 -275.302421) (xy 313.528705 -275.279078) (xy 313.487109 -275.248857)
			(xy 313.450753 -275.212501) (xy 313.420532 -275.170905) (xy 313.397189 -275.125093) (xy 313.381301 -275.076194)
			(xy 313.373258 -275.025412) (xy 313.054367 -275.025412) (xy 313.04661 -275.073142) (xy 313.031026 -275.119823)
			(xy 313.008155 -275.1634) (xy 312.97859 -275.202744) (xy 312.943097 -275.236836) (xy 312.902594 -275.264792)
			(xy 312.858132 -275.28589) (xy 312.810861 -275.299582) (xy 312.762006 -275.305514) (xy 312.712831 -275.303533)
			(xy 312.664612 -275.293689) (xy 312.618596 -275.276237) (xy 312.575975 -275.25163) (xy 312.537854 -275.220505)
			(xy 312.505219 -275.183668) (xy 312.478916 -275.142072) (xy 312.459625 -275.096796) (xy 312.447848 -275.049012)
			(xy 312.443888 -274.999958) (xy 312.12663 -274.999958) (xy 312.126126 -275.025666) (xy 312.118083 -275.076448)
			(xy 312.102195 -275.125347) (xy 312.078852 -275.171159) (xy 312.048631 -275.212755) (xy 312.012275 -275.249111)
			(xy 311.970679 -275.279332) (xy 311.924867 -275.302675) (xy 311.875968 -275.318563) (xy 311.825186 -275.326606)
			(xy 311.77377 -275.326606) (xy 311.722988 -275.318563) (xy 311.674089 -275.302675) (xy 311.628277 -275.279332)
			(xy 311.586681 -275.249111) (xy 311.550325 -275.212755) (xy 311.520104 -275.171159) (xy 311.496761 -275.125347)
			(xy 311.480873 -275.076448) (xy 311.47283 -275.025666) (xy 311.154152 -275.025666) (xy 311.146436 -275.073142)
			(xy 311.130852 -275.119823) (xy 311.107981 -275.1634) (xy 311.078416 -275.202744) (xy 311.042923 -275.236836)
			(xy 311.00242 -275.264792) (xy 310.957958 -275.28589) (xy 310.910687 -275.299582) (xy 310.861832 -275.305514)
			(xy 310.812657 -275.303533) (xy 310.764438 -275.293689) (xy 310.718422 -275.276237) (xy 310.675801 -275.25163)
			(xy 310.63768 -275.220505) (xy 310.605045 -275.183668) (xy 310.578742 -275.142072) (xy 310.559451 -275.096796)
			(xy 310.547674 -275.049012) (xy 310.543714 -274.999958) (xy 310.22671 -274.999958) (xy 310.226206 -275.025666)
			(xy 310.218163 -275.076448) (xy 310.202275 -275.125347) (xy 310.178932 -275.171159) (xy 310.148711 -275.212755)
			(xy 310.112355 -275.249111) (xy 310.070759 -275.279332) (xy 310.024947 -275.302675) (xy 309.976048 -275.318563)
			(xy 309.925266 -275.326606) (xy 309.87385 -275.326606) (xy 309.823068 -275.318563) (xy 309.774169 -275.302675)
			(xy 309.728357 -275.279332) (xy 309.686761 -275.249111) (xy 309.650405 -275.212755) (xy 309.620184 -275.171159)
			(xy 309.596841 -275.125347) (xy 309.580953 -275.076448) (xy 309.57291 -275.025666) (xy 309.254232 -275.025666)
			(xy 309.246516 -275.073142) (xy 309.230932 -275.119823) (xy 309.208061 -275.1634) (xy 309.178496 -275.202744)
			(xy 309.143003 -275.236836) (xy 309.1025 -275.264792) (xy 309.058038 -275.28589) (xy 309.010767 -275.299582)
			(xy 308.961912 -275.305514) (xy 308.912737 -275.303533) (xy 308.864518 -275.293689) (xy 308.818502 -275.276237)
			(xy 308.775881 -275.25163) (xy 308.73776 -275.220505) (xy 308.705125 -275.183668) (xy 308.678822 -275.142072)
			(xy 308.659531 -275.096796) (xy 308.647754 -275.049012) (xy 308.643794 -274.999958) (xy 308.326785 -274.999958)
			(xy 308.326286 -275.025412) (xy 308.318243 -275.076194) (xy 308.302355 -275.125093) (xy 308.279012 -275.170905)
			(xy 308.248791 -275.212501) (xy 308.212435 -275.248857) (xy 308.170839 -275.279078) (xy 308.125027 -275.302421)
			(xy 308.076128 -275.318309) (xy 308.025346 -275.326352) (xy 307.97393 -275.326352) (xy 307.923148 -275.318309)
			(xy 307.874249 -275.302421) (xy 307.828437 -275.279078) (xy 307.786841 -275.248857) (xy 307.750485 -275.212501)
			(xy 307.720264 -275.170905) (xy 307.696921 -275.125093) (xy 307.681033 -275.076194) (xy 307.67299 -275.025412)
			(xy 307.354353 -275.025412) (xy 307.346596 -275.073142) (xy 307.331012 -275.119823) (xy 307.308141 -275.1634)
			(xy 307.278576 -275.202744) (xy 307.243083 -275.236836) (xy 307.20258 -275.264792) (xy 307.158118 -275.28589)
			(xy 307.110847 -275.299582) (xy 307.061992 -275.305514) (xy 307.012817 -275.303533) (xy 306.964598 -275.293689)
			(xy 306.918582 -275.276237) (xy 306.875961 -275.25163) (xy 306.83784 -275.220505) (xy 306.805205 -275.183668)
			(xy 306.778902 -275.142072) (xy 306.759611 -275.096796) (xy 306.747834 -275.049012) (xy 306.743874 -274.999958)
			(xy 306.426616 -274.999958) (xy 306.426112 -275.025666) (xy 306.418069 -275.076448) (xy 306.402181 -275.125347)
			(xy 306.378838 -275.171159) (xy 306.348617 -275.212755) (xy 306.312261 -275.249111) (xy 306.270665 -275.279332)
			(xy 306.224853 -275.302675) (xy 306.175954 -275.318563) (xy 306.125172 -275.326606) (xy 306.073756 -275.326606)
			(xy 306.022974 -275.318563) (xy 305.974075 -275.302675) (xy 305.928263 -275.279332) (xy 305.886667 -275.249111)
			(xy 305.850311 -275.212755) (xy 305.82009 -275.171159) (xy 305.796747 -275.125347) (xy 305.780859 -275.076448)
			(xy 305.772816 -275.025666) (xy 305.454392 -275.025666) (xy 305.446676 -275.073142) (xy 305.431092 -275.119823)
			(xy 305.408221 -275.1634) (xy 305.378656 -275.202744) (xy 305.343163 -275.236836) (xy 305.30266 -275.264792)
			(xy 305.258198 -275.28589) (xy 305.210927 -275.299582) (xy 305.162072 -275.305514) (xy 305.112897 -275.303533)
			(xy 305.064678 -275.293689) (xy 305.018662 -275.276237) (xy 304.976041 -275.25163) (xy 304.93792 -275.220505)
			(xy 304.905285 -275.183668) (xy 304.878982 -275.142072) (xy 304.859691 -275.096796) (xy 304.847914 -275.049012)
			(xy 304.843954 -274.999958) (xy 304.526691 -274.999958) (xy 304.526192 -275.025412) (xy 304.518149 -275.076194)
			(xy 304.502261 -275.125093) (xy 304.478918 -275.170905) (xy 304.448697 -275.212501) (xy 304.412341 -275.248857)
			(xy 304.370745 -275.279078) (xy 304.324933 -275.302421) (xy 304.276034 -275.318309) (xy 304.225252 -275.326352)
			(xy 304.173836 -275.326352) (xy 304.123054 -275.318309) (xy 304.074155 -275.302421) (xy 304.028343 -275.279078)
			(xy 303.986747 -275.248857) (xy 303.950391 -275.212501) (xy 303.92017 -275.170905) (xy 303.896827 -275.125093)
			(xy 303.880939 -275.076194) (xy 303.872896 -275.025412) (xy 303.554513 -275.025412) (xy 303.546756 -275.073142)
			(xy 303.531172 -275.119823) (xy 303.508301 -275.1634) (xy 303.478736 -275.202744) (xy 303.443243 -275.236836)
			(xy 303.40274 -275.264792) (xy 303.358278 -275.28589) (xy 303.311007 -275.299582) (xy 303.262152 -275.305514)
			(xy 303.212977 -275.303533) (xy 303.164758 -275.293689) (xy 303.118742 -275.276237) (xy 303.076121 -275.25163)
			(xy 303.038 -275.220505) (xy 303.005365 -275.183668) (xy 302.979062 -275.142072) (xy 302.959771 -275.096796)
			(xy 302.947994 -275.049012) (xy 302.944034 -274.999958) (xy 302.626522 -274.999958) (xy 302.626018 -275.025666)
			(xy 302.617975 -275.076448) (xy 302.602087 -275.125347) (xy 302.578744 -275.171159) (xy 302.548523 -275.212755)
			(xy 302.512167 -275.249111) (xy 302.470571 -275.279332) (xy 302.424759 -275.302675) (xy 302.37586 -275.318563)
			(xy 302.325078 -275.326606) (xy 302.273662 -275.326606) (xy 302.22288 -275.318563) (xy 302.173981 -275.302675)
			(xy 302.128169 -275.279332) (xy 302.086573 -275.249111) (xy 302.050217 -275.212755) (xy 302.019996 -275.171159)
			(xy 301.996653 -275.125347) (xy 301.980765 -275.076448) (xy 301.972722 -275.025666) (xy 301.654552 -275.025666)
			(xy 301.646836 -275.073142) (xy 301.631252 -275.119823) (xy 301.608381 -275.1634) (xy 301.578816 -275.202744)
			(xy 301.543323 -275.236836) (xy 301.50282 -275.264792) (xy 301.458358 -275.28589) (xy 301.411087 -275.299582)
			(xy 301.362232 -275.305514) (xy 301.313057 -275.303533) (xy 301.264838 -275.293689) (xy 301.218822 -275.276237)
			(xy 301.176201 -275.25163) (xy 301.13808 -275.220505) (xy 301.105445 -275.183668) (xy 301.079142 -275.142072)
			(xy 301.059851 -275.096796) (xy 301.048074 -275.049012) (xy 301.044114 -274.999958) (xy 300.726597 -274.999958)
			(xy 300.726098 -275.025412) (xy 300.718055 -275.076194) (xy 300.702167 -275.125093) (xy 300.678824 -275.170905)
			(xy 300.648603 -275.212501) (xy 300.612247 -275.248857) (xy 300.570651 -275.279078) (xy 300.524839 -275.302421)
			(xy 300.47594 -275.318309) (xy 300.425158 -275.326352) (xy 300.373742 -275.326352) (xy 300.32296 -275.318309)
			(xy 300.274061 -275.302421) (xy 300.228249 -275.279078) (xy 300.186653 -275.248857) (xy 300.150297 -275.212501)
			(xy 300.120076 -275.170905) (xy 300.096733 -275.125093) (xy 300.080845 -275.076194) (xy 300.072802 -275.025412)
			(xy 299.754419 -275.025412) (xy 299.746662 -275.073142) (xy 299.731078 -275.119823) (xy 299.708207 -275.1634)
			(xy 299.678642 -275.202744) (xy 299.643149 -275.236836) (xy 299.602646 -275.264792) (xy 299.558184 -275.28589)
			(xy 299.510913 -275.299582) (xy 299.462058 -275.305514) (xy 299.412883 -275.303533) (xy 299.364664 -275.293689)
			(xy 299.318648 -275.276237) (xy 299.276027 -275.25163) (xy 299.237906 -275.220505) (xy 299.205271 -275.183668)
			(xy 299.178968 -275.142072) (xy 299.159677 -275.096796) (xy 299.1479 -275.049012) (xy 299.14394 -274.999958)
			(xy 298.826682 -274.999958) (xy 298.826178 -275.025666) (xy 298.818135 -275.076448) (xy 298.802247 -275.125347)
			(xy 298.778904 -275.171159) (xy 298.748683 -275.212755) (xy 298.712327 -275.249111) (xy 298.670731 -275.279332)
			(xy 298.624919 -275.302675) (xy 298.57602 -275.318563) (xy 298.525238 -275.326606) (xy 298.473822 -275.326606)
			(xy 298.42304 -275.318563) (xy 298.374141 -275.302675) (xy 298.328329 -275.279332) (xy 298.286733 -275.249111)
			(xy 298.250377 -275.212755) (xy 298.220156 -275.171159) (xy 298.196813 -275.125347) (xy 298.180925 -275.076448)
			(xy 298.172882 -275.025666) (xy 297.854458 -275.025666) (xy 297.846742 -275.073142) (xy 297.831158 -275.119823)
			(xy 297.808287 -275.1634) (xy 297.778722 -275.202744) (xy 297.743229 -275.236836) (xy 297.702726 -275.264792)
			(xy 297.658264 -275.28589) (xy 297.610993 -275.299582) (xy 297.562138 -275.305514) (xy 297.512963 -275.303533)
			(xy 297.464744 -275.293689) (xy 297.418728 -275.276237) (xy 297.376107 -275.25163) (xy 297.337986 -275.220505)
			(xy 297.305351 -275.183668) (xy 297.279048 -275.142072) (xy 297.259757 -275.096796) (xy 297.24798 -275.049012)
			(xy 297.24402 -274.999958) (xy 296.926757 -274.999958) (xy 296.926258 -275.025412) (xy 296.918215 -275.076194)
			(xy 296.902327 -275.125093) (xy 296.878984 -275.170905) (xy 296.848763 -275.212501) (xy 296.812407 -275.248857)
			(xy 296.770811 -275.279078) (xy 296.724999 -275.302421) (xy 296.6761 -275.318309) (xy 296.625318 -275.326352)
			(xy 296.573902 -275.326352) (xy 296.52312 -275.318309) (xy 296.474221 -275.302421) (xy 296.428409 -275.279078)
			(xy 296.386813 -275.248857) (xy 296.350457 -275.212501) (xy 296.320236 -275.170905) (xy 296.296893 -275.125093)
			(xy 296.281005 -275.076194) (xy 296.272962 -275.025412) (xy 295.954579 -275.025412) (xy 295.946822 -275.073142)
			(xy 295.931238 -275.119823) (xy 295.908367 -275.1634) (xy 295.878802 -275.202744) (xy 295.843309 -275.236836)
			(xy 295.802806 -275.264792) (xy 295.758344 -275.28589) (xy 295.711073 -275.299582) (xy 295.662218 -275.305514)
			(xy 295.613043 -275.303533) (xy 295.564824 -275.293689) (xy 295.518808 -275.276237) (xy 295.476187 -275.25163)
			(xy 295.438066 -275.220505) (xy 295.405431 -275.183668) (xy 295.379128 -275.142072) (xy 295.359837 -275.096796)
			(xy 295.34806 -275.049012) (xy 295.3441 -274.999958) (xy 295.026588 -274.999958) (xy 295.026084 -275.025666)
			(xy 295.018041 -275.076448) (xy 295.002153 -275.125347) (xy 294.97881 -275.171159) (xy 294.948589 -275.212755)
			(xy 294.912233 -275.249111) (xy 294.870637 -275.279332) (xy 294.824825 -275.302675) (xy 294.775926 -275.318563)
			(xy 294.725144 -275.326606) (xy 294.673728 -275.326606) (xy 294.622946 -275.318563) (xy 294.574047 -275.302675)
			(xy 294.528235 -275.279332) (xy 294.486639 -275.249111) (xy 294.450283 -275.212755) (xy 294.420062 -275.171159)
			(xy 294.396719 -275.125347) (xy 294.380831 -275.076448) (xy 294.372788 -275.025666) (xy 294.054364 -275.025666)
			(xy 294.046648 -275.073142) (xy 294.031064 -275.119823) (xy 294.008193 -275.1634) (xy 293.978628 -275.202744)
			(xy 293.943135 -275.236836) (xy 293.902632 -275.264792) (xy 293.85817 -275.28589) (xy 293.810899 -275.299582)
			(xy 293.762044 -275.305514) (xy 293.712869 -275.303533) (xy 293.66465 -275.293689) (xy 293.618634 -275.276237)
			(xy 293.576013 -275.25163) (xy 293.537892 -275.220505) (xy 293.505257 -275.183668) (xy 293.478954 -275.142072)
			(xy 293.459663 -275.096796) (xy 293.447886 -275.049012) (xy 293.443926 -274.999958) (xy 293.126663 -274.999958)
			(xy 293.126164 -275.025412) (xy 293.118121 -275.076194) (xy 293.102233 -275.125093) (xy 293.07889 -275.170905)
			(xy 293.048669 -275.212501) (xy 293.012313 -275.248857) (xy 292.970717 -275.279078) (xy 292.924905 -275.302421)
			(xy 292.876006 -275.318309) (xy 292.825224 -275.326352) (xy 292.773808 -275.326352) (xy 292.723026 -275.318309)
			(xy 292.674127 -275.302421) (xy 292.628315 -275.279078) (xy 292.586719 -275.248857) (xy 292.550363 -275.212501)
			(xy 292.520142 -275.170905) (xy 292.496799 -275.125093) (xy 292.480911 -275.076194) (xy 292.472868 -275.025412)
			(xy 292.154593 -275.025412) (xy 292.154576 -275.026213) (xy 292.145602 -275.077951) (xy 292.127913 -275.127392)
			(xy 292.102029 -275.173079) (xy 292.068712 -275.213666) (xy 292.028945 -275.247957) (xy 291.983899 -275.274942)
			(xy 291.934902 -275.293825) (xy 291.909246 -275.299424) (xy 291.898561 -275.302096) (xy 291.88076 -275.315024)
			(xy 291.870011 -275.33422) (xy 291.868606 -275.345144) (xy 291.865848 -275.375205) (xy 291.857079 -275.434938)
			(xy 291.85108 -275.464524) (xy 291.850136 -275.469689) (xy 291.850144 -275.480186) (xy 291.85108 -275.485352)
			(xy 291.85709 -275.514936) (xy 291.86586 -275.574669) (xy 291.868606 -275.604732) (xy 291.87003 -275.615647)
			(xy 291.880794 -275.634822) (xy 291.898572 -275.647762) (xy 291.909246 -275.650452) (xy 291.934889 -275.656099)
			(xy 291.98388 -275.674979) (xy 292.028921 -275.701958) (xy 292.068684 -275.736243) (xy 292.101998 -275.776824)
			(xy 292.127881 -275.822503) (xy 292.145572 -275.871936) (xy 292.154548 -275.923666) (xy 292.155118 -275.949918)
			(xy 292.154669 -275.973529) (xy 292.154381 -275.975372) (xy 292.472868 -275.975372) (xy 292.472868 -275.923956)
			(xy 292.480911 -275.873174) (xy 292.496799 -275.824275) (xy 292.520142 -275.778463) (xy 292.550363 -275.736867)
			(xy 292.586719 -275.700511) (xy 292.628315 -275.67029) (xy 292.674127 -275.646947) (xy 292.723026 -275.631059)
			(xy 292.773808 -275.623016) (xy 292.825224 -275.623016) (xy 292.876006 -275.631059) (xy 292.924905 -275.646947)
			(xy 292.970717 -275.67029) (xy 293.012313 -275.700511) (xy 293.048669 -275.736867) (xy 293.07889 -275.778463)
			(xy 293.102233 -275.824275) (xy 293.118121 -275.873174) (xy 293.126164 -275.923956) (xy 293.126668 -275.949664)
			(xy 293.126663 -275.949918) (xy 293.443926 -275.949918) (xy 293.447886 -275.900864) (xy 293.459663 -275.85308)
			(xy 293.478954 -275.807804) (xy 293.505257 -275.766208) (xy 293.537892 -275.729371) (xy 293.576013 -275.698246)
			(xy 293.618634 -275.673639) (xy 293.66465 -275.656187) (xy 293.712869 -275.646343) (xy 293.762044 -275.644362)
			(xy 293.810899 -275.650294) (xy 293.85817 -275.663986) (xy 293.902632 -275.685084) (xy 293.943135 -275.71304)
			(xy 293.978628 -275.747132) (xy 294.008193 -275.786476) (xy 294.031064 -275.830053) (xy 294.046648 -275.876734)
			(xy 294.054543 -275.925311) (xy 294.055038 -275.949918) (xy 294.054543 -275.974525) (xy 294.054364 -275.975626)
			(xy 294.372788 -275.975626) (xy 294.372788 -275.92421) (xy 294.380831 -275.873428) (xy 294.396719 -275.824529)
			(xy 294.420062 -275.778717) (xy 294.450283 -275.737121) (xy 294.486639 -275.700765) (xy 294.528235 -275.670544)
			(xy 294.574047 -275.647201) (xy 294.622946 -275.631313) (xy 294.673728 -275.62327) (xy 294.725144 -275.62327)
			(xy 294.775926 -275.631313) (xy 294.824825 -275.647201) (xy 294.870637 -275.670544) (xy 294.912233 -275.700765)
			(xy 294.948589 -275.737121) (xy 294.97881 -275.778717) (xy 295.002153 -275.824529) (xy 295.018041 -275.873428)
			(xy 295.026084 -275.92421) (xy 295.026588 -275.949918) (xy 295.3441 -275.949918) (xy 295.34806 -275.900864)
			(xy 295.359837 -275.85308) (xy 295.379128 -275.807804) (xy 295.405431 -275.766208) (xy 295.438066 -275.729371)
			(xy 295.476187 -275.698246) (xy 295.518808 -275.673639) (xy 295.564824 -275.656187) (xy 295.613043 -275.646343)
			(xy 295.662218 -275.644362) (xy 295.711073 -275.650294) (xy 295.758344 -275.663986) (xy 295.802806 -275.685084)
			(xy 295.843309 -275.71304) (xy 295.878802 -275.747132) (xy 295.908367 -275.786476) (xy 295.931238 -275.830053)
			(xy 295.946822 -275.876734) (xy 295.954717 -275.925311) (xy 295.955212 -275.949918) (xy 295.954717 -275.974525)
			(xy 295.954579 -275.975372) (xy 296.272962 -275.975372) (xy 296.272962 -275.923956) (xy 296.281005 -275.873174)
			(xy 296.296893 -275.824275) (xy 296.320236 -275.778463) (xy 296.350457 -275.736867) (xy 296.386813 -275.700511)
			(xy 296.428409 -275.67029) (xy 296.474221 -275.646947) (xy 296.52312 -275.631059) (xy 296.573902 -275.623016)
			(xy 296.625318 -275.623016) (xy 296.6761 -275.631059) (xy 296.724999 -275.646947) (xy 296.770811 -275.67029)
			(xy 296.812407 -275.700511) (xy 296.848763 -275.736867) (xy 296.878984 -275.778463) (xy 296.902327 -275.824275)
			(xy 296.918215 -275.873174) (xy 296.926258 -275.923956) (xy 296.926762 -275.949664) (xy 296.926757 -275.949918)
			(xy 297.24402 -275.949918) (xy 297.24798 -275.900864) (xy 297.259757 -275.85308) (xy 297.279048 -275.807804)
			(xy 297.305351 -275.766208) (xy 297.337986 -275.729371) (xy 297.376107 -275.698246) (xy 297.418728 -275.673639)
			(xy 297.464744 -275.656187) (xy 297.512963 -275.646343) (xy 297.562138 -275.644362) (xy 297.610993 -275.650294)
			(xy 297.658264 -275.663986) (xy 297.702726 -275.685084) (xy 297.743229 -275.71304) (xy 297.778722 -275.747132)
			(xy 297.808287 -275.786476) (xy 297.831158 -275.830053) (xy 297.846742 -275.876734) (xy 297.854637 -275.925311)
			(xy 297.855132 -275.949918) (xy 297.854637 -275.974525) (xy 297.854458 -275.975626) (xy 298.172882 -275.975626)
			(xy 298.172882 -275.92421) (xy 298.180925 -275.873428) (xy 298.196813 -275.824529) (xy 298.220156 -275.778717)
			(xy 298.250377 -275.737121) (xy 298.286733 -275.700765) (xy 298.328329 -275.670544) (xy 298.374141 -275.647201)
			(xy 298.42304 -275.631313) (xy 298.473822 -275.62327) (xy 298.525238 -275.62327) (xy 298.57602 -275.631313)
			(xy 298.624919 -275.647201) (xy 298.670731 -275.670544) (xy 298.712327 -275.700765) (xy 298.748683 -275.737121)
			(xy 298.778904 -275.778717) (xy 298.802247 -275.824529) (xy 298.818135 -275.873428) (xy 298.826178 -275.92421)
			(xy 298.826682 -275.949918) (xy 299.14394 -275.949918) (xy 299.1479 -275.900864) (xy 299.159677 -275.85308)
			(xy 299.178968 -275.807804) (xy 299.205271 -275.766208) (xy 299.237906 -275.729371) (xy 299.276027 -275.698246)
			(xy 299.318648 -275.673639) (xy 299.364664 -275.656187) (xy 299.412883 -275.646343) (xy 299.462058 -275.644362)
			(xy 299.510913 -275.650294) (xy 299.558184 -275.663986) (xy 299.602646 -275.685084) (xy 299.643149 -275.71304)
			(xy 299.678642 -275.747132) (xy 299.708207 -275.786476) (xy 299.731078 -275.830053) (xy 299.746662 -275.876734)
			(xy 299.754557 -275.925311) (xy 299.755052 -275.949918) (xy 299.754557 -275.974525) (xy 299.754419 -275.975372)
			(xy 300.072802 -275.975372) (xy 300.072802 -275.923956) (xy 300.080845 -275.873174) (xy 300.096733 -275.824275)
			(xy 300.120076 -275.778463) (xy 300.150297 -275.736867) (xy 300.186653 -275.700511) (xy 300.228249 -275.67029)
			(xy 300.274061 -275.646947) (xy 300.32296 -275.631059) (xy 300.373742 -275.623016) (xy 300.425158 -275.623016)
			(xy 300.47594 -275.631059) (xy 300.524839 -275.646947) (xy 300.570651 -275.67029) (xy 300.612247 -275.700511)
			(xy 300.648603 -275.736867) (xy 300.678824 -275.778463) (xy 300.702167 -275.824275) (xy 300.718055 -275.873174)
			(xy 300.726098 -275.923956) (xy 300.726602 -275.949664) (xy 300.726597 -275.949918) (xy 301.044114 -275.949918)
			(xy 301.048074 -275.900864) (xy 301.059851 -275.85308) (xy 301.079142 -275.807804) (xy 301.105445 -275.766208)
			(xy 301.13808 -275.729371) (xy 301.176201 -275.698246) (xy 301.218822 -275.673639) (xy 301.264838 -275.656187)
			(xy 301.313057 -275.646343) (xy 301.362232 -275.644362) (xy 301.411087 -275.650294) (xy 301.458358 -275.663986)
			(xy 301.50282 -275.685084) (xy 301.543323 -275.71304) (xy 301.578816 -275.747132) (xy 301.608381 -275.786476)
			(xy 301.631252 -275.830053) (xy 301.646836 -275.876734) (xy 301.654731 -275.925311) (xy 301.655226 -275.949918)
			(xy 301.654731 -275.974525) (xy 301.654552 -275.975626) (xy 301.972722 -275.975626) (xy 301.972722 -275.92421)
			(xy 301.980765 -275.873428) (xy 301.996653 -275.824529) (xy 302.019996 -275.778717) (xy 302.050217 -275.737121)
			(xy 302.086573 -275.700765) (xy 302.128169 -275.670544) (xy 302.173981 -275.647201) (xy 302.22288 -275.631313)
			(xy 302.273662 -275.62327) (xy 302.325078 -275.62327) (xy 302.37586 -275.631313) (xy 302.424759 -275.647201)
			(xy 302.470571 -275.670544) (xy 302.512167 -275.700765) (xy 302.548523 -275.737121) (xy 302.578744 -275.778717)
			(xy 302.602087 -275.824529) (xy 302.617975 -275.873428) (xy 302.626018 -275.92421) (xy 302.626522 -275.949918)
			(xy 302.944034 -275.949918) (xy 302.947994 -275.900864) (xy 302.959771 -275.85308) (xy 302.979062 -275.807804)
			(xy 303.005365 -275.766208) (xy 303.038 -275.729371) (xy 303.076121 -275.698246) (xy 303.118742 -275.673639)
			(xy 303.164758 -275.656187) (xy 303.212977 -275.646343) (xy 303.262152 -275.644362) (xy 303.311007 -275.650294)
			(xy 303.358278 -275.663986) (xy 303.40274 -275.685084) (xy 303.443243 -275.71304) (xy 303.478736 -275.747132)
			(xy 303.508301 -275.786476) (xy 303.531172 -275.830053) (xy 303.546756 -275.876734) (xy 303.554651 -275.925311)
			(xy 303.555146 -275.949918) (xy 303.554651 -275.974525) (xy 303.554513 -275.975372) (xy 303.872896 -275.975372)
			(xy 303.872896 -275.923956) (xy 303.880939 -275.873174) (xy 303.896827 -275.824275) (xy 303.92017 -275.778463)
			(xy 303.950391 -275.736867) (xy 303.986747 -275.700511) (xy 304.028343 -275.67029) (xy 304.074155 -275.646947)
			(xy 304.123054 -275.631059) (xy 304.173836 -275.623016) (xy 304.225252 -275.623016) (xy 304.276034 -275.631059)
			(xy 304.324933 -275.646947) (xy 304.370745 -275.67029) (xy 304.412341 -275.700511) (xy 304.448697 -275.736867)
			(xy 304.478918 -275.778463) (xy 304.502261 -275.824275) (xy 304.518149 -275.873174) (xy 304.526192 -275.923956)
			(xy 304.526696 -275.949664) (xy 304.526691 -275.949918) (xy 304.843954 -275.949918) (xy 304.847914 -275.900864)
			(xy 304.859691 -275.85308) (xy 304.878982 -275.807804) (xy 304.905285 -275.766208) (xy 304.93792 -275.729371)
			(xy 304.976041 -275.698246) (xy 305.018662 -275.673639) (xy 305.064678 -275.656187) (xy 305.112897 -275.646343)
			(xy 305.162072 -275.644362) (xy 305.210927 -275.650294) (xy 305.258198 -275.663986) (xy 305.30266 -275.685084)
			(xy 305.343163 -275.71304) (xy 305.378656 -275.747132) (xy 305.408221 -275.786476) (xy 305.431092 -275.830053)
			(xy 305.446676 -275.876734) (xy 305.454571 -275.925311) (xy 305.455066 -275.949918) (xy 305.454571 -275.974525)
			(xy 305.454392 -275.975626) (xy 305.772816 -275.975626) (xy 305.772816 -275.92421) (xy 305.780859 -275.873428)
			(xy 305.796747 -275.824529) (xy 305.82009 -275.778717) (xy 305.850311 -275.737121) (xy 305.886667 -275.700765)
			(xy 305.928263 -275.670544) (xy 305.974075 -275.647201) (xy 306.022974 -275.631313) (xy 306.073756 -275.62327)
			(xy 306.125172 -275.62327) (xy 306.175954 -275.631313) (xy 306.224853 -275.647201) (xy 306.270665 -275.670544)
			(xy 306.312261 -275.700765) (xy 306.348617 -275.737121) (xy 306.378838 -275.778717) (xy 306.402181 -275.824529)
			(xy 306.418069 -275.873428) (xy 306.426112 -275.92421) (xy 306.426616 -275.949918) (xy 306.744128 -275.949918)
			(xy 306.748088 -275.900864) (xy 306.759865 -275.85308) (xy 306.779156 -275.807804) (xy 306.805459 -275.766208)
			(xy 306.838094 -275.729371) (xy 306.876215 -275.698246) (xy 306.918836 -275.673639) (xy 306.964852 -275.656187)
			(xy 307.013071 -275.646343) (xy 307.062246 -275.644362) (xy 307.111101 -275.650294) (xy 307.158372 -275.663986)
			(xy 307.202834 -275.685084) (xy 307.243337 -275.71304) (xy 307.27883 -275.747132) (xy 307.308395 -275.786476)
			(xy 307.331266 -275.830053) (xy 307.34685 -275.876734) (xy 307.354745 -275.925311) (xy 307.35524 -275.949918)
			(xy 307.354745 -275.974525) (xy 307.354607 -275.975372) (xy 307.67299 -275.975372) (xy 307.67299 -275.923956)
			(xy 307.681033 -275.873174) (xy 307.696921 -275.824275) (xy 307.720264 -275.778463) (xy 307.750485 -275.736867)
			(xy 307.786841 -275.700511) (xy 307.828437 -275.67029) (xy 307.874249 -275.646947) (xy 307.923148 -275.631059)
			(xy 307.97393 -275.623016) (xy 308.025346 -275.623016) (xy 308.076128 -275.631059) (xy 308.125027 -275.646947)
			(xy 308.170839 -275.67029) (xy 308.212435 -275.700511) (xy 308.248791 -275.736867) (xy 308.279012 -275.778463)
			(xy 308.302355 -275.824275) (xy 308.318243 -275.873174) (xy 308.326286 -275.923956) (xy 308.32679 -275.949664)
			(xy 308.326785 -275.949918) (xy 308.644048 -275.949918) (xy 308.648008 -275.900864) (xy 308.659785 -275.85308)
			(xy 308.679076 -275.807804) (xy 308.705379 -275.766208) (xy 308.738014 -275.729371) (xy 308.776135 -275.698246)
			(xy 308.818756 -275.673639) (xy 308.864772 -275.656187) (xy 308.912991 -275.646343) (xy 308.962166 -275.644362)
			(xy 309.011021 -275.650294) (xy 309.058292 -275.663986) (xy 309.102754 -275.685084) (xy 309.143257 -275.71304)
			(xy 309.17875 -275.747132) (xy 309.208315 -275.786476) (xy 309.231186 -275.830053) (xy 309.24677 -275.876734)
			(xy 309.254665 -275.925311) (xy 309.25516 -275.949918) (xy 309.254665 -275.974525) (xy 309.254486 -275.975626)
			(xy 309.57291 -275.975626) (xy 309.57291 -275.92421) (xy 309.580953 -275.873428) (xy 309.596841 -275.824529)
			(xy 309.620184 -275.778717) (xy 309.650405 -275.737121) (xy 309.686761 -275.700765) (xy 309.728357 -275.670544)
			(xy 309.774169 -275.647201) (xy 309.823068 -275.631313) (xy 309.87385 -275.62327) (xy 309.925266 -275.62327)
			(xy 309.976048 -275.631313) (xy 310.024947 -275.647201) (xy 310.070759 -275.670544) (xy 310.112355 -275.700765)
			(xy 310.148711 -275.737121) (xy 310.178932 -275.778717) (xy 310.202275 -275.824529) (xy 310.218163 -275.873428)
			(xy 310.226206 -275.92421) (xy 310.22671 -275.949918) (xy 310.543968 -275.949918) (xy 310.547928 -275.900864)
			(xy 310.559705 -275.85308) (xy 310.578996 -275.807804) (xy 310.605299 -275.766208) (xy 310.637934 -275.729371)
			(xy 310.676055 -275.698246) (xy 310.718676 -275.673639) (xy 310.764692 -275.656187) (xy 310.812911 -275.646343)
			(xy 310.862086 -275.644362) (xy 310.910941 -275.650294) (xy 310.958212 -275.663986) (xy 311.002674 -275.685084)
			(xy 311.043177 -275.71304) (xy 311.07867 -275.747132) (xy 311.108235 -275.786476) (xy 311.131106 -275.830053)
			(xy 311.14669 -275.876734) (xy 311.154585 -275.925311) (xy 311.15508 -275.949918) (xy 311.154585 -275.974525)
			(xy 311.154406 -275.975626) (xy 311.47283 -275.975626) (xy 311.47283 -275.92421) (xy 311.480873 -275.873428)
			(xy 311.496761 -275.824529) (xy 311.520104 -275.778717) (xy 311.550325 -275.737121) (xy 311.586681 -275.700765)
			(xy 311.628277 -275.670544) (xy 311.674089 -275.647201) (xy 311.722988 -275.631313) (xy 311.77377 -275.62327)
			(xy 311.825186 -275.62327) (xy 311.875968 -275.631313) (xy 311.924867 -275.647201) (xy 311.970679 -275.670544)
			(xy 312.012275 -275.700765) (xy 312.048631 -275.737121) (xy 312.078852 -275.778717) (xy 312.102195 -275.824529)
			(xy 312.118083 -275.873428) (xy 312.126126 -275.92421) (xy 312.12663 -275.949918) (xy 312.444142 -275.949918)
			(xy 312.448102 -275.900864) (xy 312.459879 -275.85308) (xy 312.47917 -275.807804) (xy 312.505473 -275.766208)
			(xy 312.538108 -275.729371) (xy 312.576229 -275.698246) (xy 312.61885 -275.673639) (xy 312.664866 -275.656187)
			(xy 312.713085 -275.646343) (xy 312.76226 -275.644362) (xy 312.811115 -275.650294) (xy 312.858386 -275.663986)
			(xy 312.902848 -275.685084) (xy 312.943351 -275.71304) (xy 312.978844 -275.747132) (xy 313.008409 -275.786476)
			(xy 313.03128 -275.830053) (xy 313.046864 -275.876734) (xy 313.054759 -275.925311) (xy 313.055254 -275.949918)
			(xy 313.394102 -275.949918) (xy 313.398062 -275.900864) (xy 313.409839 -275.85308) (xy 313.42913 -275.807804)
			(xy 313.455433 -275.766208) (xy 313.488068 -275.729371) (xy 313.526189 -275.698246) (xy 313.56881 -275.673639)
			(xy 313.614826 -275.656187) (xy 313.663045 -275.646343) (xy 313.71222 -275.644362) (xy 313.761075 -275.650294)
			(xy 313.808346 -275.663986) (xy 313.852808 -275.685084) (xy 313.893311 -275.71304) (xy 313.928804 -275.747132)
			(xy 313.958369 -275.786476) (xy 313.98124 -275.830053) (xy 313.996824 -275.876734) (xy 314.004719 -275.925311)
			(xy 314.005214 -275.949918) (xy 314.344062 -275.949918) (xy 314.348022 -275.900864) (xy 314.359799 -275.85308)
			(xy 314.37909 -275.807804) (xy 314.405393 -275.766208) (xy 314.438028 -275.729371) (xy 314.476149 -275.698246)
			(xy 314.51877 -275.673639) (xy 314.564786 -275.656187) (xy 314.613005 -275.646343) (xy 314.66218 -275.644362)
			(xy 314.711035 -275.650294) (xy 314.758306 -275.663986) (xy 314.802768 -275.685084) (xy 314.843271 -275.71304)
			(xy 314.878764 -275.747132) (xy 314.908329 -275.786476) (xy 314.9312 -275.830053) (xy 314.946784 -275.876734)
			(xy 314.954679 -275.925311) (xy 314.955174 -275.949918) (xy 314.954679 -275.974525) (xy 314.946784 -276.023102)
			(xy 314.9312 -276.069783) (xy 314.908329 -276.11336) (xy 314.878764 -276.152704) (xy 314.843271 -276.186796)
			(xy 314.802768 -276.214752) (xy 314.758306 -276.23585) (xy 314.711035 -276.249542) (xy 314.66218 -276.255474)
			(xy 314.613005 -276.253493) (xy 314.564786 -276.243649) (xy 314.51877 -276.226197) (xy 314.476149 -276.20159)
			(xy 314.438028 -276.170465) (xy 314.405393 -276.133628) (xy 314.37909 -276.092032) (xy 314.359799 -276.046756)
			(xy 314.348022 -275.998972) (xy 314.344062 -275.949918) (xy 314.005214 -275.949918) (xy 314.004719 -275.974525)
			(xy 313.996824 -276.023102) (xy 313.98124 -276.069783) (xy 313.958369 -276.11336) (xy 313.928804 -276.152704)
			(xy 313.893311 -276.186796) (xy 313.852808 -276.214752) (xy 313.808346 -276.23585) (xy 313.761075 -276.249542)
			(xy 313.71222 -276.255474) (xy 313.663045 -276.253493) (xy 313.614826 -276.243649) (xy 313.56881 -276.226197)
			(xy 313.526189 -276.20159) (xy 313.488068 -276.170465) (xy 313.455433 -276.133628) (xy 313.42913 -276.092032)
			(xy 313.409839 -276.046756) (xy 313.398062 -275.998972) (xy 313.394102 -275.949918) (xy 313.055254 -275.949918)
			(xy 313.054759 -275.974525) (xy 313.046864 -276.023102) (xy 313.03128 -276.069783) (xy 313.008409 -276.11336)
			(xy 312.978844 -276.152704) (xy 312.943351 -276.186796) (xy 312.902848 -276.214752) (xy 312.858386 -276.23585)
			(xy 312.811115 -276.249542) (xy 312.76226 -276.255474) (xy 312.713085 -276.253493) (xy 312.664866 -276.243649)
			(xy 312.61885 -276.226197) (xy 312.576229 -276.20159) (xy 312.538108 -276.170465) (xy 312.505473 -276.133628)
			(xy 312.47917 -276.092032) (xy 312.459879 -276.046756) (xy 312.448102 -275.998972) (xy 312.444142 -275.949918)
			(xy 312.12663 -275.949918) (xy 312.126126 -275.975626) (xy 312.118083 -276.026408) (xy 312.102195 -276.075307)
			(xy 312.078852 -276.121119) (xy 312.048631 -276.162715) (xy 312.012275 -276.199071) (xy 311.970679 -276.229292)
			(xy 311.924867 -276.252635) (xy 311.875968 -276.268523) (xy 311.825186 -276.276566) (xy 311.77377 -276.276566)
			(xy 311.722988 -276.268523) (xy 311.674089 -276.252635) (xy 311.628277 -276.229292) (xy 311.586681 -276.199071)
			(xy 311.550325 -276.162715) (xy 311.520104 -276.121119) (xy 311.496761 -276.075307) (xy 311.480873 -276.026408)
			(xy 311.47283 -275.975626) (xy 311.154406 -275.975626) (xy 311.14669 -276.023102) (xy 311.131106 -276.069783)
			(xy 311.108235 -276.11336) (xy 311.07867 -276.152704) (xy 311.043177 -276.186796) (xy 311.002674 -276.214752)
			(xy 310.958212 -276.23585) (xy 310.910941 -276.249542) (xy 310.862086 -276.255474) (xy 310.812911 -276.253493)
			(xy 310.764692 -276.243649) (xy 310.718676 -276.226197) (xy 310.676055 -276.20159) (xy 310.637934 -276.170465)
			(xy 310.605299 -276.133628) (xy 310.578996 -276.092032) (xy 310.559705 -276.046756) (xy 310.547928 -275.998972)
			(xy 310.543968 -275.949918) (xy 310.22671 -275.949918) (xy 310.226206 -275.975626) (xy 310.218163 -276.026408)
			(xy 310.202275 -276.075307) (xy 310.178932 -276.121119) (xy 310.148711 -276.162715) (xy 310.112355 -276.199071)
			(xy 310.070759 -276.229292) (xy 310.024947 -276.252635) (xy 309.976048 -276.268523) (xy 309.925266 -276.276566)
			(xy 309.87385 -276.276566) (xy 309.823068 -276.268523) (xy 309.774169 -276.252635) (xy 309.728357 -276.229292)
			(xy 309.686761 -276.199071) (xy 309.650405 -276.162715) (xy 309.620184 -276.121119) (xy 309.596841 -276.075307)
			(xy 309.580953 -276.026408) (xy 309.57291 -275.975626) (xy 309.254486 -275.975626) (xy 309.24677 -276.023102)
			(xy 309.231186 -276.069783) (xy 309.208315 -276.11336) (xy 309.17875 -276.152704) (xy 309.143257 -276.186796)
			(xy 309.102754 -276.214752) (xy 309.058292 -276.23585) (xy 309.011021 -276.249542) (xy 308.962166 -276.255474)
			(xy 308.912991 -276.253493) (xy 308.864772 -276.243649) (xy 308.818756 -276.226197) (xy 308.776135 -276.20159)
			(xy 308.738014 -276.170465) (xy 308.705379 -276.133628) (xy 308.679076 -276.092032) (xy 308.659785 -276.046756)
			(xy 308.648008 -275.998972) (xy 308.644048 -275.949918) (xy 308.326785 -275.949918) (xy 308.326286 -275.975372)
			(xy 308.318243 -276.026154) (xy 308.302355 -276.075053) (xy 308.279012 -276.120865) (xy 308.248791 -276.162461)
			(xy 308.212435 -276.198817) (xy 308.170839 -276.229038) (xy 308.125027 -276.252381) (xy 308.076128 -276.268269)
			(xy 308.025346 -276.276312) (xy 307.97393 -276.276312) (xy 307.923148 -276.268269) (xy 307.874249 -276.252381)
			(xy 307.828437 -276.229038) (xy 307.786841 -276.198817) (xy 307.750485 -276.162461) (xy 307.720264 -276.120865)
			(xy 307.696921 -276.075053) (xy 307.681033 -276.026154) (xy 307.67299 -275.975372) (xy 307.354607 -275.975372)
			(xy 307.34685 -276.023102) (xy 307.331266 -276.069783) (xy 307.308395 -276.11336) (xy 307.27883 -276.152704)
			(xy 307.243337 -276.186796) (xy 307.202834 -276.214752) (xy 307.158372 -276.23585) (xy 307.111101 -276.249542)
			(xy 307.062246 -276.255474) (xy 307.013071 -276.253493) (xy 306.964852 -276.243649) (xy 306.918836 -276.226197)
			(xy 306.876215 -276.20159) (xy 306.838094 -276.170465) (xy 306.805459 -276.133628) (xy 306.779156 -276.092032)
			(xy 306.759865 -276.046756) (xy 306.748088 -275.998972) (xy 306.744128 -275.949918) (xy 306.426616 -275.949918)
			(xy 306.426112 -275.975626) (xy 306.418069 -276.026408) (xy 306.402181 -276.075307) (xy 306.378838 -276.121119)
			(xy 306.348617 -276.162715) (xy 306.312261 -276.199071) (xy 306.270665 -276.229292) (xy 306.224853 -276.252635)
			(xy 306.175954 -276.268523) (xy 306.125172 -276.276566) (xy 306.073756 -276.276566) (xy 306.022974 -276.268523)
			(xy 305.974075 -276.252635) (xy 305.928263 -276.229292) (xy 305.886667 -276.199071) (xy 305.850311 -276.162715)
			(xy 305.82009 -276.121119) (xy 305.796747 -276.075307) (xy 305.780859 -276.026408) (xy 305.772816 -275.975626)
			(xy 305.454392 -275.975626) (xy 305.446676 -276.023102) (xy 305.431092 -276.069783) (xy 305.408221 -276.11336)
			(xy 305.378656 -276.152704) (xy 305.343163 -276.186796) (xy 305.30266 -276.214752) (xy 305.258198 -276.23585)
			(xy 305.210927 -276.249542) (xy 305.162072 -276.255474) (xy 305.112897 -276.253493) (xy 305.064678 -276.243649)
			(xy 305.018662 -276.226197) (xy 304.976041 -276.20159) (xy 304.93792 -276.170465) (xy 304.905285 -276.133628)
			(xy 304.878982 -276.092032) (xy 304.859691 -276.046756) (xy 304.847914 -275.998972) (xy 304.843954 -275.949918)
			(xy 304.526691 -275.949918) (xy 304.526192 -275.975372) (xy 304.518149 -276.026154) (xy 304.502261 -276.075053)
			(xy 304.478918 -276.120865) (xy 304.448697 -276.162461) (xy 304.412341 -276.198817) (xy 304.370745 -276.229038)
			(xy 304.324933 -276.252381) (xy 304.276034 -276.268269) (xy 304.225252 -276.276312) (xy 304.173836 -276.276312)
			(xy 304.123054 -276.268269) (xy 304.074155 -276.252381) (xy 304.028343 -276.229038) (xy 303.986747 -276.198817)
			(xy 303.950391 -276.162461) (xy 303.92017 -276.120865) (xy 303.896827 -276.075053) (xy 303.880939 -276.026154)
			(xy 303.872896 -275.975372) (xy 303.554513 -275.975372) (xy 303.546756 -276.023102) (xy 303.531172 -276.069783)
			(xy 303.508301 -276.11336) (xy 303.478736 -276.152704) (xy 303.443243 -276.186796) (xy 303.40274 -276.214752)
			(xy 303.358278 -276.23585) (xy 303.311007 -276.249542) (xy 303.262152 -276.255474) (xy 303.212977 -276.253493)
			(xy 303.164758 -276.243649) (xy 303.118742 -276.226197) (xy 303.076121 -276.20159) (xy 303.038 -276.170465)
			(xy 303.005365 -276.133628) (xy 302.979062 -276.092032) (xy 302.959771 -276.046756) (xy 302.947994 -275.998972)
			(xy 302.944034 -275.949918) (xy 302.626522 -275.949918) (xy 302.626018 -275.975626) (xy 302.617975 -276.026408)
			(xy 302.602087 -276.075307) (xy 302.578744 -276.121119) (xy 302.548523 -276.162715) (xy 302.512167 -276.199071)
			(xy 302.470571 -276.229292) (xy 302.424759 -276.252635) (xy 302.37586 -276.268523) (xy 302.325078 -276.276566)
			(xy 302.273662 -276.276566) (xy 302.22288 -276.268523) (xy 302.173981 -276.252635) (xy 302.128169 -276.229292)
			(xy 302.086573 -276.199071) (xy 302.050217 -276.162715) (xy 302.019996 -276.121119) (xy 301.996653 -276.075307)
			(xy 301.980765 -276.026408) (xy 301.972722 -275.975626) (xy 301.654552 -275.975626) (xy 301.646836 -276.023102)
			(xy 301.631252 -276.069783) (xy 301.608381 -276.11336) (xy 301.578816 -276.152704) (xy 301.543323 -276.186796)
			(xy 301.50282 -276.214752) (xy 301.458358 -276.23585) (xy 301.411087 -276.249542) (xy 301.362232 -276.255474)
			(xy 301.313057 -276.253493) (xy 301.264838 -276.243649) (xy 301.218822 -276.226197) (xy 301.176201 -276.20159)
			(xy 301.13808 -276.170465) (xy 301.105445 -276.133628) (xy 301.079142 -276.092032) (xy 301.059851 -276.046756)
			(xy 301.048074 -275.998972) (xy 301.044114 -275.949918) (xy 300.726597 -275.949918) (xy 300.726098 -275.975372)
			(xy 300.718055 -276.026154) (xy 300.702167 -276.075053) (xy 300.678824 -276.120865) (xy 300.648603 -276.162461)
			(xy 300.612247 -276.198817) (xy 300.570651 -276.229038) (xy 300.524839 -276.252381) (xy 300.47594 -276.268269)
			(xy 300.425158 -276.276312) (xy 300.373742 -276.276312) (xy 300.32296 -276.268269) (xy 300.274061 -276.252381)
			(xy 300.228249 -276.229038) (xy 300.186653 -276.198817) (xy 300.150297 -276.162461) (xy 300.120076 -276.120865)
			(xy 300.096733 -276.075053) (xy 300.080845 -276.026154) (xy 300.072802 -275.975372) (xy 299.754419 -275.975372)
			(xy 299.746662 -276.023102) (xy 299.731078 -276.069783) (xy 299.708207 -276.11336) (xy 299.678642 -276.152704)
			(xy 299.643149 -276.186796) (xy 299.602646 -276.214752) (xy 299.558184 -276.23585) (xy 299.510913 -276.249542)
			(xy 299.462058 -276.255474) (xy 299.412883 -276.253493) (xy 299.364664 -276.243649) (xy 299.318648 -276.226197)
			(xy 299.276027 -276.20159) (xy 299.237906 -276.170465) (xy 299.205271 -276.133628) (xy 299.178968 -276.092032)
			(xy 299.159677 -276.046756) (xy 299.1479 -275.998972) (xy 299.14394 -275.949918) (xy 298.826682 -275.949918)
			(xy 298.826178 -275.975626) (xy 298.818135 -276.026408) (xy 298.802247 -276.075307) (xy 298.778904 -276.121119)
			(xy 298.748683 -276.162715) (xy 298.712327 -276.199071) (xy 298.670731 -276.229292) (xy 298.624919 -276.252635)
			(xy 298.57602 -276.268523) (xy 298.525238 -276.276566) (xy 298.473822 -276.276566) (xy 298.42304 -276.268523)
			(xy 298.374141 -276.252635) (xy 298.328329 -276.229292) (xy 298.286733 -276.199071) (xy 298.250377 -276.162715)
			(xy 298.220156 -276.121119) (xy 298.196813 -276.075307) (xy 298.180925 -276.026408) (xy 298.172882 -275.975626)
			(xy 297.854458 -275.975626) (xy 297.846742 -276.023102) (xy 297.831158 -276.069783) (xy 297.808287 -276.11336)
			(xy 297.778722 -276.152704) (xy 297.743229 -276.186796) (xy 297.702726 -276.214752) (xy 297.658264 -276.23585)
			(xy 297.610993 -276.249542) (xy 297.562138 -276.255474) (xy 297.512963 -276.253493) (xy 297.464744 -276.243649)
			(xy 297.418728 -276.226197) (xy 297.376107 -276.20159) (xy 297.337986 -276.170465) (xy 297.305351 -276.133628)
			(xy 297.279048 -276.092032) (xy 297.259757 -276.046756) (xy 297.24798 -275.998972) (xy 297.24402 -275.949918)
			(xy 296.926757 -275.949918) (xy 296.926258 -275.975372) (xy 296.918215 -276.026154) (xy 296.902327 -276.075053)
			(xy 296.878984 -276.120865) (xy 296.848763 -276.162461) (xy 296.812407 -276.198817) (xy 296.770811 -276.229038)
			(xy 296.724999 -276.252381) (xy 296.6761 -276.268269) (xy 296.625318 -276.276312) (xy 296.573902 -276.276312)
			(xy 296.52312 -276.268269) (xy 296.474221 -276.252381) (xy 296.428409 -276.229038) (xy 296.386813 -276.198817)
			(xy 296.350457 -276.162461) (xy 296.320236 -276.120865) (xy 296.296893 -276.075053) (xy 296.281005 -276.026154)
			(xy 296.272962 -275.975372) (xy 295.954579 -275.975372) (xy 295.946822 -276.023102) (xy 295.931238 -276.069783)
			(xy 295.908367 -276.11336) (xy 295.878802 -276.152704) (xy 295.843309 -276.186796) (xy 295.802806 -276.214752)
			(xy 295.758344 -276.23585) (xy 295.711073 -276.249542) (xy 295.662218 -276.255474) (xy 295.613043 -276.253493)
			(xy 295.564824 -276.243649) (xy 295.518808 -276.226197) (xy 295.476187 -276.20159) (xy 295.438066 -276.170465)
			(xy 295.405431 -276.133628) (xy 295.379128 -276.092032) (xy 295.359837 -276.046756) (xy 295.34806 -275.998972)
			(xy 295.3441 -275.949918) (xy 295.026588 -275.949918) (xy 295.026084 -275.975626) (xy 295.018041 -276.026408)
			(xy 295.002153 -276.075307) (xy 294.97881 -276.121119) (xy 294.948589 -276.162715) (xy 294.912233 -276.199071)
			(xy 294.870637 -276.229292) (xy 294.824825 -276.252635) (xy 294.775926 -276.268523) (xy 294.725144 -276.276566)
			(xy 294.673728 -276.276566) (xy 294.622946 -276.268523) (xy 294.574047 -276.252635) (xy 294.528235 -276.229292)
			(xy 294.486639 -276.199071) (xy 294.450283 -276.162715) (xy 294.420062 -276.121119) (xy 294.396719 -276.075307)
			(xy 294.380831 -276.026408) (xy 294.372788 -275.975626) (xy 294.054364 -275.975626) (xy 294.046648 -276.023102)
			(xy 294.031064 -276.069783) (xy 294.008193 -276.11336) (xy 293.978628 -276.152704) (xy 293.943135 -276.186796)
			(xy 293.902632 -276.214752) (xy 293.85817 -276.23585) (xy 293.810899 -276.249542) (xy 293.762044 -276.255474)
			(xy 293.712869 -276.253493) (xy 293.66465 -276.243649) (xy 293.618634 -276.226197) (xy 293.576013 -276.20159)
			(xy 293.537892 -276.170465) (xy 293.505257 -276.133628) (xy 293.478954 -276.092032) (xy 293.459663 -276.046756)
			(xy 293.447886 -275.998972) (xy 293.443926 -275.949918) (xy 293.126663 -275.949918) (xy 293.126164 -275.975372)
			(xy 293.118121 -276.026154) (xy 293.102233 -276.075053) (xy 293.07889 -276.120865) (xy 293.048669 -276.162461)
			(xy 293.012313 -276.198817) (xy 292.970717 -276.229038) (xy 292.924905 -276.252381) (xy 292.876006 -276.268269)
			(xy 292.825224 -276.276312) (xy 292.773808 -276.276312) (xy 292.723026 -276.268269) (xy 292.674127 -276.252381)
			(xy 292.628315 -276.229038) (xy 292.586719 -276.198817) (xy 292.550363 -276.162461) (xy 292.520142 -276.120865)
			(xy 292.496799 -276.075053) (xy 292.480911 -276.026154) (xy 292.472868 -275.975372) (xy 292.154381 -275.975372)
			(xy 292.147385 -276.020185) (xy 292.133009 -276.065166) (xy 292.111884 -276.107399) (xy 292.084512 -276.145878)
			(xy 292.051545 -276.179688) (xy 292.013769 -276.208022) (xy 291.972083 -276.230207) (xy 291.92748 -276.245714)
			(xy 291.881022 -276.254173) (xy 291.85743 -276.255226) (xy 291.847301 -276.25587) (xy 291.828772 -276.264107)
			(xy 291.814899 -276.278897) (xy 291.810948 -276.288246) (xy 291.795653 -276.328081) (xy 291.759021 -276.405153)
			(xy 291.737796 -276.44217) (xy 291.730684 -276.454616) (xy 291.730938 -276.482302) (xy 291.79266 -276.58314)
			(xy 291.817298 -276.596094) (xy 291.831522 -276.595078) (xy 291.84981 -276.59457) (xy 291.874633 -276.595057)
			(xy 291.923624 -276.60309) (xy 291.970671 -276.618944) (xy 292.014532 -276.6422) (xy 292.054054 -276.672246)
			(xy 292.088194 -276.70829) (xy 292.116052 -276.749382) (xy 292.136896 -276.79444) (xy 292.150176 -276.842277)
			(xy 292.155541 -276.891632) (xy 292.155094 -276.899878) (xy 292.493966 -276.899878) (xy 292.497926 -276.850824)
			(xy 292.509703 -276.80304) (xy 292.528994 -276.757764) (xy 292.555297 -276.716168) (xy 292.587932 -276.679331)
			(xy 292.626053 -276.648206) (xy 292.668674 -276.623599) (xy 292.71469 -276.606147) (xy 292.762909 -276.596303)
			(xy 292.812084 -276.594322) (xy 292.860939 -276.600254) (xy 292.90821 -276.613946) (xy 292.952672 -276.635044)
			(xy 292.993175 -276.663) (xy 293.028668 -276.697092) (xy 293.058233 -276.736436) (xy 293.081104 -276.780013)
			(xy 293.096688 -276.826694) (xy 293.104583 -276.875271) (xy 293.105078 -276.899878) (xy 293.443926 -276.899878)
			(xy 293.447886 -276.850824) (xy 293.459663 -276.80304) (xy 293.478954 -276.757764) (xy 293.505257 -276.716168)
			(xy 293.537892 -276.679331) (xy 293.576013 -276.648206) (xy 293.618634 -276.623599) (xy 293.66465 -276.606147)
			(xy 293.712869 -276.596303) (xy 293.762044 -276.594322) (xy 293.810899 -276.600254) (xy 293.85817 -276.613946)
			(xy 293.902632 -276.635044) (xy 293.943135 -276.663) (xy 293.978628 -276.697092) (xy 294.008193 -276.736436)
			(xy 294.031064 -276.780013) (xy 294.046648 -276.826694) (xy 294.054543 -276.875271) (xy 294.055038 -276.899878)
			(xy 294.393886 -276.899878) (xy 294.397846 -276.850824) (xy 294.409623 -276.80304) (xy 294.428914 -276.757764)
			(xy 294.455217 -276.716168) (xy 294.487852 -276.679331) (xy 294.525973 -276.648206) (xy 294.568594 -276.623599)
			(xy 294.61461 -276.606147) (xy 294.662829 -276.596303) (xy 294.712004 -276.594322) (xy 294.760859 -276.600254)
			(xy 294.80813 -276.613946) (xy 294.852592 -276.635044) (xy 294.893095 -276.663) (xy 294.928588 -276.697092)
			(xy 294.958153 -276.736436) (xy 294.981024 -276.780013) (xy 294.996608 -276.826694) (xy 295.004503 -276.875271)
			(xy 295.004998 -276.899878) (xy 295.3441 -276.899878) (xy 295.34806 -276.850824) (xy 295.359837 -276.80304)
			(xy 295.379128 -276.757764) (xy 295.405431 -276.716168) (xy 295.438066 -276.679331) (xy 295.476187 -276.648206)
			(xy 295.518808 -276.623599) (xy 295.564824 -276.606147) (xy 295.613043 -276.596303) (xy 295.662218 -276.594322)
			(xy 295.711073 -276.600254) (xy 295.758344 -276.613946) (xy 295.802806 -276.635044) (xy 295.843309 -276.663)
			(xy 295.878802 -276.697092) (xy 295.908367 -276.736436) (xy 295.931238 -276.780013) (xy 295.946822 -276.826694)
			(xy 295.954717 -276.875271) (xy 295.955212 -276.899878) (xy 296.29406 -276.899878) (xy 296.29802 -276.850824)
			(xy 296.309797 -276.80304) (xy 296.329088 -276.757764) (xy 296.355391 -276.716168) (xy 296.388026 -276.679331)
			(xy 296.426147 -276.648206) (xy 296.468768 -276.623599) (xy 296.514784 -276.606147) (xy 296.563003 -276.596303)
			(xy 296.612178 -276.594322) (xy 296.661033 -276.600254) (xy 296.708304 -276.613946) (xy 296.752766 -276.635044)
			(xy 296.793269 -276.663) (xy 296.828762 -276.697092) (xy 296.858327 -276.736436) (xy 296.881198 -276.780013)
			(xy 296.896782 -276.826694) (xy 296.904677 -276.875271) (xy 296.905172 -276.899878) (xy 297.24402 -276.899878)
			(xy 297.24798 -276.850824) (xy 297.259757 -276.80304) (xy 297.279048 -276.757764) (xy 297.305351 -276.716168)
			(xy 297.337986 -276.679331) (xy 297.376107 -276.648206) (xy 297.418728 -276.623599) (xy 297.464744 -276.606147)
			(xy 297.512963 -276.596303) (xy 297.562138 -276.594322) (xy 297.610993 -276.600254) (xy 297.658264 -276.613946)
			(xy 297.702726 -276.635044) (xy 297.743229 -276.663) (xy 297.778722 -276.697092) (xy 297.808287 -276.736436)
			(xy 297.831158 -276.780013) (xy 297.846742 -276.826694) (xy 297.854637 -276.875271) (xy 297.855132 -276.899878)
			(xy 298.19398 -276.899878) (xy 298.19794 -276.850824) (xy 298.209717 -276.80304) (xy 298.229008 -276.757764)
			(xy 298.255311 -276.716168) (xy 298.287946 -276.679331) (xy 298.326067 -276.648206) (xy 298.368688 -276.623599)
			(xy 298.414704 -276.606147) (xy 298.462923 -276.596303) (xy 298.512098 -276.594322) (xy 298.560953 -276.600254)
			(xy 298.608224 -276.613946) (xy 298.652686 -276.635044) (xy 298.693189 -276.663) (xy 298.728682 -276.697092)
			(xy 298.758247 -276.736436) (xy 298.781118 -276.780013) (xy 298.796702 -276.826694) (xy 298.804597 -276.875271)
			(xy 298.805092 -276.899878) (xy 299.14394 -276.899878) (xy 299.1479 -276.850824) (xy 299.159677 -276.80304)
			(xy 299.178968 -276.757764) (xy 299.205271 -276.716168) (xy 299.237906 -276.679331) (xy 299.276027 -276.648206)
			(xy 299.318648 -276.623599) (xy 299.364664 -276.606147) (xy 299.412883 -276.596303) (xy 299.462058 -276.594322)
			(xy 299.510913 -276.600254) (xy 299.558184 -276.613946) (xy 299.602646 -276.635044) (xy 299.643149 -276.663)
			(xy 299.678642 -276.697092) (xy 299.708207 -276.736436) (xy 299.731078 -276.780013) (xy 299.746662 -276.826694)
			(xy 299.754557 -276.875271) (xy 299.755052 -276.899878) (xy 300.0939 -276.899878) (xy 300.09786 -276.850824)
			(xy 300.109637 -276.80304) (xy 300.128928 -276.757764) (xy 300.155231 -276.716168) (xy 300.187866 -276.679331)
			(xy 300.225987 -276.648206) (xy 300.268608 -276.623599) (xy 300.314624 -276.606147) (xy 300.362843 -276.596303)
			(xy 300.412018 -276.594322) (xy 300.460873 -276.600254) (xy 300.508144 -276.613946) (xy 300.552606 -276.635044)
			(xy 300.593109 -276.663) (xy 300.628602 -276.697092) (xy 300.658167 -276.736436) (xy 300.681038 -276.780013)
			(xy 300.696622 -276.826694) (xy 300.704517 -276.875271) (xy 300.705012 -276.899878) (xy 301.044114 -276.899878)
			(xy 301.048074 -276.850824) (xy 301.059851 -276.80304) (xy 301.079142 -276.757764) (xy 301.105445 -276.716168)
			(xy 301.13808 -276.679331) (xy 301.176201 -276.648206) (xy 301.218822 -276.623599) (xy 301.264838 -276.606147)
			(xy 301.313057 -276.596303) (xy 301.362232 -276.594322) (xy 301.411087 -276.600254) (xy 301.458358 -276.613946)
			(xy 301.50282 -276.635044) (xy 301.543323 -276.663) (xy 301.578816 -276.697092) (xy 301.608381 -276.736436)
			(xy 301.631252 -276.780013) (xy 301.646836 -276.826694) (xy 301.654731 -276.875271) (xy 301.655226 -276.899878)
			(xy 301.994074 -276.899878) (xy 301.998034 -276.850824) (xy 302.009811 -276.80304) (xy 302.029102 -276.757764)
			(xy 302.055405 -276.716168) (xy 302.08804 -276.679331) (xy 302.126161 -276.648206) (xy 302.168782 -276.623599)
			(xy 302.214798 -276.606147) (xy 302.263017 -276.596303) (xy 302.312192 -276.594322) (xy 302.361047 -276.600254)
			(xy 302.408318 -276.613946) (xy 302.45278 -276.635044) (xy 302.493283 -276.663) (xy 302.528776 -276.697092)
			(xy 302.558341 -276.736436) (xy 302.581212 -276.780013) (xy 302.596796 -276.826694) (xy 302.604691 -276.875271)
			(xy 302.605186 -276.899878) (xy 302.944034 -276.899878) (xy 302.947994 -276.850824) (xy 302.959771 -276.80304)
			(xy 302.979062 -276.757764) (xy 303.005365 -276.716168) (xy 303.038 -276.679331) (xy 303.076121 -276.648206)
			(xy 303.118742 -276.623599) (xy 303.164758 -276.606147) (xy 303.212977 -276.596303) (xy 303.262152 -276.594322)
			(xy 303.311007 -276.600254) (xy 303.358278 -276.613946) (xy 303.40274 -276.635044) (xy 303.443243 -276.663)
			(xy 303.478736 -276.697092) (xy 303.508301 -276.736436) (xy 303.531172 -276.780013) (xy 303.546756 -276.826694)
			(xy 303.554651 -276.875271) (xy 303.555146 -276.899878) (xy 303.893994 -276.899878) (xy 303.897954 -276.850824)
			(xy 303.909731 -276.80304) (xy 303.929022 -276.757764) (xy 303.955325 -276.716168) (xy 303.98796 -276.679331)
			(xy 304.026081 -276.648206) (xy 304.068702 -276.623599) (xy 304.114718 -276.606147) (xy 304.162937 -276.596303)
			(xy 304.212112 -276.594322) (xy 304.260967 -276.600254) (xy 304.308238 -276.613946) (xy 304.3527 -276.635044)
			(xy 304.393203 -276.663) (xy 304.428696 -276.697092) (xy 304.458261 -276.736436) (xy 304.481132 -276.780013)
			(xy 304.496716 -276.826694) (xy 304.504611 -276.875271) (xy 304.505106 -276.899878) (xy 304.843954 -276.899878)
			(xy 304.847914 -276.850824) (xy 304.859691 -276.80304) (xy 304.878982 -276.757764) (xy 304.905285 -276.716168)
			(xy 304.93792 -276.679331) (xy 304.976041 -276.648206) (xy 305.018662 -276.623599) (xy 305.064678 -276.606147)
			(xy 305.112897 -276.596303) (xy 305.162072 -276.594322) (xy 305.210927 -276.600254) (xy 305.258198 -276.613946)
			(xy 305.30266 -276.635044) (xy 305.343163 -276.663) (xy 305.378656 -276.697092) (xy 305.408221 -276.736436)
			(xy 305.431092 -276.780013) (xy 305.446676 -276.826694) (xy 305.454571 -276.875271) (xy 305.455066 -276.899878)
			(xy 305.79366 -276.899878) (xy 305.79762 -276.850824) (xy 305.809397 -276.80304) (xy 305.828688 -276.757764)
			(xy 305.854991 -276.716168) (xy 305.887626 -276.679331) (xy 305.925747 -276.648206) (xy 305.968368 -276.623599)
			(xy 306.014384 -276.606147) (xy 306.062603 -276.596303) (xy 306.111778 -276.594322) (xy 306.160633 -276.600254)
			(xy 306.207904 -276.613946) (xy 306.252366 -276.635044) (xy 306.292869 -276.663) (xy 306.328362 -276.697092)
			(xy 306.357927 -276.736436) (xy 306.380798 -276.780013) (xy 306.396382 -276.826694) (xy 306.404277 -276.875271)
			(xy 306.404772 -276.899878) (xy 306.743874 -276.899878) (xy 306.747834 -276.850824) (xy 306.759611 -276.80304)
			(xy 306.778902 -276.757764) (xy 306.805205 -276.716168) (xy 306.83784 -276.679331) (xy 306.875961 -276.648206)
			(xy 306.918582 -276.623599) (xy 306.964598 -276.606147) (xy 307.012817 -276.596303) (xy 307.061992 -276.594322)
			(xy 307.110847 -276.600254) (xy 307.158118 -276.613946) (xy 307.20258 -276.635044) (xy 307.243083 -276.663)
			(xy 307.278576 -276.697092) (xy 307.308141 -276.736436) (xy 307.331012 -276.780013) (xy 307.346596 -276.826694)
			(xy 307.354491 -276.875271) (xy 307.354986 -276.899878) (xy 307.693834 -276.899878) (xy 307.697794 -276.850824)
			(xy 307.709571 -276.80304) (xy 307.728862 -276.757764) (xy 307.755165 -276.716168) (xy 307.7878 -276.679331)
			(xy 307.825921 -276.648206) (xy 307.868542 -276.623599) (xy 307.914558 -276.606147) (xy 307.962777 -276.596303)
			(xy 308.011952 -276.594322) (xy 308.060807 -276.600254) (xy 308.108078 -276.613946) (xy 308.15254 -276.635044)
			(xy 308.193043 -276.663) (xy 308.228536 -276.697092) (xy 308.258101 -276.736436) (xy 308.280972 -276.780013)
			(xy 308.296556 -276.826694) (xy 308.304451 -276.875271) (xy 308.304946 -276.899878) (xy 308.643794 -276.899878)
			(xy 308.647754 -276.850824) (xy 308.659531 -276.80304) (xy 308.678822 -276.757764) (xy 308.705125 -276.716168)
			(xy 308.73776 -276.679331) (xy 308.775881 -276.648206) (xy 308.818502 -276.623599) (xy 308.864518 -276.606147)
			(xy 308.912737 -276.596303) (xy 308.961912 -276.594322) (xy 309.010767 -276.600254) (xy 309.058038 -276.613946)
			(xy 309.1025 -276.635044) (xy 309.143003 -276.663) (xy 309.178496 -276.697092) (xy 309.208061 -276.736436)
			(xy 309.230932 -276.780013) (xy 309.246516 -276.826694) (xy 309.254411 -276.875271) (xy 309.254906 -276.899878)
			(xy 309.593754 -276.899878) (xy 309.597714 -276.850824) (xy 309.609491 -276.80304) (xy 309.628782 -276.757764)
			(xy 309.655085 -276.716168) (xy 309.68772 -276.679331) (xy 309.725841 -276.648206) (xy 309.768462 -276.623599)
			(xy 309.814478 -276.606147) (xy 309.862697 -276.596303) (xy 309.911872 -276.594322) (xy 309.960727 -276.600254)
			(xy 310.007998 -276.613946) (xy 310.05246 -276.635044) (xy 310.092963 -276.663) (xy 310.128456 -276.697092)
			(xy 310.158021 -276.736436) (xy 310.180892 -276.780013) (xy 310.196476 -276.826694) (xy 310.204371 -276.875271)
			(xy 310.204866 -276.899878) (xy 310.543714 -276.899878) (xy 310.547674 -276.850824) (xy 310.559451 -276.80304)
			(xy 310.578742 -276.757764) (xy 310.605045 -276.716168) (xy 310.63768 -276.679331) (xy 310.675801 -276.648206)
			(xy 310.718422 -276.623599) (xy 310.764438 -276.606147) (xy 310.812657 -276.596303) (xy 310.861832 -276.594322)
			(xy 310.910687 -276.600254) (xy 310.957958 -276.613946) (xy 311.00242 -276.635044) (xy 311.042923 -276.663)
			(xy 311.078416 -276.697092) (xy 311.107981 -276.736436) (xy 311.130852 -276.780013) (xy 311.146436 -276.826694)
			(xy 311.154331 -276.875271) (xy 311.154826 -276.899878) (xy 311.493674 -276.899878) (xy 311.497634 -276.850824)
			(xy 311.509411 -276.80304) (xy 311.528702 -276.757764) (xy 311.555005 -276.716168) (xy 311.58764 -276.679331)
			(xy 311.625761 -276.648206) (xy 311.668382 -276.623599) (xy 311.714398 -276.606147) (xy 311.762617 -276.596303)
			(xy 311.811792 -276.594322) (xy 311.860647 -276.600254) (xy 311.907918 -276.613946) (xy 311.95238 -276.635044)
			(xy 311.992883 -276.663) (xy 312.028376 -276.697092) (xy 312.057941 -276.736436) (xy 312.080812 -276.780013)
			(xy 312.096396 -276.826694) (xy 312.104291 -276.875271) (xy 312.104786 -276.899878) (xy 312.443888 -276.899878)
			(xy 312.447848 -276.850824) (xy 312.459625 -276.80304) (xy 312.478916 -276.757764) (xy 312.505219 -276.716168)
			(xy 312.537854 -276.679331) (xy 312.575975 -276.648206) (xy 312.618596 -276.623599) (xy 312.664612 -276.606147)
			(xy 312.712831 -276.596303) (xy 312.762006 -276.594322) (xy 312.810861 -276.600254) (xy 312.858132 -276.613946)
			(xy 312.902594 -276.635044) (xy 312.943097 -276.663) (xy 312.97859 -276.697092) (xy 313.008155 -276.736436)
			(xy 313.031026 -276.780013) (xy 313.04661 -276.826694) (xy 313.054505 -276.875271) (xy 313.055 -276.899878)
			(xy 313.394102 -276.899878) (xy 313.398062 -276.850824) (xy 313.409839 -276.80304) (xy 313.42913 -276.757764)
			(xy 313.455433 -276.716168) (xy 313.488068 -276.679331) (xy 313.526189 -276.648206) (xy 313.56881 -276.623599)
			(xy 313.614826 -276.606147) (xy 313.663045 -276.596303) (xy 313.71222 -276.594322) (xy 313.761075 -276.600254)
			(xy 313.808346 -276.613946) (xy 313.852808 -276.635044) (xy 313.893311 -276.663) (xy 313.928804 -276.697092)
			(xy 313.958369 -276.736436) (xy 313.98124 -276.780013) (xy 313.996824 -276.826694) (xy 314.004719 -276.875271)
			(xy 314.005214 -276.899878) (xy 314.344062 -276.899878) (xy 314.348022 -276.850824) (xy 314.359799 -276.80304)
			(xy 314.37909 -276.757764) (xy 314.405393 -276.716168) (xy 314.438028 -276.679331) (xy 314.476149 -276.648206)
			(xy 314.51877 -276.623599) (xy 314.564786 -276.606147) (xy 314.613005 -276.596303) (xy 314.66218 -276.594322)
			(xy 314.711035 -276.600254) (xy 314.758306 -276.613946) (xy 314.802768 -276.635044) (xy 314.843271 -276.663)
			(xy 314.878764 -276.697092) (xy 314.908329 -276.736436) (xy 314.9312 -276.780013) (xy 314.946784 -276.826694)
			(xy 314.954679 -276.875271) (xy 314.955174 -276.899878) (xy 314.955169 -276.900132) (xy 315.294276 -276.900132)
			(xy 315.298236 -276.851078) (xy 315.310013 -276.803294) (xy 315.329304 -276.758018) (xy 315.355607 -276.716422)
			(xy 315.388242 -276.679585) (xy 315.426363 -276.64846) (xy 315.468984 -276.623853) (xy 315.515 -276.606401)
			(xy 315.563219 -276.596557) (xy 315.612394 -276.594576) (xy 315.661249 -276.600508) (xy 315.70852 -276.6142)
			(xy 315.752982 -276.635298) (xy 315.793485 -276.663254) (xy 315.828978 -276.697346) (xy 315.858543 -276.73669)
			(xy 315.881414 -276.780267) (xy 315.896998 -276.826948) (xy 315.904893 -276.875525) (xy 315.905388 -276.900132)
			(xy 315.904893 -276.924739) (xy 315.896998 -276.973316) (xy 315.881414 -277.019997) (xy 315.858543 -277.063574)
			(xy 315.828978 -277.102918) (xy 315.793485 -277.13701) (xy 315.752982 -277.164966) (xy 315.70852 -277.186064)
			(xy 315.661249 -277.199756) (xy 315.612394 -277.205688) (xy 315.563219 -277.203707) (xy 315.515 -277.193863)
			(xy 315.468984 -277.176411) (xy 315.426363 -277.151804) (xy 315.388242 -277.120679) (xy 315.355607 -277.083842)
			(xy 315.329304 -277.042246) (xy 315.310013 -276.99697) (xy 315.298236 -276.949186) (xy 315.294276 -276.900132)
			(xy 314.955169 -276.900132) (xy 314.954679 -276.924485) (xy 314.946784 -276.973062) (xy 314.9312 -277.019743)
			(xy 314.908329 -277.06332) (xy 314.878764 -277.102664) (xy 314.843271 -277.136756) (xy 314.802768 -277.164712)
			(xy 314.758306 -277.18581) (xy 314.711035 -277.199502) (xy 314.66218 -277.205434) (xy 314.613005 -277.203453)
			(xy 314.564786 -277.193609) (xy 314.51877 -277.176157) (xy 314.476149 -277.15155) (xy 314.438028 -277.120425)
			(xy 314.405393 -277.083588) (xy 314.37909 -277.041992) (xy 314.359799 -276.996716) (xy 314.348022 -276.948932)
			(xy 314.344062 -276.899878) (xy 314.005214 -276.899878) (xy 314.004719 -276.924485) (xy 313.996824 -276.973062)
			(xy 313.98124 -277.019743) (xy 313.958369 -277.06332) (xy 313.928804 -277.102664) (xy 313.893311 -277.136756)
			(xy 313.852808 -277.164712) (xy 313.808346 -277.18581) (xy 313.761075 -277.199502) (xy 313.71222 -277.205434)
			(xy 313.663045 -277.203453) (xy 313.614826 -277.193609) (xy 313.56881 -277.176157) (xy 313.526189 -277.15155)
			(xy 313.488068 -277.120425) (xy 313.455433 -277.083588) (xy 313.42913 -277.041992) (xy 313.409839 -276.996716)
			(xy 313.398062 -276.948932) (xy 313.394102 -276.899878) (xy 313.055 -276.899878) (xy 313.054505 -276.924485)
			(xy 313.04661 -276.973062) (xy 313.031026 -277.019743) (xy 313.008155 -277.06332) (xy 312.97859 -277.102664)
			(xy 312.943097 -277.136756) (xy 312.902594 -277.164712) (xy 312.858132 -277.18581) (xy 312.810861 -277.199502)
			(xy 312.762006 -277.205434) (xy 312.712831 -277.203453) (xy 312.664612 -277.193609) (xy 312.618596 -277.176157)
			(xy 312.575975 -277.15155) (xy 312.537854 -277.120425) (xy 312.505219 -277.083588) (xy 312.478916 -277.041992)
			(xy 312.459625 -276.996716) (xy 312.447848 -276.948932) (xy 312.443888 -276.899878) (xy 312.104786 -276.899878)
			(xy 312.104291 -276.924485) (xy 312.096396 -276.973062) (xy 312.080812 -277.019743) (xy 312.057941 -277.06332)
			(xy 312.028376 -277.102664) (xy 311.992883 -277.136756) (xy 311.95238 -277.164712) (xy 311.907918 -277.18581)
			(xy 311.860647 -277.199502) (xy 311.811792 -277.205434) (xy 311.762617 -277.203453) (xy 311.714398 -277.193609)
			(xy 311.668382 -277.176157) (xy 311.625761 -277.15155) (xy 311.58764 -277.120425) (xy 311.555005 -277.083588)
			(xy 311.528702 -277.041992) (xy 311.509411 -276.996716) (xy 311.497634 -276.948932) (xy 311.493674 -276.899878)
			(xy 311.154826 -276.899878) (xy 311.154331 -276.924485) (xy 311.146436 -276.973062) (xy 311.130852 -277.019743)
			(xy 311.107981 -277.06332) (xy 311.078416 -277.102664) (xy 311.042923 -277.136756) (xy 311.00242 -277.164712)
			(xy 310.957958 -277.18581) (xy 310.910687 -277.199502) (xy 310.861832 -277.205434) (xy 310.812657 -277.203453)
			(xy 310.764438 -277.193609) (xy 310.718422 -277.176157) (xy 310.675801 -277.15155) (xy 310.63768 -277.120425)
			(xy 310.605045 -277.083588) (xy 310.578742 -277.041992) (xy 310.559451 -276.996716) (xy 310.547674 -276.948932)
			(xy 310.543714 -276.899878) (xy 310.204866 -276.899878) (xy 310.204371 -276.924485) (xy 310.196476 -276.973062)
			(xy 310.180892 -277.019743) (xy 310.158021 -277.06332) (xy 310.128456 -277.102664) (xy 310.092963 -277.136756)
			(xy 310.05246 -277.164712) (xy 310.007998 -277.18581) (xy 309.960727 -277.199502) (xy 309.911872 -277.205434)
			(xy 309.862697 -277.203453) (xy 309.814478 -277.193609) (xy 309.768462 -277.176157) (xy 309.725841 -277.15155)
			(xy 309.68772 -277.120425) (xy 309.655085 -277.083588) (xy 309.628782 -277.041992) (xy 309.609491 -276.996716)
			(xy 309.597714 -276.948932) (xy 309.593754 -276.899878) (xy 309.254906 -276.899878) (xy 309.254411 -276.924485)
			(xy 309.246516 -276.973062) (xy 309.230932 -277.019743) (xy 309.208061 -277.06332) (xy 309.178496 -277.102664)
			(xy 309.143003 -277.136756) (xy 309.1025 -277.164712) (xy 309.058038 -277.18581) (xy 309.010767 -277.199502)
			(xy 308.961912 -277.205434) (xy 308.912737 -277.203453) (xy 308.864518 -277.193609) (xy 308.818502 -277.176157)
			(xy 308.775881 -277.15155) (xy 308.73776 -277.120425) (xy 308.705125 -277.083588) (xy 308.678822 -277.041992)
			(xy 308.659531 -276.996716) (xy 308.647754 -276.948932) (xy 308.643794 -276.899878) (xy 308.304946 -276.899878)
			(xy 308.304451 -276.924485) (xy 308.296556 -276.973062) (xy 308.280972 -277.019743) (xy 308.258101 -277.06332)
			(xy 308.228536 -277.102664) (xy 308.193043 -277.136756) (xy 308.15254 -277.164712) (xy 308.108078 -277.18581)
			(xy 308.060807 -277.199502) (xy 308.011952 -277.205434) (xy 307.962777 -277.203453) (xy 307.914558 -277.193609)
			(xy 307.868542 -277.176157) (xy 307.825921 -277.15155) (xy 307.7878 -277.120425) (xy 307.755165 -277.083588)
			(xy 307.728862 -277.041992) (xy 307.709571 -276.996716) (xy 307.697794 -276.948932) (xy 307.693834 -276.899878)
			(xy 307.354986 -276.899878) (xy 307.354491 -276.924485) (xy 307.346596 -276.973062) (xy 307.331012 -277.019743)
			(xy 307.308141 -277.06332) (xy 307.278576 -277.102664) (xy 307.243083 -277.136756) (xy 307.20258 -277.164712)
			(xy 307.158118 -277.18581) (xy 307.110847 -277.199502) (xy 307.061992 -277.205434) (xy 307.012817 -277.203453)
			(xy 306.964598 -277.193609) (xy 306.918582 -277.176157) (xy 306.875961 -277.15155) (xy 306.83784 -277.120425)
			(xy 306.805205 -277.083588) (xy 306.778902 -277.041992) (xy 306.759611 -276.996716) (xy 306.747834 -276.948932)
			(xy 306.743874 -276.899878) (xy 306.404772 -276.899878) (xy 306.404277 -276.924485) (xy 306.396382 -276.973062)
			(xy 306.380798 -277.019743) (xy 306.357927 -277.06332) (xy 306.328362 -277.102664) (xy 306.292869 -277.136756)
			(xy 306.252366 -277.164712) (xy 306.207904 -277.18581) (xy 306.160633 -277.199502) (xy 306.111778 -277.205434)
			(xy 306.062603 -277.203453) (xy 306.014384 -277.193609) (xy 305.968368 -277.176157) (xy 305.925747 -277.15155)
			(xy 305.887626 -277.120425) (xy 305.854991 -277.083588) (xy 305.828688 -277.041992) (xy 305.809397 -276.996716)
			(xy 305.79762 -276.948932) (xy 305.79366 -276.899878) (xy 305.455066 -276.899878) (xy 305.454571 -276.924485)
			(xy 305.446676 -276.973062) (xy 305.431092 -277.019743) (xy 305.408221 -277.06332) (xy 305.378656 -277.102664)
			(xy 305.343163 -277.136756) (xy 305.30266 -277.164712) (xy 305.258198 -277.18581) (xy 305.210927 -277.199502)
			(xy 305.162072 -277.205434) (xy 305.112897 -277.203453) (xy 305.064678 -277.193609) (xy 305.018662 -277.176157)
			(xy 304.976041 -277.15155) (xy 304.93792 -277.120425) (xy 304.905285 -277.083588) (xy 304.878982 -277.041992)
			(xy 304.859691 -276.996716) (xy 304.847914 -276.948932) (xy 304.843954 -276.899878) (xy 304.505106 -276.899878)
			(xy 304.504611 -276.924485) (xy 304.496716 -276.973062) (xy 304.481132 -277.019743) (xy 304.458261 -277.06332)
			(xy 304.428696 -277.102664) (xy 304.393203 -277.136756) (xy 304.3527 -277.164712) (xy 304.308238 -277.18581)
			(xy 304.260967 -277.199502) (xy 304.212112 -277.205434) (xy 304.162937 -277.203453) (xy 304.114718 -277.193609)
			(xy 304.068702 -277.176157) (xy 304.026081 -277.15155) (xy 303.98796 -277.120425) (xy 303.955325 -277.083588)
			(xy 303.929022 -277.041992) (xy 303.909731 -276.996716) (xy 303.897954 -276.948932) (xy 303.893994 -276.899878)
			(xy 303.555146 -276.899878) (xy 303.554651 -276.924485) (xy 303.546756 -276.973062) (xy 303.531172 -277.019743)
			(xy 303.508301 -277.06332) (xy 303.478736 -277.102664) (xy 303.443243 -277.136756) (xy 303.40274 -277.164712)
			(xy 303.358278 -277.18581) (xy 303.311007 -277.199502) (xy 303.262152 -277.205434) (xy 303.212977 -277.203453)
			(xy 303.164758 -277.193609) (xy 303.118742 -277.176157) (xy 303.076121 -277.15155) (xy 303.038 -277.120425)
			(xy 303.005365 -277.083588) (xy 302.979062 -277.041992) (xy 302.959771 -276.996716) (xy 302.947994 -276.948932)
			(xy 302.944034 -276.899878) (xy 302.605186 -276.899878) (xy 302.604691 -276.924485) (xy 302.596796 -276.973062)
			(xy 302.581212 -277.019743) (xy 302.558341 -277.06332) (xy 302.528776 -277.102664) (xy 302.493283 -277.136756)
			(xy 302.45278 -277.164712) (xy 302.408318 -277.18581) (xy 302.361047 -277.199502) (xy 302.312192 -277.205434)
			(xy 302.263017 -277.203453) (xy 302.214798 -277.193609) (xy 302.168782 -277.176157) (xy 302.126161 -277.15155)
			(xy 302.08804 -277.120425) (xy 302.055405 -277.083588) (xy 302.029102 -277.041992) (xy 302.009811 -276.996716)
			(xy 301.998034 -276.948932) (xy 301.994074 -276.899878) (xy 301.655226 -276.899878) (xy 301.654731 -276.924485)
			(xy 301.646836 -276.973062) (xy 301.631252 -277.019743) (xy 301.608381 -277.06332) (xy 301.578816 -277.102664)
			(xy 301.543323 -277.136756) (xy 301.50282 -277.164712) (xy 301.458358 -277.18581) (xy 301.411087 -277.199502)
			(xy 301.362232 -277.205434) (xy 301.313057 -277.203453) (xy 301.264838 -277.193609) (xy 301.218822 -277.176157)
			(xy 301.176201 -277.15155) (xy 301.13808 -277.120425) (xy 301.105445 -277.083588) (xy 301.079142 -277.041992)
			(xy 301.059851 -276.996716) (xy 301.048074 -276.948932) (xy 301.044114 -276.899878) (xy 300.705012 -276.899878)
			(xy 300.704517 -276.924485) (xy 300.696622 -276.973062) (xy 300.681038 -277.019743) (xy 300.658167 -277.06332)
			(xy 300.628602 -277.102664) (xy 300.593109 -277.136756) (xy 300.552606 -277.164712) (xy 300.508144 -277.18581)
			(xy 300.460873 -277.199502) (xy 300.412018 -277.205434) (xy 300.362843 -277.203453) (xy 300.314624 -277.193609)
			(xy 300.268608 -277.176157) (xy 300.225987 -277.15155) (xy 300.187866 -277.120425) (xy 300.155231 -277.083588)
			(xy 300.128928 -277.041992) (xy 300.109637 -276.996716) (xy 300.09786 -276.948932) (xy 300.0939 -276.899878)
			(xy 299.755052 -276.899878) (xy 299.754557 -276.924485) (xy 299.746662 -276.973062) (xy 299.731078 -277.019743)
			(xy 299.708207 -277.06332) (xy 299.678642 -277.102664) (xy 299.643149 -277.136756) (xy 299.602646 -277.164712)
			(xy 299.558184 -277.18581) (xy 299.510913 -277.199502) (xy 299.462058 -277.205434) (xy 299.412883 -277.203453)
			(xy 299.364664 -277.193609) (xy 299.318648 -277.176157) (xy 299.276027 -277.15155) (xy 299.237906 -277.120425)
			(xy 299.205271 -277.083588) (xy 299.178968 -277.041992) (xy 299.159677 -276.996716) (xy 299.1479 -276.948932)
			(xy 299.14394 -276.899878) (xy 298.805092 -276.899878) (xy 298.804597 -276.924485) (xy 298.796702 -276.973062)
			(xy 298.781118 -277.019743) (xy 298.758247 -277.06332) (xy 298.728682 -277.102664) (xy 298.693189 -277.136756)
			(xy 298.652686 -277.164712) (xy 298.608224 -277.18581) (xy 298.560953 -277.199502) (xy 298.512098 -277.205434)
			(xy 298.462923 -277.203453) (xy 298.414704 -277.193609) (xy 298.368688 -277.176157) (xy 298.326067 -277.15155)
			(xy 298.287946 -277.120425) (xy 298.255311 -277.083588) (xy 298.229008 -277.041992) (xy 298.209717 -276.996716)
			(xy 298.19794 -276.948932) (xy 298.19398 -276.899878) (xy 297.855132 -276.899878) (xy 297.854637 -276.924485)
			(xy 297.846742 -276.973062) (xy 297.831158 -277.019743) (xy 297.808287 -277.06332) (xy 297.778722 -277.102664)
			(xy 297.743229 -277.136756) (xy 297.702726 -277.164712) (xy 297.658264 -277.18581) (xy 297.610993 -277.199502)
			(xy 297.562138 -277.205434) (xy 297.512963 -277.203453) (xy 297.464744 -277.193609) (xy 297.418728 -277.176157)
			(xy 297.376107 -277.15155) (xy 297.337986 -277.120425) (xy 297.305351 -277.083588) (xy 297.279048 -277.041992)
			(xy 297.259757 -276.996716) (xy 297.24798 -276.948932) (xy 297.24402 -276.899878) (xy 296.905172 -276.899878)
			(xy 296.904677 -276.924485) (xy 296.896782 -276.973062) (xy 296.881198 -277.019743) (xy 296.858327 -277.06332)
			(xy 296.828762 -277.102664) (xy 296.793269 -277.136756) (xy 296.752766 -277.164712) (xy 296.708304 -277.18581)
			(xy 296.661033 -277.199502) (xy 296.612178 -277.205434) (xy 296.563003 -277.203453) (xy 296.514784 -277.193609)
			(xy 296.468768 -277.176157) (xy 296.426147 -277.15155) (xy 296.388026 -277.120425) (xy 296.355391 -277.083588)
			(xy 296.329088 -277.041992) (xy 296.309797 -276.996716) (xy 296.29802 -276.948932) (xy 296.29406 -276.899878)
			(xy 295.955212 -276.899878) (xy 295.954717 -276.924485) (xy 295.946822 -276.973062) (xy 295.931238 -277.019743)
			(xy 295.908367 -277.06332) (xy 295.878802 -277.102664) (xy 295.843309 -277.136756) (xy 295.802806 -277.164712)
			(xy 295.758344 -277.18581) (xy 295.711073 -277.199502) (xy 295.662218 -277.205434) (xy 295.613043 -277.203453)
			(xy 295.564824 -277.193609) (xy 295.518808 -277.176157) (xy 295.476187 -277.15155) (xy 295.438066 -277.120425)
			(xy 295.405431 -277.083588) (xy 295.379128 -277.041992) (xy 295.359837 -276.996716) (xy 295.34806 -276.948932)
			(xy 295.3441 -276.899878) (xy 295.004998 -276.899878) (xy 295.004503 -276.924485) (xy 294.996608 -276.973062)
			(xy 294.981024 -277.019743) (xy 294.958153 -277.06332) (xy 294.928588 -277.102664) (xy 294.893095 -277.136756)
			(xy 294.852592 -277.164712) (xy 294.80813 -277.18581) (xy 294.760859 -277.199502) (xy 294.712004 -277.205434)
			(xy 294.662829 -277.203453) (xy 294.61461 -277.193609) (xy 294.568594 -277.176157) (xy 294.525973 -277.15155)
			(xy 294.487852 -277.120425) (xy 294.455217 -277.083588) (xy 294.428914 -277.041992) (xy 294.409623 -276.996716)
			(xy 294.397846 -276.948932) (xy 294.393886 -276.899878) (xy 294.055038 -276.899878) (xy 294.054543 -276.924485)
			(xy 294.046648 -276.973062) (xy 294.031064 -277.019743) (xy 294.008193 -277.06332) (xy 293.978628 -277.102664)
			(xy 293.943135 -277.136756) (xy 293.902632 -277.164712) (xy 293.85817 -277.18581) (xy 293.810899 -277.199502)
			(xy 293.762044 -277.205434) (xy 293.712869 -277.203453) (xy 293.66465 -277.193609) (xy 293.618634 -277.176157)
			(xy 293.576013 -277.15155) (xy 293.537892 -277.120425) (xy 293.505257 -277.083588) (xy 293.478954 -277.041992)
			(xy 293.459663 -276.996716) (xy 293.447886 -276.948932) (xy 293.443926 -276.899878) (xy 293.105078 -276.899878)
			(xy 293.104583 -276.924485) (xy 293.096688 -276.973062) (xy 293.081104 -277.019743) (xy 293.058233 -277.06332)
			(xy 293.028668 -277.102664) (xy 292.993175 -277.136756) (xy 292.952672 -277.164712) (xy 292.90821 -277.18581)
			(xy 292.860939 -277.199502) (xy 292.812084 -277.205434) (xy 292.762909 -277.203453) (xy 292.71469 -277.193609)
			(xy 292.668674 -277.176157) (xy 292.626053 -277.15155) (xy 292.587932 -277.120425) (xy 292.555297 -277.083588)
			(xy 292.528994 -277.041992) (xy 292.509703 -276.996716) (xy 292.497926 -276.948932) (xy 292.493966 -276.899878)
			(xy 292.155094 -276.899878) (xy 292.152851 -276.941204) (xy 292.142176 -276.989689) (xy 292.123798 -277.035808)
			(xy 292.098201 -277.078346) (xy 292.066059 -277.116182) (xy 292.02822 -277.14832) (xy 291.985679 -277.173913)
			(xy 291.939558 -277.192286) (xy 291.891073 -277.202955) (xy 291.8415 -277.20564) (xy 291.792145 -277.20027)
			(xy 291.74431 -277.186985) (xy 291.699254 -277.166137) (xy 291.658165 -277.138274) (xy 291.622124 -277.10413)
			(xy 291.592083 -277.064605) (xy 291.568831 -277.020741) (xy 291.552982 -276.973693) (xy 291.544954 -276.924701)
			(xy 291.544502 -276.899878) (xy 291.545245 -276.869526) (xy 291.557265 -276.810022) (xy 291.568378 -276.781768)
			(xy 291.571662 -276.772814) (xy 291.572035 -276.753758) (xy 291.565431 -276.735879) (xy 291.552763 -276.72164)
			(xy 291.535773 -276.713002) (xy 291.516803 -276.711156) (xy 291.498467 -276.716355) (xy 291.490654 -276.721824)
			(xy 291.442648 -276.756114) (xy 291.432627 -276.763642) (xy 291.420902 -276.785759) (xy 291.420296 -276.798278)
			(xy 291.420296 -277.572978) (xy 291.419858 -277.583042) (xy 291.412124 -277.601625) (xy 291.40531 -277.609046)
			(xy 291.211762 -277.802594) (xy 291.204142 -277.822406) (xy 291.20465 -277.833582) (xy 291.205158 -277.849838)
			(xy 291.543752 -277.849838) (xy 291.547712 -277.800784) (xy 291.559489 -277.753) (xy 291.57878 -277.707724)
			(xy 291.605083 -277.666128) (xy 291.637718 -277.629291) (xy 291.675839 -277.598166) (xy 291.71846 -277.573559)
			(xy 291.764476 -277.556107) (xy 291.812695 -277.546263) (xy 291.86187 -277.544282) (xy 291.910725 -277.550214)
			(xy 291.957996 -277.563906) (xy 292.002458 -277.585004) (xy 292.042961 -277.61296) (xy 292.078454 -277.647052)
			(xy 292.108019 -277.686396) (xy 292.13089 -277.729973) (xy 292.146474 -277.776654) (xy 292.154369 -277.825231)
			(xy 292.154864 -277.849838) (xy 292.493966 -277.849838) (xy 292.497926 -277.800784) (xy 292.509703 -277.753)
			(xy 292.528994 -277.707724) (xy 292.555297 -277.666128) (xy 292.587932 -277.629291) (xy 292.626053 -277.598166)
			(xy 292.668674 -277.573559) (xy 292.71469 -277.556107) (xy 292.762909 -277.546263) (xy 292.812084 -277.544282)
			(xy 292.860939 -277.550214) (xy 292.90821 -277.563906) (xy 292.952672 -277.585004) (xy 292.993175 -277.61296)
			(xy 293.028668 -277.647052) (xy 293.058233 -277.686396) (xy 293.081104 -277.729973) (xy 293.096688 -277.776654)
			(xy 293.104583 -277.825231) (xy 293.105078 -277.849838) (xy 293.443672 -277.849838) (xy 293.447632 -277.800784)
			(xy 293.459409 -277.753) (xy 293.4787 -277.707724) (xy 293.505003 -277.666128) (xy 293.537638 -277.629291)
			(xy 293.575759 -277.598166) (xy 293.61838 -277.573559) (xy 293.664396 -277.556107) (xy 293.712615 -277.546263)
			(xy 293.76179 -277.544282) (xy 293.810645 -277.550214) (xy 293.857916 -277.563906) (xy 293.902378 -277.585004)
			(xy 293.942881 -277.61296) (xy 293.978374 -277.647052) (xy 294.007939 -277.686396) (xy 294.03081 -277.729973)
			(xy 294.046394 -277.776654) (xy 294.054289 -277.825231) (xy 294.054784 -277.849838) (xy 294.393886 -277.849838)
			(xy 294.397846 -277.800784) (xy 294.409623 -277.753) (xy 294.428914 -277.707724) (xy 294.455217 -277.666128)
			(xy 294.487852 -277.629291) (xy 294.525973 -277.598166) (xy 294.568594 -277.573559) (xy 294.61461 -277.556107)
			(xy 294.662829 -277.546263) (xy 294.712004 -277.544282) (xy 294.760859 -277.550214) (xy 294.80813 -277.563906)
			(xy 294.852592 -277.585004) (xy 294.893095 -277.61296) (xy 294.928588 -277.647052) (xy 294.958153 -277.686396)
			(xy 294.981024 -277.729973) (xy 294.996608 -277.776654) (xy 295.004503 -277.825231) (xy 295.004998 -277.849838)
			(xy 295.343846 -277.849838) (xy 295.347806 -277.800784) (xy 295.359583 -277.753) (xy 295.378874 -277.707724)
			(xy 295.405177 -277.666128) (xy 295.437812 -277.629291) (xy 295.475933 -277.598166) (xy 295.518554 -277.573559)
			(xy 295.56457 -277.556107) (xy 295.612789 -277.546263) (xy 295.661964 -277.544282) (xy 295.710819 -277.550214)
			(xy 295.75809 -277.563906) (xy 295.802552 -277.585004) (xy 295.843055 -277.61296) (xy 295.878548 -277.647052)
			(xy 295.908113 -277.686396) (xy 295.930984 -277.729973) (xy 295.946568 -277.776654) (xy 295.954463 -277.825231)
			(xy 295.954958 -277.849838) (xy 296.29406 -277.849838) (xy 296.29802 -277.800784) (xy 296.309797 -277.753)
			(xy 296.329088 -277.707724) (xy 296.355391 -277.666128) (xy 296.388026 -277.629291) (xy 296.426147 -277.598166)
			(xy 296.468768 -277.573559) (xy 296.514784 -277.556107) (xy 296.563003 -277.546263) (xy 296.612178 -277.544282)
			(xy 296.661033 -277.550214) (xy 296.708304 -277.563906) (xy 296.752766 -277.585004) (xy 296.793269 -277.61296)
			(xy 296.828762 -277.647052) (xy 296.858327 -277.686396) (xy 296.881198 -277.729973) (xy 296.896782 -277.776654)
			(xy 296.904677 -277.825231) (xy 296.905172 -277.849838) (xy 297.243766 -277.849838) (xy 297.247726 -277.800784)
			(xy 297.259503 -277.753) (xy 297.278794 -277.707724) (xy 297.305097 -277.666128) (xy 297.337732 -277.629291)
			(xy 297.375853 -277.598166) (xy 297.418474 -277.573559) (xy 297.46449 -277.556107) (xy 297.512709 -277.546263)
			(xy 297.561884 -277.544282) (xy 297.610739 -277.550214) (xy 297.65801 -277.563906) (xy 297.702472 -277.585004)
			(xy 297.742975 -277.61296) (xy 297.778468 -277.647052) (xy 297.808033 -277.686396) (xy 297.830904 -277.729973)
			(xy 297.846488 -277.776654) (xy 297.854383 -277.825231) (xy 297.854878 -277.849838) (xy 298.19398 -277.849838)
			(xy 298.19794 -277.800784) (xy 298.209717 -277.753) (xy 298.229008 -277.707724) (xy 298.255311 -277.666128)
			(xy 298.287946 -277.629291) (xy 298.326067 -277.598166) (xy 298.368688 -277.573559) (xy 298.414704 -277.556107)
			(xy 298.462923 -277.546263) (xy 298.512098 -277.544282) (xy 298.560953 -277.550214) (xy 298.608224 -277.563906)
			(xy 298.652686 -277.585004) (xy 298.693189 -277.61296) (xy 298.728682 -277.647052) (xy 298.758247 -277.686396)
			(xy 298.781118 -277.729973) (xy 298.796702 -277.776654) (xy 298.804597 -277.825231) (xy 298.805092 -277.849838)
			(xy 299.143686 -277.849838) (xy 299.147646 -277.800784) (xy 299.159423 -277.753) (xy 299.178714 -277.707724)
			(xy 299.205017 -277.666128) (xy 299.237652 -277.629291) (xy 299.275773 -277.598166) (xy 299.318394 -277.573559)
			(xy 299.36441 -277.556107) (xy 299.412629 -277.546263) (xy 299.461804 -277.544282) (xy 299.510659 -277.550214)
			(xy 299.55793 -277.563906) (xy 299.602392 -277.585004) (xy 299.642895 -277.61296) (xy 299.678388 -277.647052)
			(xy 299.707953 -277.686396) (xy 299.730824 -277.729973) (xy 299.746408 -277.776654) (xy 299.754303 -277.825231)
			(xy 299.754798 -277.849838) (xy 300.0939 -277.849838) (xy 300.09786 -277.800784) (xy 300.109637 -277.753)
			(xy 300.128928 -277.707724) (xy 300.155231 -277.666128) (xy 300.187866 -277.629291) (xy 300.225987 -277.598166)
			(xy 300.268608 -277.573559) (xy 300.314624 -277.556107) (xy 300.362843 -277.546263) (xy 300.412018 -277.544282)
			(xy 300.460873 -277.550214) (xy 300.508144 -277.563906) (xy 300.552606 -277.585004) (xy 300.593109 -277.61296)
			(xy 300.628602 -277.647052) (xy 300.658167 -277.686396) (xy 300.681038 -277.729973) (xy 300.696622 -277.776654)
			(xy 300.704517 -277.825231) (xy 300.705012 -277.849838) (xy 301.04386 -277.849838) (xy 301.04782 -277.800784)
			(xy 301.059597 -277.753) (xy 301.078888 -277.707724) (xy 301.105191 -277.666128) (xy 301.137826 -277.629291)
			(xy 301.175947 -277.598166) (xy 301.218568 -277.573559) (xy 301.264584 -277.556107) (xy 301.312803 -277.546263)
			(xy 301.361978 -277.544282) (xy 301.410833 -277.550214) (xy 301.458104 -277.563906) (xy 301.502566 -277.585004)
			(xy 301.543069 -277.61296) (xy 301.578562 -277.647052) (xy 301.608127 -277.686396) (xy 301.630998 -277.729973)
			(xy 301.646582 -277.776654) (xy 301.654477 -277.825231) (xy 301.654972 -277.849838) (xy 301.994074 -277.849838)
			(xy 301.998034 -277.800784) (xy 302.009811 -277.753) (xy 302.029102 -277.707724) (xy 302.055405 -277.666128)
			(xy 302.08804 -277.629291) (xy 302.126161 -277.598166) (xy 302.168782 -277.573559) (xy 302.214798 -277.556107)
			(xy 302.263017 -277.546263) (xy 302.312192 -277.544282) (xy 302.361047 -277.550214) (xy 302.408318 -277.563906)
			(xy 302.45278 -277.585004) (xy 302.493283 -277.61296) (xy 302.528776 -277.647052) (xy 302.558341 -277.686396)
			(xy 302.581212 -277.729973) (xy 302.596796 -277.776654) (xy 302.604691 -277.825231) (xy 302.605186 -277.849838)
			(xy 302.94378 -277.849838) (xy 302.94774 -277.800784) (xy 302.959517 -277.753) (xy 302.978808 -277.707724)
			(xy 303.005111 -277.666128) (xy 303.037746 -277.629291) (xy 303.075867 -277.598166) (xy 303.118488 -277.573559)
			(xy 303.164504 -277.556107) (xy 303.212723 -277.546263) (xy 303.261898 -277.544282) (xy 303.310753 -277.550214)
			(xy 303.358024 -277.563906) (xy 303.402486 -277.585004) (xy 303.442989 -277.61296) (xy 303.478482 -277.647052)
			(xy 303.508047 -277.686396) (xy 303.530918 -277.729973) (xy 303.546502 -277.776654) (xy 303.554397 -277.825231)
			(xy 303.554892 -277.849838) (xy 303.893994 -277.849838) (xy 303.897954 -277.800784) (xy 303.909731 -277.753)
			(xy 303.929022 -277.707724) (xy 303.955325 -277.666128) (xy 303.98796 -277.629291) (xy 304.026081 -277.598166)
			(xy 304.068702 -277.573559) (xy 304.114718 -277.556107) (xy 304.162937 -277.546263) (xy 304.212112 -277.544282)
			(xy 304.260967 -277.550214) (xy 304.308238 -277.563906) (xy 304.3527 -277.585004) (xy 304.393203 -277.61296)
			(xy 304.428696 -277.647052) (xy 304.458261 -277.686396) (xy 304.481132 -277.729973) (xy 304.496716 -277.776654)
			(xy 304.504611 -277.825231) (xy 304.505106 -277.849838) (xy 304.8437 -277.849838) (xy 304.84766 -277.800784)
			(xy 304.859437 -277.753) (xy 304.878728 -277.707724) (xy 304.905031 -277.666128) (xy 304.937666 -277.629291)
			(xy 304.975787 -277.598166) (xy 305.018408 -277.573559) (xy 305.064424 -277.556107) (xy 305.112643 -277.546263)
			(xy 305.161818 -277.544282) (xy 305.210673 -277.550214) (xy 305.257944 -277.563906) (xy 305.302406 -277.585004)
			(xy 305.342909 -277.61296) (xy 305.378402 -277.647052) (xy 305.407967 -277.686396) (xy 305.430838 -277.729973)
			(xy 305.446422 -277.776654) (xy 305.454317 -277.825231) (xy 305.454812 -277.849838) (xy 305.793914 -277.849838)
			(xy 305.797874 -277.800784) (xy 305.809651 -277.753) (xy 305.828942 -277.707724) (xy 305.855245 -277.666128)
			(xy 305.88788 -277.629291) (xy 305.926001 -277.598166) (xy 305.968622 -277.573559) (xy 306.014638 -277.556107)
			(xy 306.062857 -277.546263) (xy 306.112032 -277.544282) (xy 306.160887 -277.550214) (xy 306.208158 -277.563906)
			(xy 306.25262 -277.585004) (xy 306.293123 -277.61296) (xy 306.328616 -277.647052) (xy 306.358181 -277.686396)
			(xy 306.381052 -277.729973) (xy 306.396636 -277.776654) (xy 306.404531 -277.825231) (xy 306.405026 -277.849838)
			(xy 306.743874 -277.849838) (xy 306.747834 -277.800784) (xy 306.759611 -277.753) (xy 306.778902 -277.707724)
			(xy 306.805205 -277.666128) (xy 306.83784 -277.629291) (xy 306.875961 -277.598166) (xy 306.918582 -277.573559)
			(xy 306.964598 -277.556107) (xy 307.012817 -277.546263) (xy 307.061992 -277.544282) (xy 307.110847 -277.550214)
			(xy 307.158118 -277.563906) (xy 307.20258 -277.585004) (xy 307.243083 -277.61296) (xy 307.278576 -277.647052)
			(xy 307.308141 -277.686396) (xy 307.331012 -277.729973) (xy 307.346596 -277.776654) (xy 307.354491 -277.825231)
			(xy 307.354986 -277.849838) (xy 307.694088 -277.849838) (xy 307.698048 -277.800784) (xy 307.709825 -277.753)
			(xy 307.729116 -277.707724) (xy 307.755419 -277.666128) (xy 307.788054 -277.629291) (xy 307.826175 -277.598166)
			(xy 307.868796 -277.573559) (xy 307.914812 -277.556107) (xy 307.963031 -277.546263) (xy 308.012206 -277.544282)
			(xy 308.061061 -277.550214) (xy 308.108332 -277.563906) (xy 308.152794 -277.585004) (xy 308.193297 -277.61296)
			(xy 308.22879 -277.647052) (xy 308.258355 -277.686396) (xy 308.281226 -277.729973) (xy 308.29681 -277.776654)
			(xy 308.304705 -277.825231) (xy 308.3052 -277.849838) (xy 308.643794 -277.849838) (xy 308.647754 -277.800784)
			(xy 308.659531 -277.753) (xy 308.678822 -277.707724) (xy 308.705125 -277.666128) (xy 308.73776 -277.629291)
			(xy 308.775881 -277.598166) (xy 308.818502 -277.573559) (xy 308.864518 -277.556107) (xy 308.912737 -277.546263)
			(xy 308.961912 -277.544282) (xy 309.010767 -277.550214) (xy 309.058038 -277.563906) (xy 309.1025 -277.585004)
			(xy 309.143003 -277.61296) (xy 309.178496 -277.647052) (xy 309.208061 -277.686396) (xy 309.230932 -277.729973)
			(xy 309.246516 -277.776654) (xy 309.254411 -277.825231) (xy 309.254906 -277.849838) (xy 309.594008 -277.849838)
			(xy 309.597968 -277.800784) (xy 309.609745 -277.753) (xy 309.629036 -277.707724) (xy 309.655339 -277.666128)
			(xy 309.687974 -277.629291) (xy 309.726095 -277.598166) (xy 309.768716 -277.573559) (xy 309.814732 -277.556107)
			(xy 309.862951 -277.546263) (xy 309.912126 -277.544282) (xy 309.960981 -277.550214) (xy 310.008252 -277.563906)
			(xy 310.052714 -277.585004) (xy 310.093217 -277.61296) (xy 310.12871 -277.647052) (xy 310.158275 -277.686396)
			(xy 310.181146 -277.729973) (xy 310.19673 -277.776654) (xy 310.204625 -277.825231) (xy 310.20512 -277.849838)
			(xy 310.543714 -277.849838) (xy 310.547674 -277.800784) (xy 310.559451 -277.753) (xy 310.578742 -277.707724)
			(xy 310.605045 -277.666128) (xy 310.63768 -277.629291) (xy 310.675801 -277.598166) (xy 310.718422 -277.573559)
			(xy 310.764438 -277.556107) (xy 310.812657 -277.546263) (xy 310.861832 -277.544282) (xy 310.910687 -277.550214)
			(xy 310.957958 -277.563906) (xy 311.00242 -277.585004) (xy 311.042923 -277.61296) (xy 311.078416 -277.647052)
			(xy 311.107981 -277.686396) (xy 311.130852 -277.729973) (xy 311.146436 -277.776654) (xy 311.154331 -277.825231)
			(xy 311.154826 -277.849838) (xy 311.493928 -277.849838) (xy 311.497888 -277.800784) (xy 311.509665 -277.753)
			(xy 311.528956 -277.707724) (xy 311.555259 -277.666128) (xy 311.587894 -277.629291) (xy 311.626015 -277.598166)
			(xy 311.668636 -277.573559) (xy 311.714652 -277.556107) (xy 311.762871 -277.546263) (xy 311.812046 -277.544282)
			(xy 311.860901 -277.550214) (xy 311.908172 -277.563906) (xy 311.952634 -277.585004) (xy 311.993137 -277.61296)
			(xy 312.02863 -277.647052) (xy 312.058195 -277.686396) (xy 312.081066 -277.729973) (xy 312.09665 -277.776654)
			(xy 312.104545 -277.825231) (xy 312.10504 -277.849838) (xy 312.443888 -277.849838) (xy 312.447848 -277.800784)
			(xy 312.459625 -277.753) (xy 312.478916 -277.707724) (xy 312.505219 -277.666128) (xy 312.537854 -277.629291)
			(xy 312.575975 -277.598166) (xy 312.618596 -277.573559) (xy 312.664612 -277.556107) (xy 312.712831 -277.546263)
			(xy 312.762006 -277.544282) (xy 312.810861 -277.550214) (xy 312.858132 -277.563906) (xy 312.902594 -277.585004)
			(xy 312.943097 -277.61296) (xy 312.97859 -277.647052) (xy 313.008155 -277.686396) (xy 313.031026 -277.729973)
			(xy 313.04661 -277.776654) (xy 313.054505 -277.825231) (xy 313.055 -277.849838) (xy 313.394102 -277.849838)
			(xy 313.398062 -277.800784) (xy 313.409839 -277.753) (xy 313.42913 -277.707724) (xy 313.455433 -277.666128)
			(xy 313.488068 -277.629291) (xy 313.526189 -277.598166) (xy 313.56881 -277.573559) (xy 313.614826 -277.556107)
			(xy 313.663045 -277.546263) (xy 313.71222 -277.544282) (xy 313.761075 -277.550214) (xy 313.808346 -277.563906)
			(xy 313.852808 -277.585004) (xy 313.893311 -277.61296) (xy 313.928804 -277.647052) (xy 313.958369 -277.686396)
			(xy 313.98124 -277.729973) (xy 313.996824 -277.776654) (xy 314.004719 -277.825231) (xy 314.005214 -277.849838)
			(xy 314.344062 -277.849838) (xy 314.348022 -277.800784) (xy 314.359799 -277.753) (xy 314.37909 -277.707724)
			(xy 314.405393 -277.666128) (xy 314.438028 -277.629291) (xy 314.476149 -277.598166) (xy 314.51877 -277.573559)
			(xy 314.564786 -277.556107) (xy 314.613005 -277.546263) (xy 314.66218 -277.544282) (xy 314.711035 -277.550214)
			(xy 314.758306 -277.563906) (xy 314.802768 -277.585004) (xy 314.843271 -277.61296) (xy 314.878764 -277.647052)
			(xy 314.908329 -277.686396) (xy 314.9312 -277.729973) (xy 314.946784 -277.776654) (xy 314.954679 -277.825231)
			(xy 314.955174 -277.849838) (xy 314.954679 -277.874445) (xy 314.946784 -277.923022) (xy 314.9312 -277.969703)
			(xy 314.908329 -278.01328) (xy 314.878764 -278.052624) (xy 314.843271 -278.086716) (xy 314.802768 -278.114672)
			(xy 314.758306 -278.13577) (xy 314.711035 -278.149462) (xy 314.66218 -278.155394) (xy 314.613005 -278.153413)
			(xy 314.564786 -278.143569) (xy 314.51877 -278.126117) (xy 314.476149 -278.10151) (xy 314.438028 -278.070385)
			(xy 314.405393 -278.033548) (xy 314.37909 -277.991952) (xy 314.359799 -277.946676) (xy 314.348022 -277.898892)
			(xy 314.344062 -277.849838) (xy 314.005214 -277.849838) (xy 314.004719 -277.874445) (xy 313.996824 -277.923022)
			(xy 313.98124 -277.969703) (xy 313.958369 -278.01328) (xy 313.928804 -278.052624) (xy 313.893311 -278.086716)
			(xy 313.852808 -278.114672) (xy 313.808346 -278.13577) (xy 313.761075 -278.149462) (xy 313.71222 -278.155394)
			(xy 313.663045 -278.153413) (xy 313.614826 -278.143569) (xy 313.56881 -278.126117) (xy 313.526189 -278.10151)
			(xy 313.488068 -278.070385) (xy 313.455433 -278.033548) (xy 313.42913 -277.991952) (xy 313.409839 -277.946676)
			(xy 313.398062 -277.898892) (xy 313.394102 -277.849838) (xy 313.055 -277.849838) (xy 313.054505 -277.874445)
			(xy 313.04661 -277.923022) (xy 313.031026 -277.969703) (xy 313.008155 -278.01328) (xy 312.97859 -278.052624)
			(xy 312.943097 -278.086716) (xy 312.902594 -278.114672) (xy 312.858132 -278.13577) (xy 312.810861 -278.149462)
			(xy 312.762006 -278.155394) (xy 312.712831 -278.153413) (xy 312.664612 -278.143569) (xy 312.618596 -278.126117)
			(xy 312.575975 -278.10151) (xy 312.537854 -278.070385) (xy 312.505219 -278.033548) (xy 312.478916 -277.991952)
			(xy 312.459625 -277.946676) (xy 312.447848 -277.898892) (xy 312.443888 -277.849838) (xy 312.10504 -277.849838)
			(xy 312.104545 -277.874445) (xy 312.09665 -277.923022) (xy 312.081066 -277.969703) (xy 312.058195 -278.01328)
			(xy 312.02863 -278.052624) (xy 311.993137 -278.086716) (xy 311.952634 -278.114672) (xy 311.908172 -278.13577)
			(xy 311.860901 -278.149462) (xy 311.812046 -278.155394) (xy 311.762871 -278.153413) (xy 311.714652 -278.143569)
			(xy 311.668636 -278.126117) (xy 311.626015 -278.10151) (xy 311.587894 -278.070385) (xy 311.555259 -278.033548)
			(xy 311.528956 -277.991952) (xy 311.509665 -277.946676) (xy 311.497888 -277.898892) (xy 311.493928 -277.849838)
			(xy 311.154826 -277.849838) (xy 311.154331 -277.874445) (xy 311.146436 -277.923022) (xy 311.130852 -277.969703)
			(xy 311.107981 -278.01328) (xy 311.078416 -278.052624) (xy 311.042923 -278.086716) (xy 311.00242 -278.114672)
			(xy 310.957958 -278.13577) (xy 310.910687 -278.149462) (xy 310.861832 -278.155394) (xy 310.812657 -278.153413)
			(xy 310.764438 -278.143569) (xy 310.718422 -278.126117) (xy 310.675801 -278.10151) (xy 310.63768 -278.070385)
			(xy 310.605045 -278.033548) (xy 310.578742 -277.991952) (xy 310.559451 -277.946676) (xy 310.547674 -277.898892)
			(xy 310.543714 -277.849838) (xy 310.20512 -277.849838) (xy 310.204625 -277.874445) (xy 310.19673 -277.923022)
			(xy 310.181146 -277.969703) (xy 310.158275 -278.01328) (xy 310.12871 -278.052624) (xy 310.093217 -278.086716)
			(xy 310.052714 -278.114672) (xy 310.008252 -278.13577) (xy 309.960981 -278.149462) (xy 309.912126 -278.155394)
			(xy 309.862951 -278.153413) (xy 309.814732 -278.143569) (xy 309.768716 -278.126117) (xy 309.726095 -278.10151)
			(xy 309.687974 -278.070385) (xy 309.655339 -278.033548) (xy 309.629036 -277.991952) (xy 309.609745 -277.946676)
			(xy 309.597968 -277.898892) (xy 309.594008 -277.849838) (xy 309.254906 -277.849838) (xy 309.254411 -277.874445)
			(xy 309.246516 -277.923022) (xy 309.230932 -277.969703) (xy 309.208061 -278.01328) (xy 309.178496 -278.052624)
			(xy 309.143003 -278.086716) (xy 309.1025 -278.114672) (xy 309.058038 -278.13577) (xy 309.010767 -278.149462)
			(xy 308.961912 -278.155394) (xy 308.912737 -278.153413) (xy 308.864518 -278.143569) (xy 308.818502 -278.126117)
			(xy 308.775881 -278.10151) (xy 308.73776 -278.070385) (xy 308.705125 -278.033548) (xy 308.678822 -277.991952)
			(xy 308.659531 -277.946676) (xy 308.647754 -277.898892) (xy 308.643794 -277.849838) (xy 308.3052 -277.849838)
			(xy 308.304705 -277.874445) (xy 308.29681 -277.923022) (xy 308.281226 -277.969703) (xy 308.258355 -278.01328)
			(xy 308.22879 -278.052624) (xy 308.193297 -278.086716) (xy 308.152794 -278.114672) (xy 308.108332 -278.13577)
			(xy 308.061061 -278.149462) (xy 308.012206 -278.155394) (xy 307.963031 -278.153413) (xy 307.914812 -278.143569)
			(xy 307.868796 -278.126117) (xy 307.826175 -278.10151) (xy 307.788054 -278.070385) (xy 307.755419 -278.033548)
			(xy 307.729116 -277.991952) (xy 307.709825 -277.946676) (xy 307.698048 -277.898892) (xy 307.694088 -277.849838)
			(xy 307.354986 -277.849838) (xy 307.354491 -277.874445) (xy 307.346596 -277.923022) (xy 307.331012 -277.969703)
			(xy 307.308141 -278.01328) (xy 307.278576 -278.052624) (xy 307.243083 -278.086716) (xy 307.20258 -278.114672)
			(xy 307.158118 -278.13577) (xy 307.110847 -278.149462) (xy 307.061992 -278.155394) (xy 307.012817 -278.153413)
			(xy 306.964598 -278.143569) (xy 306.918582 -278.126117) (xy 306.875961 -278.10151) (xy 306.83784 -278.070385)
			(xy 306.805205 -278.033548) (xy 306.778902 -277.991952) (xy 306.759611 -277.946676) (xy 306.747834 -277.898892)
			(xy 306.743874 -277.849838) (xy 306.405026 -277.849838) (xy 306.404531 -277.874445) (xy 306.396636 -277.923022)
			(xy 306.381052 -277.969703) (xy 306.358181 -278.01328) (xy 306.328616 -278.052624) (xy 306.293123 -278.086716)
			(xy 306.25262 -278.114672) (xy 306.208158 -278.13577) (xy 306.160887 -278.149462) (xy 306.112032 -278.155394)
			(xy 306.062857 -278.153413) (xy 306.014638 -278.143569) (xy 305.968622 -278.126117) (xy 305.926001 -278.10151)
			(xy 305.88788 -278.070385) (xy 305.855245 -278.033548) (xy 305.828942 -277.991952) (xy 305.809651 -277.946676)
			(xy 305.797874 -277.898892) (xy 305.793914 -277.849838) (xy 305.454812 -277.849838) (xy 305.454317 -277.874445)
			(xy 305.446422 -277.923022) (xy 305.430838 -277.969703) (xy 305.407967 -278.01328) (xy 305.378402 -278.052624)
			(xy 305.342909 -278.086716) (xy 305.302406 -278.114672) (xy 305.257944 -278.13577) (xy 305.210673 -278.149462)
			(xy 305.161818 -278.155394) (xy 305.112643 -278.153413) (xy 305.064424 -278.143569) (xy 305.018408 -278.126117)
			(xy 304.975787 -278.10151) (xy 304.937666 -278.070385) (xy 304.905031 -278.033548) (xy 304.878728 -277.991952)
			(xy 304.859437 -277.946676) (xy 304.84766 -277.898892) (xy 304.8437 -277.849838) (xy 304.505106 -277.849838)
			(xy 304.504611 -277.874445) (xy 304.496716 -277.923022) (xy 304.481132 -277.969703) (xy 304.458261 -278.01328)
			(xy 304.428696 -278.052624) (xy 304.393203 -278.086716) (xy 304.3527 -278.114672) (xy 304.308238 -278.13577)
			(xy 304.260967 -278.149462) (xy 304.212112 -278.155394) (xy 304.162937 -278.153413) (xy 304.114718 -278.143569)
			(xy 304.068702 -278.126117) (xy 304.026081 -278.10151) (xy 303.98796 -278.070385) (xy 303.955325 -278.033548)
			(xy 303.929022 -277.991952) (xy 303.909731 -277.946676) (xy 303.897954 -277.898892) (xy 303.893994 -277.849838)
			(xy 303.554892 -277.849838) (xy 303.554397 -277.874445) (xy 303.546502 -277.923022) (xy 303.530918 -277.969703)
			(xy 303.508047 -278.01328) (xy 303.478482 -278.052624) (xy 303.442989 -278.086716) (xy 303.402486 -278.114672)
			(xy 303.358024 -278.13577) (xy 303.310753 -278.149462) (xy 303.261898 -278.155394) (xy 303.212723 -278.153413)
			(xy 303.164504 -278.143569) (xy 303.118488 -278.126117) (xy 303.075867 -278.10151) (xy 303.037746 -278.070385)
			(xy 303.005111 -278.033548) (xy 302.978808 -277.991952) (xy 302.959517 -277.946676) (xy 302.94774 -277.898892)
			(xy 302.94378 -277.849838) (xy 302.605186 -277.849838) (xy 302.604691 -277.874445) (xy 302.596796 -277.923022)
			(xy 302.581212 -277.969703) (xy 302.558341 -278.01328) (xy 302.528776 -278.052624) (xy 302.493283 -278.086716)
			(xy 302.45278 -278.114672) (xy 302.408318 -278.13577) (xy 302.361047 -278.149462) (xy 302.312192 -278.155394)
			(xy 302.263017 -278.153413) (xy 302.214798 -278.143569) (xy 302.168782 -278.126117) (xy 302.126161 -278.10151)
			(xy 302.08804 -278.070385) (xy 302.055405 -278.033548) (xy 302.029102 -277.991952) (xy 302.009811 -277.946676)
			(xy 301.998034 -277.898892) (xy 301.994074 -277.849838) (xy 301.654972 -277.849838) (xy 301.654477 -277.874445)
			(xy 301.646582 -277.923022) (xy 301.630998 -277.969703) (xy 301.608127 -278.01328) (xy 301.578562 -278.052624)
			(xy 301.543069 -278.086716) (xy 301.502566 -278.114672) (xy 301.458104 -278.13577) (xy 301.410833 -278.149462)
			(xy 301.361978 -278.155394) (xy 301.312803 -278.153413) (xy 301.264584 -278.143569) (xy 301.218568 -278.126117)
			(xy 301.175947 -278.10151) (xy 301.137826 -278.070385) (xy 301.105191 -278.033548) (xy 301.078888 -277.991952)
			(xy 301.059597 -277.946676) (xy 301.04782 -277.898892) (xy 301.04386 -277.849838) (xy 300.705012 -277.849838)
			(xy 300.704517 -277.874445) (xy 300.696622 -277.923022) (xy 300.681038 -277.969703) (xy 300.658167 -278.01328)
			(xy 300.628602 -278.052624) (xy 300.593109 -278.086716) (xy 300.552606 -278.114672) (xy 300.508144 -278.13577)
			(xy 300.460873 -278.149462) (xy 300.412018 -278.155394) (xy 300.362843 -278.153413) (xy 300.314624 -278.143569)
			(xy 300.268608 -278.126117) (xy 300.225987 -278.10151) (xy 300.187866 -278.070385) (xy 300.155231 -278.033548)
			(xy 300.128928 -277.991952) (xy 300.109637 -277.946676) (xy 300.09786 -277.898892) (xy 300.0939 -277.849838)
			(xy 299.754798 -277.849838) (xy 299.754303 -277.874445) (xy 299.746408 -277.923022) (xy 299.730824 -277.969703)
			(xy 299.707953 -278.01328) (xy 299.678388 -278.052624) (xy 299.642895 -278.086716) (xy 299.602392 -278.114672)
			(xy 299.55793 -278.13577) (xy 299.510659 -278.149462) (xy 299.461804 -278.155394) (xy 299.412629 -278.153413)
			(xy 299.36441 -278.143569) (xy 299.318394 -278.126117) (xy 299.275773 -278.10151) (xy 299.237652 -278.070385)
			(xy 299.205017 -278.033548) (xy 299.178714 -277.991952) (xy 299.159423 -277.946676) (xy 299.147646 -277.898892)
			(xy 299.143686 -277.849838) (xy 298.805092 -277.849838) (xy 298.804597 -277.874445) (xy 298.796702 -277.923022)
			(xy 298.781118 -277.969703) (xy 298.758247 -278.01328) (xy 298.728682 -278.052624) (xy 298.693189 -278.086716)
			(xy 298.652686 -278.114672) (xy 298.608224 -278.13577) (xy 298.560953 -278.149462) (xy 298.512098 -278.155394)
			(xy 298.462923 -278.153413) (xy 298.414704 -278.143569) (xy 298.368688 -278.126117) (xy 298.326067 -278.10151)
			(xy 298.287946 -278.070385) (xy 298.255311 -278.033548) (xy 298.229008 -277.991952) (xy 298.209717 -277.946676)
			(xy 298.19794 -277.898892) (xy 298.19398 -277.849838) (xy 297.854878 -277.849838) (xy 297.854383 -277.874445)
			(xy 297.846488 -277.923022) (xy 297.830904 -277.969703) (xy 297.808033 -278.01328) (xy 297.778468 -278.052624)
			(xy 297.742975 -278.086716) (xy 297.702472 -278.114672) (xy 297.65801 -278.13577) (xy 297.610739 -278.149462)
			(xy 297.561884 -278.155394) (xy 297.512709 -278.153413) (xy 297.46449 -278.143569) (xy 297.418474 -278.126117)
			(xy 297.375853 -278.10151) (xy 297.337732 -278.070385) (xy 297.305097 -278.033548) (xy 297.278794 -277.991952)
			(xy 297.259503 -277.946676) (xy 297.247726 -277.898892) (xy 297.243766 -277.849838) (xy 296.905172 -277.849838)
			(xy 296.904677 -277.874445) (xy 296.896782 -277.923022) (xy 296.881198 -277.969703) (xy 296.858327 -278.01328)
			(xy 296.828762 -278.052624) (xy 296.793269 -278.086716) (xy 296.752766 -278.114672) (xy 296.708304 -278.13577)
			(xy 296.661033 -278.149462) (xy 296.612178 -278.155394) (xy 296.563003 -278.153413) (xy 296.514784 -278.143569)
			(xy 296.468768 -278.126117) (xy 296.426147 -278.10151) (xy 296.388026 -278.070385) (xy 296.355391 -278.033548)
			(xy 296.329088 -277.991952) (xy 296.309797 -277.946676) (xy 296.29802 -277.898892) (xy 296.29406 -277.849838)
			(xy 295.954958 -277.849838) (xy 295.954463 -277.874445) (xy 295.946568 -277.923022) (xy 295.930984 -277.969703)
			(xy 295.908113 -278.01328) (xy 295.878548 -278.052624) (xy 295.843055 -278.086716) (xy 295.802552 -278.114672)
			(xy 295.75809 -278.13577) (xy 295.710819 -278.149462) (xy 295.661964 -278.155394) (xy 295.612789 -278.153413)
			(xy 295.56457 -278.143569) (xy 295.518554 -278.126117) (xy 295.475933 -278.10151) (xy 295.437812 -278.070385)
			(xy 295.405177 -278.033548) (xy 295.378874 -277.991952) (xy 295.359583 -277.946676) (xy 295.347806 -277.898892)
			(xy 295.343846 -277.849838) (xy 295.004998 -277.849838) (xy 295.004503 -277.874445) (xy 294.996608 -277.923022)
			(xy 294.981024 -277.969703) (xy 294.958153 -278.01328) (xy 294.928588 -278.052624) (xy 294.893095 -278.086716)
			(xy 294.852592 -278.114672) (xy 294.80813 -278.13577) (xy 294.760859 -278.149462) (xy 294.712004 -278.155394)
			(xy 294.662829 -278.153413) (xy 294.61461 -278.143569) (xy 294.568594 -278.126117) (xy 294.525973 -278.10151)
			(xy 294.487852 -278.070385) (xy 294.455217 -278.033548) (xy 294.428914 -277.991952) (xy 294.409623 -277.946676)
			(xy 294.397846 -277.898892) (xy 294.393886 -277.849838) (xy 294.054784 -277.849838) (xy 294.054289 -277.874445)
			(xy 294.046394 -277.923022) (xy 294.03081 -277.969703) (xy 294.007939 -278.01328) (xy 293.978374 -278.052624)
			(xy 293.942881 -278.086716) (xy 293.902378 -278.114672) (xy 293.857916 -278.13577) (xy 293.810645 -278.149462)
			(xy 293.76179 -278.155394) (xy 293.712615 -278.153413) (xy 293.664396 -278.143569) (xy 293.61838 -278.126117)
			(xy 293.575759 -278.10151) (xy 293.537638 -278.070385) (xy 293.505003 -278.033548) (xy 293.4787 -277.991952)
			(xy 293.459409 -277.946676) (xy 293.447632 -277.898892) (xy 293.443672 -277.849838) (xy 293.105078 -277.849838)
			(xy 293.104583 -277.874445) (xy 293.096688 -277.923022) (xy 293.081104 -277.969703) (xy 293.058233 -278.01328)
			(xy 293.028668 -278.052624) (xy 292.993175 -278.086716) (xy 292.952672 -278.114672) (xy 292.90821 -278.13577)
			(xy 292.860939 -278.149462) (xy 292.812084 -278.155394) (xy 292.762909 -278.153413) (xy 292.71469 -278.143569)
			(xy 292.668674 -278.126117) (xy 292.626053 -278.10151) (xy 292.587932 -278.070385) (xy 292.555297 -278.033548)
			(xy 292.528994 -277.991952) (xy 292.509703 -277.946676) (xy 292.497926 -277.898892) (xy 292.493966 -277.849838)
			(xy 292.154864 -277.849838) (xy 292.154369 -277.874445) (xy 292.146474 -277.923022) (xy 292.13089 -277.969703)
			(xy 292.108019 -278.01328) (xy 292.078454 -278.052624) (xy 292.042961 -278.086716) (xy 292.002458 -278.114672)
			(xy 291.957996 -278.13577) (xy 291.910725 -278.149462) (xy 291.86187 -278.155394) (xy 291.812695 -278.153413)
			(xy 291.764476 -278.143569) (xy 291.71846 -278.126117) (xy 291.675839 -278.10151) (xy 291.637718 -278.070385)
			(xy 291.605083 -278.033548) (xy 291.57878 -277.991952) (xy 291.559489 -277.946676) (xy 291.547712 -277.898892)
			(xy 291.543752 -277.849838) (xy 291.205158 -277.849838) (xy 291.204685 -277.873829) (xy 291.197174 -277.921219)
			(xy 291.182344 -277.966851) (xy 291.160559 -278.009602) (xy 291.132356 -278.048419) (xy 291.098429 -278.082348)
			(xy 291.059612 -278.110553) (xy 291.016862 -278.132339) (xy 290.97123 -278.147171) (xy 290.923841 -278.154684)
			(xy 290.89985 -278.155146) (xy 290.885667 -278.154962) (xy 290.857427 -278.152293) (xy 290.843462 -278.149812)
			(xy 290.831016 -278.147526) (xy 290.807394 -278.154892) (xy 290.729924 -278.232362) (xy 290.722558 -278.255984)
			(xy 290.724844 -278.26843) (xy 290.727319 -278.282332) (xy 290.729989 -278.310445) (xy 290.730178 -278.324564)
			(xy 290.730178 -278.328374) (xy 290.729862 -278.341665) (xy 290.727191 -278.36812) (xy 290.724844 -278.381206)
			(xy 290.722558 -278.393652) (xy 290.729924 -278.417274) (xy 290.807394 -278.494744) (xy 290.831016 -278.50211)
			(xy 290.843462 -278.499824) (xy 290.857427 -278.497341) (xy 290.885667 -278.494674) (xy 290.89985 -278.49449)
			(xy 290.92467 -278.49498) (xy 290.973655 -278.503019) (xy 291.020695 -278.518876) (xy 291.064549 -278.542134)
			(xy 291.104063 -278.572181) (xy 291.138196 -278.608224) (xy 291.166048 -278.649315) (xy 291.186886 -278.69437)
			(xy 291.20016 -278.742203) (xy 291.205522 -278.791553) (xy 291.205074 -278.799798) (xy 291.543752 -278.799798)
			(xy 291.547712 -278.750744) (xy 291.559489 -278.70296) (xy 291.57878 -278.657684) (xy 291.605083 -278.616088)
			(xy 291.637718 -278.579251) (xy 291.675839 -278.548126) (xy 291.71846 -278.523519) (xy 291.764476 -278.506067)
			(xy 291.812695 -278.496223) (xy 291.86187 -278.494242) (xy 291.910725 -278.500174) (xy 291.957996 -278.513866)
			(xy 292.002458 -278.534964) (xy 292.042961 -278.56292) (xy 292.078454 -278.597012) (xy 292.108019 -278.636356)
			(xy 292.13089 -278.679933) (xy 292.146474 -278.726614) (xy 292.154369 -278.775191) (xy 292.154864 -278.799798)
			(xy 292.493966 -278.799798) (xy 292.497926 -278.750744) (xy 292.509703 -278.70296) (xy 292.528994 -278.657684)
			(xy 292.555297 -278.616088) (xy 292.587932 -278.579251) (xy 292.626053 -278.548126) (xy 292.668674 -278.523519)
			(xy 292.71469 -278.506067) (xy 292.762909 -278.496223) (xy 292.812084 -278.494242) (xy 292.860939 -278.500174)
			(xy 292.90821 -278.513866) (xy 292.952672 -278.534964) (xy 292.993175 -278.56292) (xy 293.028668 -278.597012)
			(xy 293.058233 -278.636356) (xy 293.081104 -278.679933) (xy 293.096688 -278.726614) (xy 293.104583 -278.775191)
			(xy 293.105078 -278.799798) (xy 293.443672 -278.799798) (xy 293.447632 -278.750744) (xy 293.459409 -278.70296)
			(xy 293.4787 -278.657684) (xy 293.505003 -278.616088) (xy 293.537638 -278.579251) (xy 293.575759 -278.548126)
			(xy 293.61838 -278.523519) (xy 293.664396 -278.506067) (xy 293.712615 -278.496223) (xy 293.76179 -278.494242)
			(xy 293.810645 -278.500174) (xy 293.857916 -278.513866) (xy 293.902378 -278.534964) (xy 293.942881 -278.56292)
			(xy 293.978374 -278.597012) (xy 294.007939 -278.636356) (xy 294.03081 -278.679933) (xy 294.046394 -278.726614)
			(xy 294.054289 -278.775191) (xy 294.054784 -278.799798) (xy 294.393886 -278.799798) (xy 294.397846 -278.750744)
			(xy 294.409623 -278.70296) (xy 294.428914 -278.657684) (xy 294.455217 -278.616088) (xy 294.487852 -278.579251)
			(xy 294.525973 -278.548126) (xy 294.568594 -278.523519) (xy 294.61461 -278.506067) (xy 294.662829 -278.496223)
			(xy 294.712004 -278.494242) (xy 294.760859 -278.500174) (xy 294.80813 -278.513866) (xy 294.852592 -278.534964)
			(xy 294.893095 -278.56292) (xy 294.928588 -278.597012) (xy 294.958153 -278.636356) (xy 294.981024 -278.679933)
			(xy 294.996608 -278.726614) (xy 295.004503 -278.775191) (xy 295.004998 -278.799798) (xy 295.343846 -278.799798)
			(xy 295.347806 -278.750744) (xy 295.359583 -278.70296) (xy 295.378874 -278.657684) (xy 295.405177 -278.616088)
			(xy 295.437812 -278.579251) (xy 295.475933 -278.548126) (xy 295.518554 -278.523519) (xy 295.56457 -278.506067)
			(xy 295.612789 -278.496223) (xy 295.661964 -278.494242) (xy 295.710819 -278.500174) (xy 295.75809 -278.513866)
			(xy 295.802552 -278.534964) (xy 295.843055 -278.56292) (xy 295.878548 -278.597012) (xy 295.908113 -278.636356)
			(xy 295.930984 -278.679933) (xy 295.946568 -278.726614) (xy 295.954463 -278.775191) (xy 295.954958 -278.799798)
			(xy 296.29406 -278.799798) (xy 296.29802 -278.750744) (xy 296.309797 -278.70296) (xy 296.329088 -278.657684)
			(xy 296.355391 -278.616088) (xy 296.388026 -278.579251) (xy 296.426147 -278.548126) (xy 296.468768 -278.523519)
			(xy 296.514784 -278.506067) (xy 296.563003 -278.496223) (xy 296.612178 -278.494242) (xy 296.661033 -278.500174)
			(xy 296.708304 -278.513866) (xy 296.752766 -278.534964) (xy 296.793269 -278.56292) (xy 296.828762 -278.597012)
			(xy 296.858327 -278.636356) (xy 296.881198 -278.679933) (xy 296.896782 -278.726614) (xy 296.904677 -278.775191)
			(xy 296.905172 -278.799798) (xy 297.243766 -278.799798) (xy 297.247726 -278.750744) (xy 297.259503 -278.70296)
			(xy 297.278794 -278.657684) (xy 297.305097 -278.616088) (xy 297.337732 -278.579251) (xy 297.375853 -278.548126)
			(xy 297.418474 -278.523519) (xy 297.46449 -278.506067) (xy 297.512709 -278.496223) (xy 297.561884 -278.494242)
			(xy 297.610739 -278.500174) (xy 297.65801 -278.513866) (xy 297.702472 -278.534964) (xy 297.742975 -278.56292)
			(xy 297.778468 -278.597012) (xy 297.808033 -278.636356) (xy 297.830904 -278.679933) (xy 297.846488 -278.726614)
			(xy 297.854383 -278.775191) (xy 297.854878 -278.799798) (xy 298.19398 -278.799798) (xy 298.19794 -278.750744)
			(xy 298.209717 -278.70296) (xy 298.229008 -278.657684) (xy 298.255311 -278.616088) (xy 298.287946 -278.579251)
			(xy 298.326067 -278.548126) (xy 298.368688 -278.523519) (xy 298.414704 -278.506067) (xy 298.462923 -278.496223)
			(xy 298.512098 -278.494242) (xy 298.560953 -278.500174) (xy 298.608224 -278.513866) (xy 298.652686 -278.534964)
			(xy 298.693189 -278.56292) (xy 298.728682 -278.597012) (xy 298.758247 -278.636356) (xy 298.781118 -278.679933)
			(xy 298.796702 -278.726614) (xy 298.804597 -278.775191) (xy 298.805092 -278.799798) (xy 299.143686 -278.799798)
			(xy 299.147646 -278.750744) (xy 299.159423 -278.70296) (xy 299.178714 -278.657684) (xy 299.205017 -278.616088)
			(xy 299.237652 -278.579251) (xy 299.275773 -278.548126) (xy 299.318394 -278.523519) (xy 299.36441 -278.506067)
			(xy 299.412629 -278.496223) (xy 299.461804 -278.494242) (xy 299.510659 -278.500174) (xy 299.55793 -278.513866)
			(xy 299.602392 -278.534964) (xy 299.642895 -278.56292) (xy 299.678388 -278.597012) (xy 299.707953 -278.636356)
			(xy 299.730824 -278.679933) (xy 299.746408 -278.726614) (xy 299.754303 -278.775191) (xy 299.754798 -278.799798)
			(xy 300.0939 -278.799798) (xy 300.09786 -278.750744) (xy 300.109637 -278.70296) (xy 300.128928 -278.657684)
			(xy 300.155231 -278.616088) (xy 300.187866 -278.579251) (xy 300.225987 -278.548126) (xy 300.268608 -278.523519)
			(xy 300.314624 -278.506067) (xy 300.362843 -278.496223) (xy 300.412018 -278.494242) (xy 300.460873 -278.500174)
			(xy 300.508144 -278.513866) (xy 300.552606 -278.534964) (xy 300.593109 -278.56292) (xy 300.628602 -278.597012)
			(xy 300.658167 -278.636356) (xy 300.681038 -278.679933) (xy 300.696622 -278.726614) (xy 300.704517 -278.775191)
			(xy 300.705012 -278.799798) (xy 301.04386 -278.799798) (xy 301.04782 -278.750744) (xy 301.059597 -278.70296)
			(xy 301.078888 -278.657684) (xy 301.105191 -278.616088) (xy 301.137826 -278.579251) (xy 301.175947 -278.548126)
			(xy 301.218568 -278.523519) (xy 301.264584 -278.506067) (xy 301.312803 -278.496223) (xy 301.361978 -278.494242)
			(xy 301.410833 -278.500174) (xy 301.458104 -278.513866) (xy 301.502566 -278.534964) (xy 301.543069 -278.56292)
			(xy 301.578562 -278.597012) (xy 301.608127 -278.636356) (xy 301.630998 -278.679933) (xy 301.646582 -278.726614)
			(xy 301.654477 -278.775191) (xy 301.654972 -278.799798) (xy 301.994074 -278.799798) (xy 301.998034 -278.750744)
			(xy 302.009811 -278.70296) (xy 302.029102 -278.657684) (xy 302.055405 -278.616088) (xy 302.08804 -278.579251)
			(xy 302.126161 -278.548126) (xy 302.168782 -278.523519) (xy 302.214798 -278.506067) (xy 302.263017 -278.496223)
			(xy 302.312192 -278.494242) (xy 302.361047 -278.500174) (xy 302.408318 -278.513866) (xy 302.45278 -278.534964)
			(xy 302.493283 -278.56292) (xy 302.528776 -278.597012) (xy 302.558341 -278.636356) (xy 302.581212 -278.679933)
			(xy 302.596796 -278.726614) (xy 302.604691 -278.775191) (xy 302.605186 -278.799798) (xy 302.94378 -278.799798)
			(xy 302.94774 -278.750744) (xy 302.959517 -278.70296) (xy 302.978808 -278.657684) (xy 303.005111 -278.616088)
			(xy 303.037746 -278.579251) (xy 303.075867 -278.548126) (xy 303.118488 -278.523519) (xy 303.164504 -278.506067)
			(xy 303.212723 -278.496223) (xy 303.261898 -278.494242) (xy 303.310753 -278.500174) (xy 303.358024 -278.513866)
			(xy 303.402486 -278.534964) (xy 303.442989 -278.56292) (xy 303.478482 -278.597012) (xy 303.508047 -278.636356)
			(xy 303.530918 -278.679933) (xy 303.546502 -278.726614) (xy 303.554397 -278.775191) (xy 303.554892 -278.799798)
			(xy 303.893994 -278.799798) (xy 303.897954 -278.750744) (xy 303.909731 -278.70296) (xy 303.929022 -278.657684)
			(xy 303.955325 -278.616088) (xy 303.98796 -278.579251) (xy 304.026081 -278.548126) (xy 304.068702 -278.523519)
			(xy 304.114718 -278.506067) (xy 304.162937 -278.496223) (xy 304.212112 -278.494242) (xy 304.260967 -278.500174)
			(xy 304.308238 -278.513866) (xy 304.3527 -278.534964) (xy 304.393203 -278.56292) (xy 304.428696 -278.597012)
			(xy 304.458261 -278.636356) (xy 304.481132 -278.679933) (xy 304.496716 -278.726614) (xy 304.504611 -278.775191)
			(xy 304.505106 -278.799798) (xy 304.8437 -278.799798) (xy 304.84766 -278.750744) (xy 304.859437 -278.70296)
			(xy 304.878728 -278.657684) (xy 304.905031 -278.616088) (xy 304.937666 -278.579251) (xy 304.975787 -278.548126)
			(xy 305.018408 -278.523519) (xy 305.064424 -278.506067) (xy 305.112643 -278.496223) (xy 305.161818 -278.494242)
			(xy 305.210673 -278.500174) (xy 305.257944 -278.513866) (xy 305.302406 -278.534964) (xy 305.342909 -278.56292)
			(xy 305.378402 -278.597012) (xy 305.407967 -278.636356) (xy 305.430838 -278.679933) (xy 305.446422 -278.726614)
			(xy 305.454317 -278.775191) (xy 305.454812 -278.799798) (xy 305.793914 -278.799798) (xy 305.797874 -278.750744)
			(xy 305.809651 -278.70296) (xy 305.828942 -278.657684) (xy 305.855245 -278.616088) (xy 305.88788 -278.579251)
			(xy 305.926001 -278.548126) (xy 305.968622 -278.523519) (xy 306.014638 -278.506067) (xy 306.062857 -278.496223)
			(xy 306.112032 -278.494242) (xy 306.160887 -278.500174) (xy 306.208158 -278.513866) (xy 306.25262 -278.534964)
			(xy 306.293123 -278.56292) (xy 306.328616 -278.597012) (xy 306.358181 -278.636356) (xy 306.381052 -278.679933)
			(xy 306.396636 -278.726614) (xy 306.404531 -278.775191) (xy 306.405026 -278.799798) (xy 306.743874 -278.799798)
			(xy 306.747834 -278.750744) (xy 306.759611 -278.70296) (xy 306.778902 -278.657684) (xy 306.805205 -278.616088)
			(xy 306.83784 -278.579251) (xy 306.875961 -278.548126) (xy 306.918582 -278.523519) (xy 306.964598 -278.506067)
			(xy 307.012817 -278.496223) (xy 307.061992 -278.494242) (xy 307.110847 -278.500174) (xy 307.158118 -278.513866)
			(xy 307.20258 -278.534964) (xy 307.243083 -278.56292) (xy 307.278576 -278.597012) (xy 307.308141 -278.636356)
			(xy 307.331012 -278.679933) (xy 307.346596 -278.726614) (xy 307.354491 -278.775191) (xy 307.354986 -278.799798)
			(xy 307.694088 -278.799798) (xy 307.698048 -278.750744) (xy 307.709825 -278.70296) (xy 307.729116 -278.657684)
			(xy 307.755419 -278.616088) (xy 307.788054 -278.579251) (xy 307.826175 -278.548126) (xy 307.868796 -278.523519)
			(xy 307.914812 -278.506067) (xy 307.963031 -278.496223) (xy 308.012206 -278.494242) (xy 308.061061 -278.500174)
			(xy 308.108332 -278.513866) (xy 308.152794 -278.534964) (xy 308.193297 -278.56292) (xy 308.22879 -278.597012)
			(xy 308.258355 -278.636356) (xy 308.281226 -278.679933) (xy 308.29681 -278.726614) (xy 308.304705 -278.775191)
			(xy 308.3052 -278.799798) (xy 308.643794 -278.799798) (xy 308.647754 -278.750744) (xy 308.659531 -278.70296)
			(xy 308.678822 -278.657684) (xy 308.705125 -278.616088) (xy 308.73776 -278.579251) (xy 308.775881 -278.548126)
			(xy 308.818502 -278.523519) (xy 308.864518 -278.506067) (xy 308.912737 -278.496223) (xy 308.961912 -278.494242)
			(xy 309.010767 -278.500174) (xy 309.058038 -278.513866) (xy 309.1025 -278.534964) (xy 309.143003 -278.56292)
			(xy 309.178496 -278.597012) (xy 309.208061 -278.636356) (xy 309.230932 -278.679933) (xy 309.246516 -278.726614)
			(xy 309.254411 -278.775191) (xy 309.254906 -278.799798) (xy 309.594008 -278.799798) (xy 309.597968 -278.750744)
			(xy 309.609745 -278.70296) (xy 309.629036 -278.657684) (xy 309.655339 -278.616088) (xy 309.687974 -278.579251)
			(xy 309.726095 -278.548126) (xy 309.768716 -278.523519) (xy 309.814732 -278.506067) (xy 309.862951 -278.496223)
			(xy 309.912126 -278.494242) (xy 309.960981 -278.500174) (xy 310.008252 -278.513866) (xy 310.052714 -278.534964)
			(xy 310.093217 -278.56292) (xy 310.12871 -278.597012) (xy 310.158275 -278.636356) (xy 310.181146 -278.679933)
			(xy 310.19673 -278.726614) (xy 310.204625 -278.775191) (xy 310.20512 -278.799798) (xy 310.543714 -278.799798)
			(xy 310.547674 -278.750744) (xy 310.559451 -278.70296) (xy 310.578742 -278.657684) (xy 310.605045 -278.616088)
			(xy 310.63768 -278.579251) (xy 310.675801 -278.548126) (xy 310.718422 -278.523519) (xy 310.764438 -278.506067)
			(xy 310.812657 -278.496223) (xy 310.861832 -278.494242) (xy 310.910687 -278.500174) (xy 310.957958 -278.513866)
			(xy 311.00242 -278.534964) (xy 311.042923 -278.56292) (xy 311.078416 -278.597012) (xy 311.107981 -278.636356)
			(xy 311.130852 -278.679933) (xy 311.146436 -278.726614) (xy 311.154331 -278.775191) (xy 311.154826 -278.799798)
			(xy 311.493928 -278.799798) (xy 311.497888 -278.750744) (xy 311.509665 -278.70296) (xy 311.528956 -278.657684)
			(xy 311.555259 -278.616088) (xy 311.587894 -278.579251) (xy 311.626015 -278.548126) (xy 311.668636 -278.523519)
			(xy 311.714652 -278.506067) (xy 311.762871 -278.496223) (xy 311.812046 -278.494242) (xy 311.860901 -278.500174)
			(xy 311.908172 -278.513866) (xy 311.952634 -278.534964) (xy 311.993137 -278.56292) (xy 312.02863 -278.597012)
			(xy 312.058195 -278.636356) (xy 312.081066 -278.679933) (xy 312.09665 -278.726614) (xy 312.104545 -278.775191)
			(xy 312.10504 -278.799798) (xy 312.443888 -278.799798) (xy 312.447848 -278.750744) (xy 312.459625 -278.70296)
			(xy 312.478916 -278.657684) (xy 312.505219 -278.616088) (xy 312.537854 -278.579251) (xy 312.575975 -278.548126)
			(xy 312.618596 -278.523519) (xy 312.664612 -278.506067) (xy 312.712831 -278.496223) (xy 312.762006 -278.494242)
			(xy 312.810861 -278.500174) (xy 312.858132 -278.513866) (xy 312.902594 -278.534964) (xy 312.943097 -278.56292)
			(xy 312.97859 -278.597012) (xy 313.008155 -278.636356) (xy 313.031026 -278.679933) (xy 313.04661 -278.726614)
			(xy 313.054505 -278.775191) (xy 313.055 -278.799798) (xy 313.394102 -278.799798) (xy 313.398062 -278.750744)
			(xy 313.409839 -278.70296) (xy 313.42913 -278.657684) (xy 313.455433 -278.616088) (xy 313.488068 -278.579251)
			(xy 313.526189 -278.548126) (xy 313.56881 -278.523519) (xy 313.614826 -278.506067) (xy 313.663045 -278.496223)
			(xy 313.71222 -278.494242) (xy 313.761075 -278.500174) (xy 313.808346 -278.513866) (xy 313.852808 -278.534964)
			(xy 313.893311 -278.56292) (xy 313.928804 -278.597012) (xy 313.958369 -278.636356) (xy 313.98124 -278.679933)
			(xy 313.996824 -278.726614) (xy 314.004719 -278.775191) (xy 314.005214 -278.799798) (xy 314.344062 -278.799798)
			(xy 314.348022 -278.750744) (xy 314.359799 -278.70296) (xy 314.37909 -278.657684) (xy 314.405393 -278.616088)
			(xy 314.438028 -278.579251) (xy 314.476149 -278.548126) (xy 314.51877 -278.523519) (xy 314.564786 -278.506067)
			(xy 314.613005 -278.496223) (xy 314.66218 -278.494242) (xy 314.711035 -278.500174) (xy 314.758306 -278.513866)
			(xy 314.802768 -278.534964) (xy 314.843271 -278.56292) (xy 314.878764 -278.597012) (xy 314.908329 -278.636356)
			(xy 314.9312 -278.679933) (xy 314.946784 -278.726614) (xy 314.954679 -278.775191) (xy 314.955174 -278.799798)
			(xy 314.954679 -278.824405) (xy 314.946784 -278.872982) (xy 314.9312 -278.919663) (xy 314.908329 -278.96324)
			(xy 314.878764 -279.002584) (xy 314.843271 -279.036676) (xy 314.802768 -279.064632) (xy 314.758306 -279.08573)
			(xy 314.711035 -279.099422) (xy 314.66218 -279.105354) (xy 314.613005 -279.103373) (xy 314.564786 -279.093529)
			(xy 314.51877 -279.076077) (xy 314.476149 -279.05147) (xy 314.438028 -279.020345) (xy 314.405393 -278.983508)
			(xy 314.37909 -278.941912) (xy 314.359799 -278.896636) (xy 314.348022 -278.848852) (xy 314.344062 -278.799798)
			(xy 314.005214 -278.799798) (xy 314.004719 -278.824405) (xy 313.996824 -278.872982) (xy 313.98124 -278.919663)
			(xy 313.958369 -278.96324) (xy 313.928804 -279.002584) (xy 313.893311 -279.036676) (xy 313.852808 -279.064632)
			(xy 313.808346 -279.08573) (xy 313.761075 -279.099422) (xy 313.71222 -279.105354) (xy 313.663045 -279.103373)
			(xy 313.614826 -279.093529) (xy 313.56881 -279.076077) (xy 313.526189 -279.05147) (xy 313.488068 -279.020345)
			(xy 313.455433 -278.983508) (xy 313.42913 -278.941912) (xy 313.409839 -278.896636) (xy 313.398062 -278.848852)
			(xy 313.394102 -278.799798) (xy 313.055 -278.799798) (xy 313.054505 -278.824405) (xy 313.04661 -278.872982)
			(xy 313.031026 -278.919663) (xy 313.008155 -278.96324) (xy 312.97859 -279.002584) (xy 312.943097 -279.036676)
			(xy 312.902594 -279.064632) (xy 312.858132 -279.08573) (xy 312.810861 -279.099422) (xy 312.762006 -279.105354)
			(xy 312.712831 -279.103373) (xy 312.664612 -279.093529) (xy 312.618596 -279.076077) (xy 312.575975 -279.05147)
			(xy 312.537854 -279.020345) (xy 312.505219 -278.983508) (xy 312.478916 -278.941912) (xy 312.459625 -278.896636)
			(xy 312.447848 -278.848852) (xy 312.443888 -278.799798) (xy 312.10504 -278.799798) (xy 312.104545 -278.824405)
			(xy 312.09665 -278.872982) (xy 312.081066 -278.919663) (xy 312.058195 -278.96324) (xy 312.02863 -279.002584)
			(xy 311.993137 -279.036676) (xy 311.952634 -279.064632) (xy 311.908172 -279.08573) (xy 311.860901 -279.099422)
			(xy 311.812046 -279.105354) (xy 311.762871 -279.103373) (xy 311.714652 -279.093529) (xy 311.668636 -279.076077)
			(xy 311.626015 -279.05147) (xy 311.587894 -279.020345) (xy 311.555259 -278.983508) (xy 311.528956 -278.941912)
			(xy 311.509665 -278.896636) (xy 311.497888 -278.848852) (xy 311.493928 -278.799798) (xy 311.154826 -278.799798)
			(xy 311.154331 -278.824405) (xy 311.146436 -278.872982) (xy 311.130852 -278.919663) (xy 311.107981 -278.96324)
			(xy 311.078416 -279.002584) (xy 311.042923 -279.036676) (xy 311.00242 -279.064632) (xy 310.957958 -279.08573)
			(xy 310.910687 -279.099422) (xy 310.861832 -279.105354) (xy 310.812657 -279.103373) (xy 310.764438 -279.093529)
			(xy 310.718422 -279.076077) (xy 310.675801 -279.05147) (xy 310.63768 -279.020345) (xy 310.605045 -278.983508)
			(xy 310.578742 -278.941912) (xy 310.559451 -278.896636) (xy 310.547674 -278.848852) (xy 310.543714 -278.799798)
			(xy 310.20512 -278.799798) (xy 310.204625 -278.824405) (xy 310.19673 -278.872982) (xy 310.181146 -278.919663)
			(xy 310.158275 -278.96324) (xy 310.12871 -279.002584) (xy 310.093217 -279.036676) (xy 310.052714 -279.064632)
			(xy 310.008252 -279.08573) (xy 309.960981 -279.099422) (xy 309.912126 -279.105354) (xy 309.862951 -279.103373)
			(xy 309.814732 -279.093529) (xy 309.768716 -279.076077) (xy 309.726095 -279.05147) (xy 309.687974 -279.020345)
			(xy 309.655339 -278.983508) (xy 309.629036 -278.941912) (xy 309.609745 -278.896636) (xy 309.597968 -278.848852)
			(xy 309.594008 -278.799798) (xy 309.254906 -278.799798) (xy 309.254411 -278.824405) (xy 309.246516 -278.872982)
			(xy 309.230932 -278.919663) (xy 309.208061 -278.96324) (xy 309.178496 -279.002584) (xy 309.143003 -279.036676)
			(xy 309.1025 -279.064632) (xy 309.058038 -279.08573) (xy 309.010767 -279.099422) (xy 308.961912 -279.105354)
			(xy 308.912737 -279.103373) (xy 308.864518 -279.093529) (xy 308.818502 -279.076077) (xy 308.775881 -279.05147)
			(xy 308.73776 -279.020345) (xy 308.705125 -278.983508) (xy 308.678822 -278.941912) (xy 308.659531 -278.896636)
			(xy 308.647754 -278.848852) (xy 308.643794 -278.799798) (xy 308.3052 -278.799798) (xy 308.304705 -278.824405)
			(xy 308.29681 -278.872982) (xy 308.281226 -278.919663) (xy 308.258355 -278.96324) (xy 308.22879 -279.002584)
			(xy 308.193297 -279.036676) (xy 308.152794 -279.064632) (xy 308.108332 -279.08573) (xy 308.061061 -279.099422)
			(xy 308.012206 -279.105354) (xy 307.963031 -279.103373) (xy 307.914812 -279.093529) (xy 307.868796 -279.076077)
			(xy 307.826175 -279.05147) (xy 307.788054 -279.020345) (xy 307.755419 -278.983508) (xy 307.729116 -278.941912)
			(xy 307.709825 -278.896636) (xy 307.698048 -278.848852) (xy 307.694088 -278.799798) (xy 307.354986 -278.799798)
			(xy 307.354491 -278.824405) (xy 307.346596 -278.872982) (xy 307.331012 -278.919663) (xy 307.308141 -278.96324)
			(xy 307.278576 -279.002584) (xy 307.243083 -279.036676) (xy 307.20258 -279.064632) (xy 307.158118 -279.08573)
			(xy 307.110847 -279.099422) (xy 307.061992 -279.105354) (xy 307.012817 -279.103373) (xy 306.964598 -279.093529)
			(xy 306.918582 -279.076077) (xy 306.875961 -279.05147) (xy 306.83784 -279.020345) (xy 306.805205 -278.983508)
			(xy 306.778902 -278.941912) (xy 306.759611 -278.896636) (xy 306.747834 -278.848852) (xy 306.743874 -278.799798)
			(xy 306.405026 -278.799798) (xy 306.404531 -278.824405) (xy 306.396636 -278.872982) (xy 306.381052 -278.919663)
			(xy 306.358181 -278.96324) (xy 306.328616 -279.002584) (xy 306.293123 -279.036676) (xy 306.25262 -279.064632)
			(xy 306.208158 -279.08573) (xy 306.160887 -279.099422) (xy 306.112032 -279.105354) (xy 306.062857 -279.103373)
			(xy 306.014638 -279.093529) (xy 305.968622 -279.076077) (xy 305.926001 -279.05147) (xy 305.88788 -279.020345)
			(xy 305.855245 -278.983508) (xy 305.828942 -278.941912) (xy 305.809651 -278.896636) (xy 305.797874 -278.848852)
			(xy 305.793914 -278.799798) (xy 305.454812 -278.799798) (xy 305.454317 -278.824405) (xy 305.446422 -278.872982)
			(xy 305.430838 -278.919663) (xy 305.407967 -278.96324) (xy 305.378402 -279.002584) (xy 305.342909 -279.036676)
			(xy 305.302406 -279.064632) (xy 305.257944 -279.08573) (xy 305.210673 -279.099422) (xy 305.161818 -279.105354)
			(xy 305.112643 -279.103373) (xy 305.064424 -279.093529) (xy 305.018408 -279.076077) (xy 304.975787 -279.05147)
			(xy 304.937666 -279.020345) (xy 304.905031 -278.983508) (xy 304.878728 -278.941912) (xy 304.859437 -278.896636)
			(xy 304.84766 -278.848852) (xy 304.8437 -278.799798) (xy 304.505106 -278.799798) (xy 304.504611 -278.824405)
			(xy 304.496716 -278.872982) (xy 304.481132 -278.919663) (xy 304.458261 -278.96324) (xy 304.428696 -279.002584)
			(xy 304.393203 -279.036676) (xy 304.3527 -279.064632) (xy 304.308238 -279.08573) (xy 304.260967 -279.099422)
			(xy 304.212112 -279.105354) (xy 304.162937 -279.103373) (xy 304.114718 -279.093529) (xy 304.068702 -279.076077)
			(xy 304.026081 -279.05147) (xy 303.98796 -279.020345) (xy 303.955325 -278.983508) (xy 303.929022 -278.941912)
			(xy 303.909731 -278.896636) (xy 303.897954 -278.848852) (xy 303.893994 -278.799798) (xy 303.554892 -278.799798)
			(xy 303.554397 -278.824405) (xy 303.546502 -278.872982) (xy 303.530918 -278.919663) (xy 303.508047 -278.96324)
			(xy 303.478482 -279.002584) (xy 303.442989 -279.036676) (xy 303.402486 -279.064632) (xy 303.358024 -279.08573)
			(xy 303.310753 -279.099422) (xy 303.261898 -279.105354) (xy 303.212723 -279.103373) (xy 303.164504 -279.093529)
			(xy 303.118488 -279.076077) (xy 303.075867 -279.05147) (xy 303.037746 -279.020345) (xy 303.005111 -278.983508)
			(xy 302.978808 -278.941912) (xy 302.959517 -278.896636) (xy 302.94774 -278.848852) (xy 302.94378 -278.799798)
			(xy 302.605186 -278.799798) (xy 302.604691 -278.824405) (xy 302.596796 -278.872982) (xy 302.581212 -278.919663)
			(xy 302.558341 -278.96324) (xy 302.528776 -279.002584) (xy 302.493283 -279.036676) (xy 302.45278 -279.064632)
			(xy 302.408318 -279.08573) (xy 302.361047 -279.099422) (xy 302.312192 -279.105354) (xy 302.263017 -279.103373)
			(xy 302.214798 -279.093529) (xy 302.168782 -279.076077) (xy 302.126161 -279.05147) (xy 302.08804 -279.020345)
			(xy 302.055405 -278.983508) (xy 302.029102 -278.941912) (xy 302.009811 -278.896636) (xy 301.998034 -278.848852)
			(xy 301.994074 -278.799798) (xy 301.654972 -278.799798) (xy 301.654477 -278.824405) (xy 301.646582 -278.872982)
			(xy 301.630998 -278.919663) (xy 301.608127 -278.96324) (xy 301.578562 -279.002584) (xy 301.543069 -279.036676)
			(xy 301.502566 -279.064632) (xy 301.458104 -279.08573) (xy 301.410833 -279.099422) (xy 301.361978 -279.105354)
			(xy 301.312803 -279.103373) (xy 301.264584 -279.093529) (xy 301.218568 -279.076077) (xy 301.175947 -279.05147)
			(xy 301.137826 -279.020345) (xy 301.105191 -278.983508) (xy 301.078888 -278.941912) (xy 301.059597 -278.896636)
			(xy 301.04782 -278.848852) (xy 301.04386 -278.799798) (xy 300.705012 -278.799798) (xy 300.704517 -278.824405)
			(xy 300.696622 -278.872982) (xy 300.681038 -278.919663) (xy 300.658167 -278.96324) (xy 300.628602 -279.002584)
			(xy 300.593109 -279.036676) (xy 300.552606 -279.064632) (xy 300.508144 -279.08573) (xy 300.460873 -279.099422)
			(xy 300.412018 -279.105354) (xy 300.362843 -279.103373) (xy 300.314624 -279.093529) (xy 300.268608 -279.076077)
			(xy 300.225987 -279.05147) (xy 300.187866 -279.020345) (xy 300.155231 -278.983508) (xy 300.128928 -278.941912)
			(xy 300.109637 -278.896636) (xy 300.09786 -278.848852) (xy 300.0939 -278.799798) (xy 299.754798 -278.799798)
			(xy 299.754303 -278.824405) (xy 299.746408 -278.872982) (xy 299.730824 -278.919663) (xy 299.707953 -278.96324)
			(xy 299.678388 -279.002584) (xy 299.642895 -279.036676) (xy 299.602392 -279.064632) (xy 299.55793 -279.08573)
			(xy 299.510659 -279.099422) (xy 299.461804 -279.105354) (xy 299.412629 -279.103373) (xy 299.36441 -279.093529)
			(xy 299.318394 -279.076077) (xy 299.275773 -279.05147) (xy 299.237652 -279.020345) (xy 299.205017 -278.983508)
			(xy 299.178714 -278.941912) (xy 299.159423 -278.896636) (xy 299.147646 -278.848852) (xy 299.143686 -278.799798)
			(xy 298.805092 -278.799798) (xy 298.804597 -278.824405) (xy 298.796702 -278.872982) (xy 298.781118 -278.919663)
			(xy 298.758247 -278.96324) (xy 298.728682 -279.002584) (xy 298.693189 -279.036676) (xy 298.652686 -279.064632)
			(xy 298.608224 -279.08573) (xy 298.560953 -279.099422) (xy 298.512098 -279.105354) (xy 298.462923 -279.103373)
			(xy 298.414704 -279.093529) (xy 298.368688 -279.076077) (xy 298.326067 -279.05147) (xy 298.287946 -279.020345)
			(xy 298.255311 -278.983508) (xy 298.229008 -278.941912) (xy 298.209717 -278.896636) (xy 298.19794 -278.848852)
			(xy 298.19398 -278.799798) (xy 297.854878 -278.799798) (xy 297.854383 -278.824405) (xy 297.846488 -278.872982)
			(xy 297.830904 -278.919663) (xy 297.808033 -278.96324) (xy 297.778468 -279.002584) (xy 297.742975 -279.036676)
			(xy 297.702472 -279.064632) (xy 297.65801 -279.08573) (xy 297.610739 -279.099422) (xy 297.561884 -279.105354)
			(xy 297.512709 -279.103373) (xy 297.46449 -279.093529) (xy 297.418474 -279.076077) (xy 297.375853 -279.05147)
			(xy 297.337732 -279.020345) (xy 297.305097 -278.983508) (xy 297.278794 -278.941912) (xy 297.259503 -278.896636)
			(xy 297.247726 -278.848852) (xy 297.243766 -278.799798) (xy 296.905172 -278.799798) (xy 296.904677 -278.824405)
			(xy 296.896782 -278.872982) (xy 296.881198 -278.919663) (xy 296.858327 -278.96324) (xy 296.828762 -279.002584)
			(xy 296.793269 -279.036676) (xy 296.752766 -279.064632) (xy 296.708304 -279.08573) (xy 296.661033 -279.099422)
			(xy 296.612178 -279.105354) (xy 296.563003 -279.103373) (xy 296.514784 -279.093529) (xy 296.468768 -279.076077)
			(xy 296.426147 -279.05147) (xy 296.388026 -279.020345) (xy 296.355391 -278.983508) (xy 296.329088 -278.941912)
			(xy 296.309797 -278.896636) (xy 296.29802 -278.848852) (xy 296.29406 -278.799798) (xy 295.954958 -278.799798)
			(xy 295.954463 -278.824405) (xy 295.946568 -278.872982) (xy 295.930984 -278.919663) (xy 295.908113 -278.96324)
			(xy 295.878548 -279.002584) (xy 295.843055 -279.036676) (xy 295.802552 -279.064632) (xy 295.75809 -279.08573)
			(xy 295.710819 -279.099422) (xy 295.661964 -279.105354) (xy 295.612789 -279.103373) (xy 295.56457 -279.093529)
			(xy 295.518554 -279.076077) (xy 295.475933 -279.05147) (xy 295.437812 -279.020345) (xy 295.405177 -278.983508)
			(xy 295.378874 -278.941912) (xy 295.359583 -278.896636) (xy 295.347806 -278.848852) (xy 295.343846 -278.799798)
			(xy 295.004998 -278.799798) (xy 295.004503 -278.824405) (xy 294.996608 -278.872982) (xy 294.981024 -278.919663)
			(xy 294.958153 -278.96324) (xy 294.928588 -279.002584) (xy 294.893095 -279.036676) (xy 294.852592 -279.064632)
			(xy 294.80813 -279.08573) (xy 294.760859 -279.099422) (xy 294.712004 -279.105354) (xy 294.662829 -279.103373)
			(xy 294.61461 -279.093529) (xy 294.568594 -279.076077) (xy 294.525973 -279.05147) (xy 294.487852 -279.020345)
			(xy 294.455217 -278.983508) (xy 294.428914 -278.941912) (xy 294.409623 -278.896636) (xy 294.397846 -278.848852)
			(xy 294.393886 -278.799798) (xy 294.054784 -278.799798) (xy 294.054289 -278.824405) (xy 294.046394 -278.872982)
			(xy 294.03081 -278.919663) (xy 294.007939 -278.96324) (xy 293.978374 -279.002584) (xy 293.942881 -279.036676)
			(xy 293.902378 -279.064632) (xy 293.857916 -279.08573) (xy 293.810645 -279.099422) (xy 293.76179 -279.105354)
			(xy 293.712615 -279.103373) (xy 293.664396 -279.093529) (xy 293.61838 -279.076077) (xy 293.575759 -279.05147)
			(xy 293.537638 -279.020345) (xy 293.505003 -278.983508) (xy 293.4787 -278.941912) (xy 293.459409 -278.896636)
			(xy 293.447632 -278.848852) (xy 293.443672 -278.799798) (xy 293.105078 -278.799798) (xy 293.104583 -278.824405)
			(xy 293.096688 -278.872982) (xy 293.081104 -278.919663) (xy 293.058233 -278.96324) (xy 293.028668 -279.002584)
			(xy 292.993175 -279.036676) (xy 292.952672 -279.064632) (xy 292.90821 -279.08573) (xy 292.860939 -279.099422)
			(xy 292.812084 -279.105354) (xy 292.762909 -279.103373) (xy 292.71469 -279.093529) (xy 292.668674 -279.076077)
			(xy 292.626053 -279.05147) (xy 292.587932 -279.020345) (xy 292.555297 -278.983508) (xy 292.528994 -278.941912)
			(xy 292.509703 -278.896636) (xy 292.497926 -278.848852) (xy 292.493966 -278.799798) (xy 292.154864 -278.799798)
			(xy 292.154369 -278.824405) (xy 292.146474 -278.872982) (xy 292.13089 -278.919663) (xy 292.108019 -278.96324)
			(xy 292.078454 -279.002584) (xy 292.042961 -279.036676) (xy 292.002458 -279.064632) (xy 291.957996 -279.08573)
			(xy 291.910725 -279.099422) (xy 291.86187 -279.105354) (xy 291.812695 -279.103373) (xy 291.764476 -279.093529)
			(xy 291.71846 -279.076077) (xy 291.675839 -279.05147) (xy 291.637718 -279.020345) (xy 291.605083 -278.983508)
			(xy 291.57878 -278.941912) (xy 291.559489 -278.896636) (xy 291.547712 -278.848852) (xy 291.543752 -278.799798)
			(xy 291.205074 -278.799798) (xy 291.202829 -278.84112) (xy 291.192153 -278.889599) (xy 291.173774 -278.935711)
			(xy 291.148178 -278.978244) (xy 291.116038 -279.016075) (xy 291.078202 -279.048208) (xy 291.035665 -279.073797)
			(xy 290.989549 -279.092168) (xy 290.941068 -279.102836) (xy 290.8915 -279.10552) (xy 290.842151 -279.100151)
			(xy 290.794321 -279.086868) (xy 290.74927 -279.066023) (xy 290.708184 -279.038163) (xy 290.672146 -279.004024)
			(xy 290.642106 -278.964505) (xy 290.618855 -278.920647) (xy 290.603006 -278.873605) (xy 290.594976 -278.824618)
			(xy 290.594542 -278.799798) (xy 290.594729 -278.785616) (xy 290.597402 -278.757376) (xy 290.599876 -278.74341)
			(xy 290.602162 -278.730964) (xy 290.594796 -278.707342) (xy 290.517326 -278.629872) (xy 290.493704 -278.622506)
			(xy 290.481258 -278.624792) (xy 290.467293 -278.627276) (xy 290.439053 -278.629945) (xy 290.42487 -278.630126)
			(xy 290.410687 -278.629943) (xy 290.382447 -278.627276) (xy 290.368482 -278.624792) (xy 290.356036 -278.622506)
			(xy 290.332414 -278.629872) (xy 290.254944 -278.707342) (xy 290.247578 -278.730964) (xy 290.249864 -278.74341)
			(xy 290.252349 -278.757375) (xy 290.255022 -278.785615) (xy 290.255198 -278.799798) (xy 290.254676 -278.825053)
			(xy 290.246363 -278.874875) (xy 290.229962 -278.922649) (xy 290.205921 -278.967072) (xy 290.174897 -279.006932)
			(xy 290.137735 -279.041142) (xy 290.095449 -279.068768) (xy 290.049193 -279.089058) (xy 290.000228 -279.101458)
			(xy 289.94989 -279.105629) (xy 289.899552 -279.101458) (xy 289.850587 -279.089058) (xy 289.804331 -279.068768)
			(xy 289.762045 -279.041142) (xy 289.724883 -279.006932) (xy 289.693859 -278.967072) (xy 289.669818 -278.922649)
			(xy 289.653417 -278.874875) (xy 289.645104 -278.825053) (xy 289.644582 -278.799798) (xy 289.644679 -278.790694)
			(xy 289.64582 -278.77252) (xy 289.646868 -278.763476) (xy 289.648138 -278.751284) (xy 289.640264 -278.729186)
			(xy 289.56381 -278.656034) (xy 289.541204 -278.649176) (xy 289.529012 -278.651208) (xy 289.515461 -278.653345)
			(xy 289.48812 -278.655632) (xy 289.474402 -278.65578) (xy 289.46088 -278.65566) (xy 289.433923 -278.653494)
			(xy 289.420554 -278.651462) (xy 289.408616 -278.64943) (xy 289.38601 -278.656288) (xy 289.309556 -278.729186)
			(xy 289.301682 -278.751538) (xy 289.303206 -278.76373) (xy 289.30419 -278.772714) (xy 289.30521 -278.79076)
			(xy 289.305238 -278.799798) (xy 289.304716 -278.825053) (xy 289.296403 -278.874875) (xy 289.280002 -278.922649)
			(xy 289.255961 -278.967072) (xy 289.224937 -279.006932) (xy 289.187775 -279.041142) (xy 289.145489 -279.068768)
			(xy 289.099233 -279.089058) (xy 289.050268 -279.101458) (xy 288.99993 -279.105629) (xy 288.949592 -279.101458)
			(xy 288.900627 -279.089058) (xy 288.854371 -279.068768) (xy 288.812085 -279.041142) (xy 288.774923 -279.006932)
			(xy 288.743899 -278.967072) (xy 288.719858 -278.922649) (xy 288.703457 -278.874875) (xy 288.695144 -278.825053)
			(xy 288.694622 -278.799798) (xy 288.694809 -278.785616) (xy 288.697483 -278.757376) (xy 288.699956 -278.74341)
			(xy 288.702242 -278.730964) (xy 288.694876 -278.707088) (xy 288.61766 -278.629872) (xy 288.59353 -278.622506)
			(xy 288.581338 -278.624792) (xy 288.567311 -278.627289) (xy 288.538943 -278.629958) (xy 288.524696 -278.630126)
			(xy 288.510514 -278.629939) (xy 288.482274 -278.627266) (xy 288.468308 -278.624792) (xy 288.455862 -278.622506)
			(xy 288.43224 -278.629872) (xy 288.35477 -278.707342) (xy 288.347404 -278.730964) (xy 288.34969 -278.74341)
			(xy 288.352175 -278.757375) (xy 288.354847 -278.785615) (xy 288.355024 -278.799798) (xy 288.354502 -278.825053)
			(xy 288.346189 -278.874875) (xy 288.329788 -278.922649) (xy 288.305747 -278.967072) (xy 288.274723 -279.006932)
			(xy 288.237561 -279.041142) (xy 288.195275 -279.068768) (xy 288.149019 -279.089058) (xy 288.100054 -279.101458)
			(xy 288.049716 -279.105629) (xy 287.999378 -279.101458) (xy 287.950413 -279.089058) (xy 287.904157 -279.068768)
			(xy 287.861871 -279.041142) (xy 287.824709 -279.006932) (xy 287.793685 -278.967072) (xy 287.769644 -278.922649)
			(xy 287.753243 -278.874875) (xy 287.74493 -278.825053) (xy 287.744408 -278.799798) (xy 287.744505 -278.790694)
			(xy 287.745646 -278.77252) (xy 287.746694 -278.763476) (xy 287.747964 -278.751284) (xy 287.74009 -278.729186)
			(xy 287.663636 -278.656034) (xy 287.64103 -278.649176) (xy 287.628838 -278.651208) (xy 287.615287 -278.653345)
			(xy 287.587946 -278.65563) (xy 287.574228 -278.65578) (xy 287.560706 -278.655661) (xy 287.533749 -278.653497)
			(xy 287.52038 -278.651462) (xy 287.508442 -278.64943) (xy 287.485836 -278.656288) (xy 287.409382 -278.729186)
			(xy 287.401508 -278.751538) (xy 287.403032 -278.76373) (xy 287.404016 -278.772714) (xy 287.405036 -278.79076)
			(xy 287.405064 -278.799798) (xy 287.404542 -278.825053) (xy 287.396229 -278.874875) (xy 287.379828 -278.922649)
			(xy 287.355787 -278.967072) (xy 287.324763 -279.006932) (xy 287.287601 -279.041142) (xy 287.245315 -279.068768)
			(xy 287.199059 -279.089058) (xy 287.150094 -279.101458) (xy 287.099756 -279.105629) (xy 287.049418 -279.101458)
			(xy 287.000453 -279.089058) (xy 286.954197 -279.068768) (xy 286.911911 -279.041142) (xy 286.874749 -279.006932)
			(xy 286.843725 -278.967072) (xy 286.819684 -278.922649) (xy 286.803283 -278.874875) (xy 286.79497 -278.825053)
			(xy 286.794448 -278.799798) (xy 286.794635 -278.785616) (xy 286.797308 -278.757376) (xy 286.799782 -278.74341)
			(xy 286.802068 -278.730964) (xy 286.794702 -278.707342) (xy 286.717232 -278.629872) (xy 286.69361 -278.622506)
			(xy 286.681164 -278.624792) (xy 286.667199 -278.627276) (xy 286.638959 -278.629946) (xy 286.624776 -278.630126)
			(xy 286.610594 -278.629938) (xy 286.582355 -278.627263) (xy 286.568388 -278.624792) (xy 286.555942 -278.622506)
			(xy 286.53232 -278.629872) (xy 286.45485 -278.707342) (xy 286.447484 -278.730964) (xy 286.44977 -278.74341)
			(xy 286.452255 -278.757375) (xy 286.454928 -278.785615) (xy 286.455104 -278.799798) (xy 286.454582 -278.825053)
			(xy 286.446269 -278.874875) (xy 286.429868 -278.922649) (xy 286.405827 -278.967072) (xy 286.374803 -279.006932)
			(xy 286.337641 -279.041142) (xy 286.295355 -279.068768) (xy 286.249099 -279.089058) (xy 286.200134 -279.101458)
			(xy 286.149796 -279.105629) (xy 286.099458 -279.101458) (xy 286.050493 -279.089058) (xy 286.004237 -279.068768)
			(xy 285.961951 -279.041142) (xy 285.924789 -279.006932) (xy 285.893765 -278.967072) (xy 285.869724 -278.922649)
			(xy 285.853323 -278.874875) (xy 285.84501 -278.825053) (xy 285.844488 -278.799798) (xy 285.844585 -278.790694)
			(xy 285.845726 -278.77252) (xy 285.846774 -278.763476) (xy 285.848044 -278.751284) (xy 285.84017 -278.729186)
			(xy 285.763462 -278.656034) (xy 285.74111 -278.649176) (xy 285.728918 -278.651208) (xy 285.715304 -278.653352)
			(xy 285.687836 -278.655638) (xy 285.674054 -278.65578) (xy 285.660596 -278.655652) (xy 285.633766 -278.653487)
			(xy 285.62046 -278.651462) (xy 285.608268 -278.64943) (xy 285.585662 -278.656288) (xy 285.509462 -278.72944)
			(xy 285.501588 -278.751538) (xy 285.503112 -278.76373) (xy 285.504096 -278.772714) (xy 285.505116 -278.79076)
			(xy 285.505144 -278.799798) (xy 285.504622 -278.825053) (xy 285.496309 -278.874875) (xy 285.479908 -278.922649)
			(xy 285.455867 -278.967072) (xy 285.424843 -279.006932) (xy 285.387681 -279.041142) (xy 285.345395 -279.068768)
			(xy 285.299139 -279.089058) (xy 285.250174 -279.101458) (xy 285.199836 -279.105629) (xy 285.149498 -279.101458)
			(xy 285.100533 -279.089058) (xy 285.054277 -279.068768) (xy 285.011991 -279.041142) (xy 284.974829 -279.006932)
			(xy 284.943805 -278.967072) (xy 284.919764 -278.922649) (xy 284.903363 -278.874875) (xy 284.89505 -278.825053)
			(xy 284.894528 -278.799798) (xy 284.894715 -278.785616) (xy 284.897389 -278.757376) (xy 284.899862 -278.74341)
			(xy 284.902148 -278.730964) (xy 284.894782 -278.707342) (xy 284.817312 -278.629872) (xy 284.79369 -278.622506)
			(xy 284.781244 -278.624792) (xy 284.767279 -278.627275) (xy 284.739039 -278.629943) (xy 284.724856 -278.630126)
			(xy 284.710673 -278.629942) (xy 284.682433 -278.627274) (xy 284.668468 -278.624792) (xy 284.656022 -278.622506)
			(xy 284.6324 -278.629872) (xy 284.55493 -278.707342) (xy 284.547564 -278.730964) (xy 284.54985 -278.74341)
			(xy 284.552336 -278.757375) (xy 284.555008 -278.785615) (xy 284.555184 -278.799798) (xy 284.554662 -278.825053)
			(xy 284.546349 -278.874875) (xy 284.529948 -278.922649) (xy 284.505907 -278.967072) (xy 284.474883 -279.006932)
			(xy 284.437721 -279.041142) (xy 284.395435 -279.068768) (xy 284.349179 -279.089058) (xy 284.300214 -279.101458)
			(xy 284.249876 -279.105629) (xy 284.199538 -279.101458) (xy 284.150573 -279.089058) (xy 284.104317 -279.068768)
			(xy 284.062031 -279.041142) (xy 284.024869 -279.006932) (xy 283.993845 -278.967072) (xy 283.969804 -278.922649)
			(xy 283.953403 -278.874875) (xy 283.94509 -278.825053) (xy 283.944568 -278.799798) (xy 283.944665 -278.790694)
			(xy 283.945806 -278.77252) (xy 283.946854 -278.763476) (xy 283.948124 -278.751284) (xy 283.94025 -278.729186)
			(xy 283.863542 -278.656034) (xy 283.84119 -278.649176) (xy 283.828998 -278.651208) (xy 283.815383 -278.653351)
			(xy 283.787915 -278.655636) (xy 283.774134 -278.65578) (xy 283.760675 -278.655655) (xy 283.733845 -278.653496)
			(xy 283.72054 -278.651462) (xy 283.708348 -278.64943) (xy 283.685742 -278.656288) (xy 283.609542 -278.72944)
			(xy 283.601668 -278.751538) (xy 283.603192 -278.76373) (xy 283.604176 -278.772714) (xy 283.605195 -278.79076)
			(xy 283.605224 -278.799798) (xy 283.604702 -278.825053) (xy 283.596389 -278.874875) (xy 283.579988 -278.922649)
			(xy 283.555947 -278.967072) (xy 283.524923 -279.006932) (xy 283.487761 -279.041142) (xy 283.445475 -279.068768)
			(xy 283.399219 -279.089058) (xy 283.350254 -279.101458) (xy 283.299916 -279.105629) (xy 283.249578 -279.101458)
			(xy 283.200613 -279.089058) (xy 283.154357 -279.068768) (xy 283.112071 -279.041142) (xy 283.074909 -279.006932)
			(xy 283.043885 -278.967072) (xy 283.019844 -278.922649) (xy 283.003443 -278.874875) (xy 282.99513 -278.825053)
			(xy 282.994608 -278.799798) (xy 282.994795 -278.785616) (xy 282.997468 -278.757376) (xy 282.999942 -278.74341)
			(xy 283.002228 -278.730964) (xy 282.994862 -278.707342) (xy 282.917392 -278.629872) (xy 282.89377 -278.622506)
			(xy 282.881324 -278.624792) (xy 282.867359 -278.627279) (xy 282.839119 -278.629954) (xy 282.824936 -278.630126)
			(xy 282.81069 -278.629948) (xy 282.782323 -278.627274) (xy 282.768294 -278.624792) (xy 282.756102 -278.622506)
			(xy 282.731972 -278.629872) (xy 282.654756 -278.707088) (xy 282.64739 -278.730964) (xy 282.649676 -278.74341)
			(xy 282.652161 -278.757375) (xy 282.654834 -278.785615) (xy 282.65501 -278.799798) (xy 282.654488 -278.825053)
			(xy 282.646175 -278.874875) (xy 282.629774 -278.922649) (xy 282.605733 -278.967072) (xy 282.574709 -279.006932)
			(xy 282.537547 -279.041142) (xy 282.495261 -279.068768) (xy 282.449005 -279.089058) (xy 282.40004 -279.101458)
			(xy 282.349702 -279.105629) (xy 282.299364 -279.101458) (xy 282.250399 -279.089058) (xy 282.204143 -279.068768)
			(xy 282.161857 -279.041142) (xy 282.124695 -279.006932) (xy 282.093671 -278.967072) (xy 282.06963 -278.922649)
			(xy 282.053229 -278.874875) (xy 282.044916 -278.825053) (xy 282.044394 -278.799798) (xy 282.044491 -278.790694)
			(xy 282.045632 -278.77252) (xy 282.04668 -278.763476) (xy 282.04795 -278.751284) (xy 282.040076 -278.729186)
			(xy 281.963622 -278.656034) (xy 281.941016 -278.649176) (xy 281.928824 -278.651208) (xy 281.915273 -278.653345)
			(xy 281.887932 -278.655634) (xy 281.874214 -278.65578) (xy 281.860692 -278.65566) (xy 281.833735 -278.653495)
			(xy 281.820366 -278.651462) (xy 281.808428 -278.64943) (xy 281.785822 -278.656288) (xy 281.709368 -278.729186)
			(xy 281.701494 -278.751538) (xy 281.703018 -278.76373) (xy 281.704002 -278.772714) (xy 281.705022 -278.79076)
			(xy 281.70505 -278.799798) (xy 281.704528 -278.825053) (xy 281.696215 -278.874875) (xy 281.679814 -278.922649)
			(xy 281.655773 -278.967072) (xy 281.624749 -279.006932) (xy 281.587587 -279.041142) (xy 281.545301 -279.068768)
			(xy 281.499045 -279.089058) (xy 281.45008 -279.101458) (xy 281.399742 -279.105629) (xy 281.349404 -279.101458)
			(xy 281.300439 -279.089058) (xy 281.254183 -279.068768) (xy 281.211897 -279.041142) (xy 281.174735 -279.006932)
			(xy 281.143711 -278.967072) (xy 281.11967 -278.922649) (xy 281.103269 -278.874875) (xy 281.094956 -278.825053)
			(xy 281.094434 -278.799798) (xy 281.094621 -278.785616) (xy 281.097294 -278.757376) (xy 281.099768 -278.74341)
			(xy 281.102054 -278.730964) (xy 281.094688 -278.707342) (xy 281.017218 -278.629872) (xy 280.993596 -278.622506)
			(xy 280.98115 -278.624792) (xy 280.967185 -278.627275) (xy 280.938945 -278.629944) (xy 280.924762 -278.630126)
			(xy 280.910579 -278.629942) (xy 280.882339 -278.627275) (xy 280.868374 -278.624792) (xy 280.855928 -278.622506)
			(xy 280.832306 -278.629872) (xy 280.754836 -278.707342) (xy 280.74747 -278.730964) (xy 280.749756 -278.74341)
			(xy 280.752241 -278.757375) (xy 280.754914 -278.785615) (xy 280.75509 -278.799798) (xy 280.754644 -278.823791)
			(xy 280.747137 -278.871185) (xy 280.732309 -278.916822) (xy 280.710523 -278.959577) (xy 280.682317 -278.998398)
			(xy 280.648386 -279.032328) (xy 280.609564 -279.060532) (xy 280.566807 -279.082315) (xy 280.52117 -279.097141)
			(xy 280.473775 -279.104645) (xy 280.449782 -279.105106) (xy 280.421083 -279.104451) (xy 280.3647 -279.093706)
			(xy 280.337768 -279.08377) (xy 280.328878 -279.080214) (xy 280.319226 -279.080214) (xy 280.309202 -279.080629)
			(xy 280.290679 -279.088295) (xy 280.276502 -279.102469) (xy 280.268831 -279.12099) (xy 280.268426 -279.131014)
			(xy 280.268426 -279.180036) (xy 280.268934 -279.186132) (xy 280.270204 -279.197308) (xy 280.272236 -279.206198)
			(xy 280.275901 -279.223106) (xy 280.279847 -279.257479) (xy 280.28011 -279.274778) (xy 280.28011 -279.291288)
			(xy 280.279602 -279.29713) (xy 280.279602 -279.297638) (xy 280.278332 -279.30856) (xy 280.278332 -279.308814)
			(xy 280.277824 -279.312878) (xy 280.275284 -279.331674) (xy 280.274268 -279.337262) (xy 280.270204 -279.35301)
			(xy 280.268426 -279.36571) (xy 280.268426 -279.418542) (xy 280.268922 -279.428542) (xy 280.276589 -279.447015)
			(xy 280.290742 -279.461149) (xy 280.309225 -279.468792) (xy 280.319226 -279.469342) (xy 280.328878 -279.469342)
			(xy 280.337768 -279.465786) (xy 280.364705 -279.455868) (xy 280.421086 -279.445132) (xy 280.449782 -279.44445)
			(xy 280.475044 -279.444941) (xy 280.52488 -279.453255) (xy 280.572667 -279.469658) (xy 280.617103 -279.493703)
			(xy 280.656975 -279.524734) (xy 280.691195 -279.561905) (xy 280.71883 -279.604202) (xy 280.739126 -279.65047)
			(xy 280.75153 -279.699448) (xy 280.755677 -279.749504) (xy 281.093938 -279.749504) (xy 281.097898 -279.70045)
			(xy 281.109675 -279.652666) (xy 281.128966 -279.60739) (xy 281.155269 -279.565794) (xy 281.187904 -279.528957)
			(xy 281.226025 -279.497832) (xy 281.268646 -279.473225) (xy 281.314662 -279.455773) (xy 281.362881 -279.445929)
			(xy 281.412056 -279.443948) (xy 281.460911 -279.44988) (xy 281.508182 -279.463572) (xy 281.552644 -279.48467)
			(xy 281.593147 -279.512626) (xy 281.62864 -279.546718) (xy 281.658205 -279.586062) (xy 281.681076 -279.629639)
			(xy 281.69666 -279.67632) (xy 281.704555 -279.724897) (xy 281.70505 -279.749504) (xy 281.705045 -279.749758)
			(xy 282.043898 -279.749758) (xy 282.047858 -279.700704) (xy 282.059635 -279.65292) (xy 282.078926 -279.607644)
			(xy 282.105229 -279.566048) (xy 282.137864 -279.529211) (xy 282.175985 -279.498086) (xy 282.218606 -279.473479)
			(xy 282.264622 -279.456027) (xy 282.312841 -279.446183) (xy 282.362016 -279.444202) (xy 282.410871 -279.450134)
			(xy 282.458142 -279.463826) (xy 282.502604 -279.484924) (xy 282.543107 -279.51288) (xy 282.5786 -279.546972)
			(xy 282.608165 -279.586316) (xy 282.631036 -279.629893) (xy 282.64662 -279.676574) (xy 282.654515 -279.725151)
			(xy 282.655005 -279.749504) (xy 282.994112 -279.749504) (xy 282.998072 -279.70045) (xy 283.009849 -279.652666)
			(xy 283.02914 -279.60739) (xy 283.055443 -279.565794) (xy 283.088078 -279.528957) (xy 283.126199 -279.497832)
			(xy 283.16882 -279.473225) (xy 283.214836 -279.455773) (xy 283.263055 -279.445929) (xy 283.31223 -279.443948)
			(xy 283.361085 -279.44988) (xy 283.408356 -279.463572) (xy 283.452818 -279.48467) (xy 283.493321 -279.512626)
			(xy 283.528814 -279.546718) (xy 283.558379 -279.586062) (xy 283.58125 -279.629639) (xy 283.596834 -279.67632)
			(xy 283.604729 -279.724897) (xy 283.605224 -279.749504) (xy 283.605219 -279.749758) (xy 283.944072 -279.749758)
			(xy 283.948032 -279.700704) (xy 283.959809 -279.65292) (xy 283.9791 -279.607644) (xy 284.005403 -279.566048)
			(xy 284.038038 -279.529211) (xy 284.076159 -279.498086) (xy 284.11878 -279.473479) (xy 284.164796 -279.456027)
			(xy 284.213015 -279.446183) (xy 284.26219 -279.444202) (xy 284.311045 -279.450134) (xy 284.358316 -279.463826)
			(xy 284.402778 -279.484924) (xy 284.443281 -279.51288) (xy 284.478774 -279.546972) (xy 284.508339 -279.586316)
			(xy 284.53121 -279.629893) (xy 284.546794 -279.676574) (xy 284.554689 -279.725151) (xy 284.555179 -279.749504)
			(xy 284.894032 -279.749504) (xy 284.897992 -279.70045) (xy 284.909769 -279.652666) (xy 284.92906 -279.60739)
			(xy 284.955363 -279.565794) (xy 284.987998 -279.528957) (xy 285.026119 -279.497832) (xy 285.06874 -279.473225)
			(xy 285.114756 -279.455773) (xy 285.162975 -279.445929) (xy 285.21215 -279.443948) (xy 285.261005 -279.44988)
			(xy 285.308276 -279.463572) (xy 285.352738 -279.48467) (xy 285.393241 -279.512626) (xy 285.428734 -279.546718)
			(xy 285.458299 -279.586062) (xy 285.48117 -279.629639) (xy 285.496754 -279.67632) (xy 285.504649 -279.724897)
			(xy 285.505144 -279.749504) (xy 285.505139 -279.749758) (xy 285.843992 -279.749758) (xy 285.847952 -279.700704)
			(xy 285.859729 -279.65292) (xy 285.87902 -279.607644) (xy 285.905323 -279.566048) (xy 285.937958 -279.529211)
			(xy 285.976079 -279.498086) (xy 286.0187 -279.473479) (xy 286.064716 -279.456027) (xy 286.112935 -279.446183)
			(xy 286.16211 -279.444202) (xy 286.210965 -279.450134) (xy 286.258236 -279.463826) (xy 286.302698 -279.484924)
			(xy 286.343201 -279.51288) (xy 286.378694 -279.546972) (xy 286.408259 -279.586316) (xy 286.43113 -279.629893)
			(xy 286.446714 -279.676574) (xy 286.454609 -279.725151) (xy 286.455099 -279.749504) (xy 286.793952 -279.749504)
			(xy 286.797912 -279.70045) (xy 286.809689 -279.652666) (xy 286.82898 -279.60739) (xy 286.855283 -279.565794)
			(xy 286.887918 -279.528957) (xy 286.926039 -279.497832) (xy 286.96866 -279.473225) (xy 287.014676 -279.455773)
			(xy 287.062895 -279.445929) (xy 287.11207 -279.443948) (xy 287.160925 -279.44988) (xy 287.208196 -279.463572)
			(xy 287.252658 -279.48467) (xy 287.293161 -279.512626) (xy 287.328654 -279.546718) (xy 287.358219 -279.586062)
			(xy 287.38109 -279.629639) (xy 287.396674 -279.67632) (xy 287.404569 -279.724897) (xy 287.405064 -279.749504)
			(xy 287.405059 -279.749758) (xy 287.743912 -279.749758) (xy 287.747872 -279.700704) (xy 287.759649 -279.65292)
			(xy 287.77894 -279.607644) (xy 287.805243 -279.566048) (xy 287.837878 -279.529211) (xy 287.875999 -279.498086)
			(xy 287.91862 -279.473479) (xy 287.964636 -279.456027) (xy 288.012855 -279.446183) (xy 288.06203 -279.444202)
			(xy 288.110885 -279.450134) (xy 288.158156 -279.463826) (xy 288.202618 -279.484924) (xy 288.243121 -279.51288)
			(xy 288.278614 -279.546972) (xy 288.308179 -279.586316) (xy 288.33105 -279.629893) (xy 288.346634 -279.676574)
			(xy 288.354529 -279.725151) (xy 288.355019 -279.749504) (xy 288.693872 -279.749504) (xy 288.697832 -279.70045)
			(xy 288.709609 -279.652666) (xy 288.7289 -279.60739) (xy 288.755203 -279.565794) (xy 288.787838 -279.528957)
			(xy 288.825959 -279.497832) (xy 288.86858 -279.473225) (xy 288.914596 -279.455773) (xy 288.962815 -279.445929)
			(xy 289.01199 -279.443948) (xy 289.060845 -279.44988) (xy 289.108116 -279.463572) (xy 289.152578 -279.48467)
			(xy 289.193081 -279.512626) (xy 289.228574 -279.546718) (xy 289.258139 -279.586062) (xy 289.28101 -279.629639)
			(xy 289.296594 -279.67632) (xy 289.304489 -279.724897) (xy 289.304984 -279.749504) (xy 289.304979 -279.749758)
			(xy 289.644086 -279.749758) (xy 289.648046 -279.700704) (xy 289.659823 -279.65292) (xy 289.679114 -279.607644)
			(xy 289.705417 -279.566048) (xy 289.738052 -279.529211) (xy 289.776173 -279.498086) (xy 289.818794 -279.473479)
			(xy 289.86481 -279.456027) (xy 289.913029 -279.446183) (xy 289.962204 -279.444202) (xy 290.011059 -279.450134)
			(xy 290.05833 -279.463826) (xy 290.102792 -279.484924) (xy 290.143295 -279.51288) (xy 290.178788 -279.546972)
			(xy 290.208353 -279.586316) (xy 290.231224 -279.629893) (xy 290.246808 -279.676574) (xy 290.254703 -279.725151)
			(xy 290.255193 -279.749504) (xy 290.594046 -279.749504) (xy 290.598006 -279.70045) (xy 290.609783 -279.652666)
			(xy 290.629074 -279.60739) (xy 290.655377 -279.565794) (xy 290.688012 -279.528957) (xy 290.726133 -279.497832)
			(xy 290.768754 -279.473225) (xy 290.81477 -279.455773) (xy 290.862989 -279.445929) (xy 290.912164 -279.443948)
			(xy 290.961019 -279.44988) (xy 291.00829 -279.463572) (xy 291.052752 -279.48467) (xy 291.093255 -279.512626)
			(xy 291.128748 -279.546718) (xy 291.158313 -279.586062) (xy 291.181184 -279.629639) (xy 291.196768 -279.67632)
			(xy 291.204663 -279.724897) (xy 291.205158 -279.749504) (xy 291.205153 -279.749758) (xy 291.544006 -279.749758)
			(xy 291.547966 -279.700704) (xy 291.559743 -279.65292) (xy 291.579034 -279.607644) (xy 291.605337 -279.566048)
			(xy 291.637972 -279.529211) (xy 291.676093 -279.498086) (xy 291.718714 -279.473479) (xy 291.76473 -279.456027)
			(xy 291.812949 -279.446183) (xy 291.862124 -279.444202) (xy 291.910979 -279.450134) (xy 291.95825 -279.463826)
			(xy 292.002712 -279.484924) (xy 292.043215 -279.51288) (xy 292.078708 -279.546972) (xy 292.108273 -279.586316)
			(xy 292.131144 -279.629893) (xy 292.146728 -279.676574) (xy 292.154623 -279.725151) (xy 292.155113 -279.749504)
			(xy 292.493966 -279.749504) (xy 292.497926 -279.70045) (xy 292.509703 -279.652666) (xy 292.528994 -279.60739)
			(xy 292.555297 -279.565794) (xy 292.587932 -279.528957) (xy 292.626053 -279.497832) (xy 292.668674 -279.473225)
			(xy 292.71469 -279.455773) (xy 292.762909 -279.445929) (xy 292.812084 -279.443948) (xy 292.860939 -279.44988)
			(xy 292.90821 -279.463572) (xy 292.952672 -279.48467) (xy 292.993175 -279.512626) (xy 293.028668 -279.546718)
			(xy 293.058233 -279.586062) (xy 293.081104 -279.629639) (xy 293.096688 -279.67632) (xy 293.104583 -279.724897)
			(xy 293.105078 -279.749504) (xy 293.105073 -279.749758) (xy 293.443926 -279.749758) (xy 293.447886 -279.700704)
			(xy 293.459663 -279.65292) (xy 293.478954 -279.607644) (xy 293.505257 -279.566048) (xy 293.537892 -279.529211)
			(xy 293.576013 -279.498086) (xy 293.618634 -279.473479) (xy 293.66465 -279.456027) (xy 293.712869 -279.446183)
			(xy 293.762044 -279.444202) (xy 293.810899 -279.450134) (xy 293.85817 -279.463826) (xy 293.902632 -279.484924)
			(xy 293.943135 -279.51288) (xy 293.978628 -279.546972) (xy 294.008193 -279.586316) (xy 294.031064 -279.629893)
			(xy 294.046648 -279.676574) (xy 294.054543 -279.725151) (xy 294.055033 -279.749504) (xy 294.393886 -279.749504)
			(xy 294.397846 -279.70045) (xy 294.409623 -279.652666) (xy 294.428914 -279.60739) (xy 294.455217 -279.565794)
			(xy 294.487852 -279.528957) (xy 294.525973 -279.497832) (xy 294.568594 -279.473225) (xy 294.61461 -279.455773)
			(xy 294.662829 -279.445929) (xy 294.712004 -279.443948) (xy 294.760859 -279.44988) (xy 294.80813 -279.463572)
			(xy 294.852592 -279.48467) (xy 294.893095 -279.512626) (xy 294.928588 -279.546718) (xy 294.958153 -279.586062)
			(xy 294.981024 -279.629639) (xy 294.996608 -279.67632) (xy 295.004503 -279.724897) (xy 295.004998 -279.749504)
			(xy 295.004993 -279.749758) (xy 295.3441 -279.749758) (xy 295.34806 -279.700704) (xy 295.359837 -279.65292)
			(xy 295.379128 -279.607644) (xy 295.405431 -279.566048) (xy 295.438066 -279.529211) (xy 295.476187 -279.498086)
			(xy 295.518808 -279.473479) (xy 295.564824 -279.456027) (xy 295.613043 -279.446183) (xy 295.662218 -279.444202)
			(xy 295.711073 -279.450134) (xy 295.758344 -279.463826) (xy 295.802806 -279.484924) (xy 295.843309 -279.51288)
			(xy 295.878802 -279.546972) (xy 295.908367 -279.586316) (xy 295.931238 -279.629893) (xy 295.946822 -279.676574)
			(xy 295.954717 -279.725151) (xy 295.955207 -279.749504) (xy 296.29406 -279.749504) (xy 296.29802 -279.70045)
			(xy 296.309797 -279.652666) (xy 296.329088 -279.60739) (xy 296.355391 -279.565794) (xy 296.388026 -279.528957)
			(xy 296.426147 -279.497832) (xy 296.468768 -279.473225) (xy 296.514784 -279.455773) (xy 296.563003 -279.445929)
			(xy 296.612178 -279.443948) (xy 296.661033 -279.44988) (xy 296.708304 -279.463572) (xy 296.752766 -279.48467)
			(xy 296.793269 -279.512626) (xy 296.828762 -279.546718) (xy 296.858327 -279.586062) (xy 296.881198 -279.629639)
			(xy 296.896782 -279.67632) (xy 296.904677 -279.724897) (xy 296.905172 -279.749504) (xy 296.905167 -279.749758)
			(xy 297.24402 -279.749758) (xy 297.24798 -279.700704) (xy 297.259757 -279.65292) (xy 297.279048 -279.607644)
			(xy 297.305351 -279.566048) (xy 297.337986 -279.529211) (xy 297.376107 -279.498086) (xy 297.418728 -279.473479)
			(xy 297.464744 -279.456027) (xy 297.512963 -279.446183) (xy 297.562138 -279.444202) (xy 297.610993 -279.450134)
			(xy 297.658264 -279.463826) (xy 297.702726 -279.484924) (xy 297.743229 -279.51288) (xy 297.778722 -279.546972)
			(xy 297.808287 -279.586316) (xy 297.831158 -279.629893) (xy 297.846742 -279.676574) (xy 297.854637 -279.725151)
			(xy 297.855127 -279.749504) (xy 298.19398 -279.749504) (xy 298.19794 -279.70045) (xy 298.209717 -279.652666)
			(xy 298.229008 -279.60739) (xy 298.255311 -279.565794) (xy 298.287946 -279.528957) (xy 298.326067 -279.497832)
			(xy 298.368688 -279.473225) (xy 298.414704 -279.455773) (xy 298.462923 -279.445929) (xy 298.512098 -279.443948)
			(xy 298.560953 -279.44988) (xy 298.608224 -279.463572) (xy 298.652686 -279.48467) (xy 298.693189 -279.512626)
			(xy 298.728682 -279.546718) (xy 298.758247 -279.586062) (xy 298.781118 -279.629639) (xy 298.796702 -279.67632)
			(xy 298.804597 -279.724897) (xy 298.805092 -279.749504) (xy 298.805087 -279.749758) (xy 299.14394 -279.749758)
			(xy 299.1479 -279.700704) (xy 299.159677 -279.65292) (xy 299.178968 -279.607644) (xy 299.205271 -279.566048)
			(xy 299.237906 -279.529211) (xy 299.276027 -279.498086) (xy 299.318648 -279.473479) (xy 299.364664 -279.456027)
			(xy 299.412883 -279.446183) (xy 299.462058 -279.444202) (xy 299.510913 -279.450134) (xy 299.558184 -279.463826)
			(xy 299.602646 -279.484924) (xy 299.643149 -279.51288) (xy 299.678642 -279.546972) (xy 299.708207 -279.586316)
			(xy 299.731078 -279.629893) (xy 299.746662 -279.676574) (xy 299.754557 -279.725151) (xy 299.755047 -279.749504)
			(xy 300.0939 -279.749504) (xy 300.09786 -279.70045) (xy 300.109637 -279.652666) (xy 300.128928 -279.60739)
			(xy 300.155231 -279.565794) (xy 300.187866 -279.528957) (xy 300.225987 -279.497832) (xy 300.268608 -279.473225)
			(xy 300.314624 -279.455773) (xy 300.362843 -279.445929) (xy 300.412018 -279.443948) (xy 300.460873 -279.44988)
			(xy 300.508144 -279.463572) (xy 300.552606 -279.48467) (xy 300.593109 -279.512626) (xy 300.628602 -279.546718)
			(xy 300.658167 -279.586062) (xy 300.681038 -279.629639) (xy 300.696622 -279.67632) (xy 300.704517 -279.724897)
			(xy 300.705012 -279.749504) (xy 300.705007 -279.749758) (xy 301.044114 -279.749758) (xy 301.048074 -279.700704)
			(xy 301.059851 -279.65292) (xy 301.079142 -279.607644) (xy 301.105445 -279.566048) (xy 301.13808 -279.529211)
			(xy 301.176201 -279.498086) (xy 301.218822 -279.473479) (xy 301.264838 -279.456027) (xy 301.313057 -279.446183)
			(xy 301.362232 -279.444202) (xy 301.411087 -279.450134) (xy 301.458358 -279.463826) (xy 301.50282 -279.484924)
			(xy 301.543323 -279.51288) (xy 301.578816 -279.546972) (xy 301.608381 -279.586316) (xy 301.631252 -279.629893)
			(xy 301.646836 -279.676574) (xy 301.654731 -279.725151) (xy 301.655221 -279.749504) (xy 301.994074 -279.749504)
			(xy 301.998034 -279.70045) (xy 302.009811 -279.652666) (xy 302.029102 -279.60739) (xy 302.055405 -279.565794)
			(xy 302.08804 -279.528957) (xy 302.126161 -279.497832) (xy 302.168782 -279.473225) (xy 302.214798 -279.455773)
			(xy 302.263017 -279.445929) (xy 302.312192 -279.443948) (xy 302.361047 -279.44988) (xy 302.408318 -279.463572)
			(xy 302.45278 -279.48467) (xy 302.493283 -279.512626) (xy 302.528776 -279.546718) (xy 302.558341 -279.586062)
			(xy 302.581212 -279.629639) (xy 302.596796 -279.67632) (xy 302.604691 -279.724897) (xy 302.605186 -279.749504)
			(xy 302.605181 -279.749758) (xy 302.944034 -279.749758) (xy 302.947994 -279.700704) (xy 302.959771 -279.65292)
			(xy 302.979062 -279.607644) (xy 303.005365 -279.566048) (xy 303.038 -279.529211) (xy 303.076121 -279.498086)
			(xy 303.118742 -279.473479) (xy 303.164758 -279.456027) (xy 303.212977 -279.446183) (xy 303.262152 -279.444202)
			(xy 303.311007 -279.450134) (xy 303.358278 -279.463826) (xy 303.40274 -279.484924) (xy 303.443243 -279.51288)
			(xy 303.478736 -279.546972) (xy 303.508301 -279.586316) (xy 303.531172 -279.629893) (xy 303.546756 -279.676574)
			(xy 303.554651 -279.725151) (xy 303.555141 -279.749504) (xy 303.893994 -279.749504) (xy 303.897954 -279.70045)
			(xy 303.909731 -279.652666) (xy 303.929022 -279.60739) (xy 303.955325 -279.565794) (xy 303.98796 -279.528957)
			(xy 304.026081 -279.497832) (xy 304.068702 -279.473225) (xy 304.114718 -279.455773) (xy 304.162937 -279.445929)
			(xy 304.212112 -279.443948) (xy 304.260967 -279.44988) (xy 304.308238 -279.463572) (xy 304.3527 -279.48467)
			(xy 304.393203 -279.512626) (xy 304.428696 -279.546718) (xy 304.458261 -279.586062) (xy 304.481132 -279.629639)
			(xy 304.496716 -279.67632) (xy 304.504611 -279.724897) (xy 304.505106 -279.749504) (xy 304.505101 -279.749758)
			(xy 304.843954 -279.749758) (xy 304.847914 -279.700704) (xy 304.859691 -279.65292) (xy 304.878982 -279.607644)
			(xy 304.905285 -279.566048) (xy 304.93792 -279.529211) (xy 304.976041 -279.498086) (xy 305.018662 -279.473479)
			(xy 305.064678 -279.456027) (xy 305.112897 -279.446183) (xy 305.162072 -279.444202) (xy 305.210927 -279.450134)
			(xy 305.258198 -279.463826) (xy 305.30266 -279.484924) (xy 305.343163 -279.51288) (xy 305.378656 -279.546972)
			(xy 305.408221 -279.586316) (xy 305.431092 -279.629893) (xy 305.446676 -279.676574) (xy 305.454571 -279.725151)
			(xy 305.455061 -279.749504) (xy 305.793914 -279.749504) (xy 305.797874 -279.70045) (xy 305.809651 -279.652666)
			(xy 305.828942 -279.60739) (xy 305.855245 -279.565794) (xy 305.88788 -279.528957) (xy 305.926001 -279.497832)
			(xy 305.968622 -279.473225) (xy 306.014638 -279.455773) (xy 306.062857 -279.445929) (xy 306.112032 -279.443948)
			(xy 306.160887 -279.44988) (xy 306.208158 -279.463572) (xy 306.25262 -279.48467) (xy 306.293123 -279.512626)
			(xy 306.328616 -279.546718) (xy 306.358181 -279.586062) (xy 306.381052 -279.629639) (xy 306.396636 -279.67632)
			(xy 306.404531 -279.724897) (xy 306.405026 -279.749504) (xy 306.405021 -279.749758) (xy 306.743874 -279.749758)
			(xy 306.747834 -279.700704) (xy 306.759611 -279.65292) (xy 306.778902 -279.607644) (xy 306.805205 -279.566048)
			(xy 306.83784 -279.529211) (xy 306.875961 -279.498086) (xy 306.918582 -279.473479) (xy 306.964598 -279.456027)
			(xy 307.012817 -279.446183) (xy 307.061992 -279.444202) (xy 307.110847 -279.450134) (xy 307.158118 -279.463826)
			(xy 307.20258 -279.484924) (xy 307.243083 -279.51288) (xy 307.278576 -279.546972) (xy 307.308141 -279.586316)
			(xy 307.331012 -279.629893) (xy 307.346596 -279.676574) (xy 307.354491 -279.725151) (xy 307.354981 -279.749504)
			(xy 307.694088 -279.749504) (xy 307.698048 -279.70045) (xy 307.709825 -279.652666) (xy 307.729116 -279.60739)
			(xy 307.755419 -279.565794) (xy 307.788054 -279.528957) (xy 307.826175 -279.497832) (xy 307.868796 -279.473225)
			(xy 307.914812 -279.455773) (xy 307.963031 -279.445929) (xy 308.012206 -279.443948) (xy 308.061061 -279.44988)
			(xy 308.108332 -279.463572) (xy 308.152794 -279.48467) (xy 308.193297 -279.512626) (xy 308.22879 -279.546718)
			(xy 308.258355 -279.586062) (xy 308.281226 -279.629639) (xy 308.29681 -279.67632) (xy 308.304705 -279.724897)
			(xy 308.3052 -279.749504) (xy 308.305195 -279.749758) (xy 308.644048 -279.749758) (xy 308.648008 -279.700704)
			(xy 308.659785 -279.65292) (xy 308.679076 -279.607644) (xy 308.705379 -279.566048) (xy 308.738014 -279.529211)
			(xy 308.776135 -279.498086) (xy 308.818756 -279.473479) (xy 308.864772 -279.456027) (xy 308.912991 -279.446183)
			(xy 308.962166 -279.444202) (xy 309.011021 -279.450134) (xy 309.058292 -279.463826) (xy 309.102754 -279.484924)
			(xy 309.143257 -279.51288) (xy 309.17875 -279.546972) (xy 309.208315 -279.586316) (xy 309.231186 -279.629893)
			(xy 309.24677 -279.676574) (xy 309.254665 -279.725151) (xy 309.255155 -279.749504) (xy 309.594008 -279.749504)
			(xy 309.597968 -279.70045) (xy 309.609745 -279.652666) (xy 309.629036 -279.60739) (xy 309.655339 -279.565794)
			(xy 309.687974 -279.528957) (xy 309.726095 -279.497832) (xy 309.768716 -279.473225) (xy 309.814732 -279.455773)
			(xy 309.862951 -279.445929) (xy 309.912126 -279.443948) (xy 309.960981 -279.44988) (xy 310.008252 -279.463572)
			(xy 310.052714 -279.48467) (xy 310.093217 -279.512626) (xy 310.12871 -279.546718) (xy 310.158275 -279.586062)
			(xy 310.181146 -279.629639) (xy 310.19673 -279.67632) (xy 310.204625 -279.724897) (xy 310.20512 -279.749504)
			(xy 310.205115 -279.749758) (xy 310.543968 -279.749758) (xy 310.547928 -279.700704) (xy 310.559705 -279.65292)
			(xy 310.578996 -279.607644) (xy 310.605299 -279.566048) (xy 310.637934 -279.529211) (xy 310.676055 -279.498086)
			(xy 310.718676 -279.473479) (xy 310.764692 -279.456027) (xy 310.812911 -279.446183) (xy 310.862086 -279.444202)
			(xy 310.910941 -279.450134) (xy 310.958212 -279.463826) (xy 311.002674 -279.484924) (xy 311.043177 -279.51288)
			(xy 311.07867 -279.546972) (xy 311.108235 -279.586316) (xy 311.131106 -279.629893) (xy 311.14669 -279.676574)
			(xy 311.154585 -279.725151) (xy 311.15508 -279.749758) (xy 311.493928 -279.749758) (xy 311.497888 -279.700704)
			(xy 311.509665 -279.65292) (xy 311.528956 -279.607644) (xy 311.555259 -279.566048) (xy 311.587894 -279.529211)
			(xy 311.626015 -279.498086) (xy 311.668636 -279.473479) (xy 311.714652 -279.456027) (xy 311.762871 -279.446183)
			(xy 311.812046 -279.444202) (xy 311.860901 -279.450134) (xy 311.908172 -279.463826) (xy 311.952634 -279.484924)
			(xy 311.993137 -279.51288) (xy 312.02863 -279.546972) (xy 312.058195 -279.586316) (xy 312.081066 -279.629893)
			(xy 312.09665 -279.676574) (xy 312.104545 -279.725151) (xy 312.10504 -279.749758) (xy 312.443888 -279.749758)
			(xy 312.447848 -279.700704) (xy 312.459625 -279.65292) (xy 312.478916 -279.607644) (xy 312.505219 -279.566048)
			(xy 312.537854 -279.529211) (xy 312.575975 -279.498086) (xy 312.618596 -279.473479) (xy 312.664612 -279.456027)
			(xy 312.712831 -279.446183) (xy 312.762006 -279.444202) (xy 312.810861 -279.450134) (xy 312.858132 -279.463826)
			(xy 312.902594 -279.484924) (xy 312.943097 -279.51288) (xy 312.97859 -279.546972) (xy 313.008155 -279.586316)
			(xy 313.031026 -279.629893) (xy 313.04661 -279.676574) (xy 313.054505 -279.725151) (xy 313.055 -279.749758)
			(xy 313.394102 -279.749758) (xy 313.398062 -279.700704) (xy 313.409839 -279.65292) (xy 313.42913 -279.607644)
			(xy 313.455433 -279.566048) (xy 313.488068 -279.529211) (xy 313.526189 -279.498086) (xy 313.56881 -279.473479)
			(xy 313.614826 -279.456027) (xy 313.663045 -279.446183) (xy 313.71222 -279.444202) (xy 313.761075 -279.450134)
			(xy 313.808346 -279.463826) (xy 313.852808 -279.484924) (xy 313.893311 -279.51288) (xy 313.928804 -279.546972)
			(xy 313.958369 -279.586316) (xy 313.98124 -279.629893) (xy 313.996824 -279.676574) (xy 314.004719 -279.725151)
			(xy 314.005214 -279.749758) (xy 314.344062 -279.749758) (xy 314.348022 -279.700704) (xy 314.359799 -279.65292)
			(xy 314.37909 -279.607644) (xy 314.405393 -279.566048) (xy 314.438028 -279.529211) (xy 314.476149 -279.498086)
			(xy 314.51877 -279.473479) (xy 314.564786 -279.456027) (xy 314.613005 -279.446183) (xy 314.66218 -279.444202)
			(xy 314.711035 -279.450134) (xy 314.758306 -279.463826) (xy 314.802768 -279.484924) (xy 314.843271 -279.51288)
			(xy 314.878764 -279.546972) (xy 314.908329 -279.586316) (xy 314.9312 -279.629893) (xy 314.946784 -279.676574)
			(xy 314.954679 -279.725151) (xy 314.955174 -279.749758) (xy 314.955169 -279.750012) (xy 315.294276 -279.750012)
			(xy 315.298236 -279.700958) (xy 315.310013 -279.653174) (xy 315.329304 -279.607898) (xy 315.355607 -279.566302)
			(xy 315.388242 -279.529465) (xy 315.426363 -279.49834) (xy 315.468984 -279.473733) (xy 315.515 -279.456281)
			(xy 315.563219 -279.446437) (xy 315.612394 -279.444456) (xy 315.661249 -279.450388) (xy 315.70852 -279.46408)
			(xy 315.752982 -279.485178) (xy 315.793485 -279.513134) (xy 315.828978 -279.547226) (xy 315.858543 -279.58657)
			(xy 315.881414 -279.630147) (xy 315.896998 -279.676828) (xy 315.904893 -279.725405) (xy 315.905388 -279.750012)
			(xy 315.904893 -279.774619) (xy 315.896998 -279.823196) (xy 315.881414 -279.869877) (xy 315.858543 -279.913454)
			(xy 315.828978 -279.952798) (xy 315.793485 -279.98689) (xy 315.752982 -280.014846) (xy 315.70852 -280.035944)
			(xy 315.661249 -280.049636) (xy 315.612394 -280.055568) (xy 315.563219 -280.053587) (xy 315.515 -280.043743)
			(xy 315.468984 -280.026291) (xy 315.426363 -280.001684) (xy 315.388242 -279.970559) (xy 315.355607 -279.933722)
			(xy 315.329304 -279.892126) (xy 315.310013 -279.84685) (xy 315.298236 -279.799066) (xy 315.294276 -279.750012)
			(xy 314.955169 -279.750012) (xy 314.954679 -279.774365) (xy 314.946784 -279.822942) (xy 314.9312 -279.869623)
			(xy 314.908329 -279.9132) (xy 314.878764 -279.952544) (xy 314.843271 -279.986636) (xy 314.802768 -280.014592)
			(xy 314.758306 -280.03569) (xy 314.711035 -280.049382) (xy 314.66218 -280.055314) (xy 314.613005 -280.053333)
			(xy 314.564786 -280.043489) (xy 314.51877 -280.026037) (xy 314.476149 -280.00143) (xy 314.438028 -279.970305)
			(xy 314.405393 -279.933468) (xy 314.37909 -279.891872) (xy 314.359799 -279.846596) (xy 314.348022 -279.798812)
			(xy 314.344062 -279.749758) (xy 314.005214 -279.749758) (xy 314.004719 -279.774365) (xy 313.996824 -279.822942)
			(xy 313.98124 -279.869623) (xy 313.958369 -279.9132) (xy 313.928804 -279.952544) (xy 313.893311 -279.986636)
			(xy 313.852808 -280.014592) (xy 313.808346 -280.03569) (xy 313.761075 -280.049382) (xy 313.71222 -280.055314)
			(xy 313.663045 -280.053333) (xy 313.614826 -280.043489) (xy 313.56881 -280.026037) (xy 313.526189 -280.00143)
			(xy 313.488068 -279.970305) (xy 313.455433 -279.933468) (xy 313.42913 -279.891872) (xy 313.409839 -279.846596)
			(xy 313.398062 -279.798812) (xy 313.394102 -279.749758) (xy 313.055 -279.749758) (xy 313.054505 -279.774365)
			(xy 313.04661 -279.822942) (xy 313.031026 -279.869623) (xy 313.008155 -279.9132) (xy 312.97859 -279.952544)
			(xy 312.943097 -279.986636) (xy 312.902594 -280.014592) (xy 312.858132 -280.03569) (xy 312.810861 -280.049382)
			(xy 312.762006 -280.055314) (xy 312.712831 -280.053333) (xy 312.664612 -280.043489) (xy 312.618596 -280.026037)
			(xy 312.575975 -280.00143) (xy 312.537854 -279.970305) (xy 312.505219 -279.933468) (xy 312.478916 -279.891872)
			(xy 312.459625 -279.846596) (xy 312.447848 -279.798812) (xy 312.443888 -279.749758) (xy 312.10504 -279.749758)
			(xy 312.104545 -279.774365) (xy 312.09665 -279.822942) (xy 312.081066 -279.869623) (xy 312.058195 -279.9132)
			(xy 312.02863 -279.952544) (xy 311.993137 -279.986636) (xy 311.952634 -280.014592) (xy 311.908172 -280.03569)
			(xy 311.860901 -280.049382) (xy 311.812046 -280.055314) (xy 311.762871 -280.053333) (xy 311.714652 -280.043489)
			(xy 311.668636 -280.026037) (xy 311.626015 -280.00143) (xy 311.587894 -279.970305) (xy 311.555259 -279.933468)
			(xy 311.528956 -279.891872) (xy 311.509665 -279.846596) (xy 311.497888 -279.798812) (xy 311.493928 -279.749758)
			(xy 311.15508 -279.749758) (xy 311.154585 -279.774365) (xy 311.14669 -279.822942) (xy 311.131106 -279.869623)
			(xy 311.108235 -279.9132) (xy 311.07867 -279.952544) (xy 311.043177 -279.986636) (xy 311.002674 -280.014592)
			(xy 310.958212 -280.03569) (xy 310.910941 -280.049382) (xy 310.862086 -280.055314) (xy 310.812911 -280.053333)
			(xy 310.764692 -280.043489) (xy 310.718676 -280.026037) (xy 310.676055 -280.00143) (xy 310.637934 -279.970305)
			(xy 310.605299 -279.933468) (xy 310.578996 -279.891872) (xy 310.559705 -279.846596) (xy 310.547928 -279.798812)
			(xy 310.543968 -279.749758) (xy 310.205115 -279.749758) (xy 310.204625 -279.774111) (xy 310.19673 -279.822688)
			(xy 310.181146 -279.869369) (xy 310.158275 -279.912946) (xy 310.12871 -279.95229) (xy 310.093217 -279.986382)
			(xy 310.052714 -280.014338) (xy 310.008252 -280.035436) (xy 309.960981 -280.049128) (xy 309.912126 -280.05506)
			(xy 309.862951 -280.053079) (xy 309.814732 -280.043235) (xy 309.768716 -280.025783) (xy 309.726095 -280.001176)
			(xy 309.687974 -279.970051) (xy 309.655339 -279.933214) (xy 309.629036 -279.891618) (xy 309.609745 -279.846342)
			(xy 309.597968 -279.798558) (xy 309.594008 -279.749504) (xy 309.255155 -279.749504) (xy 309.25516 -279.749758)
			(xy 309.254665 -279.774365) (xy 309.24677 -279.822942) (xy 309.231186 -279.869623) (xy 309.208315 -279.9132)
			(xy 309.17875 -279.952544) (xy 309.143257 -279.986636) (xy 309.102754 -280.014592) (xy 309.058292 -280.03569)
			(xy 309.011021 -280.049382) (xy 308.962166 -280.055314) (xy 308.912991 -280.053333) (xy 308.864772 -280.043489)
			(xy 308.818756 -280.026037) (xy 308.776135 -280.00143) (xy 308.738014 -279.970305) (xy 308.705379 -279.933468)
			(xy 308.679076 -279.891872) (xy 308.659785 -279.846596) (xy 308.648008 -279.798812) (xy 308.644048 -279.749758)
			(xy 308.305195 -279.749758) (xy 308.304705 -279.774111) (xy 308.29681 -279.822688) (xy 308.281226 -279.869369)
			(xy 308.258355 -279.912946) (xy 308.22879 -279.95229) (xy 308.193297 -279.986382) (xy 308.152794 -280.014338)
			(xy 308.108332 -280.035436) (xy 308.061061 -280.049128) (xy 308.012206 -280.05506) (xy 307.963031 -280.053079)
			(xy 307.914812 -280.043235) (xy 307.868796 -280.025783) (xy 307.826175 -280.001176) (xy 307.788054 -279.970051)
			(xy 307.755419 -279.933214) (xy 307.729116 -279.891618) (xy 307.709825 -279.846342) (xy 307.698048 -279.798558)
			(xy 307.694088 -279.749504) (xy 307.354981 -279.749504) (xy 307.354986 -279.749758) (xy 307.354491 -279.774365)
			(xy 307.346596 -279.822942) (xy 307.331012 -279.869623) (xy 307.308141 -279.9132) (xy 307.278576 -279.952544)
			(xy 307.243083 -279.986636) (xy 307.20258 -280.014592) (xy 307.158118 -280.03569) (xy 307.110847 -280.049382)
			(xy 307.061992 -280.055314) (xy 307.012817 -280.053333) (xy 306.964598 -280.043489) (xy 306.918582 -280.026037)
			(xy 306.875961 -280.00143) (xy 306.83784 -279.970305) (xy 306.805205 -279.933468) (xy 306.778902 -279.891872)
			(xy 306.759611 -279.846596) (xy 306.747834 -279.798812) (xy 306.743874 -279.749758) (xy 306.405021 -279.749758)
			(xy 306.404531 -279.774111) (xy 306.396636 -279.822688) (xy 306.381052 -279.869369) (xy 306.358181 -279.912946)
			(xy 306.328616 -279.95229) (xy 306.293123 -279.986382) (xy 306.25262 -280.014338) (xy 306.208158 -280.035436)
			(xy 306.160887 -280.049128) (xy 306.112032 -280.05506) (xy 306.062857 -280.053079) (xy 306.014638 -280.043235)
			(xy 305.968622 -280.025783) (xy 305.926001 -280.001176) (xy 305.88788 -279.970051) (xy 305.855245 -279.933214)
			(xy 305.828942 -279.891618) (xy 305.809651 -279.846342) (xy 305.797874 -279.798558) (xy 305.793914 -279.749504)
			(xy 305.455061 -279.749504) (xy 305.455066 -279.749758) (xy 305.454571 -279.774365) (xy 305.446676 -279.822942)
			(xy 305.431092 -279.869623) (xy 305.408221 -279.9132) (xy 305.378656 -279.952544) (xy 305.343163 -279.986636)
			(xy 305.30266 -280.014592) (xy 305.258198 -280.03569) (xy 305.210927 -280.049382) (xy 305.162072 -280.055314)
			(xy 305.112897 -280.053333) (xy 305.064678 -280.043489) (xy 305.018662 -280.026037) (xy 304.976041 -280.00143)
			(xy 304.93792 -279.970305) (xy 304.905285 -279.933468) (xy 304.878982 -279.891872) (xy 304.859691 -279.846596)
			(xy 304.847914 -279.798812) (xy 304.843954 -279.749758) (xy 304.505101 -279.749758) (xy 304.504611 -279.774111)
			(xy 304.496716 -279.822688) (xy 304.481132 -279.869369) (xy 304.458261 -279.912946) (xy 304.428696 -279.95229)
			(xy 304.393203 -279.986382) (xy 304.3527 -280.014338) (xy 304.308238 -280.035436) (xy 304.260967 -280.049128)
			(xy 304.212112 -280.05506) (xy 304.162937 -280.053079) (xy 304.114718 -280.043235) (xy 304.068702 -280.025783)
			(xy 304.026081 -280.001176) (xy 303.98796 -279.970051) (xy 303.955325 -279.933214) (xy 303.929022 -279.891618)
			(xy 303.909731 -279.846342) (xy 303.897954 -279.798558) (xy 303.893994 -279.749504) (xy 303.555141 -279.749504)
			(xy 303.555146 -279.749758) (xy 303.554651 -279.774365) (xy 303.546756 -279.822942) (xy 303.531172 -279.869623)
			(xy 303.508301 -279.9132) (xy 303.478736 -279.952544) (xy 303.443243 -279.986636) (xy 303.40274 -280.014592)
			(xy 303.358278 -280.03569) (xy 303.311007 -280.049382) (xy 303.262152 -280.055314) (xy 303.212977 -280.053333)
			(xy 303.164758 -280.043489) (xy 303.118742 -280.026037) (xy 303.076121 -280.00143) (xy 303.038 -279.970305)
			(xy 303.005365 -279.933468) (xy 302.979062 -279.891872) (xy 302.959771 -279.846596) (xy 302.947994 -279.798812)
			(xy 302.944034 -279.749758) (xy 302.605181 -279.749758) (xy 302.604691 -279.774111) (xy 302.596796 -279.822688)
			(xy 302.581212 -279.869369) (xy 302.558341 -279.912946) (xy 302.528776 -279.95229) (xy 302.493283 -279.986382)
			(xy 302.45278 -280.014338) (xy 302.408318 -280.035436) (xy 302.361047 -280.049128) (xy 302.312192 -280.05506)
			(xy 302.263017 -280.053079) (xy 302.214798 -280.043235) (xy 302.168782 -280.025783) (xy 302.126161 -280.001176)
			(xy 302.08804 -279.970051) (xy 302.055405 -279.933214) (xy 302.029102 -279.891618) (xy 302.009811 -279.846342)
			(xy 301.998034 -279.798558) (xy 301.994074 -279.749504) (xy 301.655221 -279.749504) (xy 301.655226 -279.749758)
			(xy 301.654731 -279.774365) (xy 301.646836 -279.822942) (xy 301.631252 -279.869623) (xy 301.608381 -279.9132)
			(xy 301.578816 -279.952544) (xy 301.543323 -279.986636) (xy 301.50282 -280.014592) (xy 301.458358 -280.03569)
			(xy 301.411087 -280.049382) (xy 301.362232 -280.055314) (xy 301.313057 -280.053333) (xy 301.264838 -280.043489)
			(xy 301.218822 -280.026037) (xy 301.176201 -280.00143) (xy 301.13808 -279.970305) (xy 301.105445 -279.933468)
			(xy 301.079142 -279.891872) (xy 301.059851 -279.846596) (xy 301.048074 -279.798812) (xy 301.044114 -279.749758)
			(xy 300.705007 -279.749758) (xy 300.704517 -279.774111) (xy 300.696622 -279.822688) (xy 300.681038 -279.869369)
			(xy 300.658167 -279.912946) (xy 300.628602 -279.95229) (xy 300.593109 -279.986382) (xy 300.552606 -280.014338)
			(xy 300.508144 -280.035436) (xy 300.460873 -280.049128) (xy 300.412018 -280.05506) (xy 300.362843 -280.053079)
			(xy 300.314624 -280.043235) (xy 300.268608 -280.025783) (xy 300.225987 -280.001176) (xy 300.187866 -279.970051)
			(xy 300.155231 -279.933214) (xy 300.128928 -279.891618) (xy 300.109637 -279.846342) (xy 300.09786 -279.798558)
			(xy 300.0939 -279.749504) (xy 299.755047 -279.749504) (xy 299.755052 -279.749758) (xy 299.754557 -279.774365)
			(xy 299.746662 -279.822942) (xy 299.731078 -279.869623) (xy 299.708207 -279.9132) (xy 299.678642 -279.952544)
			(xy 299.643149 -279.986636) (xy 299.602646 -280.014592) (xy 299.558184 -280.03569) (xy 299.510913 -280.049382)
			(xy 299.462058 -280.055314) (xy 299.412883 -280.053333) (xy 299.364664 -280.043489) (xy 299.318648 -280.026037)
			(xy 299.276027 -280.00143) (xy 299.237906 -279.970305) (xy 299.205271 -279.933468) (xy 299.178968 -279.891872)
			(xy 299.159677 -279.846596) (xy 299.1479 -279.798812) (xy 299.14394 -279.749758) (xy 298.805087 -279.749758)
			(xy 298.804597 -279.774111) (xy 298.796702 -279.822688) (xy 298.781118 -279.869369) (xy 298.758247 -279.912946)
			(xy 298.728682 -279.95229) (xy 298.693189 -279.986382) (xy 298.652686 -280.014338) (xy 298.608224 -280.035436)
			(xy 298.560953 -280.049128) (xy 298.512098 -280.05506) (xy 298.462923 -280.053079) (xy 298.414704 -280.043235)
			(xy 298.368688 -280.025783) (xy 298.326067 -280.001176) (xy 298.287946 -279.970051) (xy 298.255311 -279.933214)
			(xy 298.229008 -279.891618) (xy 298.209717 -279.846342) (xy 298.19794 -279.798558) (xy 298.19398 -279.749504)
			(xy 297.855127 -279.749504) (xy 297.855132 -279.749758) (xy 297.854637 -279.774365) (xy 297.846742 -279.822942)
			(xy 297.831158 -279.869623) (xy 297.808287 -279.9132) (xy 297.778722 -279.952544) (xy 297.743229 -279.986636)
			(xy 297.702726 -280.014592) (xy 297.658264 -280.03569) (xy 297.610993 -280.049382) (xy 297.562138 -280.055314)
			(xy 297.512963 -280.053333) (xy 297.464744 -280.043489) (xy 297.418728 -280.026037) (xy 297.376107 -280.00143)
			(xy 297.337986 -279.970305) (xy 297.305351 -279.933468) (xy 297.279048 -279.891872) (xy 297.259757 -279.846596)
			(xy 297.24798 -279.798812) (xy 297.24402 -279.749758) (xy 296.905167 -279.749758) (xy 296.904677 -279.774111)
			(xy 296.896782 -279.822688) (xy 296.881198 -279.869369) (xy 296.858327 -279.912946) (xy 296.828762 -279.95229)
			(xy 296.793269 -279.986382) (xy 296.752766 -280.014338) (xy 296.708304 -280.035436) (xy 296.661033 -280.049128)
			(xy 296.612178 -280.05506) (xy 296.563003 -280.053079) (xy 296.514784 -280.043235) (xy 296.468768 -280.025783)
			(xy 296.426147 -280.001176) (xy 296.388026 -279.970051) (xy 296.355391 -279.933214) (xy 296.329088 -279.891618)
			(xy 296.309797 -279.846342) (xy 296.29802 -279.798558) (xy 296.29406 -279.749504) (xy 295.955207 -279.749504)
			(xy 295.955212 -279.749758) (xy 295.954717 -279.774365) (xy 295.946822 -279.822942) (xy 295.931238 -279.869623)
			(xy 295.908367 -279.9132) (xy 295.878802 -279.952544) (xy 295.843309 -279.986636) (xy 295.802806 -280.014592)
			(xy 295.758344 -280.03569) (xy 295.711073 -280.049382) (xy 295.662218 -280.055314) (xy 295.613043 -280.053333)
			(xy 295.564824 -280.043489) (xy 295.518808 -280.026037) (xy 295.476187 -280.00143) (xy 295.438066 -279.970305)
			(xy 295.405431 -279.933468) (xy 295.379128 -279.891872) (xy 295.359837 -279.846596) (xy 295.34806 -279.798812)
			(xy 295.3441 -279.749758) (xy 295.004993 -279.749758) (xy 295.004503 -279.774111) (xy 294.996608 -279.822688)
			(xy 294.981024 -279.869369) (xy 294.958153 -279.912946) (xy 294.928588 -279.95229) (xy 294.893095 -279.986382)
			(xy 294.852592 -280.014338) (xy 294.80813 -280.035436) (xy 294.760859 -280.049128) (xy 294.712004 -280.05506)
			(xy 294.662829 -280.053079) (xy 294.61461 -280.043235) (xy 294.568594 -280.025783) (xy 294.525973 -280.001176)
			(xy 294.487852 -279.970051) (xy 294.455217 -279.933214) (xy 294.428914 -279.891618) (xy 294.409623 -279.846342)
			(xy 294.397846 -279.798558) (xy 294.393886 -279.749504) (xy 294.055033 -279.749504) (xy 294.055038 -279.749758)
			(xy 294.054543 -279.774365) (xy 294.046648 -279.822942) (xy 294.031064 -279.869623) (xy 294.008193 -279.9132)
			(xy 293.978628 -279.952544) (xy 293.943135 -279.986636) (xy 293.902632 -280.014592) (xy 293.85817 -280.03569)
			(xy 293.810899 -280.049382) (xy 293.762044 -280.055314) (xy 293.712869 -280.053333) (xy 293.66465 -280.043489)
			(xy 293.618634 -280.026037) (xy 293.576013 -280.00143) (xy 293.537892 -279.970305) (xy 293.505257 -279.933468)
			(xy 293.478954 -279.891872) (xy 293.459663 -279.846596) (xy 293.447886 -279.798812) (xy 293.443926 -279.749758)
			(xy 293.105073 -279.749758) (xy 293.104583 -279.774111) (xy 293.096688 -279.822688) (xy 293.081104 -279.869369)
			(xy 293.058233 -279.912946) (xy 293.028668 -279.95229) (xy 292.993175 -279.986382) (xy 292.952672 -280.014338)
			(xy 292.90821 -280.035436) (xy 292.860939 -280.049128) (xy 292.812084 -280.05506) (xy 292.762909 -280.053079)
			(xy 292.71469 -280.043235) (xy 292.668674 -280.025783) (xy 292.626053 -280.001176) (xy 292.587932 -279.970051)
			(xy 292.555297 -279.933214) (xy 292.528994 -279.891618) (xy 292.509703 -279.846342) (xy 292.497926 -279.798558)
			(xy 292.493966 -279.749504) (xy 292.155113 -279.749504) (xy 292.155118 -279.749758) (xy 292.154623 -279.774365)
			(xy 292.146728 -279.822942) (xy 292.131144 -279.869623) (xy 292.108273 -279.9132) (xy 292.078708 -279.952544)
			(xy 292.043215 -279.986636) (xy 292.002712 -280.014592) (xy 291.95825 -280.03569) (xy 291.910979 -280.049382)
			(xy 291.862124 -280.055314) (xy 291.812949 -280.053333) (xy 291.76473 -280.043489) (xy 291.718714 -280.026037)
			(xy 291.676093 -280.00143) (xy 291.637972 -279.970305) (xy 291.605337 -279.933468) (xy 291.579034 -279.891872)
			(xy 291.559743 -279.846596) (xy 291.547966 -279.798812) (xy 291.544006 -279.749758) (xy 291.205153 -279.749758)
			(xy 291.204663 -279.774111) (xy 291.196768 -279.822688) (xy 291.181184 -279.869369) (xy 291.158313 -279.912946)
			(xy 291.128748 -279.95229) (xy 291.093255 -279.986382) (xy 291.052752 -280.014338) (xy 291.00829 -280.035436)
			(xy 290.961019 -280.049128) (xy 290.912164 -280.05506) (xy 290.862989 -280.053079) (xy 290.81477 -280.043235)
			(xy 290.768754 -280.025783) (xy 290.726133 -280.001176) (xy 290.688012 -279.970051) (xy 290.655377 -279.933214)
			(xy 290.629074 -279.891618) (xy 290.609783 -279.846342) (xy 290.598006 -279.798558) (xy 290.594046 -279.749504)
			(xy 290.255193 -279.749504) (xy 290.255198 -279.749758) (xy 290.254703 -279.774365) (xy 290.246808 -279.822942)
			(xy 290.231224 -279.869623) (xy 290.208353 -279.9132) (xy 290.178788 -279.952544) (xy 290.143295 -279.986636)
			(xy 290.102792 -280.014592) (xy 290.05833 -280.03569) (xy 290.011059 -280.049382) (xy 289.962204 -280.055314)
			(xy 289.913029 -280.053333) (xy 289.86481 -280.043489) (xy 289.818794 -280.026037) (xy 289.776173 -280.00143)
			(xy 289.738052 -279.970305) (xy 289.705417 -279.933468) (xy 289.679114 -279.891872) (xy 289.659823 -279.846596)
			(xy 289.648046 -279.798812) (xy 289.644086 -279.749758) (xy 289.304979 -279.749758) (xy 289.304489 -279.774111)
			(xy 289.296594 -279.822688) (xy 289.28101 -279.869369) (xy 289.258139 -279.912946) (xy 289.228574 -279.95229)
			(xy 289.193081 -279.986382) (xy 289.152578 -280.014338) (xy 289.108116 -280.035436) (xy 289.060845 -280.049128)
			(xy 289.01199 -280.05506) (xy 288.962815 -280.053079) (xy 288.914596 -280.043235) (xy 288.86858 -280.025783)
			(xy 288.825959 -280.001176) (xy 288.787838 -279.970051) (xy 288.755203 -279.933214) (xy 288.7289 -279.891618)
			(xy 288.709609 -279.846342) (xy 288.697832 -279.798558) (xy 288.693872 -279.749504) (xy 288.355019 -279.749504)
			(xy 288.355024 -279.749758) (xy 288.354529 -279.774365) (xy 288.346634 -279.822942) (xy 288.33105 -279.869623)
			(xy 288.308179 -279.9132) (xy 288.278614 -279.952544) (xy 288.243121 -279.986636) (xy 288.202618 -280.014592)
			(xy 288.158156 -280.03569) (xy 288.110885 -280.049382) (xy 288.06203 -280.055314) (xy 288.012855 -280.053333)
			(xy 287.964636 -280.043489) (xy 287.91862 -280.026037) (xy 287.875999 -280.00143) (xy 287.837878 -279.970305)
			(xy 287.805243 -279.933468) (xy 287.77894 -279.891872) (xy 287.759649 -279.846596) (xy 287.747872 -279.798812)
			(xy 287.743912 -279.749758) (xy 287.405059 -279.749758) (xy 287.404569 -279.774111) (xy 287.396674 -279.822688)
			(xy 287.38109 -279.869369) (xy 287.358219 -279.912946) (xy 287.328654 -279.95229) (xy 287.293161 -279.986382)
			(xy 287.252658 -280.014338) (xy 287.208196 -280.035436) (xy 287.160925 -280.049128) (xy 287.11207 -280.05506)
			(xy 287.062895 -280.053079) (xy 287.014676 -280.043235) (xy 286.96866 -280.025783) (xy 286.926039 -280.001176)
			(xy 286.887918 -279.970051) (xy 286.855283 -279.933214) (xy 286.82898 -279.891618) (xy 286.809689 -279.846342)
			(xy 286.797912 -279.798558) (xy 286.793952 -279.749504) (xy 286.455099 -279.749504) (xy 286.455104 -279.749758)
			(xy 286.454609 -279.774365) (xy 286.446714 -279.822942) (xy 286.43113 -279.869623) (xy 286.408259 -279.9132)
			(xy 286.378694 -279.952544) (xy 286.343201 -279.986636) (xy 286.302698 -280.014592) (xy 286.258236 -280.03569)
			(xy 286.210965 -280.049382) (xy 286.16211 -280.055314) (xy 286.112935 -280.053333) (xy 286.064716 -280.043489)
			(xy 286.0187 -280.026037) (xy 285.976079 -280.00143) (xy 285.937958 -279.970305) (xy 285.905323 -279.933468)
			(xy 285.87902 -279.891872) (xy 285.859729 -279.846596) (xy 285.847952 -279.798812) (xy 285.843992 -279.749758)
			(xy 285.505139 -279.749758) (xy 285.504649 -279.774111) (xy 285.496754 -279.822688) (xy 285.48117 -279.869369)
			(xy 285.458299 -279.912946) (xy 285.428734 -279.95229) (xy 285.393241 -279.986382) (xy 285.352738 -280.014338)
			(xy 285.308276 -280.035436) (xy 285.261005 -280.049128) (xy 285.21215 -280.05506) (xy 285.162975 -280.053079)
			(xy 285.114756 -280.043235) (xy 285.06874 -280.025783) (xy 285.026119 -280.001176) (xy 284.987998 -279.970051)
			(xy 284.955363 -279.933214) (xy 284.92906 -279.891618) (xy 284.909769 -279.846342) (xy 284.897992 -279.798558)
			(xy 284.894032 -279.749504) (xy 284.555179 -279.749504) (xy 284.555184 -279.749758) (xy 284.554689 -279.774365)
			(xy 284.546794 -279.822942) (xy 284.53121 -279.869623) (xy 284.508339 -279.9132) (xy 284.478774 -279.952544)
			(xy 284.443281 -279.986636) (xy 284.402778 -280.014592) (xy 284.358316 -280.03569) (xy 284.311045 -280.049382)
			(xy 284.26219 -280.055314) (xy 284.213015 -280.053333) (xy 284.164796 -280.043489) (xy 284.11878 -280.026037)
			(xy 284.076159 -280.00143) (xy 284.038038 -279.970305) (xy 284.005403 -279.933468) (xy 283.9791 -279.891872)
			(xy 283.959809 -279.846596) (xy 283.948032 -279.798812) (xy 283.944072 -279.749758) (xy 283.605219 -279.749758)
			(xy 283.604729 -279.774111) (xy 283.596834 -279.822688) (xy 283.58125 -279.869369) (xy 283.558379 -279.912946)
			(xy 283.528814 -279.95229) (xy 283.493321 -279.986382) (xy 283.452818 -280.014338) (xy 283.408356 -280.035436)
			(xy 283.361085 -280.049128) (xy 283.31223 -280.05506) (xy 283.263055 -280.053079) (xy 283.214836 -280.043235)
			(xy 283.16882 -280.025783) (xy 283.126199 -280.001176) (xy 283.088078 -279.970051) (xy 283.055443 -279.933214)
			(xy 283.02914 -279.891618) (xy 283.009849 -279.846342) (xy 282.998072 -279.798558) (xy 282.994112 -279.749504)
			(xy 282.655005 -279.749504) (xy 282.65501 -279.749758) (xy 282.654515 -279.774365) (xy 282.64662 -279.822942)
			(xy 282.631036 -279.869623) (xy 282.608165 -279.9132) (xy 282.5786 -279.952544) (xy 282.543107 -279.986636)
			(xy 282.502604 -280.014592) (xy 282.458142 -280.03569) (xy 282.410871 -280.049382) (xy 282.362016 -280.055314)
			(xy 282.312841 -280.053333) (xy 282.264622 -280.043489) (xy 282.218606 -280.026037) (xy 282.175985 -280.00143)
			(xy 282.137864 -279.970305) (xy 282.105229 -279.933468) (xy 282.078926 -279.891872) (xy 282.059635 -279.846596)
			(xy 282.047858 -279.798812) (xy 282.043898 -279.749758) (xy 281.705045 -279.749758) (xy 281.704555 -279.774111)
			(xy 281.69666 -279.822688) (xy 281.681076 -279.869369) (xy 281.658205 -279.912946) (xy 281.62864 -279.95229)
			(xy 281.593147 -279.986382) (xy 281.552644 -280.014338) (xy 281.508182 -280.035436) (xy 281.460911 -280.049128)
			(xy 281.412056 -280.05506) (xy 281.362881 -280.053079) (xy 281.314662 -280.043235) (xy 281.268646 -280.025783)
			(xy 281.226025 -280.001176) (xy 281.187904 -279.970051) (xy 281.155269 -279.933214) (xy 281.128966 -279.891618)
			(xy 281.109675 -279.846342) (xy 281.097898 -279.798558) (xy 281.093938 -279.749504) (xy 280.755677 -279.749504)
			(xy 280.755702 -279.7498) (xy 280.75153 -279.800152) (xy 280.739126 -279.84913) (xy 280.71883 -279.895398)
			(xy 280.691195 -279.937695) (xy 280.656975 -279.974866) (xy 280.617103 -280.005897) (xy 280.572667 -280.029942)
			(xy 280.52488 -280.046345) (xy 280.475044 -280.054659) (xy 280.449782 -280.055066) (xy 280.421083 -280.054411)
			(xy 280.364701 -280.043664) (xy 280.337768 -280.03373) (xy 280.328878 -280.030174) (xy 280.319226 -280.030174)
			(xy 280.309213 -280.030657) (xy 280.290708 -280.038311) (xy 280.27654 -280.052464) (xy 280.268867 -280.070961)
			(xy 280.268426 -280.080974) (xy 280.268426 -280.129996) (xy 280.268934 -280.136092) (xy 280.270204 -280.147268)
			(xy 280.272236 -280.156158) (xy 280.275903 -280.173066) (xy 280.279853 -280.207439) (xy 280.28011 -280.224738)
			(xy 280.28011 -280.241248) (xy 280.279602 -280.24709) (xy 280.279602 -280.247598) (xy 280.278332 -280.25852)
			(xy 280.278332 -280.258774) (xy 280.277824 -280.262838) (xy 280.275284 -280.281634) (xy 280.274268 -280.287222)
			(xy 280.270204 -280.30297) (xy 280.268426 -280.31567) (xy 280.268426 -280.368502) (xy 280.268846 -280.378521)
			(xy 280.276518 -280.397033) (xy 280.290691 -280.411198) (xy 280.309207 -280.418859) (xy 280.319226 -280.419302)
			(xy 280.328878 -280.419302) (xy 280.337768 -280.415746) (xy 280.364705 -280.405829) (xy 280.421086 -280.395094)
			(xy 280.449782 -280.39441) (xy 280.475039 -280.394901) (xy 280.524865 -280.403213) (xy 280.572643 -280.419613)
			(xy 280.61707 -280.443653) (xy 280.656934 -280.474678) (xy 280.691148 -280.511842) (xy 280.718777 -280.55413)
			(xy 280.739069 -280.60039) (xy 280.75147 -280.649358) (xy 280.755642 -280.6997) (xy 280.755641 -280.699718)
			(xy 281.093938 -280.699718) (xy 281.097898 -280.650664) (xy 281.109675 -280.60288) (xy 281.128966 -280.557604)
			(xy 281.155269 -280.516008) (xy 281.187904 -280.479171) (xy 281.226025 -280.448046) (xy 281.268646 -280.423439)
			(xy 281.314662 -280.405987) (xy 281.362881 -280.396143) (xy 281.412056 -280.394162) (xy 281.460911 -280.400094)
			(xy 281.508182 -280.413786) (xy 281.552644 -280.434884) (xy 281.593147 -280.46284) (xy 281.62864 -280.496932)
			(xy 281.658205 -280.536276) (xy 281.681076 -280.579853) (xy 281.69666 -280.626534) (xy 281.704555 -280.675111)
			(xy 281.70505 -280.699718) (xy 282.043898 -280.699718) (xy 282.047858 -280.650664) (xy 282.059635 -280.60288)
			(xy 282.078926 -280.557604) (xy 282.105229 -280.516008) (xy 282.137864 -280.479171) (xy 282.175985 -280.448046)
			(xy 282.218606 -280.423439) (xy 282.264622 -280.405987) (xy 282.312841 -280.396143) (xy 282.362016 -280.394162)
			(xy 282.410871 -280.400094) (xy 282.458142 -280.413786) (xy 282.502604 -280.434884) (xy 282.543107 -280.46284)
			(xy 282.5786 -280.496932) (xy 282.608165 -280.536276) (xy 282.631036 -280.579853) (xy 282.64662 -280.626534)
			(xy 282.654515 -280.675111) (xy 282.65501 -280.699718) (xy 282.994112 -280.699718) (xy 282.998072 -280.650664)
			(xy 283.009849 -280.60288) (xy 283.02914 -280.557604) (xy 283.055443 -280.516008) (xy 283.088078 -280.479171)
			(xy 283.126199 -280.448046) (xy 283.16882 -280.423439) (xy 283.214836 -280.405987) (xy 283.263055 -280.396143)
			(xy 283.31223 -280.394162) (xy 283.361085 -280.400094) (xy 283.408356 -280.413786) (xy 283.452818 -280.434884)
			(xy 283.493321 -280.46284) (xy 283.528814 -280.496932) (xy 283.558379 -280.536276) (xy 283.58125 -280.579853)
			(xy 283.596834 -280.626534) (xy 283.604729 -280.675111) (xy 283.605224 -280.699718) (xy 283.944072 -280.699718)
			(xy 283.948032 -280.650664) (xy 283.959809 -280.60288) (xy 283.9791 -280.557604) (xy 284.005403 -280.516008)
			(xy 284.038038 -280.479171) (xy 284.076159 -280.448046) (xy 284.11878 -280.423439) (xy 284.164796 -280.405987)
			(xy 284.213015 -280.396143) (xy 284.26219 -280.394162) (xy 284.311045 -280.400094) (xy 284.358316 -280.413786)
			(xy 284.402778 -280.434884) (xy 284.443281 -280.46284) (xy 284.478774 -280.496932) (xy 284.508339 -280.536276)
			(xy 284.53121 -280.579853) (xy 284.546794 -280.626534) (xy 284.554689 -280.675111) (xy 284.555184 -280.699718)
			(xy 284.894032 -280.699718) (xy 284.897992 -280.650664) (xy 284.909769 -280.60288) (xy 284.92906 -280.557604)
			(xy 284.955363 -280.516008) (xy 284.987998 -280.479171) (xy 285.026119 -280.448046) (xy 285.06874 -280.423439)
			(xy 285.114756 -280.405987) (xy 285.162975 -280.396143) (xy 285.21215 -280.394162) (xy 285.261005 -280.400094)
			(xy 285.308276 -280.413786) (xy 285.352738 -280.434884) (xy 285.393241 -280.46284) (xy 285.428734 -280.496932)
			(xy 285.458299 -280.536276) (xy 285.48117 -280.579853) (xy 285.496754 -280.626534) (xy 285.504649 -280.675111)
			(xy 285.505144 -280.699718) (xy 285.843992 -280.699718) (xy 285.847952 -280.650664) (xy 285.859729 -280.60288)
			(xy 285.87902 -280.557604) (xy 285.905323 -280.516008) (xy 285.937958 -280.479171) (xy 285.976079 -280.448046)
			(xy 286.0187 -280.423439) (xy 286.064716 -280.405987) (xy 286.112935 -280.396143) (xy 286.16211 -280.394162)
			(xy 286.210965 -280.400094) (xy 286.258236 -280.413786) (xy 286.302698 -280.434884) (xy 286.343201 -280.46284)
			(xy 286.378694 -280.496932) (xy 286.408259 -280.536276) (xy 286.43113 -280.579853) (xy 286.446714 -280.626534)
			(xy 286.454609 -280.675111) (xy 286.455104 -280.699718) (xy 286.793952 -280.699718) (xy 286.797912 -280.650664)
			(xy 286.809689 -280.60288) (xy 286.82898 -280.557604) (xy 286.855283 -280.516008) (xy 286.887918 -280.479171)
			(xy 286.926039 -280.448046) (xy 286.96866 -280.423439) (xy 287.014676 -280.405987) (xy 287.062895 -280.396143)
			(xy 287.11207 -280.394162) (xy 287.160925 -280.400094) (xy 287.208196 -280.413786) (xy 287.252658 -280.434884)
			(xy 287.293161 -280.46284) (xy 287.328654 -280.496932) (xy 287.358219 -280.536276) (xy 287.38109 -280.579853)
			(xy 287.396674 -280.626534) (xy 287.404569 -280.675111) (xy 287.405064 -280.699718) (xy 287.743912 -280.699718)
			(xy 287.747872 -280.650664) (xy 287.759649 -280.60288) (xy 287.77894 -280.557604) (xy 287.805243 -280.516008)
			(xy 287.837878 -280.479171) (xy 287.875999 -280.448046) (xy 287.91862 -280.423439) (xy 287.964636 -280.405987)
			(xy 288.012855 -280.396143) (xy 288.06203 -280.394162) (xy 288.110885 -280.400094) (xy 288.158156 -280.413786)
			(xy 288.202618 -280.434884) (xy 288.243121 -280.46284) (xy 288.278614 -280.496932) (xy 288.308179 -280.536276)
			(xy 288.33105 -280.579853) (xy 288.346634 -280.626534) (xy 288.354529 -280.675111) (xy 288.355024 -280.699718)
			(xy 288.693872 -280.699718) (xy 288.697832 -280.650664) (xy 288.709609 -280.60288) (xy 288.7289 -280.557604)
			(xy 288.755203 -280.516008) (xy 288.787838 -280.479171) (xy 288.825959 -280.448046) (xy 288.86858 -280.423439)
			(xy 288.914596 -280.405987) (xy 288.962815 -280.396143) (xy 289.01199 -280.394162) (xy 289.060845 -280.400094)
			(xy 289.108116 -280.413786) (xy 289.152578 -280.434884) (xy 289.193081 -280.46284) (xy 289.228574 -280.496932)
			(xy 289.258139 -280.536276) (xy 289.28101 -280.579853) (xy 289.296594 -280.626534) (xy 289.304489 -280.675111)
			(xy 289.304984 -280.699718) (xy 289.644086 -280.699718) (xy 289.648046 -280.650664) (xy 289.659823 -280.60288)
			(xy 289.679114 -280.557604) (xy 289.705417 -280.516008) (xy 289.738052 -280.479171) (xy 289.776173 -280.448046)
			(xy 289.818794 -280.423439) (xy 289.86481 -280.405987) (xy 289.913029 -280.396143) (xy 289.962204 -280.394162)
			(xy 290.011059 -280.400094) (xy 290.05833 -280.413786) (xy 290.102792 -280.434884) (xy 290.143295 -280.46284)
			(xy 290.178788 -280.496932) (xy 290.208353 -280.536276) (xy 290.231224 -280.579853) (xy 290.246808 -280.626534)
			(xy 290.254703 -280.675111) (xy 290.255198 -280.699718) (xy 290.594046 -280.699718) (xy 290.598006 -280.650664)
			(xy 290.609783 -280.60288) (xy 290.629074 -280.557604) (xy 290.655377 -280.516008) (xy 290.688012 -280.479171)
			(xy 290.726133 -280.448046) (xy 290.768754 -280.423439) (xy 290.81477 -280.405987) (xy 290.862989 -280.396143)
			(xy 290.912164 -280.394162) (xy 290.961019 -280.400094) (xy 291.00829 -280.413786) (xy 291.052752 -280.434884)
			(xy 291.093255 -280.46284) (xy 291.128748 -280.496932) (xy 291.158313 -280.536276) (xy 291.181184 -280.579853)
			(xy 291.196768 -280.626534) (xy 291.204663 -280.675111) (xy 291.205158 -280.699718) (xy 291.544006 -280.699718)
			(xy 291.547966 -280.650664) (xy 291.559743 -280.60288) (xy 291.579034 -280.557604) (xy 291.605337 -280.516008)
			(xy 291.637972 -280.479171) (xy 291.676093 -280.448046) (xy 291.718714 -280.423439) (xy 291.76473 -280.405987)
			(xy 291.812949 -280.396143) (xy 291.862124 -280.394162) (xy 291.910979 -280.400094) (xy 291.95825 -280.413786)
			(xy 292.002712 -280.434884) (xy 292.043215 -280.46284) (xy 292.078708 -280.496932) (xy 292.108273 -280.536276)
			(xy 292.131144 -280.579853) (xy 292.146728 -280.626534) (xy 292.154623 -280.675111) (xy 292.155118 -280.699718)
			(xy 292.493966 -280.699718) (xy 292.497926 -280.650664) (xy 292.509703 -280.60288) (xy 292.528994 -280.557604)
			(xy 292.555297 -280.516008) (xy 292.587932 -280.479171) (xy 292.626053 -280.448046) (xy 292.668674 -280.423439)
			(xy 292.71469 -280.405987) (xy 292.762909 -280.396143) (xy 292.812084 -280.394162) (xy 292.860939 -280.400094)
			(xy 292.90821 -280.413786) (xy 292.952672 -280.434884) (xy 292.993175 -280.46284) (xy 293.028668 -280.496932)
			(xy 293.058233 -280.536276) (xy 293.081104 -280.579853) (xy 293.096688 -280.626534) (xy 293.104583 -280.675111)
			(xy 293.105078 -280.699718) (xy 293.443926 -280.699718) (xy 293.447886 -280.650664) (xy 293.459663 -280.60288)
			(xy 293.478954 -280.557604) (xy 293.505257 -280.516008) (xy 293.537892 -280.479171) (xy 293.576013 -280.448046)
			(xy 293.618634 -280.423439) (xy 293.66465 -280.405987) (xy 293.712869 -280.396143) (xy 293.762044 -280.394162)
			(xy 293.810899 -280.400094) (xy 293.85817 -280.413786) (xy 293.902632 -280.434884) (xy 293.943135 -280.46284)
			(xy 293.978628 -280.496932) (xy 294.008193 -280.536276) (xy 294.031064 -280.579853) (xy 294.046648 -280.626534)
			(xy 294.054543 -280.675111) (xy 294.055038 -280.699718) (xy 294.393886 -280.699718) (xy 294.397846 -280.650664)
			(xy 294.409623 -280.60288) (xy 294.428914 -280.557604) (xy 294.455217 -280.516008) (xy 294.487852 -280.479171)
			(xy 294.525973 -280.448046) (xy 294.568594 -280.423439) (xy 294.61461 -280.405987) (xy 294.662829 -280.396143)
			(xy 294.712004 -280.394162) (xy 294.760859 -280.400094) (xy 294.80813 -280.413786) (xy 294.852592 -280.434884)
			(xy 294.893095 -280.46284) (xy 294.928588 -280.496932) (xy 294.958153 -280.536276) (xy 294.981024 -280.579853)
			(xy 294.996608 -280.626534) (xy 295.004503 -280.675111) (xy 295.004998 -280.699718) (xy 295.3441 -280.699718)
			(xy 295.34806 -280.650664) (xy 295.359837 -280.60288) (xy 295.379128 -280.557604) (xy 295.405431 -280.516008)
			(xy 295.438066 -280.479171) (xy 295.476187 -280.448046) (xy 295.518808 -280.423439) (xy 295.564824 -280.405987)
			(xy 295.613043 -280.396143) (xy 295.662218 -280.394162) (xy 295.711073 -280.400094) (xy 295.758344 -280.413786)
			(xy 295.802806 -280.434884) (xy 295.843309 -280.46284) (xy 295.878802 -280.496932) (xy 295.908367 -280.536276)
			(xy 295.931238 -280.579853) (xy 295.946822 -280.626534) (xy 295.954717 -280.675111) (xy 295.955212 -280.699718)
			(xy 296.29406 -280.699718) (xy 296.29802 -280.650664) (xy 296.309797 -280.60288) (xy 296.329088 -280.557604)
			(xy 296.355391 -280.516008) (xy 296.388026 -280.479171) (xy 296.426147 -280.448046) (xy 296.468768 -280.423439)
			(xy 296.514784 -280.405987) (xy 296.563003 -280.396143) (xy 296.612178 -280.394162) (xy 296.661033 -280.400094)
			(xy 296.708304 -280.413786) (xy 296.752766 -280.434884) (xy 296.793269 -280.46284) (xy 296.828762 -280.496932)
			(xy 296.858327 -280.536276) (xy 296.881198 -280.579853) (xy 296.896782 -280.626534) (xy 296.904677 -280.675111)
			(xy 296.905172 -280.699718) (xy 297.24402 -280.699718) (xy 297.24798 -280.650664) (xy 297.259757 -280.60288)
			(xy 297.279048 -280.557604) (xy 297.305351 -280.516008) (xy 297.337986 -280.479171) (xy 297.376107 -280.448046)
			(xy 297.418728 -280.423439) (xy 297.464744 -280.405987) (xy 297.512963 -280.396143) (xy 297.562138 -280.394162)
			(xy 297.610993 -280.400094) (xy 297.658264 -280.413786) (xy 297.702726 -280.434884) (xy 297.743229 -280.46284)
			(xy 297.778722 -280.496932) (xy 297.808287 -280.536276) (xy 297.831158 -280.579853) (xy 297.846742 -280.626534)
			(xy 297.854637 -280.675111) (xy 297.855132 -280.699718) (xy 298.19398 -280.699718) (xy 298.19794 -280.650664)
			(xy 298.209717 -280.60288) (xy 298.229008 -280.557604) (xy 298.255311 -280.516008) (xy 298.287946 -280.479171)
			(xy 298.326067 -280.448046) (xy 298.368688 -280.423439) (xy 298.414704 -280.405987) (xy 298.462923 -280.396143)
			(xy 298.512098 -280.394162) (xy 298.560953 -280.400094) (xy 298.608224 -280.413786) (xy 298.652686 -280.434884)
			(xy 298.693189 -280.46284) (xy 298.728682 -280.496932) (xy 298.758247 -280.536276) (xy 298.781118 -280.579853)
			(xy 298.796702 -280.626534) (xy 298.804597 -280.675111) (xy 298.805092 -280.699718) (xy 299.14394 -280.699718)
			(xy 299.1479 -280.650664) (xy 299.159677 -280.60288) (xy 299.178968 -280.557604) (xy 299.205271 -280.516008)
			(xy 299.237906 -280.479171) (xy 299.276027 -280.448046) (xy 299.318648 -280.423439) (xy 299.364664 -280.405987)
			(xy 299.412883 -280.396143) (xy 299.462058 -280.394162) (xy 299.510913 -280.400094) (xy 299.558184 -280.413786)
			(xy 299.602646 -280.434884) (xy 299.643149 -280.46284) (xy 299.678642 -280.496932) (xy 299.708207 -280.536276)
			(xy 299.731078 -280.579853) (xy 299.746662 -280.626534) (xy 299.754557 -280.675111) (xy 299.755052 -280.699718)
			(xy 300.0939 -280.699718) (xy 300.09786 -280.650664) (xy 300.109637 -280.60288) (xy 300.128928 -280.557604)
			(xy 300.155231 -280.516008) (xy 300.187866 -280.479171) (xy 300.225987 -280.448046) (xy 300.268608 -280.423439)
			(xy 300.314624 -280.405987) (xy 300.362843 -280.396143) (xy 300.412018 -280.394162) (xy 300.460873 -280.400094)
			(xy 300.508144 -280.413786) (xy 300.552606 -280.434884) (xy 300.593109 -280.46284) (xy 300.628602 -280.496932)
			(xy 300.658167 -280.536276) (xy 300.681038 -280.579853) (xy 300.696622 -280.626534) (xy 300.704517 -280.675111)
			(xy 300.705012 -280.699718) (xy 301.044114 -280.699718) (xy 301.048074 -280.650664) (xy 301.059851 -280.60288)
			(xy 301.079142 -280.557604) (xy 301.105445 -280.516008) (xy 301.13808 -280.479171) (xy 301.176201 -280.448046)
			(xy 301.218822 -280.423439) (xy 301.264838 -280.405987) (xy 301.313057 -280.396143) (xy 301.362232 -280.394162)
			(xy 301.411087 -280.400094) (xy 301.458358 -280.413786) (xy 301.50282 -280.434884) (xy 301.543323 -280.46284)
			(xy 301.578816 -280.496932) (xy 301.608381 -280.536276) (xy 301.631252 -280.579853) (xy 301.646836 -280.626534)
			(xy 301.654731 -280.675111) (xy 301.655226 -280.699718) (xy 301.994074 -280.699718) (xy 301.998034 -280.650664)
			(xy 302.009811 -280.60288) (xy 302.029102 -280.557604) (xy 302.055405 -280.516008) (xy 302.08804 -280.479171)
			(xy 302.126161 -280.448046) (xy 302.168782 -280.423439) (xy 302.214798 -280.405987) (xy 302.263017 -280.396143)
			(xy 302.312192 -280.394162) (xy 302.361047 -280.400094) (xy 302.408318 -280.413786) (xy 302.45278 -280.434884)
			(xy 302.493283 -280.46284) (xy 302.528776 -280.496932) (xy 302.558341 -280.536276) (xy 302.581212 -280.579853)
			(xy 302.596796 -280.626534) (xy 302.604691 -280.675111) (xy 302.605186 -280.699718) (xy 302.944034 -280.699718)
			(xy 302.947994 -280.650664) (xy 302.959771 -280.60288) (xy 302.979062 -280.557604) (xy 303.005365 -280.516008)
			(xy 303.038 -280.479171) (xy 303.076121 -280.448046) (xy 303.118742 -280.423439) (xy 303.164758 -280.405987)
			(xy 303.212977 -280.396143) (xy 303.262152 -280.394162) (xy 303.311007 -280.400094) (xy 303.358278 -280.413786)
			(xy 303.40274 -280.434884) (xy 303.443243 -280.46284) (xy 303.478736 -280.496932) (xy 303.508301 -280.536276)
			(xy 303.531172 -280.579853) (xy 303.546756 -280.626534) (xy 303.554651 -280.675111) (xy 303.555146 -280.699718)
			(xy 303.893994 -280.699718) (xy 303.897954 -280.650664) (xy 303.909731 -280.60288) (xy 303.929022 -280.557604)
			(xy 303.955325 -280.516008) (xy 303.98796 -280.479171) (xy 304.026081 -280.448046) (xy 304.068702 -280.423439)
			(xy 304.114718 -280.405987) (xy 304.162937 -280.396143) (xy 304.212112 -280.394162) (xy 304.260967 -280.400094)
			(xy 304.308238 -280.413786) (xy 304.3527 -280.434884) (xy 304.393203 -280.46284) (xy 304.428696 -280.496932)
			(xy 304.458261 -280.536276) (xy 304.481132 -280.579853) (xy 304.496716 -280.626534) (xy 304.504611 -280.675111)
			(xy 304.505106 -280.699718) (xy 304.843954 -280.699718) (xy 304.847914 -280.650664) (xy 304.859691 -280.60288)
			(xy 304.878982 -280.557604) (xy 304.905285 -280.516008) (xy 304.93792 -280.479171) (xy 304.976041 -280.448046)
			(xy 305.018662 -280.423439) (xy 305.064678 -280.405987) (xy 305.112897 -280.396143) (xy 305.162072 -280.394162)
			(xy 305.210927 -280.400094) (xy 305.258198 -280.413786) (xy 305.30266 -280.434884) (xy 305.343163 -280.46284)
			(xy 305.378656 -280.496932) (xy 305.408221 -280.536276) (xy 305.431092 -280.579853) (xy 305.446676 -280.626534)
			(xy 305.454571 -280.675111) (xy 305.455066 -280.699718) (xy 305.793914 -280.699718) (xy 305.797874 -280.650664)
			(xy 305.809651 -280.60288) (xy 305.828942 -280.557604) (xy 305.855245 -280.516008) (xy 305.88788 -280.479171)
			(xy 305.926001 -280.448046) (xy 305.968622 -280.423439) (xy 306.014638 -280.405987) (xy 306.062857 -280.396143)
			(xy 306.112032 -280.394162) (xy 306.160887 -280.400094) (xy 306.208158 -280.413786) (xy 306.25262 -280.434884)
			(xy 306.293123 -280.46284) (xy 306.328616 -280.496932) (xy 306.358181 -280.536276) (xy 306.381052 -280.579853)
			(xy 306.396636 -280.626534) (xy 306.404531 -280.675111) (xy 306.405026 -280.699718) (xy 306.744128 -280.699718)
			(xy 306.748088 -280.650664) (xy 306.759865 -280.60288) (xy 306.779156 -280.557604) (xy 306.805459 -280.516008)
			(xy 306.838094 -280.479171) (xy 306.876215 -280.448046) (xy 306.918836 -280.423439) (xy 306.964852 -280.405987)
			(xy 307.013071 -280.396143) (xy 307.062246 -280.394162) (xy 307.111101 -280.400094) (xy 307.158372 -280.413786)
			(xy 307.202834 -280.434884) (xy 307.243337 -280.46284) (xy 307.27883 -280.496932) (xy 307.308395 -280.536276)
			(xy 307.331266 -280.579853) (xy 307.34685 -280.626534) (xy 307.354745 -280.675111) (xy 307.35524 -280.699718)
			(xy 307.694088 -280.699718) (xy 307.698048 -280.650664) (xy 307.709825 -280.60288) (xy 307.729116 -280.557604)
			(xy 307.755419 -280.516008) (xy 307.788054 -280.479171) (xy 307.826175 -280.448046) (xy 307.868796 -280.423439)
			(xy 307.914812 -280.405987) (xy 307.963031 -280.396143) (xy 308.012206 -280.394162) (xy 308.061061 -280.400094)
			(xy 308.108332 -280.413786) (xy 308.152794 -280.434884) (xy 308.193297 -280.46284) (xy 308.22879 -280.496932)
			(xy 308.258355 -280.536276) (xy 308.281226 -280.579853) (xy 308.29681 -280.626534) (xy 308.304705 -280.675111)
			(xy 308.3052 -280.699718) (xy 308.644048 -280.699718) (xy 308.648008 -280.650664) (xy 308.659785 -280.60288)
			(xy 308.679076 -280.557604) (xy 308.705379 -280.516008) (xy 308.738014 -280.479171) (xy 308.776135 -280.448046)
			(xy 308.818756 -280.423439) (xy 308.864772 -280.405987) (xy 308.912991 -280.396143) (xy 308.962166 -280.394162)
			(xy 309.011021 -280.400094) (xy 309.058292 -280.413786) (xy 309.102754 -280.434884) (xy 309.143257 -280.46284)
			(xy 309.17875 -280.496932) (xy 309.208315 -280.536276) (xy 309.231186 -280.579853) (xy 309.24677 -280.626534)
			(xy 309.254665 -280.675111) (xy 309.25516 -280.699718) (xy 309.594008 -280.699718) (xy 309.597968 -280.650664)
			(xy 309.609745 -280.60288) (xy 309.629036 -280.557604) (xy 309.655339 -280.516008) (xy 309.687974 -280.479171)
			(xy 309.726095 -280.448046) (xy 309.768716 -280.423439) (xy 309.814732 -280.405987) (xy 309.862951 -280.396143)
			(xy 309.912126 -280.394162) (xy 309.960981 -280.400094) (xy 310.008252 -280.413786) (xy 310.052714 -280.434884)
			(xy 310.093217 -280.46284) (xy 310.12871 -280.496932) (xy 310.158275 -280.536276) (xy 310.181146 -280.579853)
			(xy 310.19673 -280.626534) (xy 310.204625 -280.675111) (xy 310.20512 -280.699718) (xy 310.543968 -280.699718)
			(xy 310.547928 -280.650664) (xy 310.559705 -280.60288) (xy 310.578996 -280.557604) (xy 310.605299 -280.516008)
			(xy 310.637934 -280.479171) (xy 310.676055 -280.448046) (xy 310.718676 -280.423439) (xy 310.764692 -280.405987)
			(xy 310.812911 -280.396143) (xy 310.862086 -280.394162) (xy 310.910941 -280.400094) (xy 310.958212 -280.413786)
			(xy 311.002674 -280.434884) (xy 311.043177 -280.46284) (xy 311.07867 -280.496932) (xy 311.108235 -280.536276)
			(xy 311.131106 -280.579853) (xy 311.14669 -280.626534) (xy 311.154585 -280.675111) (xy 311.15508 -280.699718)
			(xy 311.493928 -280.699718) (xy 311.497888 -280.650664) (xy 311.509665 -280.60288) (xy 311.528956 -280.557604)
			(xy 311.555259 -280.516008) (xy 311.587894 -280.479171) (xy 311.626015 -280.448046) (xy 311.668636 -280.423439)
			(xy 311.714652 -280.405987) (xy 311.762871 -280.396143) (xy 311.812046 -280.394162) (xy 311.860901 -280.400094)
			(xy 311.908172 -280.413786) (xy 311.952634 -280.434884) (xy 311.993137 -280.46284) (xy 312.02863 -280.496932)
			(xy 312.058195 -280.536276) (xy 312.081066 -280.579853) (xy 312.09665 -280.626534) (xy 312.104545 -280.675111)
			(xy 312.10504 -280.699718) (xy 312.444142 -280.699718) (xy 312.448102 -280.650664) (xy 312.459879 -280.60288)
			(xy 312.47917 -280.557604) (xy 312.505473 -280.516008) (xy 312.538108 -280.479171) (xy 312.576229 -280.448046)
			(xy 312.61885 -280.423439) (xy 312.664866 -280.405987) (xy 312.713085 -280.396143) (xy 312.76226 -280.394162)
			(xy 312.811115 -280.400094) (xy 312.858386 -280.413786) (xy 312.902848 -280.434884) (xy 312.943351 -280.46284)
			(xy 312.978844 -280.496932) (xy 313.008409 -280.536276) (xy 313.03128 -280.579853) (xy 313.046864 -280.626534)
			(xy 313.054759 -280.675111) (xy 313.055254 -280.699718) (xy 313.394102 -280.699718) (xy 313.398062 -280.650664)
			(xy 313.409839 -280.60288) (xy 313.42913 -280.557604) (xy 313.455433 -280.516008) (xy 313.488068 -280.479171)
			(xy 313.526189 -280.448046) (xy 313.56881 -280.423439) (xy 313.614826 -280.405987) (xy 313.663045 -280.396143)
			(xy 313.71222 -280.394162) (xy 313.761075 -280.400094) (xy 313.808346 -280.413786) (xy 313.852808 -280.434884)
			(xy 313.893311 -280.46284) (xy 313.928804 -280.496932) (xy 313.958369 -280.536276) (xy 313.98124 -280.579853)
			(xy 313.996824 -280.626534) (xy 314.004719 -280.675111) (xy 314.005214 -280.699718) (xy 314.344062 -280.699718)
			(xy 314.348022 -280.650664) (xy 314.359799 -280.60288) (xy 314.37909 -280.557604) (xy 314.405393 -280.516008)
			(xy 314.438028 -280.479171) (xy 314.476149 -280.448046) (xy 314.51877 -280.423439) (xy 314.564786 -280.405987)
			(xy 314.613005 -280.396143) (xy 314.66218 -280.394162) (xy 314.711035 -280.400094) (xy 314.758306 -280.413786)
			(xy 314.802768 -280.434884) (xy 314.843271 -280.46284) (xy 314.878764 -280.496932) (xy 314.908329 -280.536276)
			(xy 314.9312 -280.579853) (xy 314.946784 -280.626534) (xy 314.954679 -280.675111) (xy 314.955174 -280.699718)
			(xy 314.954679 -280.724325) (xy 314.946784 -280.772902) (xy 314.9312 -280.819583) (xy 314.908329 -280.86316)
			(xy 314.878764 -280.902504) (xy 314.843271 -280.936596) (xy 314.802768 -280.964552) (xy 314.758306 -280.98565)
			(xy 314.711035 -280.999342) (xy 314.66218 -281.005274) (xy 314.613005 -281.003293) (xy 314.564786 -280.993449)
			(xy 314.51877 -280.975997) (xy 314.476149 -280.95139) (xy 314.438028 -280.920265) (xy 314.405393 -280.883428)
			(xy 314.37909 -280.841832) (xy 314.359799 -280.796556) (xy 314.348022 -280.748772) (xy 314.344062 -280.699718)
			(xy 314.005214 -280.699718) (xy 314.004719 -280.724325) (xy 313.996824 -280.772902) (xy 313.98124 -280.819583)
			(xy 313.958369 -280.86316) (xy 313.928804 -280.902504) (xy 313.893311 -280.936596) (xy 313.852808 -280.964552)
			(xy 313.808346 -280.98565) (xy 313.761075 -280.999342) (xy 313.71222 -281.005274) (xy 313.663045 -281.003293)
			(xy 313.614826 -280.993449) (xy 313.56881 -280.975997) (xy 313.526189 -280.95139) (xy 313.488068 -280.920265)
			(xy 313.455433 -280.883428) (xy 313.42913 -280.841832) (xy 313.409839 -280.796556) (xy 313.398062 -280.748772)
			(xy 313.394102 -280.699718) (xy 313.055254 -280.699718) (xy 313.054759 -280.724325) (xy 313.046864 -280.772902)
			(xy 313.03128 -280.819583) (xy 313.008409 -280.86316) (xy 312.978844 -280.902504) (xy 312.943351 -280.936596)
			(xy 312.902848 -280.964552) (xy 312.858386 -280.98565) (xy 312.811115 -280.999342) (xy 312.76226 -281.005274)
			(xy 312.713085 -281.003293) (xy 312.664866 -280.993449) (xy 312.61885 -280.975997) (xy 312.576229 -280.95139)
			(xy 312.538108 -280.920265) (xy 312.505473 -280.883428) (xy 312.47917 -280.841832) (xy 312.459879 -280.796556)
			(xy 312.448102 -280.748772) (xy 312.444142 -280.699718) (xy 312.10504 -280.699718) (xy 312.104545 -280.724325)
			(xy 312.09665 -280.772902) (xy 312.081066 -280.819583) (xy 312.058195 -280.86316) (xy 312.02863 -280.902504)
			(xy 311.993137 -280.936596) (xy 311.952634 -280.964552) (xy 311.908172 -280.98565) (xy 311.860901 -280.999342)
			(xy 311.812046 -281.005274) (xy 311.762871 -281.003293) (xy 311.714652 -280.993449) (xy 311.668636 -280.975997)
			(xy 311.626015 -280.95139) (xy 311.587894 -280.920265) (xy 311.555259 -280.883428) (xy 311.528956 -280.841832)
			(xy 311.509665 -280.796556) (xy 311.497888 -280.748772) (xy 311.493928 -280.699718) (xy 311.15508 -280.699718)
			(xy 311.154585 -280.724325) (xy 311.14669 -280.772902) (xy 311.131106 -280.819583) (xy 311.108235 -280.86316)
			(xy 311.07867 -280.902504) (xy 311.043177 -280.936596) (xy 311.002674 -280.964552) (xy 310.958212 -280.98565)
			(xy 310.910941 -280.999342) (xy 310.862086 -281.005274) (xy 310.812911 -281.003293) (xy 310.764692 -280.993449)
			(xy 310.718676 -280.975997) (xy 310.676055 -280.95139) (xy 310.637934 -280.920265) (xy 310.605299 -280.883428)
			(xy 310.578996 -280.841832) (xy 310.559705 -280.796556) (xy 310.547928 -280.748772) (xy 310.543968 -280.699718)
			(xy 310.20512 -280.699718) (xy 310.204625 -280.724325) (xy 310.19673 -280.772902) (xy 310.181146 -280.819583)
			(xy 310.158275 -280.86316) (xy 310.12871 -280.902504) (xy 310.093217 -280.936596) (xy 310.052714 -280.964552)
			(xy 310.008252 -280.98565) (xy 309.960981 -280.999342) (xy 309.912126 -281.005274) (xy 309.862951 -281.003293)
			(xy 309.814732 -280.993449) (xy 309.768716 -280.975997) (xy 309.726095 -280.95139) (xy 309.687974 -280.920265)
			(xy 309.655339 -280.883428) (xy 309.629036 -280.841832) (xy 309.609745 -280.796556) (xy 309.597968 -280.748772)
			(xy 309.594008 -280.699718) (xy 309.25516 -280.699718) (xy 309.254665 -280.724325) (xy 309.24677 -280.772902)
			(xy 309.231186 -280.819583) (xy 309.208315 -280.86316) (xy 309.17875 -280.902504) (xy 309.143257 -280.936596)
			(xy 309.102754 -280.964552) (xy 309.058292 -280.98565) (xy 309.011021 -280.999342) (xy 308.962166 -281.005274)
			(xy 308.912991 -281.003293) (xy 308.864772 -280.993449) (xy 308.818756 -280.975997) (xy 308.776135 -280.95139)
			(xy 308.738014 -280.920265) (xy 308.705379 -280.883428) (xy 308.679076 -280.841832) (xy 308.659785 -280.796556)
			(xy 308.648008 -280.748772) (xy 308.644048 -280.699718) (xy 308.3052 -280.699718) (xy 308.304705 -280.724325)
			(xy 308.29681 -280.772902) (xy 308.281226 -280.819583) (xy 308.258355 -280.86316) (xy 308.22879 -280.902504)
			(xy 308.193297 -280.936596) (xy 308.152794 -280.964552) (xy 308.108332 -280.98565) (xy 308.061061 -280.999342)
			(xy 308.012206 -281.005274) (xy 307.963031 -281.003293) (xy 307.914812 -280.993449) (xy 307.868796 -280.975997)
			(xy 307.826175 -280.95139) (xy 307.788054 -280.920265) (xy 307.755419 -280.883428) (xy 307.729116 -280.841832)
			(xy 307.709825 -280.796556) (xy 307.698048 -280.748772) (xy 307.694088 -280.699718) (xy 307.35524 -280.699718)
			(xy 307.354745 -280.724325) (xy 307.34685 -280.772902) (xy 307.331266 -280.819583) (xy 307.308395 -280.86316)
			(xy 307.27883 -280.902504) (xy 307.243337 -280.936596) (xy 307.202834 -280.964552) (xy 307.158372 -280.98565)
			(xy 307.111101 -280.999342) (xy 307.062246 -281.005274) (xy 307.013071 -281.003293) (xy 306.964852 -280.993449)
			(xy 306.918836 -280.975997) (xy 306.876215 -280.95139) (xy 306.838094 -280.920265) (xy 306.805459 -280.883428)
			(xy 306.779156 -280.841832) (xy 306.759865 -280.796556) (xy 306.748088 -280.748772) (xy 306.744128 -280.699718)
			(xy 306.405026 -280.699718) (xy 306.404531 -280.724325) (xy 306.396636 -280.772902) (xy 306.381052 -280.819583)
			(xy 306.358181 -280.86316) (xy 306.328616 -280.902504) (xy 306.293123 -280.936596) (xy 306.25262 -280.964552)
			(xy 306.208158 -280.98565) (xy 306.160887 -280.999342) (xy 306.112032 -281.005274) (xy 306.062857 -281.003293)
			(xy 306.014638 -280.993449) (xy 305.968622 -280.975997) (xy 305.926001 -280.95139) (xy 305.88788 -280.920265)
			(xy 305.855245 -280.883428) (xy 305.828942 -280.841832) (xy 305.809651 -280.796556) (xy 305.797874 -280.748772)
			(xy 305.793914 -280.699718) (xy 305.455066 -280.699718) (xy 305.454571 -280.724325) (xy 305.446676 -280.772902)
			(xy 305.431092 -280.819583) (xy 305.408221 -280.86316) (xy 305.378656 -280.902504) (xy 305.343163 -280.936596)
			(xy 305.30266 -280.964552) (xy 305.258198 -280.98565) (xy 305.210927 -280.999342) (xy 305.162072 -281.005274)
			(xy 305.112897 -281.003293) (xy 305.064678 -280.993449) (xy 305.018662 -280.975997) (xy 304.976041 -280.95139)
			(xy 304.93792 -280.920265) (xy 304.905285 -280.883428) (xy 304.878982 -280.841832) (xy 304.859691 -280.796556)
			(xy 304.847914 -280.748772) (xy 304.843954 -280.699718) (xy 304.505106 -280.699718) (xy 304.504611 -280.724325)
			(xy 304.496716 -280.772902) (xy 304.481132 -280.819583) (xy 304.458261 -280.86316) (xy 304.428696 -280.902504)
			(xy 304.393203 -280.936596) (xy 304.3527 -280.964552) (xy 304.308238 -280.98565) (xy 304.260967 -280.999342)
			(xy 304.212112 -281.005274) (xy 304.162937 -281.003293) (xy 304.114718 -280.993449) (xy 304.068702 -280.975997)
			(xy 304.026081 -280.95139) (xy 303.98796 -280.920265) (xy 303.955325 -280.883428) (xy 303.929022 -280.841832)
			(xy 303.909731 -280.796556) (xy 303.897954 -280.748772) (xy 303.893994 -280.699718) (xy 303.555146 -280.699718)
			(xy 303.554651 -280.724325) (xy 303.546756 -280.772902) (xy 303.531172 -280.819583) (xy 303.508301 -280.86316)
			(xy 303.478736 -280.902504) (xy 303.443243 -280.936596) (xy 303.40274 -280.964552) (xy 303.358278 -280.98565)
			(xy 303.311007 -280.999342) (xy 303.262152 -281.005274) (xy 303.212977 -281.003293) (xy 303.164758 -280.993449)
			(xy 303.118742 -280.975997) (xy 303.076121 -280.95139) (xy 303.038 -280.920265) (xy 303.005365 -280.883428)
			(xy 302.979062 -280.841832) (xy 302.959771 -280.796556) (xy 302.947994 -280.748772) (xy 302.944034 -280.699718)
			(xy 302.605186 -280.699718) (xy 302.604691 -280.724325) (xy 302.596796 -280.772902) (xy 302.581212 -280.819583)
			(xy 302.558341 -280.86316) (xy 302.528776 -280.902504) (xy 302.493283 -280.936596) (xy 302.45278 -280.964552)
			(xy 302.408318 -280.98565) (xy 302.361047 -280.999342) (xy 302.312192 -281.005274) (xy 302.263017 -281.003293)
			(xy 302.214798 -280.993449) (xy 302.168782 -280.975997) (xy 302.126161 -280.95139) (xy 302.08804 -280.920265)
			(xy 302.055405 -280.883428) (xy 302.029102 -280.841832) (xy 302.009811 -280.796556) (xy 301.998034 -280.748772)
			(xy 301.994074 -280.699718) (xy 301.655226 -280.699718) (xy 301.654731 -280.724325) (xy 301.646836 -280.772902)
			(xy 301.631252 -280.819583) (xy 301.608381 -280.86316) (xy 301.578816 -280.902504) (xy 301.543323 -280.936596)
			(xy 301.50282 -280.964552) (xy 301.458358 -280.98565) (xy 301.411087 -280.999342) (xy 301.362232 -281.005274)
			(xy 301.313057 -281.003293) (xy 301.264838 -280.993449) (xy 301.218822 -280.975997) (xy 301.176201 -280.95139)
			(xy 301.13808 -280.920265) (xy 301.105445 -280.883428) (xy 301.079142 -280.841832) (xy 301.059851 -280.796556)
			(xy 301.048074 -280.748772) (xy 301.044114 -280.699718) (xy 300.705012 -280.699718) (xy 300.704517 -280.724325)
			(xy 300.696622 -280.772902) (xy 300.681038 -280.819583) (xy 300.658167 -280.86316) (xy 300.628602 -280.902504)
			(xy 300.593109 -280.936596) (xy 300.552606 -280.964552) (xy 300.508144 -280.98565) (xy 300.460873 -280.999342)
			(xy 300.412018 -281.005274) (xy 300.362843 -281.003293) (xy 300.314624 -280.993449) (xy 300.268608 -280.975997)
			(xy 300.225987 -280.95139) (xy 300.187866 -280.920265) (xy 300.155231 -280.883428) (xy 300.128928 -280.841832)
			(xy 300.109637 -280.796556) (xy 300.09786 -280.748772) (xy 300.0939 -280.699718) (xy 299.755052 -280.699718)
			(xy 299.754557 -280.724325) (xy 299.746662 -280.772902) (xy 299.731078 -280.819583) (xy 299.708207 -280.86316)
			(xy 299.678642 -280.902504) (xy 299.643149 -280.936596) (xy 299.602646 -280.964552) (xy 299.558184 -280.98565)
			(xy 299.510913 -280.999342) (xy 299.462058 -281.005274) (xy 299.412883 -281.003293) (xy 299.364664 -280.993449)
			(xy 299.318648 -280.975997) (xy 299.276027 -280.95139) (xy 299.237906 -280.920265) (xy 299.205271 -280.883428)
			(xy 299.178968 -280.841832) (xy 299.159677 -280.796556) (xy 299.1479 -280.748772) (xy 299.14394 -280.699718)
			(xy 298.805092 -280.699718) (xy 298.804597 -280.724325) (xy 298.796702 -280.772902) (xy 298.781118 -280.819583)
			(xy 298.758247 -280.86316) (xy 298.728682 -280.902504) (xy 298.693189 -280.936596) (xy 298.652686 -280.964552)
			(xy 298.608224 -280.98565) (xy 298.560953 -280.999342) (xy 298.512098 -281.005274) (xy 298.462923 -281.003293)
			(xy 298.414704 -280.993449) (xy 298.368688 -280.975997) (xy 298.326067 -280.95139) (xy 298.287946 -280.920265)
			(xy 298.255311 -280.883428) (xy 298.229008 -280.841832) (xy 298.209717 -280.796556) (xy 298.19794 -280.748772)
			(xy 298.19398 -280.699718) (xy 297.855132 -280.699718) (xy 297.854637 -280.724325) (xy 297.846742 -280.772902)
			(xy 297.831158 -280.819583) (xy 297.808287 -280.86316) (xy 297.778722 -280.902504) (xy 297.743229 -280.936596)
			(xy 297.702726 -280.964552) (xy 297.658264 -280.98565) (xy 297.610993 -280.999342) (xy 297.562138 -281.005274)
			(xy 297.512963 -281.003293) (xy 297.464744 -280.993449) (xy 297.418728 -280.975997) (xy 297.376107 -280.95139)
			(xy 297.337986 -280.920265) (xy 297.305351 -280.883428) (xy 297.279048 -280.841832) (xy 297.259757 -280.796556)
			(xy 297.24798 -280.748772) (xy 297.24402 -280.699718) (xy 296.905172 -280.699718) (xy 296.904677 -280.724325)
			(xy 296.896782 -280.772902) (xy 296.881198 -280.819583) (xy 296.858327 -280.86316) (xy 296.828762 -280.902504)
			(xy 296.793269 -280.936596) (xy 296.752766 -280.964552) (xy 296.708304 -280.98565) (xy 296.661033 -280.999342)
			(xy 296.612178 -281.005274) (xy 296.563003 -281.003293) (xy 296.514784 -280.993449) (xy 296.468768 -280.975997)
			(xy 296.426147 -280.95139) (xy 296.388026 -280.920265) (xy 296.355391 -280.883428) (xy 296.329088 -280.841832)
			(xy 296.309797 -280.796556) (xy 296.29802 -280.748772) (xy 296.29406 -280.699718) (xy 295.955212 -280.699718)
			(xy 295.954717 -280.724325) (xy 295.946822 -280.772902) (xy 295.931238 -280.819583) (xy 295.908367 -280.86316)
			(xy 295.878802 -280.902504) (xy 295.843309 -280.936596) (xy 295.802806 -280.964552) (xy 295.758344 -280.98565)
			(xy 295.711073 -280.999342) (xy 295.662218 -281.005274) (xy 295.613043 -281.003293) (xy 295.564824 -280.993449)
			(xy 295.518808 -280.975997) (xy 295.476187 -280.95139) (xy 295.438066 -280.920265) (xy 295.405431 -280.883428)
			(xy 295.379128 -280.841832) (xy 295.359837 -280.796556) (xy 295.34806 -280.748772) (xy 295.3441 -280.699718)
			(xy 295.004998 -280.699718) (xy 295.004503 -280.724325) (xy 294.996608 -280.772902) (xy 294.981024 -280.819583)
			(xy 294.958153 -280.86316) (xy 294.928588 -280.902504) (xy 294.893095 -280.936596) (xy 294.852592 -280.964552)
			(xy 294.80813 -280.98565) (xy 294.760859 -280.999342) (xy 294.712004 -281.005274) (xy 294.662829 -281.003293)
			(xy 294.61461 -280.993449) (xy 294.568594 -280.975997) (xy 294.525973 -280.95139) (xy 294.487852 -280.920265)
			(xy 294.455217 -280.883428) (xy 294.428914 -280.841832) (xy 294.409623 -280.796556) (xy 294.397846 -280.748772)
			(xy 294.393886 -280.699718) (xy 294.055038 -280.699718) (xy 294.054543 -280.724325) (xy 294.046648 -280.772902)
			(xy 294.031064 -280.819583) (xy 294.008193 -280.86316) (xy 293.978628 -280.902504) (xy 293.943135 -280.936596)
			(xy 293.902632 -280.964552) (xy 293.85817 -280.98565) (xy 293.810899 -280.999342) (xy 293.762044 -281.005274)
			(xy 293.712869 -281.003293) (xy 293.66465 -280.993449) (xy 293.618634 -280.975997) (xy 293.576013 -280.95139)
			(xy 293.537892 -280.920265) (xy 293.505257 -280.883428) (xy 293.478954 -280.841832) (xy 293.459663 -280.796556)
			(xy 293.447886 -280.748772) (xy 293.443926 -280.699718) (xy 293.105078 -280.699718) (xy 293.104583 -280.724325)
			(xy 293.096688 -280.772902) (xy 293.081104 -280.819583) (xy 293.058233 -280.86316) (xy 293.028668 -280.902504)
			(xy 292.993175 -280.936596) (xy 292.952672 -280.964552) (xy 292.90821 -280.98565) (xy 292.860939 -280.999342)
			(xy 292.812084 -281.005274) (xy 292.762909 -281.003293) (xy 292.71469 -280.993449) (xy 292.668674 -280.975997)
			(xy 292.626053 -280.95139) (xy 292.587932 -280.920265) (xy 292.555297 -280.883428) (xy 292.528994 -280.841832)
			(xy 292.509703 -280.796556) (xy 292.497926 -280.748772) (xy 292.493966 -280.699718) (xy 292.155118 -280.699718)
			(xy 292.154623 -280.724325) (xy 292.146728 -280.772902) (xy 292.131144 -280.819583) (xy 292.108273 -280.86316)
			(xy 292.078708 -280.902504) (xy 292.043215 -280.936596) (xy 292.002712 -280.964552) (xy 291.95825 -280.98565)
			(xy 291.910979 -280.999342) (xy 291.862124 -281.005274) (xy 291.812949 -281.003293) (xy 291.76473 -280.993449)
			(xy 291.718714 -280.975997) (xy 291.676093 -280.95139) (xy 291.637972 -280.920265) (xy 291.605337 -280.883428)
			(xy 291.579034 -280.841832) (xy 291.559743 -280.796556) (xy 291.547966 -280.748772) (xy 291.544006 -280.699718)
			(xy 291.205158 -280.699718) (xy 291.204663 -280.724325) (xy 291.196768 -280.772902) (xy 291.181184 -280.819583)
			(xy 291.158313 -280.86316) (xy 291.128748 -280.902504) (xy 291.093255 -280.936596) (xy 291.052752 -280.964552)
			(xy 291.00829 -280.98565) (xy 290.961019 -280.999342) (xy 290.912164 -281.005274) (xy 290.862989 -281.003293)
			(xy 290.81477 -280.993449) (xy 290.768754 -280.975997) (xy 290.726133 -280.95139) (xy 290.688012 -280.920265)
			(xy 290.655377 -280.883428) (xy 290.629074 -280.841832) (xy 290.609783 -280.796556) (xy 290.598006 -280.748772)
			(xy 290.594046 -280.699718) (xy 290.255198 -280.699718) (xy 290.254703 -280.724325) (xy 290.246808 -280.772902)
			(xy 290.231224 -280.819583) (xy 290.208353 -280.86316) (xy 290.178788 -280.902504) (xy 290.143295 -280.936596)
			(xy 290.102792 -280.964552) (xy 290.05833 -280.98565) (xy 290.011059 -280.999342) (xy 289.962204 -281.005274)
			(xy 289.913029 -281.003293) (xy 289.86481 -280.993449) (xy 289.818794 -280.975997) (xy 289.776173 -280.95139)
			(xy 289.738052 -280.920265) (xy 289.705417 -280.883428) (xy 289.679114 -280.841832) (xy 289.659823 -280.796556)
			(xy 289.648046 -280.748772) (xy 289.644086 -280.699718) (xy 289.304984 -280.699718) (xy 289.304489 -280.724325)
			(xy 289.296594 -280.772902) (xy 289.28101 -280.819583) (xy 289.258139 -280.86316) (xy 289.228574 -280.902504)
			(xy 289.193081 -280.936596) (xy 289.152578 -280.964552) (xy 289.108116 -280.98565) (xy 289.060845 -280.999342)
			(xy 289.01199 -281.005274) (xy 288.962815 -281.003293) (xy 288.914596 -280.993449) (xy 288.86858 -280.975997)
			(xy 288.825959 -280.95139) (xy 288.787838 -280.920265) (xy 288.755203 -280.883428) (xy 288.7289 -280.841832)
			(xy 288.709609 -280.796556) (xy 288.697832 -280.748772) (xy 288.693872 -280.699718) (xy 288.355024 -280.699718)
			(xy 288.354529 -280.724325) (xy 288.346634 -280.772902) (xy 288.33105 -280.819583) (xy 288.308179 -280.86316)
			(xy 288.278614 -280.902504) (xy 288.243121 -280.936596) (xy 288.202618 -280.964552) (xy 288.158156 -280.98565)
			(xy 288.110885 -280.999342) (xy 288.06203 -281.005274) (xy 288.012855 -281.003293) (xy 287.964636 -280.993449)
			(xy 287.91862 -280.975997) (xy 287.875999 -280.95139) (xy 287.837878 -280.920265) (xy 287.805243 -280.883428)
			(xy 287.77894 -280.841832) (xy 287.759649 -280.796556) (xy 287.747872 -280.748772) (xy 287.743912 -280.699718)
			(xy 287.405064 -280.699718) (xy 287.404569 -280.724325) (xy 287.396674 -280.772902) (xy 287.38109 -280.819583)
			(xy 287.358219 -280.86316) (xy 287.328654 -280.902504) (xy 287.293161 -280.936596) (xy 287.252658 -280.964552)
			(xy 287.208196 -280.98565) (xy 287.160925 -280.999342) (xy 287.11207 -281.005274) (xy 287.062895 -281.003293)
			(xy 287.014676 -280.993449) (xy 286.96866 -280.975997) (xy 286.926039 -280.95139) (xy 286.887918 -280.920265)
			(xy 286.855283 -280.883428) (xy 286.82898 -280.841832) (xy 286.809689 -280.796556) (xy 286.797912 -280.748772)
			(xy 286.793952 -280.699718) (xy 286.455104 -280.699718) (xy 286.454609 -280.724325) (xy 286.446714 -280.772902)
			(xy 286.43113 -280.819583) (xy 286.408259 -280.86316) (xy 286.378694 -280.902504) (xy 286.343201 -280.936596)
			(xy 286.302698 -280.964552) (xy 286.258236 -280.98565) (xy 286.210965 -280.999342) (xy 286.16211 -281.005274)
			(xy 286.112935 -281.003293) (xy 286.064716 -280.993449) (xy 286.0187 -280.975997) (xy 285.976079 -280.95139)
			(xy 285.937958 -280.920265) (xy 285.905323 -280.883428) (xy 285.87902 -280.841832) (xy 285.859729 -280.796556)
			(xy 285.847952 -280.748772) (xy 285.843992 -280.699718) (xy 285.505144 -280.699718) (xy 285.504649 -280.724325)
			(xy 285.496754 -280.772902) (xy 285.48117 -280.819583) (xy 285.458299 -280.86316) (xy 285.428734 -280.902504)
			(xy 285.393241 -280.936596) (xy 285.352738 -280.964552) (xy 285.308276 -280.98565) (xy 285.261005 -280.999342)
			(xy 285.21215 -281.005274) (xy 285.162975 -281.003293) (xy 285.114756 -280.993449) (xy 285.06874 -280.975997)
			(xy 285.026119 -280.95139) (xy 284.987998 -280.920265) (xy 284.955363 -280.883428) (xy 284.92906 -280.841832)
			(xy 284.909769 -280.796556) (xy 284.897992 -280.748772) (xy 284.894032 -280.699718) (xy 284.555184 -280.699718)
			(xy 284.554689 -280.724325) (xy 284.546794 -280.772902) (xy 284.53121 -280.819583) (xy 284.508339 -280.86316)
			(xy 284.478774 -280.902504) (xy 284.443281 -280.936596) (xy 284.402778 -280.964552) (xy 284.358316 -280.98565)
			(xy 284.311045 -280.999342) (xy 284.26219 -281.005274) (xy 284.213015 -281.003293) (xy 284.164796 -280.993449)
			(xy 284.11878 -280.975997) (xy 284.076159 -280.95139) (xy 284.038038 -280.920265) (xy 284.005403 -280.883428)
			(xy 283.9791 -280.841832) (xy 283.959809 -280.796556) (xy 283.948032 -280.748772) (xy 283.944072 -280.699718)
			(xy 283.605224 -280.699718) (xy 283.604729 -280.724325) (xy 283.596834 -280.772902) (xy 283.58125 -280.819583)
			(xy 283.558379 -280.86316) (xy 283.528814 -280.902504) (xy 283.493321 -280.936596) (xy 283.452818 -280.964552)
			(xy 283.408356 -280.98565) (xy 283.361085 -280.999342) (xy 283.31223 -281.005274) (xy 283.263055 -281.003293)
			(xy 283.214836 -280.993449) (xy 283.16882 -280.975997) (xy 283.126199 -280.95139) (xy 283.088078 -280.920265)
			(xy 283.055443 -280.883428) (xy 283.02914 -280.841832) (xy 283.009849 -280.796556) (xy 282.998072 -280.748772)
			(xy 282.994112 -280.699718) (xy 282.65501 -280.699718) (xy 282.654515 -280.724325) (xy 282.64662 -280.772902)
			(xy 282.631036 -280.819583) (xy 282.608165 -280.86316) (xy 282.5786 -280.902504) (xy 282.543107 -280.936596)
			(xy 282.502604 -280.964552) (xy 282.458142 -280.98565) (xy 282.410871 -280.999342) (xy 282.362016 -281.005274)
			(xy 282.312841 -281.003293) (xy 282.264622 -280.993449) (xy 282.218606 -280.975997) (xy 282.175985 -280.95139)
			(xy 282.137864 -280.920265) (xy 282.105229 -280.883428) (xy 282.078926 -280.841832) (xy 282.059635 -280.796556)
			(xy 282.047858 -280.748772) (xy 282.043898 -280.699718) (xy 281.70505 -280.699718) (xy 281.704555 -280.724325)
			(xy 281.69666 -280.772902) (xy 281.681076 -280.819583) (xy 281.658205 -280.86316) (xy 281.62864 -280.902504)
			(xy 281.593147 -280.936596) (xy 281.552644 -280.964552) (xy 281.508182 -280.98565) (xy 281.460911 -280.999342)
			(xy 281.412056 -281.005274) (xy 281.362881 -281.003293) (xy 281.314662 -280.993449) (xy 281.268646 -280.975997)
			(xy 281.226025 -280.95139) (xy 281.187904 -280.920265) (xy 281.155269 -280.883428) (xy 281.128966 -280.841832)
			(xy 281.109675 -280.796556) (xy 281.097898 -280.748772) (xy 281.093938 -280.699718) (xy 280.755641 -280.699718)
			(xy 280.75147 -280.750042) (xy 280.739069 -280.79901) (xy 280.718777 -280.84527) (xy 280.691148 -280.887558)
			(xy 280.656934 -280.924722) (xy 280.61707 -280.955747) (xy 280.572643 -280.979787) (xy 280.524865 -280.996187)
			(xy 280.475039 -281.004499) (xy 280.449782 -281.005026) (xy 280.421083 -281.004371) (xy 280.3647 -280.993626)
			(xy 280.337768 -280.98369) (xy 280.328878 -280.980134) (xy 280.319226 -280.980134) (xy 280.309204 -280.98055)
			(xy 280.290684 -280.988216) (xy 280.276512 -281.002391) (xy 280.268848 -281.020912) (xy 280.268426 -281.030934)
			(xy 280.268426 -281.08021) (xy 280.268934 -281.086306) (xy 280.270204 -281.097482) (xy 280.272236 -281.106372)
			(xy 280.275902 -281.12328) (xy 280.279851 -281.157653) (xy 280.28011 -281.174952) (xy 280.28011 -281.191462)
			(xy 280.279602 -281.197304) (xy 280.279602 -281.197812) (xy 280.278332 -281.208734) (xy 280.278332 -281.208988)
			(xy 280.277824 -281.213052) (xy 280.275284 -281.231848) (xy 280.274268 -281.237436) (xy 280.270204 -281.253184)
			(xy 280.268426 -281.265884) (xy 280.268426 -281.318716) (xy 280.268849 -281.328733) (xy 280.276523 -281.34724)
			(xy 280.290695 -281.361401) (xy 280.309208 -281.369059) (xy 280.319226 -281.369516) (xy 280.328878 -281.369516)
			(xy 280.337768 -281.36596) (xy 280.364705 -281.356043) (xy 280.421086 -281.345307) (xy 280.449782 -281.344624)
			(xy 280.475038 -281.345115) (xy 280.524862 -281.353427) (xy 280.572638 -281.369826) (xy 280.617063 -281.393865)
			(xy 280.656925 -281.424889) (xy 280.691137 -281.462051) (xy 280.718765 -281.504337) (xy 280.739056 -281.550594)
			(xy 280.751457 -281.59956) (xy 280.755628 -281.6499) (xy 280.755625 -281.649932) (xy 281.093938 -281.649932)
			(xy 281.097898 -281.600878) (xy 281.109675 -281.553094) (xy 281.128966 -281.507818) (xy 281.155269 -281.466222)
			(xy 281.187904 -281.429385) (xy 281.226025 -281.39826) (xy 281.268646 -281.373653) (xy 281.314662 -281.356201)
			(xy 281.362881 -281.346357) (xy 281.412056 -281.344376) (xy 281.460911 -281.350308) (xy 281.508182 -281.364)
			(xy 281.552644 -281.385098) (xy 281.593147 -281.413054) (xy 281.62864 -281.447146) (xy 281.658205 -281.48649)
			(xy 281.681076 -281.530067) (xy 281.69666 -281.576748) (xy 281.704555 -281.625325) (xy 281.70505 -281.649932)
			(xy 282.043898 -281.649932) (xy 282.047858 -281.600878) (xy 282.059635 -281.553094) (xy 282.078926 -281.507818)
			(xy 282.105229 -281.466222) (xy 282.137864 -281.429385) (xy 282.175985 -281.39826) (xy 282.218606 -281.373653)
			(xy 282.264622 -281.356201) (xy 282.312841 -281.346357) (xy 282.362016 -281.344376) (xy 282.410871 -281.350308)
			(xy 282.458142 -281.364) (xy 282.502604 -281.385098) (xy 282.543107 -281.413054) (xy 282.5786 -281.447146)
			(xy 282.608165 -281.48649) (xy 282.631036 -281.530067) (xy 282.64662 -281.576748) (xy 282.654515 -281.625325)
			(xy 282.65501 -281.649932) (xy 282.994112 -281.649932) (xy 282.998072 -281.600878) (xy 283.009849 -281.553094)
			(xy 283.02914 -281.507818) (xy 283.055443 -281.466222) (xy 283.088078 -281.429385) (xy 283.126199 -281.39826)
			(xy 283.16882 -281.373653) (xy 283.214836 -281.356201) (xy 283.263055 -281.346357) (xy 283.31223 -281.344376)
			(xy 283.361085 -281.350308) (xy 283.408356 -281.364) (xy 283.452818 -281.385098) (xy 283.493321 -281.413054)
			(xy 283.528814 -281.447146) (xy 283.558379 -281.48649) (xy 283.58125 -281.530067) (xy 283.596834 -281.576748)
			(xy 283.604729 -281.625325) (xy 283.605224 -281.649932) (xy 283.944072 -281.649932) (xy 283.948032 -281.600878)
			(xy 283.959809 -281.553094) (xy 283.9791 -281.507818) (xy 284.005403 -281.466222) (xy 284.038038 -281.429385)
			(xy 284.076159 -281.39826) (xy 284.11878 -281.373653) (xy 284.164796 -281.356201) (xy 284.213015 -281.346357)
			(xy 284.26219 -281.344376) (xy 284.311045 -281.350308) (xy 284.358316 -281.364) (xy 284.402778 -281.385098)
			(xy 284.443281 -281.413054) (xy 284.478774 -281.447146) (xy 284.508339 -281.48649) (xy 284.53121 -281.530067)
			(xy 284.546794 -281.576748) (xy 284.554689 -281.625325) (xy 284.555184 -281.649932) (xy 284.894032 -281.649932)
			(xy 284.897992 -281.600878) (xy 284.909769 -281.553094) (xy 284.92906 -281.507818) (xy 284.955363 -281.466222)
			(xy 284.987998 -281.429385) (xy 285.026119 -281.39826) (xy 285.06874 -281.373653) (xy 285.114756 -281.356201)
			(xy 285.162975 -281.346357) (xy 285.21215 -281.344376) (xy 285.261005 -281.350308) (xy 285.308276 -281.364)
			(xy 285.352738 -281.385098) (xy 285.393241 -281.413054) (xy 285.428734 -281.447146) (xy 285.458299 -281.48649)
			(xy 285.48117 -281.530067) (xy 285.496754 -281.576748) (xy 285.504649 -281.625325) (xy 285.505144 -281.649932)
			(xy 285.843992 -281.649932) (xy 285.847952 -281.600878) (xy 285.859729 -281.553094) (xy 285.87902 -281.507818)
			(xy 285.905323 -281.466222) (xy 285.937958 -281.429385) (xy 285.976079 -281.39826) (xy 286.0187 -281.373653)
			(xy 286.064716 -281.356201) (xy 286.112935 -281.346357) (xy 286.16211 -281.344376) (xy 286.210965 -281.350308)
			(xy 286.258236 -281.364) (xy 286.302698 -281.385098) (xy 286.343201 -281.413054) (xy 286.378694 -281.447146)
			(xy 286.408259 -281.48649) (xy 286.43113 -281.530067) (xy 286.446714 -281.576748) (xy 286.454609 -281.625325)
			(xy 286.455104 -281.649932) (xy 286.793952 -281.649932) (xy 286.797912 -281.600878) (xy 286.809689 -281.553094)
			(xy 286.82898 -281.507818) (xy 286.855283 -281.466222) (xy 286.887918 -281.429385) (xy 286.926039 -281.39826)
			(xy 286.96866 -281.373653) (xy 287.014676 -281.356201) (xy 287.062895 -281.346357) (xy 287.11207 -281.344376)
			(xy 287.160925 -281.350308) (xy 287.208196 -281.364) (xy 287.252658 -281.385098) (xy 287.293161 -281.413054)
			(xy 287.328654 -281.447146) (xy 287.358219 -281.48649) (xy 287.38109 -281.530067) (xy 287.396674 -281.576748)
			(xy 287.404569 -281.625325) (xy 287.405064 -281.649932) (xy 287.743912 -281.649932) (xy 287.747872 -281.600878)
			(xy 287.759649 -281.553094) (xy 287.77894 -281.507818) (xy 287.805243 -281.466222) (xy 287.837878 -281.429385)
			(xy 287.875999 -281.39826) (xy 287.91862 -281.373653) (xy 287.964636 -281.356201) (xy 288.012855 -281.346357)
			(xy 288.06203 -281.344376) (xy 288.110885 -281.350308) (xy 288.158156 -281.364) (xy 288.202618 -281.385098)
			(xy 288.243121 -281.413054) (xy 288.278614 -281.447146) (xy 288.308179 -281.48649) (xy 288.33105 -281.530067)
			(xy 288.346634 -281.576748) (xy 288.354529 -281.625325) (xy 288.355024 -281.649932) (xy 288.694126 -281.649932)
			(xy 288.698086 -281.600878) (xy 288.709863 -281.553094) (xy 288.729154 -281.507818) (xy 288.755457 -281.466222)
			(xy 288.788092 -281.429385) (xy 288.826213 -281.39826) (xy 288.868834 -281.373653) (xy 288.91485 -281.356201)
			(xy 288.963069 -281.346357) (xy 289.012244 -281.344376) (xy 289.061099 -281.350308) (xy 289.10837 -281.364)
			(xy 289.152832 -281.385098) (xy 289.193335 -281.413054) (xy 289.228828 -281.447146) (xy 289.258393 -281.48649)
			(xy 289.281264 -281.530067) (xy 289.296848 -281.576748) (xy 289.304743 -281.625325) (xy 289.305238 -281.649932)
			(xy 289.644086 -281.649932) (xy 289.648046 -281.600878) (xy 289.659823 -281.553094) (xy 289.679114 -281.507818)
			(xy 289.705417 -281.466222) (xy 289.738052 -281.429385) (xy 289.776173 -281.39826) (xy 289.818794 -281.373653)
			(xy 289.86481 -281.356201) (xy 289.913029 -281.346357) (xy 289.962204 -281.344376) (xy 290.011059 -281.350308)
			(xy 290.05833 -281.364) (xy 290.102792 -281.385098) (xy 290.143295 -281.413054) (xy 290.178788 -281.447146)
			(xy 290.208353 -281.48649) (xy 290.231224 -281.530067) (xy 290.246808 -281.576748) (xy 290.254703 -281.625325)
			(xy 290.255198 -281.649932) (xy 290.594046 -281.649932) (xy 290.598006 -281.600878) (xy 290.609783 -281.553094)
			(xy 290.629074 -281.507818) (xy 290.655377 -281.466222) (xy 290.688012 -281.429385) (xy 290.726133 -281.39826)
			(xy 290.768754 -281.373653) (xy 290.81477 -281.356201) (xy 290.862989 -281.346357) (xy 290.912164 -281.344376)
			(xy 290.961019 -281.350308) (xy 291.00829 -281.364) (xy 291.052752 -281.385098) (xy 291.093255 -281.413054)
			(xy 291.128748 -281.447146) (xy 291.158313 -281.48649) (xy 291.181184 -281.530067) (xy 291.196768 -281.576748)
			(xy 291.204663 -281.625325) (xy 291.205158 -281.649932) (xy 291.544006 -281.649932) (xy 291.547966 -281.600878)
			(xy 291.559743 -281.553094) (xy 291.579034 -281.507818) (xy 291.605337 -281.466222) (xy 291.637972 -281.429385)
			(xy 291.676093 -281.39826) (xy 291.718714 -281.373653) (xy 291.76473 -281.356201) (xy 291.812949 -281.346357)
			(xy 291.862124 -281.344376) (xy 291.910979 -281.350308) (xy 291.95825 -281.364) (xy 292.002712 -281.385098)
			(xy 292.043215 -281.413054) (xy 292.078708 -281.447146) (xy 292.108273 -281.48649) (xy 292.131144 -281.530067)
			(xy 292.146728 -281.576748) (xy 292.154623 -281.625325) (xy 292.155118 -281.649932) (xy 292.493966 -281.649932)
			(xy 292.497926 -281.600878) (xy 292.509703 -281.553094) (xy 292.528994 -281.507818) (xy 292.555297 -281.466222)
			(xy 292.587932 -281.429385) (xy 292.626053 -281.39826) (xy 292.668674 -281.373653) (xy 292.71469 -281.356201)
			(xy 292.762909 -281.346357) (xy 292.812084 -281.344376) (xy 292.860939 -281.350308) (xy 292.90821 -281.364)
			(xy 292.952672 -281.385098) (xy 292.993175 -281.413054) (xy 293.028668 -281.447146) (xy 293.058233 -281.48649)
			(xy 293.081104 -281.530067) (xy 293.096688 -281.576748) (xy 293.104583 -281.625325) (xy 293.105078 -281.649932)
			(xy 293.443926 -281.649932) (xy 293.447886 -281.600878) (xy 293.459663 -281.553094) (xy 293.478954 -281.507818)
			(xy 293.505257 -281.466222) (xy 293.537892 -281.429385) (xy 293.576013 -281.39826) (xy 293.618634 -281.373653)
			(xy 293.66465 -281.356201) (xy 293.712869 -281.346357) (xy 293.762044 -281.344376) (xy 293.810899 -281.350308)
			(xy 293.85817 -281.364) (xy 293.902632 -281.385098) (xy 293.943135 -281.413054) (xy 293.978628 -281.447146)
			(xy 294.008193 -281.48649) (xy 294.031064 -281.530067) (xy 294.046648 -281.576748) (xy 294.054543 -281.625325)
			(xy 294.055038 -281.649932) (xy 294.393886 -281.649932) (xy 294.397846 -281.600878) (xy 294.409623 -281.553094)
			(xy 294.428914 -281.507818) (xy 294.455217 -281.466222) (xy 294.487852 -281.429385) (xy 294.525973 -281.39826)
			(xy 294.568594 -281.373653) (xy 294.61461 -281.356201) (xy 294.662829 -281.346357) (xy 294.712004 -281.344376)
			(xy 294.760859 -281.350308) (xy 294.80813 -281.364) (xy 294.852592 -281.385098) (xy 294.893095 -281.413054)
			(xy 294.928588 -281.447146) (xy 294.958153 -281.48649) (xy 294.981024 -281.530067) (xy 294.996608 -281.576748)
			(xy 295.004503 -281.625325) (xy 295.004998 -281.649932) (xy 295.3441 -281.649932) (xy 295.34806 -281.600878)
			(xy 295.359837 -281.553094) (xy 295.379128 -281.507818) (xy 295.405431 -281.466222) (xy 295.438066 -281.429385)
			(xy 295.476187 -281.39826) (xy 295.518808 -281.373653) (xy 295.564824 -281.356201) (xy 295.613043 -281.346357)
			(xy 295.662218 -281.344376) (xy 295.711073 -281.350308) (xy 295.758344 -281.364) (xy 295.802806 -281.385098)
			(xy 295.843309 -281.413054) (xy 295.878802 -281.447146) (xy 295.908367 -281.48649) (xy 295.931238 -281.530067)
			(xy 295.946822 -281.576748) (xy 295.954717 -281.625325) (xy 295.955212 -281.649932) (xy 296.29406 -281.649932)
			(xy 296.29802 -281.600878) (xy 296.309797 -281.553094) (xy 296.329088 -281.507818) (xy 296.355391 -281.466222)
			(xy 296.388026 -281.429385) (xy 296.426147 -281.39826) (xy 296.468768 -281.373653) (xy 296.514784 -281.356201)
			(xy 296.563003 -281.346357) (xy 296.612178 -281.344376) (xy 296.661033 -281.350308) (xy 296.708304 -281.364)
			(xy 296.752766 -281.385098) (xy 296.793269 -281.413054) (xy 296.828762 -281.447146) (xy 296.858327 -281.48649)
			(xy 296.881198 -281.530067) (xy 296.896782 -281.576748) (xy 296.904677 -281.625325) (xy 296.905172 -281.649932)
			(xy 297.24402 -281.649932) (xy 297.24798 -281.600878) (xy 297.259757 -281.553094) (xy 297.279048 -281.507818)
			(xy 297.305351 -281.466222) (xy 297.337986 -281.429385) (xy 297.376107 -281.39826) (xy 297.418728 -281.373653)
			(xy 297.464744 -281.356201) (xy 297.512963 -281.346357) (xy 297.562138 -281.344376) (xy 297.610993 -281.350308)
			(xy 297.658264 -281.364) (xy 297.702726 -281.385098) (xy 297.743229 -281.413054) (xy 297.778722 -281.447146)
			(xy 297.808287 -281.48649) (xy 297.831158 -281.530067) (xy 297.846742 -281.576748) (xy 297.854637 -281.625325)
			(xy 297.855132 -281.649932) (xy 298.19398 -281.649932) (xy 298.19794 -281.600878) (xy 298.209717 -281.553094)
			(xy 298.229008 -281.507818) (xy 298.255311 -281.466222) (xy 298.287946 -281.429385) (xy 298.326067 -281.39826)
			(xy 298.368688 -281.373653) (xy 298.414704 -281.356201) (xy 298.462923 -281.346357) (xy 298.512098 -281.344376)
			(xy 298.560953 -281.350308) (xy 298.608224 -281.364) (xy 298.652686 -281.385098) (xy 298.693189 -281.413054)
			(xy 298.728682 -281.447146) (xy 298.758247 -281.48649) (xy 298.781118 -281.530067) (xy 298.796702 -281.576748)
			(xy 298.804597 -281.625325) (xy 298.805092 -281.649932) (xy 299.14394 -281.649932) (xy 299.1479 -281.600878)
			(xy 299.159677 -281.553094) (xy 299.178968 -281.507818) (xy 299.205271 -281.466222) (xy 299.237906 -281.429385)
			(xy 299.276027 -281.39826) (xy 299.318648 -281.373653) (xy 299.364664 -281.356201) (xy 299.412883 -281.346357)
			(xy 299.462058 -281.344376) (xy 299.510913 -281.350308) (xy 299.558184 -281.364) (xy 299.602646 -281.385098)
			(xy 299.643149 -281.413054) (xy 299.678642 -281.447146) (xy 299.708207 -281.48649) (xy 299.731078 -281.530067)
			(xy 299.746662 -281.576748) (xy 299.754557 -281.625325) (xy 299.755052 -281.649932) (xy 300.0939 -281.649932)
			(xy 300.09786 -281.600878) (xy 300.109637 -281.553094) (xy 300.128928 -281.507818) (xy 300.155231 -281.466222)
			(xy 300.187866 -281.429385) (xy 300.225987 -281.39826) (xy 300.268608 -281.373653) (xy 300.314624 -281.356201)
			(xy 300.362843 -281.346357) (xy 300.412018 -281.344376) (xy 300.460873 -281.350308) (xy 300.508144 -281.364)
			(xy 300.552606 -281.385098) (xy 300.593109 -281.413054) (xy 300.628602 -281.447146) (xy 300.658167 -281.48649)
			(xy 300.681038 -281.530067) (xy 300.696622 -281.576748) (xy 300.704517 -281.625325) (xy 300.705012 -281.649932)
			(xy 301.044114 -281.649932) (xy 301.048074 -281.600878) (xy 301.059851 -281.553094) (xy 301.079142 -281.507818)
			(xy 301.105445 -281.466222) (xy 301.13808 -281.429385) (xy 301.176201 -281.39826) (xy 301.218822 -281.373653)
			(xy 301.264838 -281.356201) (xy 301.313057 -281.346357) (xy 301.362232 -281.344376) (xy 301.411087 -281.350308)
			(xy 301.458358 -281.364) (xy 301.50282 -281.385098) (xy 301.543323 -281.413054) (xy 301.578816 -281.447146)
			(xy 301.608381 -281.48649) (xy 301.631252 -281.530067) (xy 301.646836 -281.576748) (xy 301.654731 -281.625325)
			(xy 301.655226 -281.649932) (xy 301.994074 -281.649932) (xy 301.998034 -281.600878) (xy 302.009811 -281.553094)
			(xy 302.029102 -281.507818) (xy 302.055405 -281.466222) (xy 302.08804 -281.429385) (xy 302.126161 -281.39826)
			(xy 302.168782 -281.373653) (xy 302.214798 -281.356201) (xy 302.263017 -281.346357) (xy 302.312192 -281.344376)
			(xy 302.361047 -281.350308) (xy 302.408318 -281.364) (xy 302.45278 -281.385098) (xy 302.493283 -281.413054)
			(xy 302.528776 -281.447146) (xy 302.558341 -281.48649) (xy 302.581212 -281.530067) (xy 302.596796 -281.576748)
			(xy 302.604691 -281.625325) (xy 302.605186 -281.649932) (xy 302.944034 -281.649932) (xy 302.947994 -281.600878)
			(xy 302.959771 -281.553094) (xy 302.979062 -281.507818) (xy 303.005365 -281.466222) (xy 303.038 -281.429385)
			(xy 303.076121 -281.39826) (xy 303.118742 -281.373653) (xy 303.164758 -281.356201) (xy 303.212977 -281.346357)
			(xy 303.262152 -281.344376) (xy 303.311007 -281.350308) (xy 303.358278 -281.364) (xy 303.40274 -281.385098)
			(xy 303.443243 -281.413054) (xy 303.478736 -281.447146) (xy 303.508301 -281.48649) (xy 303.531172 -281.530067)
			(xy 303.546756 -281.576748) (xy 303.554651 -281.625325) (xy 303.555146 -281.649932) (xy 303.893994 -281.649932)
			(xy 303.897954 -281.600878) (xy 303.909731 -281.553094) (xy 303.929022 -281.507818) (xy 303.955325 -281.466222)
			(xy 303.98796 -281.429385) (xy 304.026081 -281.39826) (xy 304.068702 -281.373653) (xy 304.114718 -281.356201)
			(xy 304.162937 -281.346357) (xy 304.212112 -281.344376) (xy 304.260967 -281.350308) (xy 304.308238 -281.364)
			(xy 304.3527 -281.385098) (xy 304.393203 -281.413054) (xy 304.428696 -281.447146) (xy 304.458261 -281.48649)
			(xy 304.481132 -281.530067) (xy 304.496716 -281.576748) (xy 304.504611 -281.625325) (xy 304.505106 -281.649932)
			(xy 304.843954 -281.649932) (xy 304.847914 -281.600878) (xy 304.859691 -281.553094) (xy 304.878982 -281.507818)
			(xy 304.905285 -281.466222) (xy 304.93792 -281.429385) (xy 304.976041 -281.39826) (xy 305.018662 -281.373653)
			(xy 305.064678 -281.356201) (xy 305.112897 -281.346357) (xy 305.162072 -281.344376) (xy 305.210927 -281.350308)
			(xy 305.258198 -281.364) (xy 305.30266 -281.385098) (xy 305.343163 -281.413054) (xy 305.378656 -281.447146)
			(xy 305.408221 -281.48649) (xy 305.431092 -281.530067) (xy 305.446676 -281.576748) (xy 305.454571 -281.625325)
			(xy 305.455066 -281.649932) (xy 305.793914 -281.649932) (xy 305.797874 -281.600878) (xy 305.809651 -281.553094)
			(xy 305.828942 -281.507818) (xy 305.855245 -281.466222) (xy 305.88788 -281.429385) (xy 305.926001 -281.39826)
			(xy 305.968622 -281.373653) (xy 306.014638 -281.356201) (xy 306.062857 -281.346357) (xy 306.112032 -281.344376)
			(xy 306.160887 -281.350308) (xy 306.208158 -281.364) (xy 306.25262 -281.385098) (xy 306.293123 -281.413054)
			(xy 306.328616 -281.447146) (xy 306.358181 -281.48649) (xy 306.381052 -281.530067) (xy 306.396636 -281.576748)
			(xy 306.404531 -281.625325) (xy 306.405026 -281.649932) (xy 306.744128 -281.649932) (xy 306.748088 -281.600878)
			(xy 306.759865 -281.553094) (xy 306.779156 -281.507818) (xy 306.805459 -281.466222) (xy 306.838094 -281.429385)
			(xy 306.876215 -281.39826) (xy 306.918836 -281.373653) (xy 306.964852 -281.356201) (xy 307.013071 -281.346357)
			(xy 307.062246 -281.344376) (xy 307.111101 -281.350308) (xy 307.158372 -281.364) (xy 307.202834 -281.385098)
			(xy 307.243337 -281.413054) (xy 307.27883 -281.447146) (xy 307.308395 -281.48649) (xy 307.331266 -281.530067)
			(xy 307.34685 -281.576748) (xy 307.354745 -281.625325) (xy 307.35524 -281.649932) (xy 307.694088 -281.649932)
			(xy 307.698048 -281.600878) (xy 307.709825 -281.553094) (xy 307.729116 -281.507818) (xy 307.755419 -281.466222)
			(xy 307.788054 -281.429385) (xy 307.826175 -281.39826) (xy 307.868796 -281.373653) (xy 307.914812 -281.356201)
			(xy 307.963031 -281.346357) (xy 308.012206 -281.344376) (xy 308.061061 -281.350308) (xy 308.108332 -281.364)
			(xy 308.152794 -281.385098) (xy 308.193297 -281.413054) (xy 308.22879 -281.447146) (xy 308.258355 -281.48649)
			(xy 308.281226 -281.530067) (xy 308.29681 -281.576748) (xy 308.304705 -281.625325) (xy 308.3052 -281.649932)
			(xy 308.644048 -281.649932) (xy 308.648008 -281.600878) (xy 308.659785 -281.553094) (xy 308.679076 -281.507818)
			(xy 308.705379 -281.466222) (xy 308.738014 -281.429385) (xy 308.776135 -281.39826) (xy 308.818756 -281.373653)
			(xy 308.864772 -281.356201) (xy 308.912991 -281.346357) (xy 308.962166 -281.344376) (xy 309.011021 -281.350308)
			(xy 309.058292 -281.364) (xy 309.102754 -281.385098) (xy 309.143257 -281.413054) (xy 309.17875 -281.447146)
			(xy 309.208315 -281.48649) (xy 309.231186 -281.530067) (xy 309.24677 -281.576748) (xy 309.254665 -281.625325)
			(xy 309.255155 -281.649678) (xy 309.593754 -281.649678) (xy 309.597714 -281.600624) (xy 309.609491 -281.55284)
			(xy 309.628782 -281.507564) (xy 309.655085 -281.465968) (xy 309.68772 -281.429131) (xy 309.725841 -281.398006)
			(xy 309.768462 -281.373399) (xy 309.814478 -281.355947) (xy 309.862697 -281.346103) (xy 309.911872 -281.344122)
			(xy 309.960727 -281.350054) (xy 310.007998 -281.363746) (xy 310.05246 -281.384844) (xy 310.092963 -281.4128)
			(xy 310.128456 -281.446892) (xy 310.158021 -281.486236) (xy 310.180892 -281.529813) (xy 310.196476 -281.576494)
			(xy 310.204371 -281.625071) (xy 310.204866 -281.649678) (xy 310.204861 -281.649932) (xy 310.543714 -281.649932)
			(xy 310.547674 -281.600878) (xy 310.559451 -281.553094) (xy 310.578742 -281.507818) (xy 310.605045 -281.466222)
			(xy 310.63768 -281.429385) (xy 310.675801 -281.39826) (xy 310.718422 -281.373653) (xy 310.764438 -281.356201)
			(xy 310.812657 -281.346357) (xy 310.861832 -281.344376) (xy 310.910687 -281.350308) (xy 310.957958 -281.364)
			(xy 311.00242 -281.385098) (xy 311.042923 -281.413054) (xy 311.078416 -281.447146) (xy 311.107981 -281.48649)
			(xy 311.130852 -281.530067) (xy 311.146436 -281.576748) (xy 311.154331 -281.625325) (xy 311.154826 -281.649932)
			(xy 311.493928 -281.649932) (xy 311.497888 -281.600878) (xy 311.509665 -281.553094) (xy 311.528956 -281.507818)
			(xy 311.555259 -281.466222) (xy 311.587894 -281.429385) (xy 311.626015 -281.39826) (xy 311.668636 -281.373653)
			(xy 311.714652 -281.356201) (xy 311.762871 -281.346357) (xy 311.812046 -281.344376) (xy 311.860901 -281.350308)
			(xy 311.908172 -281.364) (xy 311.952634 -281.385098) (xy 311.993137 -281.413054) (xy 312.02863 -281.447146)
			(xy 312.058195 -281.48649) (xy 312.081066 -281.530067) (xy 312.09665 -281.576748) (xy 312.104545 -281.625325)
			(xy 312.10504 -281.649932) (xy 312.443888 -281.649932) (xy 312.447848 -281.600878) (xy 312.459625 -281.553094)
			(xy 312.478916 -281.507818) (xy 312.505219 -281.466222) (xy 312.537854 -281.429385) (xy 312.575975 -281.39826)
			(xy 312.618596 -281.373653) (xy 312.664612 -281.356201) (xy 312.712831 -281.346357) (xy 312.762006 -281.344376)
			(xy 312.810861 -281.350308) (xy 312.858132 -281.364) (xy 312.902594 -281.385098) (xy 312.943097 -281.413054)
			(xy 312.97859 -281.447146) (xy 313.008155 -281.48649) (xy 313.031026 -281.530067) (xy 313.04661 -281.576748)
			(xy 313.054505 -281.625325) (xy 313.055 -281.649932) (xy 313.054505 -281.674539) (xy 313.054326 -281.67564)
			(xy 313.373258 -281.67564) (xy 313.373258 -281.624224) (xy 313.381301 -281.573442) (xy 313.397189 -281.524543)
			(xy 313.420532 -281.478731) (xy 313.450753 -281.437135) (xy 313.487109 -281.400779) (xy 313.528705 -281.370558)
			(xy 313.574517 -281.347215) (xy 313.623416 -281.331327) (xy 313.674198 -281.323284) (xy 313.725614 -281.323284)
			(xy 313.776396 -281.331327) (xy 313.825295 -281.347215) (xy 313.871107 -281.370558) (xy 313.912703 -281.400779)
			(xy 313.949059 -281.437135) (xy 313.97928 -281.478731) (xy 314.002623 -281.524543) (xy 314.018511 -281.573442)
			(xy 314.026554 -281.624224) (xy 314.027058 -281.649932) (xy 314.026554 -281.67564) (xy 314.323218 -281.67564)
			(xy 314.323218 -281.624224) (xy 314.331261 -281.573442) (xy 314.347149 -281.524543) (xy 314.370492 -281.478731)
			(xy 314.400713 -281.437135) (xy 314.437069 -281.400779) (xy 314.478665 -281.370558) (xy 314.524477 -281.347215)
			(xy 314.573376 -281.331327) (xy 314.624158 -281.323284) (xy 314.675574 -281.323284) (xy 314.726356 -281.331327)
			(xy 314.775255 -281.347215) (xy 314.821067 -281.370558) (xy 314.862663 -281.400779) (xy 314.899019 -281.437135)
			(xy 314.92924 -281.478731) (xy 314.952583 -281.524543) (xy 314.968471 -281.573442) (xy 314.976514 -281.624224)
			(xy 314.977018 -281.649932) (xy 314.977013 -281.650186) (xy 315.294276 -281.650186) (xy 315.298236 -281.601132)
			(xy 315.310013 -281.553348) (xy 315.329304 -281.508072) (xy 315.355607 -281.466476) (xy 315.388242 -281.429639)
			(xy 315.426363 -281.398514) (xy 315.468984 -281.373907) (xy 315.515 -281.356455) (xy 315.563219 -281.346611)
			(xy 315.612394 -281.34463) (xy 315.661249 -281.350562) (xy 315.70852 -281.364254) (xy 315.752982 -281.385352)
			(xy 315.793485 -281.413308) (xy 315.828978 -281.4474) (xy 315.858543 -281.486744) (xy 315.881414 -281.530321)
			(xy 315.896998 -281.577002) (xy 315.904893 -281.625579) (xy 315.905388 -281.650186) (xy 315.904893 -281.674793)
			(xy 315.896998 -281.72337) (xy 315.881414 -281.770051) (xy 315.858543 -281.813628) (xy 315.828978 -281.852972)
			(xy 315.793485 -281.887064) (xy 315.752982 -281.91502) (xy 315.70852 -281.936118) (xy 315.661249 -281.94981)
			(xy 315.612394 -281.955742) (xy 315.563219 -281.953761) (xy 315.515 -281.943917) (xy 315.468984 -281.926465)
			(xy 315.426363 -281.901858) (xy 315.388242 -281.870733) (xy 315.355607 -281.833896) (xy 315.329304 -281.7923)
			(xy 315.310013 -281.747024) (xy 315.298236 -281.69924) (xy 315.294276 -281.650186) (xy 314.977013 -281.650186)
			(xy 314.976514 -281.67564) (xy 314.968471 -281.726422) (xy 314.952583 -281.775321) (xy 314.92924 -281.821133)
			(xy 314.899019 -281.862729) (xy 314.862663 -281.899085) (xy 314.821067 -281.929306) (xy 314.775255 -281.952649)
			(xy 314.726356 -281.968537) (xy 314.675574 -281.97658) (xy 314.624158 -281.97658) (xy 314.573376 -281.968537)
			(xy 314.524477 -281.952649) (xy 314.478665 -281.929306) (xy 314.437069 -281.899085) (xy 314.400713 -281.862729)
			(xy 314.370492 -281.821133) (xy 314.347149 -281.775321) (xy 314.331261 -281.726422) (xy 314.323218 -281.67564)
			(xy 314.026554 -281.67564) (xy 314.018511 -281.726422) (xy 314.002623 -281.775321) (xy 313.97928 -281.821133)
			(xy 313.949059 -281.862729) (xy 313.912703 -281.899085) (xy 313.871107 -281.929306) (xy 313.825295 -281.952649)
			(xy 313.776396 -281.968537) (xy 313.725614 -281.97658) (xy 313.674198 -281.97658) (xy 313.623416 -281.968537)
			(xy 313.574517 -281.952649) (xy 313.528705 -281.929306) (xy 313.487109 -281.899085) (xy 313.450753 -281.862729)
			(xy 313.420532 -281.821133) (xy 313.397189 -281.775321) (xy 313.381301 -281.726422) (xy 313.373258 -281.67564)
			(xy 313.054326 -281.67564) (xy 313.04661 -281.723116) (xy 313.031026 -281.769797) (xy 313.008155 -281.813374)
			(xy 312.97859 -281.852718) (xy 312.943097 -281.88681) (xy 312.902594 -281.914766) (xy 312.858132 -281.935864)
			(xy 312.810861 -281.949556) (xy 312.762006 -281.955488) (xy 312.712831 -281.953507) (xy 312.664612 -281.943663)
			(xy 312.618596 -281.926211) (xy 312.575975 -281.901604) (xy 312.537854 -281.870479) (xy 312.505219 -281.833642)
			(xy 312.478916 -281.792046) (xy 312.459625 -281.74677) (xy 312.447848 -281.698986) (xy 312.443888 -281.649932)
			(xy 312.10504 -281.649932) (xy 312.104545 -281.674539) (xy 312.09665 -281.723116) (xy 312.081066 -281.769797)
			(xy 312.058195 -281.813374) (xy 312.02863 -281.852718) (xy 311.993137 -281.88681) (xy 311.952634 -281.914766)
			(xy 311.908172 -281.935864) (xy 311.860901 -281.949556) (xy 311.812046 -281.955488) (xy 311.762871 -281.953507)
			(xy 311.714652 -281.943663) (xy 311.668636 -281.926211) (xy 311.626015 -281.901604) (xy 311.587894 -281.870479)
			(xy 311.555259 -281.833642) (xy 311.528956 -281.792046) (xy 311.509665 -281.74677) (xy 311.497888 -281.698986)
			(xy 311.493928 -281.649932) (xy 311.154826 -281.649932) (xy 311.154331 -281.674539) (xy 311.146436 -281.723116)
			(xy 311.130852 -281.769797) (xy 311.107981 -281.813374) (xy 311.078416 -281.852718) (xy 311.042923 -281.88681)
			(xy 311.00242 -281.914766) (xy 310.957958 -281.935864) (xy 310.910687 -281.949556) (xy 310.861832 -281.955488)
			(xy 310.812657 -281.953507) (xy 310.764438 -281.943663) (xy 310.718422 -281.926211) (xy 310.675801 -281.901604)
			(xy 310.63768 -281.870479) (xy 310.605045 -281.833642) (xy 310.578742 -281.792046) (xy 310.559451 -281.74677)
			(xy 310.547674 -281.698986) (xy 310.543714 -281.649932) (xy 310.204861 -281.649932) (xy 310.204371 -281.674285)
			(xy 310.196476 -281.722862) (xy 310.180892 -281.769543) (xy 310.158021 -281.81312) (xy 310.128456 -281.852464)
			(xy 310.092963 -281.886556) (xy 310.05246 -281.914512) (xy 310.007998 -281.93561) (xy 309.960727 -281.949302)
			(xy 309.911872 -281.955234) (xy 309.862697 -281.953253) (xy 309.814478 -281.943409) (xy 309.768462 -281.925957)
			(xy 309.725841 -281.90135) (xy 309.68772 -281.870225) (xy 309.655085 -281.833388) (xy 309.628782 -281.791792)
			(xy 309.609491 -281.746516) (xy 309.597714 -281.698732) (xy 309.593754 -281.649678) (xy 309.255155 -281.649678)
			(xy 309.25516 -281.649932) (xy 309.254665 -281.674539) (xy 309.24677 -281.723116) (xy 309.231186 -281.769797)
			(xy 309.208315 -281.813374) (xy 309.17875 -281.852718) (xy 309.143257 -281.88681) (xy 309.102754 -281.914766)
			(xy 309.058292 -281.935864) (xy 309.011021 -281.949556) (xy 308.962166 -281.955488) (xy 308.912991 -281.953507)
			(xy 308.864772 -281.943663) (xy 308.818756 -281.926211) (xy 308.776135 -281.901604) (xy 308.738014 -281.870479)
			(xy 308.705379 -281.833642) (xy 308.679076 -281.792046) (xy 308.659785 -281.74677) (xy 308.648008 -281.698986)
			(xy 308.644048 -281.649932) (xy 308.3052 -281.649932) (xy 308.304705 -281.674539) (xy 308.29681 -281.723116)
			(xy 308.281226 -281.769797) (xy 308.258355 -281.813374) (xy 308.22879 -281.852718) (xy 308.193297 -281.88681)
			(xy 308.152794 -281.914766) (xy 308.108332 -281.935864) (xy 308.061061 -281.949556) (xy 308.012206 -281.955488)
			(xy 307.963031 -281.953507) (xy 307.914812 -281.943663) (xy 307.868796 -281.926211) (xy 307.826175 -281.901604)
			(xy 307.788054 -281.870479) (xy 307.755419 -281.833642) (xy 307.729116 -281.792046) (xy 307.709825 -281.74677)
			(xy 307.698048 -281.698986) (xy 307.694088 -281.649932) (xy 307.35524 -281.649932) (xy 307.354745 -281.674539)
			(xy 307.34685 -281.723116) (xy 307.331266 -281.769797) (xy 307.308395 -281.813374) (xy 307.27883 -281.852718)
			(xy 307.243337 -281.88681) (xy 307.202834 -281.914766) (xy 307.158372 -281.935864) (xy 307.111101 -281.949556)
			(xy 307.062246 -281.955488) (xy 307.013071 -281.953507) (xy 306.964852 -281.943663) (xy 306.918836 -281.926211)
			(xy 306.876215 -281.901604) (xy 306.838094 -281.870479) (xy 306.805459 -281.833642) (xy 306.779156 -281.792046)
			(xy 306.759865 -281.74677) (xy 306.748088 -281.698986) (xy 306.744128 -281.649932) (xy 306.405026 -281.649932)
			(xy 306.404531 -281.674539) (xy 306.396636 -281.723116) (xy 306.381052 -281.769797) (xy 306.358181 -281.813374)
			(xy 306.328616 -281.852718) (xy 306.293123 -281.88681) (xy 306.25262 -281.914766) (xy 306.208158 -281.935864)
			(xy 306.160887 -281.949556) (xy 306.112032 -281.955488) (xy 306.062857 -281.953507) (xy 306.014638 -281.943663)
			(xy 305.968622 -281.926211) (xy 305.926001 -281.901604) (xy 305.88788 -281.870479) (xy 305.855245 -281.833642)
			(xy 305.828942 -281.792046) (xy 305.809651 -281.74677) (xy 305.797874 -281.698986) (xy 305.793914 -281.649932)
			(xy 305.455066 -281.649932) (xy 305.454571 -281.674539) (xy 305.446676 -281.723116) (xy 305.431092 -281.769797)
			(xy 305.408221 -281.813374) (xy 305.378656 -281.852718) (xy 305.343163 -281.88681) (xy 305.30266 -281.914766)
			(xy 305.258198 -281.935864) (xy 305.210927 -281.949556) (xy 305.162072 -281.955488) (xy 305.112897 -281.953507)
			(xy 305.064678 -281.943663) (xy 305.018662 -281.926211) (xy 304.976041 -281.901604) (xy 304.93792 -281.870479)
			(xy 304.905285 -281.833642) (xy 304.878982 -281.792046) (xy 304.859691 -281.74677) (xy 304.847914 -281.698986)
			(xy 304.843954 -281.649932) (xy 304.505106 -281.649932) (xy 304.504611 -281.674539) (xy 304.496716 -281.723116)
			(xy 304.481132 -281.769797) (xy 304.458261 -281.813374) (xy 304.428696 -281.852718) (xy 304.393203 -281.88681)
			(xy 304.3527 -281.914766) (xy 304.308238 -281.935864) (xy 304.260967 -281.949556) (xy 304.212112 -281.955488)
			(xy 304.162937 -281.953507) (xy 304.114718 -281.943663) (xy 304.068702 -281.926211) (xy 304.026081 -281.901604)
			(xy 303.98796 -281.870479) (xy 303.955325 -281.833642) (xy 303.929022 -281.792046) (xy 303.909731 -281.74677)
			(xy 303.897954 -281.698986) (xy 303.893994 -281.649932) (xy 303.555146 -281.649932) (xy 303.554651 -281.674539)
			(xy 303.546756 -281.723116) (xy 303.531172 -281.769797) (xy 303.508301 -281.813374) (xy 303.478736 -281.852718)
			(xy 303.443243 -281.88681) (xy 303.40274 -281.914766) (xy 303.358278 -281.935864) (xy 303.311007 -281.949556)
			(xy 303.262152 -281.955488) (xy 303.212977 -281.953507) (xy 303.164758 -281.943663) (xy 303.118742 -281.926211)
			(xy 303.076121 -281.901604) (xy 303.038 -281.870479) (xy 303.005365 -281.833642) (xy 302.979062 -281.792046)
			(xy 302.959771 -281.74677) (xy 302.947994 -281.698986) (xy 302.944034 -281.649932) (xy 302.605186 -281.649932)
			(xy 302.604691 -281.674539) (xy 302.596796 -281.723116) (xy 302.581212 -281.769797) (xy 302.558341 -281.813374)
			(xy 302.528776 -281.852718) (xy 302.493283 -281.88681) (xy 302.45278 -281.914766) (xy 302.408318 -281.935864)
			(xy 302.361047 -281.949556) (xy 302.312192 -281.955488) (xy 302.263017 -281.953507) (xy 302.214798 -281.943663)
			(xy 302.168782 -281.926211) (xy 302.126161 -281.901604) (xy 302.08804 -281.870479) (xy 302.055405 -281.833642)
			(xy 302.029102 -281.792046) (xy 302.009811 -281.74677) (xy 301.998034 -281.698986) (xy 301.994074 -281.649932)
			(xy 301.655226 -281.649932) (xy 301.654731 -281.674539) (xy 301.646836 -281.723116) (xy 301.631252 -281.769797)
			(xy 301.608381 -281.813374) (xy 301.578816 -281.852718) (xy 301.543323 -281.88681) (xy 301.50282 -281.914766)
			(xy 301.458358 -281.935864) (xy 301.411087 -281.949556) (xy 301.362232 -281.955488) (xy 301.313057 -281.953507)
			(xy 301.264838 -281.943663) (xy 301.218822 -281.926211) (xy 301.176201 -281.901604) (xy 301.13808 -281.870479)
			(xy 301.105445 -281.833642) (xy 301.079142 -281.792046) (xy 301.059851 -281.74677) (xy 301.048074 -281.698986)
			(xy 301.044114 -281.649932) (xy 300.705012 -281.649932) (xy 300.704517 -281.674539) (xy 300.696622 -281.723116)
			(xy 300.681038 -281.769797) (xy 300.658167 -281.813374) (xy 300.628602 -281.852718) (xy 300.593109 -281.88681)
			(xy 300.552606 -281.914766) (xy 300.508144 -281.935864) (xy 300.460873 -281.949556) (xy 300.412018 -281.955488)
			(xy 300.362843 -281.953507) (xy 300.314624 -281.943663) (xy 300.268608 -281.926211) (xy 300.225987 -281.901604)
			(xy 300.187866 -281.870479) (xy 300.155231 -281.833642) (xy 300.128928 -281.792046) (xy 300.109637 -281.74677)
			(xy 300.09786 -281.698986) (xy 300.0939 -281.649932) (xy 299.755052 -281.649932) (xy 299.754557 -281.674539)
			(xy 299.746662 -281.723116) (xy 299.731078 -281.769797) (xy 299.708207 -281.813374) (xy 299.678642 -281.852718)
			(xy 299.643149 -281.88681) (xy 299.602646 -281.914766) (xy 299.558184 -281.935864) (xy 299.510913 -281.949556)
			(xy 299.462058 -281.955488) (xy 299.412883 -281.953507) (xy 299.364664 -281.943663) (xy 299.318648 -281.926211)
			(xy 299.276027 -281.901604) (xy 299.237906 -281.870479) (xy 299.205271 -281.833642) (xy 299.178968 -281.792046)
			(xy 299.159677 -281.74677) (xy 299.1479 -281.698986) (xy 299.14394 -281.649932) (xy 298.805092 -281.649932)
			(xy 298.804597 -281.674539) (xy 298.796702 -281.723116) (xy 298.781118 -281.769797) (xy 298.758247 -281.813374)
			(xy 298.728682 -281.852718) (xy 298.693189 -281.88681) (xy 298.652686 -281.914766) (xy 298.608224 -281.935864)
			(xy 298.560953 -281.949556) (xy 298.512098 -281.955488) (xy 298.462923 -281.953507) (xy 298.414704 -281.943663)
			(xy 298.368688 -281.926211) (xy 298.326067 -281.901604) (xy 298.287946 -281.870479) (xy 298.255311 -281.833642)
			(xy 298.229008 -281.792046) (xy 298.209717 -281.74677) (xy 298.19794 -281.698986) (xy 298.19398 -281.649932)
			(xy 297.855132 -281.649932) (xy 297.854637 -281.674539) (xy 297.846742 -281.723116) (xy 297.831158 -281.769797)
			(xy 297.808287 -281.813374) (xy 297.778722 -281.852718) (xy 297.743229 -281.88681) (xy 297.702726 -281.914766)
			(xy 297.658264 -281.935864) (xy 297.610993 -281.949556) (xy 297.562138 -281.955488) (xy 297.512963 -281.953507)
			(xy 297.464744 -281.943663) (xy 297.418728 -281.926211) (xy 297.376107 -281.901604) (xy 297.337986 -281.870479)
			(xy 297.305351 -281.833642) (xy 297.279048 -281.792046) (xy 297.259757 -281.74677) (xy 297.24798 -281.698986)
			(xy 297.24402 -281.649932) (xy 296.905172 -281.649932) (xy 296.904677 -281.674539) (xy 296.896782 -281.723116)
			(xy 296.881198 -281.769797) (xy 296.858327 -281.813374) (xy 296.828762 -281.852718) (xy 296.793269 -281.88681)
			(xy 296.752766 -281.914766) (xy 296.708304 -281.935864) (xy 296.661033 -281.949556) (xy 296.612178 -281.955488)
			(xy 296.563003 -281.953507) (xy 296.514784 -281.943663) (xy 296.468768 -281.926211) (xy 296.426147 -281.901604)
			(xy 296.388026 -281.870479) (xy 296.355391 -281.833642) (xy 296.329088 -281.792046) (xy 296.309797 -281.74677)
			(xy 296.29802 -281.698986) (xy 296.29406 -281.649932) (xy 295.955212 -281.649932) (xy 295.954717 -281.674539)
			(xy 295.946822 -281.723116) (xy 295.931238 -281.769797) (xy 295.908367 -281.813374) (xy 295.878802 -281.852718)
			(xy 295.843309 -281.88681) (xy 295.802806 -281.914766) (xy 295.758344 -281.935864) (xy 295.711073 -281.949556)
			(xy 295.662218 -281.955488) (xy 295.613043 -281.953507) (xy 295.564824 -281.943663) (xy 295.518808 -281.926211)
			(xy 295.476187 -281.901604) (xy 295.438066 -281.870479) (xy 295.405431 -281.833642) (xy 295.379128 -281.792046)
			(xy 295.359837 -281.74677) (xy 295.34806 -281.698986) (xy 295.3441 -281.649932) (xy 295.004998 -281.649932)
			(xy 295.004503 -281.674539) (xy 294.996608 -281.723116) (xy 294.981024 -281.769797) (xy 294.958153 -281.813374)
			(xy 294.928588 -281.852718) (xy 294.893095 -281.88681) (xy 294.852592 -281.914766) (xy 294.80813 -281.935864)
			(xy 294.760859 -281.949556) (xy 294.712004 -281.955488) (xy 294.662829 -281.953507) (xy 294.61461 -281.943663)
			(xy 294.568594 -281.926211) (xy 294.525973 -281.901604) (xy 294.487852 -281.870479) (xy 294.455217 -281.833642)
			(xy 294.428914 -281.792046) (xy 294.409623 -281.74677) (xy 294.397846 -281.698986) (xy 294.393886 -281.649932)
			(xy 294.055038 -281.649932) (xy 294.054543 -281.674539) (xy 294.046648 -281.723116) (xy 294.031064 -281.769797)
			(xy 294.008193 -281.813374) (xy 293.978628 -281.852718) (xy 293.943135 -281.88681) (xy 293.902632 -281.914766)
			(xy 293.85817 -281.935864) (xy 293.810899 -281.949556) (xy 293.762044 -281.955488) (xy 293.712869 -281.953507)
			(xy 293.66465 -281.943663) (xy 293.618634 -281.926211) (xy 293.576013 -281.901604) (xy 293.537892 -281.870479)
			(xy 293.505257 -281.833642) (xy 293.478954 -281.792046) (xy 293.459663 -281.74677) (xy 293.447886 -281.698986)
			(xy 293.443926 -281.649932) (xy 293.105078 -281.649932) (xy 293.104583 -281.674539) (xy 293.096688 -281.723116)
			(xy 293.081104 -281.769797) (xy 293.058233 -281.813374) (xy 293.028668 -281.852718) (xy 292.993175 -281.88681)
			(xy 292.952672 -281.914766) (xy 292.90821 -281.935864) (xy 292.860939 -281.949556) (xy 292.812084 -281.955488)
			(xy 292.762909 -281.953507) (xy 292.71469 -281.943663) (xy 292.668674 -281.926211) (xy 292.626053 -281.901604)
			(xy 292.587932 -281.870479) (xy 292.555297 -281.833642) (xy 292.528994 -281.792046) (xy 292.509703 -281.74677)
			(xy 292.497926 -281.698986) (xy 292.493966 -281.649932) (xy 292.155118 -281.649932) (xy 292.154623 -281.674539)
			(xy 292.146728 -281.723116) (xy 292.131144 -281.769797) (xy 292.108273 -281.813374) (xy 292.078708 -281.852718)
			(xy 292.043215 -281.88681) (xy 292.002712 -281.914766) (xy 291.95825 -281.935864) (xy 291.910979 -281.949556)
			(xy 291.862124 -281.955488) (xy 291.812949 -281.953507) (xy 291.76473 -281.943663) (xy 291.718714 -281.926211)
			(xy 291.676093 -281.901604) (xy 291.637972 -281.870479) (xy 291.605337 -281.833642) (xy 291.579034 -281.792046)
			(xy 291.559743 -281.74677) (xy 291.547966 -281.698986) (xy 291.544006 -281.649932) (xy 291.205158 -281.649932)
			(xy 291.204663 -281.674539) (xy 291.196768 -281.723116) (xy 291.181184 -281.769797) (xy 291.158313 -281.813374)
			(xy 291.128748 -281.852718) (xy 291.093255 -281.88681) (xy 291.052752 -281.914766) (xy 291.00829 -281.935864)
			(xy 290.961019 -281.949556) (xy 290.912164 -281.955488) (xy 290.862989 -281.953507) (xy 290.81477 -281.943663)
			(xy 290.768754 -281.926211) (xy 290.726133 -281.901604) (xy 290.688012 -281.870479) (xy 290.655377 -281.833642)
			(xy 290.629074 -281.792046) (xy 290.609783 -281.74677) (xy 290.598006 -281.698986) (xy 290.594046 -281.649932)
			(xy 290.255198 -281.649932) (xy 290.254703 -281.674539) (xy 290.246808 -281.723116) (xy 290.231224 -281.769797)
			(xy 290.208353 -281.813374) (xy 290.178788 -281.852718) (xy 290.143295 -281.88681) (xy 290.102792 -281.914766)
			(xy 290.05833 -281.935864) (xy 290.011059 -281.949556) (xy 289.962204 -281.955488) (xy 289.913029 -281.953507)
			(xy 289.86481 -281.943663) (xy 289.818794 -281.926211) (xy 289.776173 -281.901604) (xy 289.738052 -281.870479)
			(xy 289.705417 -281.833642) (xy 289.679114 -281.792046) (xy 289.659823 -281.74677) (xy 289.648046 -281.698986)
			(xy 289.644086 -281.649932) (xy 289.305238 -281.649932) (xy 289.304743 -281.674539) (xy 289.296848 -281.723116)
			(xy 289.281264 -281.769797) (xy 289.258393 -281.813374) (xy 289.228828 -281.852718) (xy 289.193335 -281.88681)
			(xy 289.152832 -281.914766) (xy 289.10837 -281.935864) (xy 289.061099 -281.949556) (xy 289.012244 -281.955488)
			(xy 288.963069 -281.953507) (xy 288.91485 -281.943663) (xy 288.868834 -281.926211) (xy 288.826213 -281.901604)
			(xy 288.788092 -281.870479) (xy 288.755457 -281.833642) (xy 288.729154 -281.792046) (xy 288.709863 -281.74677)
			(xy 288.698086 -281.698986) (xy 288.694126 -281.649932) (xy 288.355024 -281.649932) (xy 288.354529 -281.674539)
			(xy 288.346634 -281.723116) (xy 288.33105 -281.769797) (xy 288.308179 -281.813374) (xy 288.278614 -281.852718)
			(xy 288.243121 -281.88681) (xy 288.202618 -281.914766) (xy 288.158156 -281.935864) (xy 288.110885 -281.949556)
			(xy 288.06203 -281.955488) (xy 288.012855 -281.953507) (xy 287.964636 -281.943663) (xy 287.91862 -281.926211)
			(xy 287.875999 -281.901604) (xy 287.837878 -281.870479) (xy 287.805243 -281.833642) (xy 287.77894 -281.792046)
			(xy 287.759649 -281.74677) (xy 287.747872 -281.698986) (xy 287.743912 -281.649932) (xy 287.405064 -281.649932)
			(xy 287.404569 -281.674539) (xy 287.396674 -281.723116) (xy 287.38109 -281.769797) (xy 287.358219 -281.813374)
			(xy 287.328654 -281.852718) (xy 287.293161 -281.88681) (xy 287.252658 -281.914766) (xy 287.208196 -281.935864)
			(xy 287.160925 -281.949556) (xy 287.11207 -281.955488) (xy 287.062895 -281.953507) (xy 287.014676 -281.943663)
			(xy 286.96866 -281.926211) (xy 286.926039 -281.901604) (xy 286.887918 -281.870479) (xy 286.855283 -281.833642)
			(xy 286.82898 -281.792046) (xy 286.809689 -281.74677) (xy 286.797912 -281.698986) (xy 286.793952 -281.649932)
			(xy 286.455104 -281.649932) (xy 286.454609 -281.674539) (xy 286.446714 -281.723116) (xy 286.43113 -281.769797)
			(xy 286.408259 -281.813374) (xy 286.378694 -281.852718) (xy 286.343201 -281.88681) (xy 286.302698 -281.914766)
			(xy 286.258236 -281.935864) (xy 286.210965 -281.949556) (xy 286.16211 -281.955488) (xy 286.112935 -281.953507)
			(xy 286.064716 -281.943663) (xy 286.0187 -281.926211) (xy 285.976079 -281.901604) (xy 285.937958 -281.870479)
			(xy 285.905323 -281.833642) (xy 285.87902 -281.792046) (xy 285.859729 -281.74677) (xy 285.847952 -281.698986)
			(xy 285.843992 -281.649932) (xy 285.505144 -281.649932) (xy 285.504649 -281.674539) (xy 285.496754 -281.723116)
			(xy 285.48117 -281.769797) (xy 285.458299 -281.813374) (xy 285.428734 -281.852718) (xy 285.393241 -281.88681)
			(xy 285.352738 -281.914766) (xy 285.308276 -281.935864) (xy 285.261005 -281.949556) (xy 285.21215 -281.955488)
			(xy 285.162975 -281.953507) (xy 285.114756 -281.943663) (xy 285.06874 -281.926211) (xy 285.026119 -281.901604)
			(xy 284.987998 -281.870479) (xy 284.955363 -281.833642) (xy 284.92906 -281.792046) (xy 284.909769 -281.74677)
			(xy 284.897992 -281.698986) (xy 284.894032 -281.649932) (xy 284.555184 -281.649932) (xy 284.554689 -281.674539)
			(xy 284.546794 -281.723116) (xy 284.53121 -281.769797) (xy 284.508339 -281.813374) (xy 284.478774 -281.852718)
			(xy 284.443281 -281.88681) (xy 284.402778 -281.914766) (xy 284.358316 -281.935864) (xy 284.311045 -281.949556)
			(xy 284.26219 -281.955488) (xy 284.213015 -281.953507) (xy 284.164796 -281.943663) (xy 284.11878 -281.926211)
			(xy 284.076159 -281.901604) (xy 284.038038 -281.870479) (xy 284.005403 -281.833642) (xy 283.9791 -281.792046)
			(xy 283.959809 -281.74677) (xy 283.948032 -281.698986) (xy 283.944072 -281.649932) (xy 283.605224 -281.649932)
			(xy 283.604729 -281.674539) (xy 283.596834 -281.723116) (xy 283.58125 -281.769797) (xy 283.558379 -281.813374)
			(xy 283.528814 -281.852718) (xy 283.493321 -281.88681) (xy 283.452818 -281.914766) (xy 283.408356 -281.935864)
			(xy 283.361085 -281.949556) (xy 283.31223 -281.955488) (xy 283.263055 -281.953507) (xy 283.214836 -281.943663)
			(xy 283.16882 -281.926211) (xy 283.126199 -281.901604) (xy 283.088078 -281.870479) (xy 283.055443 -281.833642)
			(xy 283.02914 -281.792046) (xy 283.009849 -281.74677) (xy 282.998072 -281.698986) (xy 282.994112 -281.649932)
			(xy 282.65501 -281.649932) (xy 282.654515 -281.674539) (xy 282.64662 -281.723116) (xy 282.631036 -281.769797)
			(xy 282.608165 -281.813374) (xy 282.5786 -281.852718) (xy 282.543107 -281.88681) (xy 282.502604 -281.914766)
			(xy 282.458142 -281.935864) (xy 282.410871 -281.949556) (xy 282.362016 -281.955488) (xy 282.312841 -281.953507)
			(xy 282.264622 -281.943663) (xy 282.218606 -281.926211) (xy 282.175985 -281.901604) (xy 282.137864 -281.870479)
			(xy 282.105229 -281.833642) (xy 282.078926 -281.792046) (xy 282.059635 -281.74677) (xy 282.047858 -281.698986)
			(xy 282.043898 -281.649932) (xy 281.70505 -281.649932) (xy 281.704555 -281.674539) (xy 281.69666 -281.723116)
			(xy 281.681076 -281.769797) (xy 281.658205 -281.813374) (xy 281.62864 -281.852718) (xy 281.593147 -281.88681)
			(xy 281.552644 -281.914766) (xy 281.508182 -281.935864) (xy 281.460911 -281.949556) (xy 281.412056 -281.955488)
			(xy 281.362881 -281.953507) (xy 281.314662 -281.943663) (xy 281.268646 -281.926211) (xy 281.226025 -281.901604)
			(xy 281.187904 -281.870479) (xy 281.155269 -281.833642) (xy 281.128966 -281.792046) (xy 281.109675 -281.74677)
			(xy 281.097898 -281.698986) (xy 281.093938 -281.649932) (xy 280.755625 -281.649932) (xy 280.751457 -281.70024)
			(xy 280.739056 -281.749206) (xy 280.718765 -281.795463) (xy 280.691137 -281.837749) (xy 280.656925 -281.874911)
			(xy 280.617063 -281.905935) (xy 280.572638 -281.929974) (xy 280.524862 -281.946373) (xy 280.475038 -281.954685)
			(xy 280.449782 -281.95524) (xy 280.421083 -281.954585) (xy 280.364701 -281.943837) (xy 280.337768 -281.933904)
			(xy 280.328878 -281.930348) (xy 280.319226 -281.930348) (xy 280.309205 -281.930764) (xy 280.290687 -281.938431)
			(xy 280.276518 -281.952606) (xy 280.268859 -281.971127) (xy 280.268426 -281.981148) (xy 280.268426 -282.03017)
			(xy 280.268934 -282.036266) (xy 280.270204 -282.047442) (xy 280.272236 -282.056332) (xy 280.275899 -282.073241)
			(xy 280.279841 -282.107613) (xy 280.28011 -282.124912) (xy 280.28011 -282.141422) (xy 280.279602 -282.147264)
			(xy 280.279602 -282.147772) (xy 280.278332 -282.158694) (xy 280.278332 -282.158948) (xy 280.277824 -282.163012)
			(xy 280.275284 -282.181808) (xy 280.274268 -282.187396) (xy 280.270204 -282.203144) (xy 280.268426 -282.215844)
			(xy 280.268426 -282.98013) (xy 280.268934 -282.986226) (xy 280.270204 -282.997402) (xy 280.270966 -283.000704)
			(xy 280.270966 -283.001212) (xy 280.275219 -283.01933) (xy 280.279807 -283.056264) (xy 280.28011 -283.074872)
			(xy 280.618958 -283.074872) (xy 280.622918 -283.025818) (xy 280.634695 -282.978034) (xy 280.653986 -282.932758)
			(xy 280.680289 -282.891162) (xy 280.712924 -282.854325) (xy 280.751045 -282.8232) (xy 280.793666 -282.798593)
			(xy 280.839682 -282.781141) (xy 280.887901 -282.771297) (xy 280.937076 -282.769316) (xy 280.985931 -282.775248)
			(xy 281.033202 -282.78894) (xy 281.077664 -282.810038) (xy 281.118167 -282.837994) (xy 281.15366 -282.872086)
			(xy 281.183225 -282.91143) (xy 281.206096 -282.955007) (xy 281.22168 -283.001688) (xy 281.229575 -283.050265)
			(xy 281.23007 -283.074872) (xy 281.568918 -283.074872) (xy 281.572878 -283.025818) (xy 281.584655 -282.978034)
			(xy 281.603946 -282.932758) (xy 281.630249 -282.891162) (xy 281.662884 -282.854325) (xy 281.701005 -282.8232)
			(xy 281.743626 -282.798593) (xy 281.789642 -282.781141) (xy 281.837861 -282.771297) (xy 281.887036 -282.769316)
			(xy 281.935891 -282.775248) (xy 281.983162 -282.78894) (xy 282.027624 -282.810038) (xy 282.068127 -282.837994)
			(xy 282.10362 -282.872086) (xy 282.133185 -282.91143) (xy 282.156056 -282.955007) (xy 282.17164 -283.001688)
			(xy 282.179535 -283.050265) (xy 282.18003 -283.074872) (xy 282.519132 -283.074872) (xy 282.523092 -283.025818)
			(xy 282.534869 -282.978034) (xy 282.55416 -282.932758) (xy 282.580463 -282.891162) (xy 282.613098 -282.854325)
			(xy 282.651219 -282.8232) (xy 282.69384 -282.798593) (xy 282.739856 -282.781141) (xy 282.788075 -282.771297)
			(xy 282.83725 -282.769316) (xy 282.886105 -282.775248) (xy 282.933376 -282.78894) (xy 282.977838 -282.810038)
			(xy 283.018341 -282.837994) (xy 283.053834 -282.872086) (xy 283.083399 -282.91143) (xy 283.10627 -282.955007)
			(xy 283.121854 -283.001688) (xy 283.129749 -283.050265) (xy 283.130244 -283.074872) (xy 283.469092 -283.074872)
			(xy 283.473052 -283.025818) (xy 283.484829 -282.978034) (xy 283.50412 -282.932758) (xy 283.530423 -282.891162)
			(xy 283.563058 -282.854325) (xy 283.601179 -282.8232) (xy 283.6438 -282.798593) (xy 283.689816 -282.781141)
			(xy 283.738035 -282.771297) (xy 283.78721 -282.769316) (xy 283.836065 -282.775248) (xy 283.883336 -282.78894)
			(xy 283.927798 -282.810038) (xy 283.968301 -282.837994) (xy 284.003794 -282.872086) (xy 284.033359 -282.91143)
			(xy 284.05623 -282.955007) (xy 284.071814 -283.001688) (xy 284.079709 -283.050265) (xy 284.080204 -283.074872)
			(xy 284.419052 -283.074872) (xy 284.423012 -283.025818) (xy 284.434789 -282.978034) (xy 284.45408 -282.932758)
			(xy 284.480383 -282.891162) (xy 284.513018 -282.854325) (xy 284.551139 -282.8232) (xy 284.59376 -282.798593)
			(xy 284.639776 -282.781141) (xy 284.687995 -282.771297) (xy 284.73717 -282.769316) (xy 284.786025 -282.775248)
			(xy 284.833296 -282.78894) (xy 284.877758 -282.810038) (xy 284.918261 -282.837994) (xy 284.953754 -282.872086)
			(xy 284.983319 -282.91143) (xy 285.00619 -282.955007) (xy 285.021774 -283.001688) (xy 285.029669 -283.050265)
			(xy 285.030164 -283.074872) (xy 285.369012 -283.074872) (xy 285.372972 -283.025818) (xy 285.384749 -282.978034)
			(xy 285.40404 -282.932758) (xy 285.430343 -282.891162) (xy 285.462978 -282.854325) (xy 285.501099 -282.8232)
			(xy 285.54372 -282.798593) (xy 285.589736 -282.781141) (xy 285.637955 -282.771297) (xy 285.68713 -282.769316)
			(xy 285.735985 -282.775248) (xy 285.783256 -282.78894) (xy 285.827718 -282.810038) (xy 285.868221 -282.837994)
			(xy 285.903714 -282.872086) (xy 285.933279 -282.91143) (xy 285.95615 -282.955007) (xy 285.971734 -283.001688)
			(xy 285.979629 -283.050265) (xy 285.979958 -283.066643) (xy 286.319052 -283.066643) (xy 286.324416 -283.017287)
			(xy 286.337694 -282.969449) (xy 286.358536 -282.92439) (xy 286.386394 -282.883296) (xy 286.420533 -282.84725)
			(xy 286.460053 -282.817202) (xy 286.503915 -282.793944) (xy 286.550961 -282.778088) (xy 286.599953 -282.770052)
			(xy 286.624776 -282.769564) (xy 286.638959 -282.769744) (xy 286.667199 -282.772414) (xy 286.681164 -282.774898)
			(xy 286.69361 -282.777184) (xy 286.717232 -282.769818) (xy 286.794702 -282.692348) (xy 286.802068 -282.668726)
			(xy 286.799782 -282.65628) (xy 286.797307 -282.642314) (xy 286.794634 -282.614074) (xy 286.794448 -282.599892)
			(xy 286.79497 -282.574637) (xy 286.803283 -282.524815) (xy 286.819684 -282.477041) (xy 286.843725 -282.432618)
			(xy 286.874749 -282.392758) (xy 286.911911 -282.358548) (xy 286.954197 -282.330922) (xy 287.000453 -282.310632)
			(xy 287.049418 -282.298232) (xy 287.099756 -282.294061) (xy 287.150094 -282.298232) (xy 287.199059 -282.310632)
			(xy 287.245315 -282.330922) (xy 287.287601 -282.358548) (xy 287.324763 -282.392758) (xy 287.355787 -282.432618)
			(xy 287.379828 -282.477041) (xy 287.396229 -282.524815) (xy 287.404542 -282.574637) (xy 287.405064 -282.599892)
			(xy 306.743874 -282.599892) (xy 306.747834 -282.550838) (xy 306.759611 -282.503054) (xy 306.778902 -282.457778)
			(xy 306.805205 -282.416182) (xy 306.83784 -282.379345) (xy 306.875961 -282.34822) (xy 306.918582 -282.323613)
			(xy 306.964598 -282.306161) (xy 307.012817 -282.296317) (xy 307.061992 -282.294336) (xy 307.110847 -282.300268)
			(xy 307.158118 -282.31396) (xy 307.20258 -282.335058) (xy 307.243083 -282.363014) (xy 307.278576 -282.397106)
			(xy 307.308141 -282.43645) (xy 307.331012 -282.480027) (xy 307.346596 -282.526708) (xy 307.354491 -282.575285)
			(xy 307.354986 -282.599892) (xy 308.644048 -282.599892) (xy 308.648008 -282.550838) (xy 308.659785 -282.503054)
			(xy 308.679076 -282.457778) (xy 308.705379 -282.416182) (xy 308.738014 -282.379345) (xy 308.776135 -282.34822)
			(xy 308.818756 -282.323613) (xy 308.864772 -282.306161) (xy 308.912991 -282.296317) (xy 308.962166 -282.294336)
			(xy 309.011021 -282.300268) (xy 309.058292 -282.31396) (xy 309.102754 -282.335058) (xy 309.143257 -282.363014)
			(xy 309.17875 -282.397106) (xy 309.208315 -282.43645) (xy 309.231186 -282.480027) (xy 309.24677 -282.526708)
			(xy 309.254665 -282.575285) (xy 309.25516 -282.599892) (xy 309.594008 -282.599892) (xy 309.597968 -282.550838)
			(xy 309.609745 -282.503054) (xy 309.629036 -282.457778) (xy 309.655339 -282.416182) (xy 309.687974 -282.379345)
			(xy 309.726095 -282.34822) (xy 309.768716 -282.323613) (xy 309.814732 -282.306161) (xy 309.862951 -282.296317)
			(xy 309.912126 -282.294336) (xy 309.960981 -282.300268) (xy 310.008252 -282.31396) (xy 310.052714 -282.335058)
			(xy 310.093217 -282.363014) (xy 310.12871 -282.397106) (xy 310.158275 -282.43645) (xy 310.181146 -282.480027)
			(xy 310.19673 -282.526708) (xy 310.204625 -282.575285) (xy 310.20512 -282.599892) (xy 310.543968 -282.599892)
			(xy 310.547928 -282.550838) (xy 310.559705 -282.503054) (xy 310.578996 -282.457778) (xy 310.605299 -282.416182)
			(xy 310.637934 -282.379345) (xy 310.676055 -282.34822) (xy 310.718676 -282.323613) (xy 310.764692 -282.306161)
			(xy 310.812911 -282.296317) (xy 310.862086 -282.294336) (xy 310.910941 -282.300268) (xy 310.958212 -282.31396)
			(xy 311.002674 -282.335058) (xy 311.043177 -282.363014) (xy 311.07867 -282.397106) (xy 311.108235 -282.43645)
			(xy 311.131106 -282.480027) (xy 311.14669 -282.526708) (xy 311.154585 -282.575285) (xy 311.15508 -282.599892)
			(xy 311.154585 -282.624499) (xy 311.154406 -282.6256) (xy 311.473084 -282.6256) (xy 311.473084 -282.574184)
			(xy 311.481127 -282.523402) (xy 311.497015 -282.474503) (xy 311.520358 -282.428691) (xy 311.550579 -282.387095)
			(xy 311.586935 -282.350739) (xy 311.628531 -282.320518) (xy 311.674343 -282.297175) (xy 311.723242 -282.281287)
			(xy 311.774024 -282.273244) (xy 311.82544 -282.273244) (xy 311.876222 -282.281287) (xy 311.925121 -282.297175)
			(xy 311.970933 -282.320518) (xy 312.012529 -282.350739) (xy 312.048885 -282.387095) (xy 312.079106 -282.428691)
			(xy 312.102449 -282.474503) (xy 312.118337 -282.523402) (xy 312.12638 -282.574184) (xy 312.126884 -282.599892)
			(xy 312.12638 -282.6256) (xy 312.423044 -282.6256) (xy 312.423044 -282.574184) (xy 312.431087 -282.523402)
			(xy 312.446975 -282.474503) (xy 312.470318 -282.428691) (xy 312.500539 -282.387095) (xy 312.536895 -282.350739)
			(xy 312.578491 -282.320518) (xy 312.624303 -282.297175) (xy 312.673202 -282.281287) (xy 312.723984 -282.273244)
			(xy 312.7754 -282.273244) (xy 312.826182 -282.281287) (xy 312.875081 -282.297175) (xy 312.920893 -282.320518)
			(xy 312.962489 -282.350739) (xy 312.998845 -282.387095) (xy 313.029066 -282.428691) (xy 313.052409 -282.474503)
			(xy 313.068297 -282.523402) (xy 313.07634 -282.574184) (xy 313.076844 -282.599892) (xy 313.394102 -282.599892)
			(xy 313.398062 -282.550838) (xy 313.409839 -282.503054) (xy 313.42913 -282.457778) (xy 313.455433 -282.416182)
			(xy 313.488068 -282.379345) (xy 313.526189 -282.34822) (xy 313.56881 -282.323613) (xy 313.614826 -282.306161)
			(xy 313.663045 -282.296317) (xy 313.71222 -282.294336) (xy 313.761075 -282.300268) (xy 313.808346 -282.31396)
			(xy 313.852808 -282.335058) (xy 313.893311 -282.363014) (xy 313.928804 -282.397106) (xy 313.958369 -282.43645)
			(xy 313.98124 -282.480027) (xy 313.996824 -282.526708) (xy 314.004719 -282.575285) (xy 314.005214 -282.599892)
			(xy 314.344062 -282.599892) (xy 314.348022 -282.550838) (xy 314.359799 -282.503054) (xy 314.37909 -282.457778)
			(xy 314.405393 -282.416182) (xy 314.438028 -282.379345) (xy 314.476149 -282.34822) (xy 314.51877 -282.323613)
			(xy 314.564786 -282.306161) (xy 314.613005 -282.296317) (xy 314.66218 -282.294336) (xy 314.711035 -282.300268)
			(xy 314.758306 -282.31396) (xy 314.802768 -282.335058) (xy 314.843271 -282.363014) (xy 314.878764 -282.397106)
			(xy 314.908329 -282.43645) (xy 314.9312 -282.480027) (xy 314.946784 -282.526708) (xy 314.954679 -282.575285)
			(xy 314.955174 -282.599892) (xy 314.954679 -282.624499) (xy 314.946784 -282.673076) (xy 314.9312 -282.719757)
			(xy 314.908329 -282.763334) (xy 314.878764 -282.802678) (xy 314.843271 -282.83677) (xy 314.802768 -282.864726)
			(xy 314.758306 -282.885824) (xy 314.711035 -282.899516) (xy 314.66218 -282.905448) (xy 314.613005 -282.903467)
			(xy 314.564786 -282.893623) (xy 314.51877 -282.876171) (xy 314.476149 -282.851564) (xy 314.438028 -282.820439)
			(xy 314.405393 -282.783602) (xy 314.37909 -282.742006) (xy 314.359799 -282.69673) (xy 314.348022 -282.648946)
			(xy 314.344062 -282.599892) (xy 314.005214 -282.599892) (xy 314.004719 -282.624499) (xy 313.996824 -282.673076)
			(xy 313.98124 -282.719757) (xy 313.958369 -282.763334) (xy 313.928804 -282.802678) (xy 313.893311 -282.83677)
			(xy 313.852808 -282.864726) (xy 313.808346 -282.885824) (xy 313.761075 -282.899516) (xy 313.71222 -282.905448)
			(xy 313.663045 -282.903467) (xy 313.614826 -282.893623) (xy 313.56881 -282.876171) (xy 313.526189 -282.851564)
			(xy 313.488068 -282.820439) (xy 313.455433 -282.783602) (xy 313.42913 -282.742006) (xy 313.409839 -282.69673)
			(xy 313.398062 -282.648946) (xy 313.394102 -282.599892) (xy 313.076844 -282.599892) (xy 313.07634 -282.6256)
			(xy 313.068297 -282.676382) (xy 313.052409 -282.725281) (xy 313.029066 -282.771093) (xy 312.998845 -282.812689)
			(xy 312.962489 -282.849045) (xy 312.920893 -282.879266) (xy 312.875081 -282.902609) (xy 312.826182 -282.918497)
			(xy 312.7754 -282.92654) (xy 312.723984 -282.92654) (xy 312.673202 -282.918497) (xy 312.624303 -282.902609)
			(xy 312.578491 -282.879266) (xy 312.536895 -282.849045) (xy 312.500539 -282.812689) (xy 312.470318 -282.771093)
			(xy 312.446975 -282.725281) (xy 312.431087 -282.676382) (xy 312.423044 -282.6256) (xy 312.12638 -282.6256)
			(xy 312.118337 -282.676382) (xy 312.102449 -282.725281) (xy 312.079106 -282.771093) (xy 312.048885 -282.812689)
			(xy 312.012529 -282.849045) (xy 311.970933 -282.879266) (xy 311.925121 -282.902609) (xy 311.876222 -282.918497)
			(xy 311.82544 -282.92654) (xy 311.774024 -282.92654) (xy 311.723242 -282.918497) (xy 311.674343 -282.902609)
			(xy 311.628531 -282.879266) (xy 311.586935 -282.849045) (xy 311.550579 -282.812689) (xy 311.520358 -282.771093)
			(xy 311.497015 -282.725281) (xy 311.481127 -282.676382) (xy 311.473084 -282.6256) (xy 311.154406 -282.6256)
			(xy 311.14669 -282.673076) (xy 311.131106 -282.719757) (xy 311.108235 -282.763334) (xy 311.07867 -282.802678)
			(xy 311.043177 -282.83677) (xy 311.002674 -282.864726) (xy 310.958212 -282.885824) (xy 310.910941 -282.899516)
			(xy 310.862086 -282.905448) (xy 310.812911 -282.903467) (xy 310.764692 -282.893623) (xy 310.718676 -282.876171)
			(xy 310.676055 -282.851564) (xy 310.637934 -282.820439) (xy 310.605299 -282.783602) (xy 310.578996 -282.742006)
			(xy 310.559705 -282.69673) (xy 310.547928 -282.648946) (xy 310.543968 -282.599892) (xy 310.20512 -282.599892)
			(xy 310.204625 -282.624499) (xy 310.19673 -282.673076) (xy 310.181146 -282.719757) (xy 310.158275 -282.763334)
			(xy 310.12871 -282.802678) (xy 310.093217 -282.83677) (xy 310.052714 -282.864726) (xy 310.008252 -282.885824)
			(xy 309.960981 -282.899516) (xy 309.912126 -282.905448) (xy 309.862951 -282.903467) (xy 309.814732 -282.893623)
			(xy 309.768716 -282.876171) (xy 309.726095 -282.851564) (xy 309.687974 -282.820439) (xy 309.655339 -282.783602)
			(xy 309.629036 -282.742006) (xy 309.609745 -282.69673) (xy 309.597968 -282.648946) (xy 309.594008 -282.599892)
			(xy 309.25516 -282.599892) (xy 309.254665 -282.624499) (xy 309.24677 -282.673076) (xy 309.231186 -282.719757)
			(xy 309.208315 -282.763334) (xy 309.17875 -282.802678) (xy 309.143257 -282.83677) (xy 309.102754 -282.864726)
			(xy 309.058292 -282.885824) (xy 309.011021 -282.899516) (xy 308.962166 -282.905448) (xy 308.912991 -282.903467)
			(xy 308.864772 -282.893623) (xy 308.818756 -282.876171) (xy 308.776135 -282.851564) (xy 308.738014 -282.820439)
			(xy 308.705379 -282.783602) (xy 308.679076 -282.742006) (xy 308.659785 -282.69673) (xy 308.648008 -282.648946)
			(xy 308.644048 -282.599892) (xy 307.354986 -282.599892) (xy 307.354491 -282.624499) (xy 307.346596 -282.673076)
			(xy 307.331012 -282.719757) (xy 307.308141 -282.763334) (xy 307.278576 -282.802678) (xy 307.243083 -282.83677)
			(xy 307.20258 -282.864726) (xy 307.158118 -282.885824) (xy 307.110847 -282.899516) (xy 307.061992 -282.905448)
			(xy 307.012817 -282.903467) (xy 306.964598 -282.893623) (xy 306.918582 -282.876171) (xy 306.875961 -282.851564)
			(xy 306.83784 -282.820439) (xy 306.805205 -282.783602) (xy 306.778902 -282.742006) (xy 306.759611 -282.69673)
			(xy 306.747834 -282.648946) (xy 306.743874 -282.599892) (xy 287.405064 -282.599892) (xy 287.404887 -282.614075)
			(xy 287.402215 -282.642315) (xy 287.39973 -282.65628) (xy 287.397444 -282.668726) (xy 287.40481 -282.692348)
			(xy 287.48228 -282.769818) (xy 287.505902 -282.777184) (xy 287.518348 -282.774898) (xy 287.532313 -282.772419)
			(xy 287.560553 -282.769749) (xy 287.574736 -282.769564) (xy 287.599554 -282.770117) (xy 287.648535 -282.778153)
			(xy 287.69557 -282.794007) (xy 287.739421 -282.817262) (xy 287.778932 -282.847304) (xy 287.813062 -282.883343)
			(xy 287.840913 -282.924429) (xy 287.861749 -282.96948) (xy 287.875023 -283.017307) (xy 287.880384 -283.066653)
			(xy 287.879937 -283.074872) (xy 288.219146 -283.074872) (xy 288.223106 -283.025818) (xy 288.234883 -282.978034)
			(xy 288.254174 -282.932758) (xy 288.280477 -282.891162) (xy 288.313112 -282.854325) (xy 288.351233 -282.8232)
			(xy 288.393854 -282.798593) (xy 288.43987 -282.781141) (xy 288.488089 -282.771297) (xy 288.537264 -282.769316)
			(xy 288.586119 -282.775248) (xy 288.63339 -282.78894) (xy 288.677852 -282.810038) (xy 288.718355 -282.837994)
			(xy 288.753848 -282.872086) (xy 288.783413 -282.91143) (xy 288.806284 -282.955007) (xy 288.821868 -283.001688)
			(xy 288.829763 -283.050265) (xy 288.830258 -283.074872) (xy 289.169106 -283.074872) (xy 289.173066 -283.025818)
			(xy 289.184843 -282.978034) (xy 289.204134 -282.932758) (xy 289.230437 -282.891162) (xy 289.263072 -282.854325)
			(xy 289.301193 -282.8232) (xy 289.343814 -282.798593) (xy 289.38983 -282.781141) (xy 289.438049 -282.771297)
			(xy 289.487224 -282.769316) (xy 289.536079 -282.775248) (xy 289.58335 -282.78894) (xy 289.627812 -282.810038)
			(xy 289.668315 -282.837994) (xy 289.703808 -282.872086) (xy 289.733373 -282.91143) (xy 289.756244 -282.955007)
			(xy 289.771828 -283.001688) (xy 289.779723 -283.050265) (xy 289.780218 -283.074872) (xy 290.119066 -283.074872)
			(xy 290.123026 -283.025818) (xy 290.134803 -282.978034) (xy 290.154094 -282.932758) (xy 290.180397 -282.891162)
			(xy 290.213032 -282.854325) (xy 290.251153 -282.8232) (xy 290.293774 -282.798593) (xy 290.33979 -282.781141)
			(xy 290.388009 -282.771297) (xy 290.437184 -282.769316) (xy 290.486039 -282.775248) (xy 290.53331 -282.78894)
			(xy 290.577772 -282.810038) (xy 290.618275 -282.837994) (xy 290.653768 -282.872086) (xy 290.683333 -282.91143)
			(xy 290.706204 -282.955007) (xy 290.721788 -283.001688) (xy 290.729683 -283.050265) (xy 290.730178 -283.074872)
			(xy 292.018986 -283.074872) (xy 292.022946 -283.025818) (xy 292.034723 -282.978034) (xy 292.054014 -282.932758)
			(xy 292.080317 -282.891162) (xy 292.112952 -282.854325) (xy 292.151073 -282.8232) (xy 292.193694 -282.798593)
			(xy 292.23971 -282.781141) (xy 292.287929 -282.771297) (xy 292.337104 -282.769316) (xy 292.385959 -282.775248)
			(xy 292.43323 -282.78894) (xy 292.477692 -282.810038) (xy 292.518195 -282.837994) (xy 292.553688 -282.872086)
			(xy 292.583253 -282.91143) (xy 292.606124 -282.955007) (xy 292.621708 -283.001688) (xy 292.629603 -283.050265)
			(xy 292.630098 -283.074872) (xy 292.968946 -283.074872) (xy 292.972906 -283.025818) (xy 292.984683 -282.978034)
			(xy 293.003974 -282.932758) (xy 293.030277 -282.891162) (xy 293.062912 -282.854325) (xy 293.101033 -282.8232)
			(xy 293.143654 -282.798593) (xy 293.18967 -282.781141) (xy 293.237889 -282.771297) (xy 293.287064 -282.769316)
			(xy 293.335919 -282.775248) (xy 293.38319 -282.78894) (xy 293.427652 -282.810038) (xy 293.468155 -282.837994)
			(xy 293.503648 -282.872086) (xy 293.533213 -282.91143) (xy 293.556084 -282.955007) (xy 293.571668 -283.001688)
			(xy 293.579563 -283.050265) (xy 293.580058 -283.074872) (xy 293.918906 -283.074872) (xy 293.922866 -283.025818)
			(xy 293.934643 -282.978034) (xy 293.953934 -282.932758) (xy 293.980237 -282.891162) (xy 294.012872 -282.854325)
			(xy 294.050993 -282.8232) (xy 294.093614 -282.798593) (xy 294.13963 -282.781141) (xy 294.187849 -282.771297)
			(xy 294.237024 -282.769316) (xy 294.285879 -282.775248) (xy 294.33315 -282.78894) (xy 294.377612 -282.810038)
			(xy 294.418115 -282.837994) (xy 294.453608 -282.872086) (xy 294.483173 -282.91143) (xy 294.506044 -282.955007)
			(xy 294.521628 -283.001688) (xy 294.529523 -283.050265) (xy 294.530018 -283.074872) (xy 294.86912 -283.074872)
			(xy 294.87308 -283.025818) (xy 294.884857 -282.978034) (xy 294.904148 -282.932758) (xy 294.930451 -282.891162)
			(xy 294.963086 -282.854325) (xy 295.001207 -282.8232) (xy 295.043828 -282.798593) (xy 295.089844 -282.781141)
			(xy 295.138063 -282.771297) (xy 295.187238 -282.769316) (xy 295.236093 -282.775248) (xy 295.283364 -282.78894)
			(xy 295.327826 -282.810038) (xy 295.368329 -282.837994) (xy 295.403822 -282.872086) (xy 295.433387 -282.91143)
			(xy 295.456258 -282.955007) (xy 295.471842 -283.001688) (xy 295.479737 -283.050265) (xy 295.480232 -283.074872)
			(xy 295.81908 -283.074872) (xy 295.82304 -283.025818) (xy 295.834817 -282.978034) (xy 295.854108 -282.932758)
			(xy 295.880411 -282.891162) (xy 295.913046 -282.854325) (xy 295.951167 -282.8232) (xy 295.993788 -282.798593)
			(xy 296.039804 -282.781141) (xy 296.088023 -282.771297) (xy 296.137198 -282.769316) (xy 296.186053 -282.775248)
			(xy 296.233324 -282.78894) (xy 296.277786 -282.810038) (xy 296.318289 -282.837994) (xy 296.353782 -282.872086)
			(xy 296.383347 -282.91143) (xy 296.406218 -282.955007) (xy 296.421802 -283.001688) (xy 296.429697 -283.050265)
			(xy 296.430192 -283.074872) (xy 296.76904 -283.074872) (xy 296.773 -283.025818) (xy 296.784777 -282.978034)
			(xy 296.804068 -282.932758) (xy 296.830371 -282.891162) (xy 296.863006 -282.854325) (xy 296.901127 -282.8232)
			(xy 296.943748 -282.798593) (xy 296.989764 -282.781141) (xy 297.037983 -282.771297) (xy 297.087158 -282.769316)
			(xy 297.136013 -282.775248) (xy 297.183284 -282.78894) (xy 297.227746 -282.810038) (xy 297.268249 -282.837994)
			(xy 297.303742 -282.872086) (xy 297.333307 -282.91143) (xy 297.356178 -282.955007) (xy 297.371762 -283.001688)
			(xy 297.379657 -283.050265) (xy 297.380152 -283.074872) (xy 297.719 -283.074872) (xy 297.72296 -283.025818)
			(xy 297.734737 -282.978034) (xy 297.754028 -282.932758) (xy 297.780331 -282.891162) (xy 297.812966 -282.854325)
			(xy 297.851087 -282.8232) (xy 297.893708 -282.798593) (xy 297.939724 -282.781141) (xy 297.987943 -282.771297)
			(xy 298.037118 -282.769316) (xy 298.085973 -282.775248) (xy 298.133244 -282.78894) (xy 298.177706 -282.810038)
			(xy 298.218209 -282.837994) (xy 298.253702 -282.872086) (xy 298.283267 -282.91143) (xy 298.306138 -282.955007)
			(xy 298.321722 -283.001688) (xy 298.329617 -283.050265) (xy 298.330112 -283.074872) (xy 298.66896 -283.074872)
			(xy 298.67292 -283.025818) (xy 298.684697 -282.978034) (xy 298.703988 -282.932758) (xy 298.730291 -282.891162)
			(xy 298.762926 -282.854325) (xy 298.801047 -282.8232) (xy 298.843668 -282.798593) (xy 298.889684 -282.781141)
			(xy 298.937903 -282.771297) (xy 298.987078 -282.769316) (xy 299.035933 -282.775248) (xy 299.083204 -282.78894)
			(xy 299.127666 -282.810038) (xy 299.168169 -282.837994) (xy 299.203662 -282.872086) (xy 299.233227 -282.91143)
			(xy 299.256098 -282.955007) (xy 299.271682 -283.001688) (xy 299.279577 -283.050265) (xy 299.280072 -283.074872)
			(xy 300.56888 -283.074872) (xy 300.57284 -283.025818) (xy 300.584617 -282.978034) (xy 300.603908 -282.932758)
			(xy 300.630211 -282.891162) (xy 300.662846 -282.854325) (xy 300.700967 -282.8232) (xy 300.743588 -282.798593)
			(xy 300.789604 -282.781141) (xy 300.837823 -282.771297) (xy 300.886998 -282.769316) (xy 300.935853 -282.775248)
			(xy 300.983124 -282.78894) (xy 301.027586 -282.810038) (xy 301.068089 -282.837994) (xy 301.103582 -282.872086)
			(xy 301.133147 -282.91143) (xy 301.156018 -282.955007) (xy 301.171602 -283.001688) (xy 301.179497 -283.050265)
			(xy 301.179992 -283.074872) (xy 301.519094 -283.074872) (xy 301.523054 -283.025818) (xy 301.534831 -282.978034)
			(xy 301.554122 -282.932758) (xy 301.580425 -282.891162) (xy 301.61306 -282.854325) (xy 301.651181 -282.8232)
			(xy 301.693802 -282.798593) (xy 301.739818 -282.781141) (xy 301.788037 -282.771297) (xy 301.837212 -282.769316)
			(xy 301.886067 -282.775248) (xy 301.933338 -282.78894) (xy 301.9778 -282.810038) (xy 302.018303 -282.837994)
			(xy 302.053796 -282.872086) (xy 302.083361 -282.91143) (xy 302.106232 -282.955007) (xy 302.121816 -283.001688)
			(xy 302.129711 -283.050265) (xy 302.130206 -283.074872) (xy 302.469054 -283.074872) (xy 302.473014 -283.025818)
			(xy 302.484791 -282.978034) (xy 302.504082 -282.932758) (xy 302.530385 -282.891162) (xy 302.56302 -282.854325)
			(xy 302.601141 -282.8232) (xy 302.643762 -282.798593) (xy 302.689778 -282.781141) (xy 302.737997 -282.771297)
			(xy 302.787172 -282.769316) (xy 302.836027 -282.775248) (xy 302.883298 -282.78894) (xy 302.92776 -282.810038)
			(xy 302.968263 -282.837994) (xy 303.003756 -282.872086) (xy 303.033321 -282.91143) (xy 303.056192 -282.955007)
			(xy 303.071776 -283.001688) (xy 303.079671 -283.050265) (xy 303.080166 -283.074872) (xy 303.419014 -283.074872)
			(xy 303.422974 -283.025818) (xy 303.434751 -282.978034) (xy 303.454042 -282.932758) (xy 303.480345 -282.891162)
			(xy 303.51298 -282.854325) (xy 303.551101 -282.8232) (xy 303.593722 -282.798593) (xy 303.639738 -282.781141)
			(xy 303.687957 -282.771297) (xy 303.737132 -282.769316) (xy 303.785987 -282.775248) (xy 303.833258 -282.78894)
			(xy 303.87772 -282.810038) (xy 303.918223 -282.837994) (xy 303.953716 -282.872086) (xy 303.983281 -282.91143)
			(xy 304.006152 -282.955007) (xy 304.021736 -283.001688) (xy 304.029631 -283.050265) (xy 304.030126 -283.074872)
			(xy 304.368974 -283.074872) (xy 304.372934 -283.025818) (xy 304.384711 -282.978034) (xy 304.404002 -282.932758)
			(xy 304.430305 -282.891162) (xy 304.46294 -282.854325) (xy 304.501061 -282.8232) (xy 304.543682 -282.798593)
			(xy 304.589698 -282.781141) (xy 304.637917 -282.771297) (xy 304.687092 -282.769316) (xy 304.735947 -282.775248)
			(xy 304.783218 -282.78894) (xy 304.82768 -282.810038) (xy 304.868183 -282.837994) (xy 304.903676 -282.872086)
			(xy 304.933241 -282.91143) (xy 304.956112 -282.955007) (xy 304.971696 -283.001688) (xy 304.979591 -283.050265)
			(xy 304.980086 -283.074872) (xy 304.979591 -283.099479) (xy 304.971696 -283.148056) (xy 304.956112 -283.194737)
			(xy 304.933241 -283.238314) (xy 304.903676 -283.277658) (xy 304.868183 -283.31175) (xy 304.82768 -283.339706)
			(xy 304.783218 -283.360804) (xy 304.735947 -283.374496) (xy 304.687092 -283.380428) (xy 304.637917 -283.378447)
			(xy 304.589698 -283.368603) (xy 304.543682 -283.351151) (xy 304.501061 -283.326544) (xy 304.46294 -283.295419)
			(xy 304.430305 -283.258582) (xy 304.404002 -283.216986) (xy 304.384711 -283.17171) (xy 304.372934 -283.123926)
			(xy 304.368974 -283.074872) (xy 304.030126 -283.074872) (xy 304.029631 -283.099479) (xy 304.021736 -283.148056)
			(xy 304.006152 -283.194737) (xy 303.983281 -283.238314) (xy 303.953716 -283.277658) (xy 303.918223 -283.31175)
			(xy 303.87772 -283.339706) (xy 303.833258 -283.360804) (xy 303.785987 -283.374496) (xy 303.737132 -283.380428)
			(xy 303.687957 -283.378447) (xy 303.639738 -283.368603) (xy 303.593722 -283.351151) (xy 303.551101 -283.326544)
			(xy 303.51298 -283.295419) (xy 303.480345 -283.258582) (xy 303.454042 -283.216986) (xy 303.434751 -283.17171)
			(xy 303.422974 -283.123926) (xy 303.419014 -283.074872) (xy 303.080166 -283.074872) (xy 303.079671 -283.099479)
			(xy 303.071776 -283.148056) (xy 303.056192 -283.194737) (xy 303.033321 -283.238314) (xy 303.003756 -283.277658)
			(xy 302.968263 -283.31175) (xy 302.92776 -283.339706) (xy 302.883298 -283.360804) (xy 302.836027 -283.374496)
			(xy 302.787172 -283.380428) (xy 302.737997 -283.378447) (xy 302.689778 -283.368603) (xy 302.643762 -283.351151)
			(xy 302.601141 -283.326544) (xy 302.56302 -283.295419) (xy 302.530385 -283.258582) (xy 302.504082 -283.216986)
			(xy 302.484791 -283.17171) (xy 302.473014 -283.123926) (xy 302.469054 -283.074872) (xy 302.130206 -283.074872)
			(xy 302.129711 -283.099479) (xy 302.121816 -283.148056) (xy 302.106232 -283.194737) (xy 302.083361 -283.238314)
			(xy 302.053796 -283.277658) (xy 302.018303 -283.31175) (xy 301.9778 -283.339706) (xy 301.933338 -283.360804)
			(xy 301.886067 -283.374496) (xy 301.837212 -283.380428) (xy 301.788037 -283.378447) (xy 301.739818 -283.368603)
			(xy 301.693802 -283.351151) (xy 301.651181 -283.326544) (xy 301.61306 -283.295419) (xy 301.580425 -283.258582)
			(xy 301.554122 -283.216986) (xy 301.534831 -283.17171) (xy 301.523054 -283.123926) (xy 301.519094 -283.074872)
			(xy 301.179992 -283.074872) (xy 301.179497 -283.099479) (xy 301.171602 -283.148056) (xy 301.156018 -283.194737)
			(xy 301.133147 -283.238314) (xy 301.103582 -283.277658) (xy 301.068089 -283.31175) (xy 301.027586 -283.339706)
			(xy 300.983124 -283.360804) (xy 300.935853 -283.374496) (xy 300.886998 -283.380428) (xy 300.837823 -283.378447)
			(xy 300.789604 -283.368603) (xy 300.743588 -283.351151) (xy 300.700967 -283.326544) (xy 300.662846 -283.295419)
			(xy 300.630211 -283.258582) (xy 300.603908 -283.216986) (xy 300.584617 -283.17171) (xy 300.57284 -283.123926)
			(xy 300.56888 -283.074872) (xy 299.280072 -283.074872) (xy 299.279577 -283.099479) (xy 299.271682 -283.148056)
			(xy 299.256098 -283.194737) (xy 299.233227 -283.238314) (xy 299.203662 -283.277658) (xy 299.168169 -283.31175)
			(xy 299.127666 -283.339706) (xy 299.083204 -283.360804) (xy 299.035933 -283.374496) (xy 298.987078 -283.380428)
			(xy 298.937903 -283.378447) (xy 298.889684 -283.368603) (xy 298.843668 -283.351151) (xy 298.801047 -283.326544)
			(xy 298.762926 -283.295419) (xy 298.730291 -283.258582) (xy 298.703988 -283.216986) (xy 298.684697 -283.17171)
			(xy 298.67292 -283.123926) (xy 298.66896 -283.074872) (xy 298.330112 -283.074872) (xy 298.329617 -283.099479)
			(xy 298.321722 -283.148056) (xy 298.306138 -283.194737) (xy 298.283267 -283.238314) (xy 298.253702 -283.277658)
			(xy 298.218209 -283.31175) (xy 298.177706 -283.339706) (xy 298.133244 -283.360804) (xy 298.085973 -283.374496)
			(xy 298.037118 -283.380428) (xy 297.987943 -283.378447) (xy 297.939724 -283.368603) (xy 297.893708 -283.351151)
			(xy 297.851087 -283.326544) (xy 297.812966 -283.295419) (xy 297.780331 -283.258582) (xy 297.754028 -283.216986)
			(xy 297.734737 -283.17171) (xy 297.72296 -283.123926) (xy 297.719 -283.074872) (xy 297.380152 -283.074872)
			(xy 297.379657 -283.099479) (xy 297.371762 -283.148056) (xy 297.356178 -283.194737) (xy 297.333307 -283.238314)
			(xy 297.303742 -283.277658) (xy 297.268249 -283.31175) (xy 297.227746 -283.339706) (xy 297.183284 -283.360804)
			(xy 297.136013 -283.374496) (xy 297.087158 -283.380428) (xy 297.037983 -283.378447) (xy 296.989764 -283.368603)
			(xy 296.943748 -283.351151) (xy 296.901127 -283.326544) (xy 296.863006 -283.295419) (xy 296.830371 -283.258582)
			(xy 296.804068 -283.216986) (xy 296.784777 -283.17171) (xy 296.773 -283.123926) (xy 296.76904 -283.074872)
			(xy 296.430192 -283.074872) (xy 296.429697 -283.099479) (xy 296.421802 -283.148056) (xy 296.406218 -283.194737)
			(xy 296.383347 -283.238314) (xy 296.353782 -283.277658) (xy 296.318289 -283.31175) (xy 296.277786 -283.339706)
			(xy 296.233324 -283.360804) (xy 296.186053 -283.374496) (xy 296.137198 -283.380428) (xy 296.088023 -283.378447)
			(xy 296.039804 -283.368603) (xy 295.993788 -283.351151) (xy 295.951167 -283.326544) (xy 295.913046 -283.295419)
			(xy 295.880411 -283.258582) (xy 295.854108 -283.216986) (xy 295.834817 -283.17171) (xy 295.82304 -283.123926)
			(xy 295.81908 -283.074872) (xy 295.480232 -283.074872) (xy 295.479737 -283.099479) (xy 295.471842 -283.148056)
			(xy 295.456258 -283.194737) (xy 295.433387 -283.238314) (xy 295.403822 -283.277658) (xy 295.368329 -283.31175)
			(xy 295.327826 -283.339706) (xy 295.283364 -283.360804) (xy 295.236093 -283.374496) (xy 295.187238 -283.380428)
			(xy 295.138063 -283.378447) (xy 295.089844 -283.368603) (xy 295.043828 -283.351151) (xy 295.001207 -283.326544)
			(xy 294.963086 -283.295419) (xy 294.930451 -283.258582) (xy 294.904148 -283.216986) (xy 294.884857 -283.17171)
			(xy 294.87308 -283.123926) (xy 294.86912 -283.074872) (xy 294.530018 -283.074872) (xy 294.529523 -283.099479)
			(xy 294.521628 -283.148056) (xy 294.506044 -283.194737) (xy 294.483173 -283.238314) (xy 294.453608 -283.277658)
			(xy 294.418115 -283.31175) (xy 294.377612 -283.339706) (xy 294.33315 -283.360804) (xy 294.285879 -283.374496)
			(xy 294.237024 -283.380428) (xy 294.187849 -283.378447) (xy 294.13963 -283.368603) (xy 294.093614 -283.351151)
			(xy 294.050993 -283.326544) (xy 294.012872 -283.295419) (xy 293.980237 -283.258582) (xy 293.953934 -283.216986)
			(xy 293.934643 -283.17171) (xy 293.922866 -283.123926) (xy 293.918906 -283.074872) (xy 293.580058 -283.074872)
			(xy 293.579563 -283.099479) (xy 293.571668 -283.148056) (xy 293.556084 -283.194737) (xy 293.533213 -283.238314)
			(xy 293.503648 -283.277658) (xy 293.468155 -283.31175) (xy 293.427652 -283.339706) (xy 293.38319 -283.360804)
			(xy 293.335919 -283.374496) (xy 293.287064 -283.380428) (xy 293.237889 -283.378447) (xy 293.18967 -283.368603)
			(xy 293.143654 -283.351151) (xy 293.101033 -283.326544) (xy 293.062912 -283.295419) (xy 293.030277 -283.258582)
			(xy 293.003974 -283.216986) (xy 292.984683 -283.17171) (xy 292.972906 -283.123926) (xy 292.968946 -283.074872)
			(xy 292.630098 -283.074872) (xy 292.629603 -283.099479) (xy 292.621708 -283.148056) (xy 292.606124 -283.194737)
			(xy 292.583253 -283.238314) (xy 292.553688 -283.277658) (xy 292.518195 -283.31175) (xy 292.477692 -283.339706)
			(xy 292.43323 -283.360804) (xy 292.385959 -283.374496) (xy 292.337104 -283.380428) (xy 292.287929 -283.378447)
			(xy 292.23971 -283.368603) (xy 292.193694 -283.351151) (xy 292.151073 -283.326544) (xy 292.112952 -283.295419)
			(xy 292.080317 -283.258582) (xy 292.054014 -283.216986) (xy 292.034723 -283.17171) (xy 292.022946 -283.123926)
			(xy 292.018986 -283.074872) (xy 290.730178 -283.074872) (xy 290.729683 -283.099479) (xy 290.721788 -283.148056)
			(xy 290.706204 -283.194737) (xy 290.683333 -283.238314) (xy 290.653768 -283.277658) (xy 290.618275 -283.31175)
			(xy 290.577772 -283.339706) (xy 290.53331 -283.360804) (xy 290.486039 -283.374496) (xy 290.437184 -283.380428)
			(xy 290.388009 -283.378447) (xy 290.33979 -283.368603) (xy 290.293774 -283.351151) (xy 290.251153 -283.326544)
			(xy 290.213032 -283.295419) (xy 290.180397 -283.258582) (xy 290.154094 -283.216986) (xy 290.134803 -283.17171)
			(xy 290.123026 -283.123926) (xy 290.119066 -283.074872) (xy 289.780218 -283.074872) (xy 289.779723 -283.099479)
			(xy 289.771828 -283.148056) (xy 289.756244 -283.194737) (xy 289.733373 -283.238314) (xy 289.703808 -283.277658)
			(xy 289.668315 -283.31175) (xy 289.627812 -283.339706) (xy 289.58335 -283.360804) (xy 289.536079 -283.374496)
			(xy 289.487224 -283.380428) (xy 289.438049 -283.378447) (xy 289.38983 -283.368603) (xy 289.343814 -283.351151)
			(xy 289.301193 -283.326544) (xy 289.263072 -283.295419) (xy 289.230437 -283.258582) (xy 289.204134 -283.216986)
			(xy 289.184843 -283.17171) (xy 289.173066 -283.123926) (xy 289.169106 -283.074872) (xy 288.830258 -283.074872)
			(xy 288.829763 -283.099479) (xy 288.821868 -283.148056) (xy 288.806284 -283.194737) (xy 288.783413 -283.238314)
			(xy 288.753848 -283.277658) (xy 288.718355 -283.31175) (xy 288.677852 -283.339706) (xy 288.63339 -283.360804)
			(xy 288.586119 -283.374496) (xy 288.537264 -283.380428) (xy 288.488089 -283.378447) (xy 288.43987 -283.368603)
			(xy 288.393854 -283.351151) (xy 288.351233 -283.326544) (xy 288.313112 -283.295419) (xy 288.280477 -283.258582)
			(xy 288.254174 -283.216986) (xy 288.234883 -283.17171) (xy 288.223106 -283.123926) (xy 288.219146 -283.074872)
			(xy 287.879937 -283.074872) (xy 287.877691 -283.116215) (xy 287.867016 -283.164689) (xy 287.848639 -283.210798)
			(xy 287.823044 -283.253325) (xy 287.790907 -283.291152) (xy 287.753073 -283.323282) (xy 287.71054 -283.348867)
			(xy 287.664428 -283.367235) (xy 287.615952 -283.3779) (xy 287.566389 -283.380582) (xy 287.517045 -283.375211)
			(xy 287.469219 -283.361927) (xy 287.424173 -283.341081) (xy 287.383093 -283.313222) (xy 287.347061 -283.279084)
			(xy 287.317027 -283.239567) (xy 287.293781 -283.195711) (xy 287.277937 -283.148672) (xy 287.269911 -283.09969)
			(xy 287.269428 -283.074872) (xy 287.2696 -283.060689) (xy 287.272275 -283.032449) (xy 287.274762 -283.018484)
			(xy 287.277048 -283.006038) (xy 287.269682 -282.982416) (xy 287.192212 -282.904946) (xy 287.16859 -282.89758)
			(xy 287.156144 -282.899866) (xy 287.142179 -282.902346) (xy 287.113939 -282.905015) (xy 287.099756 -282.9052)
			(xy 287.085573 -282.905016) (xy 287.057333 -282.902349) (xy 287.043368 -282.899866) (xy 287.030922 -282.89758)
			(xy 287.0073 -282.904946) (xy 286.92983 -282.982416) (xy 286.922464 -283.006038) (xy 286.92475 -283.018484)
			(xy 286.927234 -283.032449) (xy 286.929901 -283.060689) (xy 286.930084 -283.074872) (xy 286.929652 -283.099695)
			(xy 286.921625 -283.148688) (xy 286.905777 -283.195737) (xy 286.882526 -283.239603) (xy 286.852485 -283.279128)
			(xy 286.816445 -283.313273) (xy 286.775356 -283.341138) (xy 286.7303 -283.361988) (xy 286.682464 -283.375274)
			(xy 286.633109 -283.380646) (xy 286.583535 -283.377963) (xy 286.535049 -283.367294) (xy 286.488927 -283.348922)
			(xy 286.446385 -283.323331) (xy 286.408543 -283.291193) (xy 286.3764 -283.253358) (xy 286.350801 -283.21082)
			(xy 286.332421 -283.164701) (xy 286.321744 -283.116216) (xy 286.319052 -283.066643) (xy 285.979958 -283.066643)
			(xy 285.980124 -283.074872) (xy 285.979629 -283.099479) (xy 285.971734 -283.148056) (xy 285.95615 -283.194737)
			(xy 285.933279 -283.238314) (xy 285.903714 -283.277658) (xy 285.868221 -283.31175) (xy 285.827718 -283.339706)
			(xy 285.783256 -283.360804) (xy 285.735985 -283.374496) (xy 285.68713 -283.380428) (xy 285.637955 -283.378447)
			(xy 285.589736 -283.368603) (xy 285.54372 -283.351151) (xy 285.501099 -283.326544) (xy 285.462978 -283.295419)
			(xy 285.430343 -283.258582) (xy 285.40404 -283.216986) (xy 285.384749 -283.17171) (xy 285.372972 -283.123926)
			(xy 285.369012 -283.074872) (xy 285.030164 -283.074872) (xy 285.029669 -283.099479) (xy 285.021774 -283.148056)
			(xy 285.00619 -283.194737) (xy 284.983319 -283.238314) (xy 284.953754 -283.277658) (xy 284.918261 -283.31175)
			(xy 284.877758 -283.339706) (xy 284.833296 -283.360804) (xy 284.786025 -283.374496) (xy 284.73717 -283.380428)
			(xy 284.687995 -283.378447) (xy 284.639776 -283.368603) (xy 284.59376 -283.351151) (xy 284.551139 -283.326544)
			(xy 284.513018 -283.295419) (xy 284.480383 -283.258582) (xy 284.45408 -283.216986) (xy 284.434789 -283.17171)
			(xy 284.423012 -283.123926) (xy 284.419052 -283.074872) (xy 284.080204 -283.074872) (xy 284.079709 -283.099479)
			(xy 284.071814 -283.148056) (xy 284.05623 -283.194737) (xy 284.033359 -283.238314) (xy 284.003794 -283.277658)
			(xy 283.968301 -283.31175) (xy 283.927798 -283.339706) (xy 283.883336 -283.360804) (xy 283.836065 -283.374496)
			(xy 283.78721 -283.380428) (xy 283.738035 -283.378447) (xy 283.689816 -283.368603) (xy 283.6438 -283.351151)
			(xy 283.601179 -283.326544) (xy 283.563058 -283.295419) (xy 283.530423 -283.258582) (xy 283.50412 -283.216986)
			(xy 283.484829 -283.17171) (xy 283.473052 -283.123926) (xy 283.469092 -283.074872) (xy 283.130244 -283.074872)
			(xy 283.129749 -283.099479) (xy 283.121854 -283.148056) (xy 283.10627 -283.194737) (xy 283.083399 -283.238314)
			(xy 283.053834 -283.277658) (xy 283.018341 -283.31175) (xy 282.977838 -283.339706) (xy 282.933376 -283.360804)
			(xy 282.886105 -283.374496) (xy 282.83725 -283.380428) (xy 282.788075 -283.378447) (xy 282.739856 -283.368603)
			(xy 282.69384 -283.351151) (xy 282.651219 -283.326544) (xy 282.613098 -283.295419) (xy 282.580463 -283.258582)
			(xy 282.55416 -283.216986) (xy 282.534869 -283.17171) (xy 282.523092 -283.123926) (xy 282.519132 -283.074872)
			(xy 282.18003 -283.074872) (xy 282.179535 -283.099479) (xy 282.17164 -283.148056) (xy 282.156056 -283.194737)
			(xy 282.133185 -283.238314) (xy 282.10362 -283.277658) (xy 282.068127 -283.31175) (xy 282.027624 -283.339706)
			(xy 281.983162 -283.360804) (xy 281.935891 -283.374496) (xy 281.887036 -283.380428) (xy 281.837861 -283.378447)
			(xy 281.789642 -283.368603) (xy 281.743626 -283.351151) (xy 281.701005 -283.326544) (xy 281.662884 -283.295419)
			(xy 281.630249 -283.258582) (xy 281.603946 -283.216986) (xy 281.584655 -283.17171) (xy 281.572878 -283.123926)
			(xy 281.568918 -283.074872) (xy 281.23007 -283.074872) (xy 281.229575 -283.099479) (xy 281.22168 -283.148056)
			(xy 281.206096 -283.194737) (xy 281.183225 -283.238314) (xy 281.15366 -283.277658) (xy 281.118167 -283.31175)
			(xy 281.077664 -283.339706) (xy 281.033202 -283.360804) (xy 280.985931 -283.374496) (xy 280.937076 -283.380428)
			(xy 280.887901 -283.378447) (xy 280.839682 -283.368603) (xy 280.793666 -283.351151) (xy 280.751045 -283.326544)
			(xy 280.712924 -283.295419) (xy 280.680289 -283.258582) (xy 280.653986 -283.216986) (xy 280.634695 -283.17171)
			(xy 280.622918 -283.123926) (xy 280.618958 -283.074872) (xy 280.28011 -283.074872) (xy 280.28011 -283.091382)
			(xy 280.279602 -283.097224) (xy 280.279602 -283.097732) (xy 280.278332 -283.108654) (xy 280.278332 -283.108908)
			(xy 280.277824 -283.112972) (xy 280.275284 -283.131768) (xy 280.274268 -283.137356) (xy 280.270204 -283.153104)
			(xy 280.268426 -283.165804) (xy 280.268426 -283.549852) (xy 305.793914 -283.549852) (xy 305.797874 -283.500798)
			(xy 305.809651 -283.453014) (xy 305.828942 -283.407738) (xy 305.855245 -283.366142) (xy 305.88788 -283.329305)
			(xy 305.926001 -283.29818) (xy 305.968622 -283.273573) (xy 306.014638 -283.256121) (xy 306.062857 -283.246277)
			(xy 306.112032 -283.244296) (xy 306.160887 -283.250228) (xy 306.208158 -283.26392) (xy 306.25262 -283.285018)
			(xy 306.293123 -283.312974) (xy 306.328616 -283.347066) (xy 306.358181 -283.38641) (xy 306.381052 -283.429987)
			(xy 306.396636 -283.476668) (xy 306.404531 -283.525245) (xy 306.405026 -283.549852) (xy 306.743874 -283.549852)
			(xy 306.747834 -283.500798) (xy 306.759611 -283.453014) (xy 306.778902 -283.407738) (xy 306.805205 -283.366142)
			(xy 306.83784 -283.329305) (xy 306.875961 -283.29818) (xy 306.918582 -283.273573) (xy 306.964598 -283.256121)
			(xy 307.012817 -283.246277) (xy 307.061992 -283.244296) (xy 307.110847 -283.250228) (xy 307.158118 -283.26392)
			(xy 307.20258 -283.285018) (xy 307.243083 -283.312974) (xy 307.278576 -283.347066) (xy 307.308141 -283.38641)
			(xy 307.331012 -283.429987) (xy 307.346596 -283.476668) (xy 307.354491 -283.525245) (xy 307.354986 -283.549852)
			(xy 307.694088 -283.549852) (xy 307.698048 -283.500798) (xy 307.709825 -283.453014) (xy 307.729116 -283.407738)
			(xy 307.755419 -283.366142) (xy 307.788054 -283.329305) (xy 307.826175 -283.29818) (xy 307.868796 -283.273573)
			(xy 307.914812 -283.256121) (xy 307.963031 -283.246277) (xy 308.012206 -283.244296) (xy 308.061061 -283.250228)
			(xy 308.108332 -283.26392) (xy 308.152794 -283.285018) (xy 308.193297 -283.312974) (xy 308.22879 -283.347066)
			(xy 308.258355 -283.38641) (xy 308.281226 -283.429987) (xy 308.29681 -283.476668) (xy 308.304705 -283.525245)
			(xy 308.3052 -283.549852) (xy 308.644048 -283.549852) (xy 308.648008 -283.500798) (xy 308.659785 -283.453014)
			(xy 308.679076 -283.407738) (xy 308.705379 -283.366142) (xy 308.738014 -283.329305) (xy 308.776135 -283.29818)
			(xy 308.818756 -283.273573) (xy 308.864772 -283.256121) (xy 308.912991 -283.246277) (xy 308.962166 -283.244296)
			(xy 309.011021 -283.250228) (xy 309.058292 -283.26392) (xy 309.102754 -283.285018) (xy 309.143257 -283.312974)
			(xy 309.17875 -283.347066) (xy 309.208315 -283.38641) (xy 309.231186 -283.429987) (xy 309.24677 -283.476668)
			(xy 309.254665 -283.525245) (xy 309.25516 -283.549852) (xy 309.594008 -283.549852) (xy 309.597968 -283.500798)
			(xy 309.609745 -283.453014) (xy 309.629036 -283.407738) (xy 309.655339 -283.366142) (xy 309.687974 -283.329305)
			(xy 309.726095 -283.29818) (xy 309.768716 -283.273573) (xy 309.814732 -283.256121) (xy 309.862951 -283.246277)
			(xy 309.912126 -283.244296) (xy 309.960981 -283.250228) (xy 310.008252 -283.26392) (xy 310.052714 -283.285018)
			(xy 310.093217 -283.312974) (xy 310.12871 -283.347066) (xy 310.158275 -283.38641) (xy 310.181146 -283.429987)
			(xy 310.19673 -283.476668) (xy 310.204625 -283.525245) (xy 310.20512 -283.549852) (xy 310.543968 -283.549852)
			(xy 310.547928 -283.500798) (xy 310.559705 -283.453014) (xy 310.578996 -283.407738) (xy 310.605299 -283.366142)
			(xy 310.637934 -283.329305) (xy 310.676055 -283.29818) (xy 310.718676 -283.273573) (xy 310.764692 -283.256121)
			(xy 310.812911 -283.246277) (xy 310.862086 -283.244296) (xy 310.910941 -283.250228) (xy 310.958212 -283.26392)
			(xy 311.002674 -283.285018) (xy 311.043177 -283.312974) (xy 311.07867 -283.347066) (xy 311.108235 -283.38641)
			(xy 311.131106 -283.429987) (xy 311.14669 -283.476668) (xy 311.154585 -283.525245) (xy 311.15508 -283.549852)
			(xy 311.493928 -283.549852) (xy 311.497888 -283.500798) (xy 311.509665 -283.453014) (xy 311.528956 -283.407738)
			(xy 311.555259 -283.366142) (xy 311.587894 -283.329305) (xy 311.626015 -283.29818) (xy 311.668636 -283.273573)
			(xy 311.714652 -283.256121) (xy 311.762871 -283.246277) (xy 311.812046 -283.244296) (xy 311.860901 -283.250228)
			(xy 311.908172 -283.26392) (xy 311.952634 -283.285018) (xy 311.993137 -283.312974) (xy 312.02863 -283.347066)
			(xy 312.058195 -283.38641) (xy 312.081066 -283.429987) (xy 312.09665 -283.476668) (xy 312.104545 -283.525245)
			(xy 312.10504 -283.549852) (xy 312.443888 -283.549852) (xy 312.447848 -283.500798) (xy 312.459625 -283.453014)
			(xy 312.478916 -283.407738) (xy 312.505219 -283.366142) (xy 312.537854 -283.329305) (xy 312.575975 -283.29818)
			(xy 312.618596 -283.273573) (xy 312.664612 -283.256121) (xy 312.712831 -283.246277) (xy 312.762006 -283.244296)
			(xy 312.810861 -283.250228) (xy 312.858132 -283.26392) (xy 312.902594 -283.285018) (xy 312.943097 -283.312974)
			(xy 312.97859 -283.347066) (xy 313.008155 -283.38641) (xy 313.031026 -283.429987) (xy 313.04661 -283.476668)
			(xy 313.054505 -283.525245) (xy 313.055 -283.549852) (xy 313.054505 -283.574459) (xy 313.054326 -283.57556)
			(xy 313.373258 -283.57556) (xy 313.373258 -283.524144) (xy 313.381301 -283.473362) (xy 313.397189 -283.424463)
			(xy 313.420532 -283.378651) (xy 313.450753 -283.337055) (xy 313.487109 -283.300699) (xy 313.528705 -283.270478)
			(xy 313.574517 -283.247135) (xy 313.623416 -283.231247) (xy 313.674198 -283.223204) (xy 313.725614 -283.223204)
			(xy 313.776396 -283.231247) (xy 313.825295 -283.247135) (xy 313.871107 -283.270478) (xy 313.912703 -283.300699)
			(xy 313.949059 -283.337055) (xy 313.97928 -283.378651) (xy 314.002623 -283.424463) (xy 314.018511 -283.473362)
			(xy 314.026554 -283.524144) (xy 314.027058 -283.549852) (xy 314.026554 -283.57556) (xy 314.323218 -283.57556)
			(xy 314.323218 -283.524144) (xy 314.331261 -283.473362) (xy 314.347149 -283.424463) (xy 314.370492 -283.378651)
			(xy 314.400713 -283.337055) (xy 314.437069 -283.300699) (xy 314.478665 -283.270478) (xy 314.524477 -283.247135)
			(xy 314.573376 -283.231247) (xy 314.624158 -283.223204) (xy 314.675574 -283.223204) (xy 314.726356 -283.231247)
			(xy 314.775255 -283.247135) (xy 314.821067 -283.270478) (xy 314.862663 -283.300699) (xy 314.899019 -283.337055)
			(xy 314.92924 -283.378651) (xy 314.952583 -283.424463) (xy 314.968471 -283.473362) (xy 314.976514 -283.524144)
			(xy 314.977018 -283.549852) (xy 314.977013 -283.550106) (xy 315.294276 -283.550106) (xy 315.298236 -283.501052)
			(xy 315.310013 -283.453268) (xy 315.329304 -283.407992) (xy 315.355607 -283.366396) (xy 315.388242 -283.329559)
			(xy 315.426363 -283.298434) (xy 315.468984 -283.273827) (xy 315.515 -283.256375) (xy 315.563219 -283.246531)
			(xy 315.612394 -283.24455) (xy 315.661249 -283.250482) (xy 315.70852 -283.264174) (xy 315.752982 -283.285272)
			(xy 315.793485 -283.313228) (xy 315.828978 -283.34732) (xy 315.858543 -283.386664) (xy 315.881414 -283.430241)
			(xy 315.896998 -283.476922) (xy 315.904893 -283.525499) (xy 315.905388 -283.550106) (xy 315.904893 -283.574713)
			(xy 315.896998 -283.62329) (xy 315.881414 -283.669971) (xy 315.858543 -283.713548) (xy 315.828978 -283.752892)
			(xy 315.793485 -283.786984) (xy 315.752982 -283.81494) (xy 315.70852 -283.836038) (xy 315.661249 -283.84973)
			(xy 315.612394 -283.855662) (xy 315.563219 -283.853681) (xy 315.515 -283.843837) (xy 315.468984 -283.826385)
			(xy 315.426363 -283.801778) (xy 315.388242 -283.770653) (xy 315.355607 -283.733816) (xy 315.329304 -283.69222)
			(xy 315.310013 -283.646944) (xy 315.298236 -283.59916) (xy 315.294276 -283.550106) (xy 314.977013 -283.550106)
			(xy 314.976514 -283.57556) (xy 314.968471 -283.626342) (xy 314.952583 -283.675241) (xy 314.92924 -283.721053)
			(xy 314.899019 -283.762649) (xy 314.862663 -283.799005) (xy 314.821067 -283.829226) (xy 314.775255 -283.852569)
			(xy 314.726356 -283.868457) (xy 314.675574 -283.8765) (xy 314.624158 -283.8765) (xy 314.573376 -283.868457)
			(xy 314.524477 -283.852569) (xy 314.478665 -283.829226) (xy 314.437069 -283.799005) (xy 314.400713 -283.762649)
			(xy 314.370492 -283.721053) (xy 314.347149 -283.675241) (xy 314.331261 -283.626342) (xy 314.323218 -283.57556)
			(xy 314.026554 -283.57556) (xy 314.018511 -283.626342) (xy 314.002623 -283.675241) (xy 313.97928 -283.721053)
			(xy 313.949059 -283.762649) (xy 313.912703 -283.799005) (xy 313.871107 -283.829226) (xy 313.825295 -283.852569)
			(xy 313.776396 -283.868457) (xy 313.725614 -283.8765) (xy 313.674198 -283.8765) (xy 313.623416 -283.868457)
			(xy 313.574517 -283.852569) (xy 313.528705 -283.829226) (xy 313.487109 -283.799005) (xy 313.450753 -283.762649)
			(xy 313.420532 -283.721053) (xy 313.397189 -283.675241) (xy 313.381301 -283.626342) (xy 313.373258 -283.57556)
			(xy 313.054326 -283.57556) (xy 313.04661 -283.623036) (xy 313.031026 -283.669717) (xy 313.008155 -283.713294)
			(xy 312.97859 -283.752638) (xy 312.943097 -283.78673) (xy 312.902594 -283.814686) (xy 312.858132 -283.835784)
			(xy 312.810861 -283.849476) (xy 312.762006 -283.855408) (xy 312.712831 -283.853427) (xy 312.664612 -283.843583)
			(xy 312.618596 -283.826131) (xy 312.575975 -283.801524) (xy 312.537854 -283.770399) (xy 312.505219 -283.733562)
			(xy 312.478916 -283.691966) (xy 312.459625 -283.64669) (xy 312.447848 -283.598906) (xy 312.443888 -283.549852)
			(xy 312.10504 -283.549852) (xy 312.104545 -283.574459) (xy 312.09665 -283.623036) (xy 312.081066 -283.669717)
			(xy 312.058195 -283.713294) (xy 312.02863 -283.752638) (xy 311.993137 -283.78673) (xy 311.952634 -283.814686)
			(xy 311.908172 -283.835784) (xy 311.860901 -283.849476) (xy 311.812046 -283.855408) (xy 311.762871 -283.853427)
			(xy 311.714652 -283.843583) (xy 311.668636 -283.826131) (xy 311.626015 -283.801524) (xy 311.587894 -283.770399)
			(xy 311.555259 -283.733562) (xy 311.528956 -283.691966) (xy 311.509665 -283.64669) (xy 311.497888 -283.598906)
			(xy 311.493928 -283.549852) (xy 311.15508 -283.549852) (xy 311.154585 -283.574459) (xy 311.14669 -283.623036)
			(xy 311.131106 -283.669717) (xy 311.108235 -283.713294) (xy 311.07867 -283.752638) (xy 311.043177 -283.78673)
			(xy 311.002674 -283.814686) (xy 310.958212 -283.835784) (xy 310.910941 -283.849476) (xy 310.862086 -283.855408)
			(xy 310.812911 -283.853427) (xy 310.764692 -283.843583) (xy 310.718676 -283.826131) (xy 310.676055 -283.801524)
			(xy 310.637934 -283.770399) (xy 310.605299 -283.733562) (xy 310.578996 -283.691966) (xy 310.559705 -283.64669)
			(xy 310.547928 -283.598906) (xy 310.543968 -283.549852) (xy 310.20512 -283.549852) (xy 310.204625 -283.574459)
			(xy 310.19673 -283.623036) (xy 310.181146 -283.669717) (xy 310.158275 -283.713294) (xy 310.12871 -283.752638)
			(xy 310.093217 -283.78673) (xy 310.052714 -283.814686) (xy 310.008252 -283.835784) (xy 309.960981 -283.849476)
			(xy 309.912126 -283.855408) (xy 309.862951 -283.853427) (xy 309.814732 -283.843583) (xy 309.768716 -283.826131)
			(xy 309.726095 -283.801524) (xy 309.687974 -283.770399) (xy 309.655339 -283.733562) (xy 309.629036 -283.691966)
			(xy 309.609745 -283.64669) (xy 309.597968 -283.598906) (xy 309.594008 -283.549852) (xy 309.25516 -283.549852)
			(xy 309.254665 -283.574459) (xy 309.24677 -283.623036) (xy 309.231186 -283.669717) (xy 309.208315 -283.713294)
			(xy 309.17875 -283.752638) (xy 309.143257 -283.78673) (xy 309.102754 -283.814686) (xy 309.058292 -283.835784)
			(xy 309.011021 -283.849476) (xy 308.962166 -283.855408) (xy 308.912991 -283.853427) (xy 308.864772 -283.843583)
			(xy 308.818756 -283.826131) (xy 308.776135 -283.801524) (xy 308.738014 -283.770399) (xy 308.705379 -283.733562)
			(xy 308.679076 -283.691966) (xy 308.659785 -283.64669) (xy 308.648008 -283.598906) (xy 308.644048 -283.549852)
			(xy 308.3052 -283.549852) (xy 308.304705 -283.574459) (xy 308.29681 -283.623036) (xy 308.281226 -283.669717)
			(xy 308.258355 -283.713294) (xy 308.22879 -283.752638) (xy 308.193297 -283.78673) (xy 308.152794 -283.814686)
			(xy 308.108332 -283.835784) (xy 308.061061 -283.849476) (xy 308.012206 -283.855408) (xy 307.963031 -283.853427)
			(xy 307.914812 -283.843583) (xy 307.868796 -283.826131) (xy 307.826175 -283.801524) (xy 307.788054 -283.770399)
			(xy 307.755419 -283.733562) (xy 307.729116 -283.691966) (xy 307.709825 -283.64669) (xy 307.698048 -283.598906)
			(xy 307.694088 -283.549852) (xy 307.354986 -283.549852) (xy 307.354491 -283.574459) (xy 307.346596 -283.623036)
			(xy 307.331012 -283.669717) (xy 307.308141 -283.713294) (xy 307.278576 -283.752638) (xy 307.243083 -283.78673)
			(xy 307.20258 -283.814686) (xy 307.158118 -283.835784) (xy 307.110847 -283.849476) (xy 307.061992 -283.855408)
			(xy 307.012817 -283.853427) (xy 306.964598 -283.843583) (xy 306.918582 -283.826131) (xy 306.875961 -283.801524)
			(xy 306.83784 -283.770399) (xy 306.805205 -283.733562) (xy 306.778902 -283.691966) (xy 306.759611 -283.64669)
			(xy 306.747834 -283.598906) (xy 306.743874 -283.549852) (xy 306.405026 -283.549852) (xy 306.404531 -283.574459)
			(xy 306.396636 -283.623036) (xy 306.381052 -283.669717) (xy 306.358181 -283.713294) (xy 306.328616 -283.752638)
			(xy 306.293123 -283.78673) (xy 306.25262 -283.814686) (xy 306.208158 -283.835784) (xy 306.160887 -283.849476)
			(xy 306.112032 -283.855408) (xy 306.062857 -283.853427) (xy 306.014638 -283.843583) (xy 305.968622 -283.826131)
			(xy 305.926001 -283.801524) (xy 305.88788 -283.770399) (xy 305.855245 -283.733562) (xy 305.828942 -283.691966)
			(xy 305.809651 -283.64669) (xy 305.797874 -283.598906) (xy 305.793914 -283.549852) (xy 280.268426 -283.549852)
			(xy 280.268426 -283.93009) (xy 280.268934 -283.936186) (xy 280.270204 -283.947362) (xy 280.270966 -283.950664)
			(xy 280.270966 -283.951172) (xy 280.275215 -283.969291) (xy 280.279796 -284.006224) (xy 280.28011 -284.024832)
			(xy 280.618958 -284.024832) (xy 280.622918 -283.975778) (xy 280.634695 -283.927994) (xy 280.653986 -283.882718)
			(xy 280.680289 -283.841122) (xy 280.712924 -283.804285) (xy 280.751045 -283.77316) (xy 280.793666 -283.748553)
			(xy 280.839682 -283.731101) (xy 280.887901 -283.721257) (xy 280.937076 -283.719276) (xy 280.985931 -283.725208)
			(xy 281.033202 -283.7389) (xy 281.077664 -283.759998) (xy 281.118167 -283.787954) (xy 281.15366 -283.822046)
			(xy 281.183225 -283.86139) (xy 281.206096 -283.904967) (xy 281.22168 -283.951648) (xy 281.229575 -284.000225)
			(xy 281.23007 -284.024832) (xy 281.568918 -284.024832) (xy 281.572878 -283.975778) (xy 281.584655 -283.927994)
			(xy 281.603946 -283.882718) (xy 281.630249 -283.841122) (xy 281.662884 -283.804285) (xy 281.701005 -283.77316)
			(xy 281.743626 -283.748553) (xy 281.789642 -283.731101) (xy 281.837861 -283.721257) (xy 281.887036 -283.719276)
			(xy 281.935891 -283.725208) (xy 281.983162 -283.7389) (xy 282.027624 -283.759998) (xy 282.068127 -283.787954)
			(xy 282.10362 -283.822046) (xy 282.133185 -283.86139) (xy 282.156056 -283.904967) (xy 282.17164 -283.951648)
			(xy 282.179535 -284.000225) (xy 282.18003 -284.024832) (xy 282.519132 -284.024832) (xy 282.523092 -283.975778)
			(xy 282.534869 -283.927994) (xy 282.55416 -283.882718) (xy 282.580463 -283.841122) (xy 282.613098 -283.804285)
			(xy 282.651219 -283.77316) (xy 282.69384 -283.748553) (xy 282.739856 -283.731101) (xy 282.788075 -283.721257)
			(xy 282.83725 -283.719276) (xy 282.886105 -283.725208) (xy 282.933376 -283.7389) (xy 282.977838 -283.759998)
			(xy 283.018341 -283.787954) (xy 283.053834 -283.822046) (xy 283.083399 -283.86139) (xy 283.10627 -283.904967)
			(xy 283.121854 -283.951648) (xy 283.129749 -284.000225) (xy 283.130244 -284.024832) (xy 283.469092 -284.024832)
			(xy 283.473052 -283.975778) (xy 283.484829 -283.927994) (xy 283.50412 -283.882718) (xy 283.530423 -283.841122)
			(xy 283.563058 -283.804285) (xy 283.601179 -283.77316) (xy 283.6438 -283.748553) (xy 283.689816 -283.731101)
			(xy 283.738035 -283.721257) (xy 283.78721 -283.719276) (xy 283.836065 -283.725208) (xy 283.883336 -283.7389)
			(xy 283.927798 -283.759998) (xy 283.968301 -283.787954) (xy 284.003794 -283.822046) (xy 284.033359 -283.86139)
			(xy 284.05623 -283.904967) (xy 284.071814 -283.951648) (xy 284.079709 -284.000225) (xy 284.080204 -284.024832)
			(xy 284.419052 -284.024832) (xy 284.423012 -283.975778) (xy 284.434789 -283.927994) (xy 284.45408 -283.882718)
			(xy 284.480383 -283.841122) (xy 284.513018 -283.804285) (xy 284.551139 -283.77316) (xy 284.59376 -283.748553)
			(xy 284.639776 -283.731101) (xy 284.687995 -283.721257) (xy 284.73717 -283.719276) (xy 284.786025 -283.725208)
			(xy 284.833296 -283.7389) (xy 284.877758 -283.759998) (xy 284.918261 -283.787954) (xy 284.953754 -283.822046)
			(xy 284.983319 -283.86139) (xy 285.00619 -283.904967) (xy 285.021774 -283.951648) (xy 285.029669 -284.000225)
			(xy 285.030164 -284.024832) (xy 285.369012 -284.024832) (xy 285.372972 -283.975778) (xy 285.384749 -283.927994)
			(xy 285.40404 -283.882718) (xy 285.430343 -283.841122) (xy 285.462978 -283.804285) (xy 285.501099 -283.77316)
			(xy 285.54372 -283.748553) (xy 285.589736 -283.731101) (xy 285.637955 -283.721257) (xy 285.68713 -283.719276)
			(xy 285.735985 -283.725208) (xy 285.783256 -283.7389) (xy 285.827718 -283.759998) (xy 285.868221 -283.787954)
			(xy 285.903714 -283.822046) (xy 285.933279 -283.86139) (xy 285.95615 -283.904967) (xy 285.971734 -283.951648)
			(xy 285.979629 -284.000225) (xy 285.980124 -284.024832) (xy 286.318972 -284.024832) (xy 286.322932 -283.975778)
			(xy 286.334709 -283.927994) (xy 286.354 -283.882718) (xy 286.380303 -283.841122) (xy 286.412938 -283.804285)
			(xy 286.451059 -283.77316) (xy 286.49368 -283.748553) (xy 286.539696 -283.731101) (xy 286.587915 -283.721257)
			(xy 286.63709 -283.719276) (xy 286.685945 -283.725208) (xy 286.733216 -283.7389) (xy 286.777678 -283.759998)
			(xy 286.818181 -283.787954) (xy 286.853674 -283.822046) (xy 286.883239 -283.86139) (xy 286.90611 -283.904967)
			(xy 286.921694 -283.951648) (xy 286.929589 -284.000225) (xy 286.930084 -284.024832) (xy 287.268932 -284.024832)
			(xy 287.272892 -283.975778) (xy 287.284669 -283.927994) (xy 287.30396 -283.882718) (xy 287.330263 -283.841122)
			(xy 287.362898 -283.804285) (xy 287.401019 -283.77316) (xy 287.44364 -283.748553) (xy 287.489656 -283.731101)
			(xy 287.537875 -283.721257) (xy 287.58705 -283.719276) (xy 287.635905 -283.725208) (xy 287.683176 -283.7389)
			(xy 287.727638 -283.759998) (xy 287.768141 -283.787954) (xy 287.803634 -283.822046) (xy 287.833199 -283.86139)
			(xy 287.85607 -283.904967) (xy 287.871654 -283.951648) (xy 287.879549 -284.000225) (xy 287.880044 -284.024832)
			(xy 288.218892 -284.024832) (xy 288.222852 -283.975778) (xy 288.234629 -283.927994) (xy 288.25392 -283.882718)
			(xy 288.280223 -283.841122) (xy 288.312858 -283.804285) (xy 288.350979 -283.77316) (xy 288.3936 -283.748553)
			(xy 288.439616 -283.731101) (xy 288.487835 -283.721257) (xy 288.53701 -283.719276) (xy 288.585865 -283.725208)
			(xy 288.633136 -283.7389) (xy 288.677598 -283.759998) (xy 288.718101 -283.787954) (xy 288.753594 -283.822046)
			(xy 288.783159 -283.86139) (xy 288.80603 -283.904967) (xy 288.821614 -283.951648) (xy 288.829509 -284.000225)
			(xy 288.830004 -284.024832) (xy 289.169106 -284.024832) (xy 289.173066 -283.975778) (xy 289.184843 -283.927994)
			(xy 289.204134 -283.882718) (xy 289.230437 -283.841122) (xy 289.263072 -283.804285) (xy 289.301193 -283.77316)
			(xy 289.343814 -283.748553) (xy 289.38983 -283.731101) (xy 289.438049 -283.721257) (xy 289.487224 -283.719276)
			(xy 289.536079 -283.725208) (xy 289.58335 -283.7389) (xy 289.627812 -283.759998) (xy 289.668315 -283.787954)
			(xy 289.703808 -283.822046) (xy 289.733373 -283.86139) (xy 289.756244 -283.904967) (xy 289.771828 -283.951648)
			(xy 289.779723 -284.000225) (xy 289.780218 -284.024832) (xy 290.119066 -284.024832) (xy 290.123026 -283.975778)
			(xy 290.134803 -283.927994) (xy 290.154094 -283.882718) (xy 290.180397 -283.841122) (xy 290.213032 -283.804285)
			(xy 290.251153 -283.77316) (xy 290.293774 -283.748553) (xy 290.33979 -283.731101) (xy 290.388009 -283.721257)
			(xy 290.437184 -283.719276) (xy 290.486039 -283.725208) (xy 290.53331 -283.7389) (xy 290.577772 -283.759998)
			(xy 290.618275 -283.787954) (xy 290.653768 -283.822046) (xy 290.683333 -283.86139) (xy 290.706204 -283.904967)
			(xy 290.721788 -283.951648) (xy 290.729683 -284.000225) (xy 290.730178 -284.024832) (xy 292.018986 -284.024832)
			(xy 292.022946 -283.975778) (xy 292.034723 -283.927994) (xy 292.054014 -283.882718) (xy 292.080317 -283.841122)
			(xy 292.112952 -283.804285) (xy 292.151073 -283.77316) (xy 292.193694 -283.748553) (xy 292.23971 -283.731101)
			(xy 292.287929 -283.721257) (xy 292.337104 -283.719276) (xy 292.385959 -283.725208) (xy 292.43323 -283.7389)
			(xy 292.477692 -283.759998) (xy 292.518195 -283.787954) (xy 292.553688 -283.822046) (xy 292.583253 -283.86139)
			(xy 292.606124 -283.904967) (xy 292.621708 -283.951648) (xy 292.629603 -284.000225) (xy 292.630098 -284.024832)
			(xy 292.968946 -284.024832) (xy 292.972906 -283.975778) (xy 292.984683 -283.927994) (xy 293.003974 -283.882718)
			(xy 293.030277 -283.841122) (xy 293.062912 -283.804285) (xy 293.101033 -283.77316) (xy 293.143654 -283.748553)
			(xy 293.18967 -283.731101) (xy 293.237889 -283.721257) (xy 293.287064 -283.719276) (xy 293.335919 -283.725208)
			(xy 293.38319 -283.7389) (xy 293.427652 -283.759998) (xy 293.468155 -283.787954) (xy 293.503648 -283.822046)
			(xy 293.533213 -283.86139) (xy 293.556084 -283.904967) (xy 293.571668 -283.951648) (xy 293.579563 -284.000225)
			(xy 293.580058 -284.024832) (xy 293.918906 -284.024832) (xy 293.922866 -283.975778) (xy 293.934643 -283.927994)
			(xy 293.953934 -283.882718) (xy 293.980237 -283.841122) (xy 294.012872 -283.804285) (xy 294.050993 -283.77316)
			(xy 294.093614 -283.748553) (xy 294.13963 -283.731101) (xy 294.187849 -283.721257) (xy 294.237024 -283.719276)
			(xy 294.285879 -283.725208) (xy 294.33315 -283.7389) (xy 294.377612 -283.759998) (xy 294.418115 -283.787954)
			(xy 294.453608 -283.822046) (xy 294.483173 -283.86139) (xy 294.506044 -283.904967) (xy 294.521628 -283.951648)
			(xy 294.529523 -284.000225) (xy 294.530018 -284.024832) (xy 294.86912 -284.024832) (xy 294.87308 -283.975778)
			(xy 294.884857 -283.927994) (xy 294.904148 -283.882718) (xy 294.930451 -283.841122) (xy 294.963086 -283.804285)
			(xy 295.001207 -283.77316) (xy 295.043828 -283.748553) (xy 295.089844 -283.731101) (xy 295.138063 -283.721257)
			(xy 295.187238 -283.719276) (xy 295.236093 -283.725208) (xy 295.283364 -283.7389) (xy 295.327826 -283.759998)
			(xy 295.368329 -283.787954) (xy 295.403822 -283.822046) (xy 295.433387 -283.86139) (xy 295.456258 -283.904967)
			(xy 295.471842 -283.951648) (xy 295.479737 -284.000225) (xy 295.480232 -284.024832) (xy 295.81908 -284.024832)
			(xy 295.82304 -283.975778) (xy 295.834817 -283.927994) (xy 295.854108 -283.882718) (xy 295.880411 -283.841122)
			(xy 295.913046 -283.804285) (xy 295.951167 -283.77316) (xy 295.993788 -283.748553) (xy 296.039804 -283.731101)
			(xy 296.088023 -283.721257) (xy 296.137198 -283.719276) (xy 296.186053 -283.725208) (xy 296.233324 -283.7389)
			(xy 296.277786 -283.759998) (xy 296.318289 -283.787954) (xy 296.353782 -283.822046) (xy 296.383347 -283.86139)
			(xy 296.406218 -283.904967) (xy 296.421802 -283.951648) (xy 296.429697 -284.000225) (xy 296.430192 -284.024832)
			(xy 296.76904 -284.024832) (xy 296.773 -283.975778) (xy 296.784777 -283.927994) (xy 296.804068 -283.882718)
			(xy 296.830371 -283.841122) (xy 296.863006 -283.804285) (xy 296.901127 -283.77316) (xy 296.943748 -283.748553)
			(xy 296.989764 -283.731101) (xy 297.037983 -283.721257) (xy 297.087158 -283.719276) (xy 297.136013 -283.725208)
			(xy 297.183284 -283.7389) (xy 297.227746 -283.759998) (xy 297.268249 -283.787954) (xy 297.303742 -283.822046)
			(xy 297.333307 -283.86139) (xy 297.356178 -283.904967) (xy 297.371762 -283.951648) (xy 297.379657 -284.000225)
			(xy 297.380152 -284.024832) (xy 297.719 -284.024832) (xy 297.72296 -283.975778) (xy 297.734737 -283.927994)
			(xy 297.754028 -283.882718) (xy 297.780331 -283.841122) (xy 297.812966 -283.804285) (xy 297.851087 -283.77316)
			(xy 297.893708 -283.748553) (xy 297.939724 -283.731101) (xy 297.987943 -283.721257) (xy 298.037118 -283.719276)
			(xy 298.085973 -283.725208) (xy 298.133244 -283.7389) (xy 298.177706 -283.759998) (xy 298.218209 -283.787954)
			(xy 298.253702 -283.822046) (xy 298.283267 -283.86139) (xy 298.306138 -283.904967) (xy 298.321722 -283.951648)
			(xy 298.329617 -284.000225) (xy 298.330112 -284.024832) (xy 298.66896 -284.024832) (xy 298.67292 -283.975778)
			(xy 298.684697 -283.927994) (xy 298.703988 -283.882718) (xy 298.730291 -283.841122) (xy 298.762926 -283.804285)
			(xy 298.801047 -283.77316) (xy 298.843668 -283.748553) (xy 298.889684 -283.731101) (xy 298.937903 -283.721257)
			(xy 298.987078 -283.719276) (xy 299.035933 -283.725208) (xy 299.083204 -283.7389) (xy 299.127666 -283.759998)
			(xy 299.168169 -283.787954) (xy 299.203662 -283.822046) (xy 299.233227 -283.86139) (xy 299.256098 -283.904967)
			(xy 299.271682 -283.951648) (xy 299.279577 -284.000225) (xy 299.280072 -284.024832) (xy 300.56888 -284.024832)
			(xy 300.57284 -283.975778) (xy 300.584617 -283.927994) (xy 300.603908 -283.882718) (xy 300.630211 -283.841122)
			(xy 300.662846 -283.804285) (xy 300.700967 -283.77316) (xy 300.743588 -283.748553) (xy 300.789604 -283.731101)
			(xy 300.837823 -283.721257) (xy 300.886998 -283.719276) (xy 300.935853 -283.725208) (xy 300.983124 -283.7389)
			(xy 301.027586 -283.759998) (xy 301.068089 -283.787954) (xy 301.103582 -283.822046) (xy 301.133147 -283.86139)
			(xy 301.156018 -283.904967) (xy 301.171602 -283.951648) (xy 301.179497 -284.000225) (xy 301.179992 -284.024832)
			(xy 301.519094 -284.024832) (xy 301.523054 -283.975778) (xy 301.534831 -283.927994) (xy 301.554122 -283.882718)
			(xy 301.580425 -283.841122) (xy 301.61306 -283.804285) (xy 301.651181 -283.77316) (xy 301.693802 -283.748553)
			(xy 301.739818 -283.731101) (xy 301.788037 -283.721257) (xy 301.837212 -283.719276) (xy 301.886067 -283.725208)
			(xy 301.933338 -283.7389) (xy 301.9778 -283.759998) (xy 302.018303 -283.787954) (xy 302.053796 -283.822046)
			(xy 302.083361 -283.86139) (xy 302.106232 -283.904967) (xy 302.121816 -283.951648) (xy 302.129711 -284.000225)
			(xy 302.130206 -284.024832) (xy 302.469054 -284.024832) (xy 302.473014 -283.975778) (xy 302.484791 -283.927994)
			(xy 302.504082 -283.882718) (xy 302.530385 -283.841122) (xy 302.56302 -283.804285) (xy 302.601141 -283.77316)
			(xy 302.643762 -283.748553) (xy 302.689778 -283.731101) (xy 302.737997 -283.721257) (xy 302.787172 -283.719276)
			(xy 302.836027 -283.725208) (xy 302.883298 -283.7389) (xy 302.92776 -283.759998) (xy 302.968263 -283.787954)
			(xy 303.003756 -283.822046) (xy 303.033321 -283.86139) (xy 303.056192 -283.904967) (xy 303.071776 -283.951648)
			(xy 303.079671 -284.000225) (xy 303.080166 -284.024832) (xy 303.419014 -284.024832) (xy 303.422974 -283.975778)
			(xy 303.434751 -283.927994) (xy 303.454042 -283.882718) (xy 303.480345 -283.841122) (xy 303.51298 -283.804285)
			(xy 303.551101 -283.77316) (xy 303.593722 -283.748553) (xy 303.639738 -283.731101) (xy 303.687957 -283.721257)
			(xy 303.737132 -283.719276) (xy 303.785987 -283.725208) (xy 303.833258 -283.7389) (xy 303.87772 -283.759998)
			(xy 303.918223 -283.787954) (xy 303.953716 -283.822046) (xy 303.983281 -283.86139) (xy 304.006152 -283.904967)
			(xy 304.021736 -283.951648) (xy 304.029631 -284.000225) (xy 304.030126 -284.024832) (xy 304.368974 -284.024832)
			(xy 304.372934 -283.975778) (xy 304.384711 -283.927994) (xy 304.404002 -283.882718) (xy 304.430305 -283.841122)
			(xy 304.46294 -283.804285) (xy 304.501061 -283.77316) (xy 304.543682 -283.748553) (xy 304.589698 -283.731101)
			(xy 304.637917 -283.721257) (xy 304.687092 -283.719276) (xy 304.735947 -283.725208) (xy 304.783218 -283.7389)
			(xy 304.82768 -283.759998) (xy 304.868183 -283.787954) (xy 304.903676 -283.822046) (xy 304.933241 -283.86139)
			(xy 304.956112 -283.904967) (xy 304.971696 -283.951648) (xy 304.979591 -284.000225) (xy 304.980086 -284.024832)
			(xy 304.979591 -284.049439) (xy 304.971696 -284.098016) (xy 304.956112 -284.144697) (xy 304.933241 -284.188274)
			(xy 304.903676 -284.227618) (xy 304.868183 -284.26171) (xy 304.82768 -284.289666) (xy 304.783218 -284.310764)
			(xy 304.735947 -284.324456) (xy 304.687092 -284.330388) (xy 304.637917 -284.328407) (xy 304.589698 -284.318563)
			(xy 304.543682 -284.301111) (xy 304.501061 -284.276504) (xy 304.46294 -284.245379) (xy 304.430305 -284.208542)
			(xy 304.404002 -284.166946) (xy 304.384711 -284.12167) (xy 304.372934 -284.073886) (xy 304.368974 -284.024832)
			(xy 304.030126 -284.024832) (xy 304.029631 -284.049439) (xy 304.021736 -284.098016) (xy 304.006152 -284.144697)
			(xy 303.983281 -284.188274) (xy 303.953716 -284.227618) (xy 303.918223 -284.26171) (xy 303.87772 -284.289666)
			(xy 303.833258 -284.310764) (xy 303.785987 -284.324456) (xy 303.737132 -284.330388) (xy 303.687957 -284.328407)
			(xy 303.639738 -284.318563) (xy 303.593722 -284.301111) (xy 303.551101 -284.276504) (xy 303.51298 -284.245379)
			(xy 303.480345 -284.208542) (xy 303.454042 -284.166946) (xy 303.434751 -284.12167) (xy 303.422974 -284.073886)
			(xy 303.419014 -284.024832) (xy 303.080166 -284.024832) (xy 303.079671 -284.049439) (xy 303.071776 -284.098016)
			(xy 303.056192 -284.144697) (xy 303.033321 -284.188274) (xy 303.003756 -284.227618) (xy 302.968263 -284.26171)
			(xy 302.92776 -284.289666) (xy 302.883298 -284.310764) (xy 302.836027 -284.324456) (xy 302.787172 -284.330388)
			(xy 302.737997 -284.328407) (xy 302.689778 -284.318563) (xy 302.643762 -284.301111) (xy 302.601141 -284.276504)
			(xy 302.56302 -284.245379) (xy 302.530385 -284.208542) (xy 302.504082 -284.166946) (xy 302.484791 -284.12167)
			(xy 302.473014 -284.073886) (xy 302.469054 -284.024832) (xy 302.130206 -284.024832) (xy 302.129711 -284.049439)
			(xy 302.121816 -284.098016) (xy 302.106232 -284.144697) (xy 302.083361 -284.188274) (xy 302.053796 -284.227618)
			(xy 302.018303 -284.26171) (xy 301.9778 -284.289666) (xy 301.933338 -284.310764) (xy 301.886067 -284.324456)
			(xy 301.837212 -284.330388) (xy 301.788037 -284.328407) (xy 301.739818 -284.318563) (xy 301.693802 -284.301111)
			(xy 301.651181 -284.276504) (xy 301.61306 -284.245379) (xy 301.580425 -284.208542) (xy 301.554122 -284.166946)
			(xy 301.534831 -284.12167) (xy 301.523054 -284.073886) (xy 301.519094 -284.024832) (xy 301.179992 -284.024832)
			(xy 301.179497 -284.049439) (xy 301.171602 -284.098016) (xy 301.156018 -284.144697) (xy 301.133147 -284.188274)
			(xy 301.103582 -284.227618) (xy 301.068089 -284.26171) (xy 301.027586 -284.289666) (xy 300.983124 -284.310764)
			(xy 300.935853 -284.324456) (xy 300.886998 -284.330388) (xy 300.837823 -284.328407) (xy 300.789604 -284.318563)
			(xy 300.743588 -284.301111) (xy 300.700967 -284.276504) (xy 300.662846 -284.245379) (xy 300.630211 -284.208542)
			(xy 300.603908 -284.166946) (xy 300.584617 -284.12167) (xy 300.57284 -284.073886) (xy 300.56888 -284.024832)
			(xy 299.280072 -284.024832) (xy 299.279577 -284.049439) (xy 299.271682 -284.098016) (xy 299.256098 -284.144697)
			(xy 299.233227 -284.188274) (xy 299.203662 -284.227618) (xy 299.168169 -284.26171) (xy 299.127666 -284.289666)
			(xy 299.083204 -284.310764) (xy 299.035933 -284.324456) (xy 298.987078 -284.330388) (xy 298.937903 -284.328407)
			(xy 298.889684 -284.318563) (xy 298.843668 -284.301111) (xy 298.801047 -284.276504) (xy 298.762926 -284.245379)
			(xy 298.730291 -284.208542) (xy 298.703988 -284.166946) (xy 298.684697 -284.12167) (xy 298.67292 -284.073886)
			(xy 298.66896 -284.024832) (xy 298.330112 -284.024832) (xy 298.329617 -284.049439) (xy 298.321722 -284.098016)
			(xy 298.306138 -284.144697) (xy 298.283267 -284.188274) (xy 298.253702 -284.227618) (xy 298.218209 -284.26171)
			(xy 298.177706 -284.289666) (xy 298.133244 -284.310764) (xy 298.085973 -284.324456) (xy 298.037118 -284.330388)
			(xy 297.987943 -284.328407) (xy 297.939724 -284.318563) (xy 297.893708 -284.301111) (xy 297.851087 -284.276504)
			(xy 297.812966 -284.245379) (xy 297.780331 -284.208542) (xy 297.754028 -284.166946) (xy 297.734737 -284.12167)
			(xy 297.72296 -284.073886) (xy 297.719 -284.024832) (xy 297.380152 -284.024832) (xy 297.379657 -284.049439)
			(xy 297.371762 -284.098016) (xy 297.356178 -284.144697) (xy 297.333307 -284.188274) (xy 297.303742 -284.227618)
			(xy 297.268249 -284.26171) (xy 297.227746 -284.289666) (xy 297.183284 -284.310764) (xy 297.136013 -284.324456)
			(xy 297.087158 -284.330388) (xy 297.037983 -284.328407) (xy 296.989764 -284.318563) (xy 296.943748 -284.301111)
			(xy 296.901127 -284.276504) (xy 296.863006 -284.245379) (xy 296.830371 -284.208542) (xy 296.804068 -284.166946)
			(xy 296.784777 -284.12167) (xy 296.773 -284.073886) (xy 296.76904 -284.024832) (xy 296.430192 -284.024832)
			(xy 296.429697 -284.049439) (xy 296.421802 -284.098016) (xy 296.406218 -284.144697) (xy 296.383347 -284.188274)
			(xy 296.353782 -284.227618) (xy 296.318289 -284.26171) (xy 296.277786 -284.289666) (xy 296.233324 -284.310764)
			(xy 296.186053 -284.324456) (xy 296.137198 -284.330388) (xy 296.088023 -284.328407) (xy 296.039804 -284.318563)
			(xy 295.993788 -284.301111) (xy 295.951167 -284.276504) (xy 295.913046 -284.245379) (xy 295.880411 -284.208542)
			(xy 295.854108 -284.166946) (xy 295.834817 -284.12167) (xy 295.82304 -284.073886) (xy 295.81908 -284.024832)
			(xy 295.480232 -284.024832) (xy 295.479737 -284.049439) (xy 295.471842 -284.098016) (xy 295.456258 -284.144697)
			(xy 295.433387 -284.188274) (xy 295.403822 -284.227618) (xy 295.368329 -284.26171) (xy 295.327826 -284.289666)
			(xy 295.283364 -284.310764) (xy 295.236093 -284.324456) (xy 295.187238 -284.330388) (xy 295.138063 -284.328407)
			(xy 295.089844 -284.318563) (xy 295.043828 -284.301111) (xy 295.001207 -284.276504) (xy 294.963086 -284.245379)
			(xy 294.930451 -284.208542) (xy 294.904148 -284.166946) (xy 294.884857 -284.12167) (xy 294.87308 -284.073886)
			(xy 294.86912 -284.024832) (xy 294.530018 -284.024832) (xy 294.529523 -284.049439) (xy 294.521628 -284.098016)
			(xy 294.506044 -284.144697) (xy 294.483173 -284.188274) (xy 294.453608 -284.227618) (xy 294.418115 -284.26171)
			(xy 294.377612 -284.289666) (xy 294.33315 -284.310764) (xy 294.285879 -284.324456) (xy 294.237024 -284.330388)
			(xy 294.187849 -284.328407) (xy 294.13963 -284.318563) (xy 294.093614 -284.301111) (xy 294.050993 -284.276504)
			(xy 294.012872 -284.245379) (xy 293.980237 -284.208542) (xy 293.953934 -284.166946) (xy 293.934643 -284.12167)
			(xy 293.922866 -284.073886) (xy 293.918906 -284.024832) (xy 293.580058 -284.024832) (xy 293.579563 -284.049439)
			(xy 293.571668 -284.098016) (xy 293.556084 -284.144697) (xy 293.533213 -284.188274) (xy 293.503648 -284.227618)
			(xy 293.468155 -284.26171) (xy 293.427652 -284.289666) (xy 293.38319 -284.310764) (xy 293.335919 -284.324456)
			(xy 293.287064 -284.330388) (xy 293.237889 -284.328407) (xy 293.18967 -284.318563) (xy 293.143654 -284.301111)
			(xy 293.101033 -284.276504) (xy 293.062912 -284.245379) (xy 293.030277 -284.208542) (xy 293.003974 -284.166946)
			(xy 292.984683 -284.12167) (xy 292.972906 -284.073886) (xy 292.968946 -284.024832) (xy 292.630098 -284.024832)
			(xy 292.629603 -284.049439) (xy 292.621708 -284.098016) (xy 292.606124 -284.144697) (xy 292.583253 -284.188274)
			(xy 292.553688 -284.227618) (xy 292.518195 -284.26171) (xy 292.477692 -284.289666) (xy 292.43323 -284.310764)
			(xy 292.385959 -284.324456) (xy 292.337104 -284.330388) (xy 292.287929 -284.328407) (xy 292.23971 -284.318563)
			(xy 292.193694 -284.301111) (xy 292.151073 -284.276504) (xy 292.112952 -284.245379) (xy 292.080317 -284.208542)
			(xy 292.054014 -284.166946) (xy 292.034723 -284.12167) (xy 292.022946 -284.073886) (xy 292.018986 -284.024832)
			(xy 290.730178 -284.024832) (xy 290.729683 -284.049439) (xy 290.721788 -284.098016) (xy 290.706204 -284.144697)
			(xy 290.683333 -284.188274) (xy 290.653768 -284.227618) (xy 290.618275 -284.26171) (xy 290.577772 -284.289666)
			(xy 290.53331 -284.310764) (xy 290.486039 -284.324456) (xy 290.437184 -284.330388) (xy 290.388009 -284.328407)
			(xy 290.33979 -284.318563) (xy 290.293774 -284.301111) (xy 290.251153 -284.276504) (xy 290.213032 -284.245379)
			(xy 290.180397 -284.208542) (xy 290.154094 -284.166946) (xy 290.134803 -284.12167) (xy 290.123026 -284.073886)
			(xy 290.119066 -284.024832) (xy 289.780218 -284.024832) (xy 289.779723 -284.049439) (xy 289.771828 -284.098016)
			(xy 289.756244 -284.144697) (xy 289.733373 -284.188274) (xy 289.703808 -284.227618) (xy 289.668315 -284.26171)
			(xy 289.627812 -284.289666) (xy 289.58335 -284.310764) (xy 289.536079 -284.324456) (xy 289.487224 -284.330388)
			(xy 289.438049 -284.328407) (xy 289.38983 -284.318563) (xy 289.343814 -284.301111) (xy 289.301193 -284.276504)
			(xy 289.263072 -284.245379) (xy 289.230437 -284.208542) (xy 289.204134 -284.166946) (xy 289.184843 -284.12167)
			(xy 289.173066 -284.073886) (xy 289.169106 -284.024832) (xy 288.830004 -284.024832) (xy 288.829509 -284.049439)
			(xy 288.821614 -284.098016) (xy 288.80603 -284.144697) (xy 288.783159 -284.188274) (xy 288.753594 -284.227618)
			(xy 288.718101 -284.26171) (xy 288.677598 -284.289666) (xy 288.633136 -284.310764) (xy 288.585865 -284.324456)
			(xy 288.53701 -284.330388) (xy 288.487835 -284.328407) (xy 288.439616 -284.318563) (xy 288.3936 -284.301111)
			(xy 288.350979 -284.276504) (xy 288.312858 -284.245379) (xy 288.280223 -284.208542) (xy 288.25392 -284.166946)
			(xy 288.234629 -284.12167) (xy 288.222852 -284.073886) (xy 288.218892 -284.024832) (xy 287.880044 -284.024832)
			(xy 287.879549 -284.049439) (xy 287.871654 -284.098016) (xy 287.85607 -284.144697) (xy 287.833199 -284.188274)
			(xy 287.803634 -284.227618) (xy 287.768141 -284.26171) (xy 287.727638 -284.289666) (xy 287.683176 -284.310764)
			(xy 287.635905 -284.324456) (xy 287.58705 -284.330388) (xy 287.537875 -284.328407) (xy 287.489656 -284.318563)
			(xy 287.44364 -284.301111) (xy 287.401019 -284.276504) (xy 287.362898 -284.245379) (xy 287.330263 -284.208542)
			(xy 287.30396 -284.166946) (xy 287.284669 -284.12167) (xy 287.272892 -284.073886) (xy 287.268932 -284.024832)
			(xy 286.930084 -284.024832) (xy 286.929589 -284.049439) (xy 286.921694 -284.098016) (xy 286.90611 -284.144697)
			(xy 286.883239 -284.188274) (xy 286.853674 -284.227618) (xy 286.818181 -284.26171) (xy 286.777678 -284.289666)
			(xy 286.733216 -284.310764) (xy 286.685945 -284.324456) (xy 286.63709 -284.330388) (xy 286.587915 -284.328407)
			(xy 286.539696 -284.318563) (xy 286.49368 -284.301111) (xy 286.451059 -284.276504) (xy 286.412938 -284.245379)
			(xy 286.380303 -284.208542) (xy 286.354 -284.166946) (xy 286.334709 -284.12167) (xy 286.322932 -284.073886)
			(xy 286.318972 -284.024832) (xy 285.980124 -284.024832) (xy 285.979629 -284.049439) (xy 285.971734 -284.098016)
			(xy 285.95615 -284.144697) (xy 285.933279 -284.188274) (xy 285.903714 -284.227618) (xy 285.868221 -284.26171)
			(xy 285.827718 -284.289666) (xy 285.783256 -284.310764) (xy 285.735985 -284.324456) (xy 285.68713 -284.330388)
			(xy 285.637955 -284.328407) (xy 285.589736 -284.318563) (xy 285.54372 -284.301111) (xy 285.501099 -284.276504)
			(xy 285.462978 -284.245379) (xy 285.430343 -284.208542) (xy 285.40404 -284.166946) (xy 285.384749 -284.12167)
			(xy 285.372972 -284.073886) (xy 285.369012 -284.024832) (xy 285.030164 -284.024832) (xy 285.029669 -284.049439)
			(xy 285.021774 -284.098016) (xy 285.00619 -284.144697) (xy 284.983319 -284.188274) (xy 284.953754 -284.227618)
			(xy 284.918261 -284.26171) (xy 284.877758 -284.289666) (xy 284.833296 -284.310764) (xy 284.786025 -284.324456)
			(xy 284.73717 -284.330388) (xy 284.687995 -284.328407) (xy 284.639776 -284.318563) (xy 284.59376 -284.301111)
			(xy 284.551139 -284.276504) (xy 284.513018 -284.245379) (xy 284.480383 -284.208542) (xy 284.45408 -284.166946)
			(xy 284.434789 -284.12167) (xy 284.423012 -284.073886) (xy 284.419052 -284.024832) (xy 284.080204 -284.024832)
			(xy 284.079709 -284.049439) (xy 284.071814 -284.098016) (xy 284.05623 -284.144697) (xy 284.033359 -284.188274)
			(xy 284.003794 -284.227618) (xy 283.968301 -284.26171) (xy 283.927798 -284.289666) (xy 283.883336 -284.310764)
			(xy 283.836065 -284.324456) (xy 283.78721 -284.330388) (xy 283.738035 -284.328407) (xy 283.689816 -284.318563)
			(xy 283.6438 -284.301111) (xy 283.601179 -284.276504) (xy 283.563058 -284.245379) (xy 283.530423 -284.208542)
			(xy 283.50412 -284.166946) (xy 283.484829 -284.12167) (xy 283.473052 -284.073886) (xy 283.469092 -284.024832)
			(xy 283.130244 -284.024832) (xy 283.129749 -284.049439) (xy 283.121854 -284.098016) (xy 283.10627 -284.144697)
			(xy 283.083399 -284.188274) (xy 283.053834 -284.227618) (xy 283.018341 -284.26171) (xy 282.977838 -284.289666)
			(xy 282.933376 -284.310764) (xy 282.886105 -284.324456) (xy 282.83725 -284.330388) (xy 282.788075 -284.328407)
			(xy 282.739856 -284.318563) (xy 282.69384 -284.301111) (xy 282.651219 -284.276504) (xy 282.613098 -284.245379)
			(xy 282.580463 -284.208542) (xy 282.55416 -284.166946) (xy 282.534869 -284.12167) (xy 282.523092 -284.073886)
			(xy 282.519132 -284.024832) (xy 282.18003 -284.024832) (xy 282.179535 -284.049439) (xy 282.17164 -284.098016)
			(xy 282.156056 -284.144697) (xy 282.133185 -284.188274) (xy 282.10362 -284.227618) (xy 282.068127 -284.26171)
			(xy 282.027624 -284.289666) (xy 281.983162 -284.310764) (xy 281.935891 -284.324456) (xy 281.887036 -284.330388)
			(xy 281.837861 -284.328407) (xy 281.789642 -284.318563) (xy 281.743626 -284.301111) (xy 281.701005 -284.276504)
			(xy 281.662884 -284.245379) (xy 281.630249 -284.208542) (xy 281.603946 -284.166946) (xy 281.584655 -284.12167)
			(xy 281.572878 -284.073886) (xy 281.568918 -284.024832) (xy 281.23007 -284.024832) (xy 281.229575 -284.049439)
			(xy 281.22168 -284.098016) (xy 281.206096 -284.144697) (xy 281.183225 -284.188274) (xy 281.15366 -284.227618)
			(xy 281.118167 -284.26171) (xy 281.077664 -284.289666) (xy 281.033202 -284.310764) (xy 280.985931 -284.324456)
			(xy 280.937076 -284.330388) (xy 280.887901 -284.328407) (xy 280.839682 -284.318563) (xy 280.793666 -284.301111)
			(xy 280.751045 -284.276504) (xy 280.712924 -284.245379) (xy 280.680289 -284.208542) (xy 280.653986 -284.166946)
			(xy 280.634695 -284.12167) (xy 280.622918 -284.073886) (xy 280.618958 -284.024832) (xy 280.28011 -284.024832)
			(xy 280.28011 -284.041342) (xy 280.279602 -284.047184) (xy 280.279602 -284.047692) (xy 280.278332 -284.058614)
			(xy 280.278332 -284.058868) (xy 280.277824 -284.062932) (xy 280.275284 -284.081728) (xy 280.274268 -284.087316)
			(xy 280.270204 -284.103064) (xy 280.268426 -284.115764) (xy 280.268426 -284.499812) (xy 305.793914 -284.499812)
			(xy 305.797874 -284.450758) (xy 305.809651 -284.402974) (xy 305.828942 -284.357698) (xy 305.855245 -284.316102)
			(xy 305.88788 -284.279265) (xy 305.926001 -284.24814) (xy 305.968622 -284.223533) (xy 306.014638 -284.206081)
			(xy 306.062857 -284.196237) (xy 306.112032 -284.194256) (xy 306.160887 -284.200188) (xy 306.208158 -284.21388)
			(xy 306.25262 -284.234978) (xy 306.293123 -284.262934) (xy 306.328616 -284.297026) (xy 306.358181 -284.33637)
			(xy 306.381052 -284.379947) (xy 306.396636 -284.426628) (xy 306.404531 -284.475205) (xy 306.405026 -284.499812)
			(xy 306.743874 -284.499812) (xy 306.747834 -284.450758) (xy 306.759611 -284.402974) (xy 306.778902 -284.357698)
			(xy 306.805205 -284.316102) (xy 306.83784 -284.279265) (xy 306.875961 -284.24814) (xy 306.918582 -284.223533)
			(xy 306.964598 -284.206081) (xy 307.012817 -284.196237) (xy 307.061992 -284.194256) (xy 307.110847 -284.200188)
			(xy 307.158118 -284.21388) (xy 307.20258 -284.234978) (xy 307.243083 -284.262934) (xy 307.278576 -284.297026)
			(xy 307.308141 -284.33637) (xy 307.331012 -284.379947) (xy 307.346596 -284.426628) (xy 307.354491 -284.475205)
			(xy 307.354986 -284.499812) (xy 307.694088 -284.499812) (xy 307.698048 -284.450758) (xy 307.709825 -284.402974)
			(xy 307.729116 -284.357698) (xy 307.755419 -284.316102) (xy 307.788054 -284.279265) (xy 307.826175 -284.24814)
			(xy 307.868796 -284.223533) (xy 307.914812 -284.206081) (xy 307.963031 -284.196237) (xy 308.012206 -284.194256)
			(xy 308.061061 -284.200188) (xy 308.108332 -284.21388) (xy 308.152794 -284.234978) (xy 308.193297 -284.262934)
			(xy 308.22879 -284.297026) (xy 308.258355 -284.33637) (xy 308.281226 -284.379947) (xy 308.29681 -284.426628)
			(xy 308.304705 -284.475205) (xy 308.3052 -284.499812) (xy 308.644048 -284.499812) (xy 308.648008 -284.450758)
			(xy 308.659785 -284.402974) (xy 308.679076 -284.357698) (xy 308.705379 -284.316102) (xy 308.738014 -284.279265)
			(xy 308.776135 -284.24814) (xy 308.818756 -284.223533) (xy 308.864772 -284.206081) (xy 308.912991 -284.196237)
			(xy 308.962166 -284.194256) (xy 309.011021 -284.200188) (xy 309.058292 -284.21388) (xy 309.102754 -284.234978)
			(xy 309.143257 -284.262934) (xy 309.17875 -284.297026) (xy 309.208315 -284.33637) (xy 309.231186 -284.379947)
			(xy 309.24677 -284.426628) (xy 309.254665 -284.475205) (xy 309.25516 -284.499812) (xy 309.594008 -284.499812)
			(xy 309.597968 -284.450758) (xy 309.609745 -284.402974) (xy 309.629036 -284.357698) (xy 309.655339 -284.316102)
			(xy 309.687974 -284.279265) (xy 309.726095 -284.24814) (xy 309.768716 -284.223533) (xy 309.814732 -284.206081)
			(xy 309.862951 -284.196237) (xy 309.912126 -284.194256) (xy 309.960981 -284.200188) (xy 310.008252 -284.21388)
			(xy 310.052714 -284.234978) (xy 310.093217 -284.262934) (xy 310.12871 -284.297026) (xy 310.158275 -284.33637)
			(xy 310.181146 -284.379947) (xy 310.19673 -284.426628) (xy 310.204625 -284.475205) (xy 310.20512 -284.499812)
			(xy 310.543968 -284.499812) (xy 310.547928 -284.450758) (xy 310.559705 -284.402974) (xy 310.578996 -284.357698)
			(xy 310.605299 -284.316102) (xy 310.637934 -284.279265) (xy 310.676055 -284.24814) (xy 310.718676 -284.223533)
			(xy 310.764692 -284.206081) (xy 310.812911 -284.196237) (xy 310.862086 -284.194256) (xy 310.910941 -284.200188)
			(xy 310.958212 -284.21388) (xy 311.002674 -284.234978) (xy 311.043177 -284.262934) (xy 311.07867 -284.297026)
			(xy 311.108235 -284.33637) (xy 311.131106 -284.379947) (xy 311.14669 -284.426628) (xy 311.154585 -284.475205)
			(xy 311.15508 -284.499812) (xy 311.154585 -284.524419) (xy 311.154406 -284.52552) (xy 311.473084 -284.52552)
			(xy 311.473084 -284.474104) (xy 311.481127 -284.423322) (xy 311.497015 -284.374423) (xy 311.520358 -284.328611)
			(xy 311.550579 -284.287015) (xy 311.586935 -284.250659) (xy 311.628531 -284.220438) (xy 311.674343 -284.197095)
			(xy 311.723242 -284.181207) (xy 311.774024 -284.173164) (xy 311.82544 -284.173164) (xy 311.876222 -284.181207)
			(xy 311.925121 -284.197095) (xy 311.970933 -284.220438) (xy 312.012529 -284.250659) (xy 312.048885 -284.287015)
			(xy 312.079106 -284.328611) (xy 312.102449 -284.374423) (xy 312.118337 -284.423322) (xy 312.12638 -284.474104)
			(xy 312.126884 -284.499812) (xy 312.12638 -284.52552) (xy 312.423044 -284.52552) (xy 312.423044 -284.474104)
			(xy 312.431087 -284.423322) (xy 312.446975 -284.374423) (xy 312.470318 -284.328611) (xy 312.500539 -284.287015)
			(xy 312.536895 -284.250659) (xy 312.578491 -284.220438) (xy 312.624303 -284.197095) (xy 312.673202 -284.181207)
			(xy 312.723984 -284.173164) (xy 312.7754 -284.173164) (xy 312.826182 -284.181207) (xy 312.875081 -284.197095)
			(xy 312.920893 -284.220438) (xy 312.962489 -284.250659) (xy 312.998845 -284.287015) (xy 313.029066 -284.328611)
			(xy 313.052409 -284.374423) (xy 313.068297 -284.423322) (xy 313.07634 -284.474104) (xy 313.076844 -284.499812)
			(xy 313.394102 -284.499812) (xy 313.398062 -284.450758) (xy 313.409839 -284.402974) (xy 313.42913 -284.357698)
			(xy 313.455433 -284.316102) (xy 313.488068 -284.279265) (xy 313.526189 -284.24814) (xy 313.56881 -284.223533)
			(xy 313.614826 -284.206081) (xy 313.663045 -284.196237) (xy 313.71222 -284.194256) (xy 313.761075 -284.200188)
			(xy 313.808346 -284.21388) (xy 313.852808 -284.234978) (xy 313.893311 -284.262934) (xy 313.928804 -284.297026)
			(xy 313.958369 -284.33637) (xy 313.98124 -284.379947) (xy 313.996824 -284.426628) (xy 314.004719 -284.475205)
			(xy 314.005214 -284.499812) (xy 314.344062 -284.499812) (xy 314.348022 -284.450758) (xy 314.359799 -284.402974)
			(xy 314.37909 -284.357698) (xy 314.405393 -284.316102) (xy 314.438028 -284.279265) (xy 314.476149 -284.24814)
			(xy 314.51877 -284.223533) (xy 314.564786 -284.206081) (xy 314.613005 -284.196237) (xy 314.66218 -284.194256)
			(xy 314.711035 -284.200188) (xy 314.758306 -284.21388) (xy 314.802768 -284.234978) (xy 314.843271 -284.262934)
			(xy 314.878764 -284.297026) (xy 314.908329 -284.33637) (xy 314.9312 -284.379947) (xy 314.946784 -284.426628)
			(xy 314.954679 -284.475205) (xy 314.955174 -284.499812) (xy 314.954679 -284.524419) (xy 314.946784 -284.572996)
			(xy 314.9312 -284.619677) (xy 314.908329 -284.663254) (xy 314.878764 -284.702598) (xy 314.843271 -284.73669)
			(xy 314.802768 -284.764646) (xy 314.758306 -284.785744) (xy 314.711035 -284.799436) (xy 314.66218 -284.805368)
			(xy 314.613005 -284.803387) (xy 314.564786 -284.793543) (xy 314.51877 -284.776091) (xy 314.476149 -284.751484)
			(xy 314.438028 -284.720359) (xy 314.405393 -284.683522) (xy 314.37909 -284.641926) (xy 314.359799 -284.59665)
			(xy 314.348022 -284.548866) (xy 314.344062 -284.499812) (xy 314.005214 -284.499812) (xy 314.004719 -284.524419)
			(xy 313.996824 -284.572996) (xy 313.98124 -284.619677) (xy 313.958369 -284.663254) (xy 313.928804 -284.702598)
			(xy 313.893311 -284.73669) (xy 313.852808 -284.764646) (xy 313.808346 -284.785744) (xy 313.761075 -284.799436)
			(xy 313.71222 -284.805368) (xy 313.663045 -284.803387) (xy 313.614826 -284.793543) (xy 313.56881 -284.776091)
			(xy 313.526189 -284.751484) (xy 313.488068 -284.720359) (xy 313.455433 -284.683522) (xy 313.42913 -284.641926)
			(xy 313.409839 -284.59665) (xy 313.398062 -284.548866) (xy 313.394102 -284.499812) (xy 313.076844 -284.499812)
			(xy 313.07634 -284.52552) (xy 313.068297 -284.576302) (xy 313.052409 -284.625201) (xy 313.029066 -284.671013)
			(xy 312.998845 -284.712609) (xy 312.962489 -284.748965) (xy 312.920893 -284.779186) (xy 312.875081 -284.802529)
			(xy 312.826182 -284.818417) (xy 312.7754 -284.82646) (xy 312.723984 -284.82646) (xy 312.673202 -284.818417)
			(xy 312.624303 -284.802529) (xy 312.578491 -284.779186) (xy 312.536895 -284.748965) (xy 312.500539 -284.712609)
			(xy 312.470318 -284.671013) (xy 312.446975 -284.625201) (xy 312.431087 -284.576302) (xy 312.423044 -284.52552)
			(xy 312.12638 -284.52552) (xy 312.118337 -284.576302) (xy 312.102449 -284.625201) (xy 312.079106 -284.671013)
			(xy 312.048885 -284.712609) (xy 312.012529 -284.748965) (xy 311.970933 -284.779186) (xy 311.925121 -284.802529)
			(xy 311.876222 -284.818417) (xy 311.82544 -284.82646) (xy 311.774024 -284.82646) (xy 311.723242 -284.818417)
			(xy 311.674343 -284.802529) (xy 311.628531 -284.779186) (xy 311.586935 -284.748965) (xy 311.550579 -284.712609)
			(xy 311.520358 -284.671013) (xy 311.497015 -284.625201) (xy 311.481127 -284.576302) (xy 311.473084 -284.52552)
			(xy 311.154406 -284.52552) (xy 311.14669 -284.572996) (xy 311.131106 -284.619677) (xy 311.108235 -284.663254)
			(xy 311.07867 -284.702598) (xy 311.043177 -284.73669) (xy 311.002674 -284.764646) (xy 310.958212 -284.785744)
			(xy 310.910941 -284.799436) (xy 310.862086 -284.805368) (xy 310.812911 -284.803387) (xy 310.764692 -284.793543)
			(xy 310.718676 -284.776091) (xy 310.676055 -284.751484) (xy 310.637934 -284.720359) (xy 310.605299 -284.683522)
			(xy 310.578996 -284.641926) (xy 310.559705 -284.59665) (xy 310.547928 -284.548866) (xy 310.543968 -284.499812)
			(xy 310.20512 -284.499812) (xy 310.204625 -284.524419) (xy 310.19673 -284.572996) (xy 310.181146 -284.619677)
			(xy 310.158275 -284.663254) (xy 310.12871 -284.702598) (xy 310.093217 -284.73669) (xy 310.052714 -284.764646)
			(xy 310.008252 -284.785744) (xy 309.960981 -284.799436) (xy 309.912126 -284.805368) (xy 309.862951 -284.803387)
			(xy 309.814732 -284.793543) (xy 309.768716 -284.776091) (xy 309.726095 -284.751484) (xy 309.687974 -284.720359)
			(xy 309.655339 -284.683522) (xy 309.629036 -284.641926) (xy 309.609745 -284.59665) (xy 309.597968 -284.548866)
			(xy 309.594008 -284.499812) (xy 309.25516 -284.499812) (xy 309.254665 -284.524419) (xy 309.24677 -284.572996)
			(xy 309.231186 -284.619677) (xy 309.208315 -284.663254) (xy 309.17875 -284.702598) (xy 309.143257 -284.73669)
			(xy 309.102754 -284.764646) (xy 309.058292 -284.785744) (xy 309.011021 -284.799436) (xy 308.962166 -284.805368)
			(xy 308.912991 -284.803387) (xy 308.864772 -284.793543) (xy 308.818756 -284.776091) (xy 308.776135 -284.751484)
			(xy 308.738014 -284.720359) (xy 308.705379 -284.683522) (xy 308.679076 -284.641926) (xy 308.659785 -284.59665)
			(xy 308.648008 -284.548866) (xy 308.644048 -284.499812) (xy 308.3052 -284.499812) (xy 308.304705 -284.524419)
			(xy 308.29681 -284.572996) (xy 308.281226 -284.619677) (xy 308.258355 -284.663254) (xy 308.22879 -284.702598)
			(xy 308.193297 -284.73669) (xy 308.152794 -284.764646) (xy 308.108332 -284.785744) (xy 308.061061 -284.799436)
			(xy 308.012206 -284.805368) (xy 307.963031 -284.803387) (xy 307.914812 -284.793543) (xy 307.868796 -284.776091)
			(xy 307.826175 -284.751484) (xy 307.788054 -284.720359) (xy 307.755419 -284.683522) (xy 307.729116 -284.641926)
			(xy 307.709825 -284.59665) (xy 307.698048 -284.548866) (xy 307.694088 -284.499812) (xy 307.354986 -284.499812)
			(xy 307.354491 -284.524419) (xy 307.346596 -284.572996) (xy 307.331012 -284.619677) (xy 307.308141 -284.663254)
			(xy 307.278576 -284.702598) (xy 307.243083 -284.73669) (xy 307.20258 -284.764646) (xy 307.158118 -284.785744)
			(xy 307.110847 -284.799436) (xy 307.061992 -284.805368) (xy 307.012817 -284.803387) (xy 306.964598 -284.793543)
			(xy 306.918582 -284.776091) (xy 306.875961 -284.751484) (xy 306.83784 -284.720359) (xy 306.805205 -284.683522)
			(xy 306.778902 -284.641926) (xy 306.759611 -284.59665) (xy 306.747834 -284.548866) (xy 306.743874 -284.499812)
			(xy 306.405026 -284.499812) (xy 306.404531 -284.524419) (xy 306.396636 -284.572996) (xy 306.381052 -284.619677)
			(xy 306.358181 -284.663254) (xy 306.328616 -284.702598) (xy 306.293123 -284.73669) (xy 306.25262 -284.764646)
			(xy 306.208158 -284.785744) (xy 306.160887 -284.799436) (xy 306.112032 -284.805368) (xy 306.062857 -284.803387)
			(xy 306.014638 -284.793543) (xy 305.968622 -284.776091) (xy 305.926001 -284.751484) (xy 305.88788 -284.720359)
			(xy 305.855245 -284.683522) (xy 305.828942 -284.641926) (xy 305.809651 -284.59665) (xy 305.797874 -284.548866)
			(xy 305.793914 -284.499812) (xy 280.268426 -284.499812) (xy 280.268426 -284.88005) (xy 280.268934 -284.886146)
			(xy 280.270204 -284.897322) (xy 280.270966 -284.900624) (xy 280.270966 -284.901132) (xy 280.275218 -284.91925)
			(xy 280.279803 -284.956184) (xy 280.28011 -284.974792) (xy 280.618958 -284.974792) (xy 280.622918 -284.925738)
			(xy 280.634695 -284.877954) (xy 280.653986 -284.832678) (xy 280.680289 -284.791082) (xy 280.712924 -284.754245)
			(xy 280.751045 -284.72312) (xy 280.793666 -284.698513) (xy 280.839682 -284.681061) (xy 280.887901 -284.671217)
			(xy 280.937076 -284.669236) (xy 280.985931 -284.675168) (xy 281.033202 -284.68886) (xy 281.077664 -284.709958)
			(xy 281.118167 -284.737914) (xy 281.15366 -284.772006) (xy 281.183225 -284.81135) (xy 281.206096 -284.854927)
			(xy 281.22168 -284.901608) (xy 281.229575 -284.950185) (xy 281.23007 -284.974792) (xy 281.568918 -284.974792)
			(xy 281.572878 -284.925738) (xy 281.584655 -284.877954) (xy 281.603946 -284.832678) (xy 281.630249 -284.791082)
			(xy 281.662884 -284.754245) (xy 281.701005 -284.72312) (xy 281.743626 -284.698513) (xy 281.789642 -284.681061)
			(xy 281.837861 -284.671217) (xy 281.887036 -284.669236) (xy 281.935891 -284.675168) (xy 281.983162 -284.68886)
			(xy 282.027624 -284.709958) (xy 282.068127 -284.737914) (xy 282.10362 -284.772006) (xy 282.133185 -284.81135)
			(xy 282.156056 -284.854927) (xy 282.17164 -284.901608) (xy 282.179535 -284.950185) (xy 282.18003 -284.974792)
			(xy 282.519132 -284.974792) (xy 282.523092 -284.925738) (xy 282.534869 -284.877954) (xy 282.55416 -284.832678)
			(xy 282.580463 -284.791082) (xy 282.613098 -284.754245) (xy 282.651219 -284.72312) (xy 282.69384 -284.698513)
			(xy 282.739856 -284.681061) (xy 282.788075 -284.671217) (xy 282.83725 -284.669236) (xy 282.886105 -284.675168)
			(xy 282.933376 -284.68886) (xy 282.977838 -284.709958) (xy 283.018341 -284.737914) (xy 283.053834 -284.772006)
			(xy 283.083399 -284.81135) (xy 283.10627 -284.854927) (xy 283.121854 -284.901608) (xy 283.129749 -284.950185)
			(xy 283.130244 -284.974792) (xy 283.469092 -284.974792) (xy 283.473052 -284.925738) (xy 283.484829 -284.877954)
			(xy 283.50412 -284.832678) (xy 283.530423 -284.791082) (xy 283.563058 -284.754245) (xy 283.601179 -284.72312)
			(xy 283.6438 -284.698513) (xy 283.689816 -284.681061) (xy 283.738035 -284.671217) (xy 283.78721 -284.669236)
			(xy 283.836065 -284.675168) (xy 283.883336 -284.68886) (xy 283.927798 -284.709958) (xy 283.968301 -284.737914)
			(xy 284.003794 -284.772006) (xy 284.033359 -284.81135) (xy 284.05623 -284.854927) (xy 284.071814 -284.901608)
			(xy 284.079709 -284.950185) (xy 284.080204 -284.974792) (xy 284.419052 -284.974792) (xy 284.423012 -284.925738)
			(xy 284.434789 -284.877954) (xy 284.45408 -284.832678) (xy 284.480383 -284.791082) (xy 284.513018 -284.754245)
			(xy 284.551139 -284.72312) (xy 284.59376 -284.698513) (xy 284.639776 -284.681061) (xy 284.687995 -284.671217)
			(xy 284.73717 -284.669236) (xy 284.786025 -284.675168) (xy 284.833296 -284.68886) (xy 284.877758 -284.709958)
			(xy 284.918261 -284.737914) (xy 284.953754 -284.772006) (xy 284.983319 -284.81135) (xy 285.00619 -284.854927)
			(xy 285.021774 -284.901608) (xy 285.029669 -284.950185) (xy 285.030164 -284.974792) (xy 285.369012 -284.974792)
			(xy 285.372972 -284.925738) (xy 285.384749 -284.877954) (xy 285.40404 -284.832678) (xy 285.430343 -284.791082)
			(xy 285.462978 -284.754245) (xy 285.501099 -284.72312) (xy 285.54372 -284.698513) (xy 285.589736 -284.681061)
			(xy 285.637955 -284.671217) (xy 285.68713 -284.669236) (xy 285.735985 -284.675168) (xy 285.783256 -284.68886)
			(xy 285.827718 -284.709958) (xy 285.868221 -284.737914) (xy 285.903714 -284.772006) (xy 285.933279 -284.81135)
			(xy 285.95615 -284.854927) (xy 285.971734 -284.901608) (xy 285.979629 -284.950185) (xy 285.980124 -284.974792)
			(xy 286.318972 -284.974792) (xy 286.322932 -284.925738) (xy 286.334709 -284.877954) (xy 286.354 -284.832678)
			(xy 286.380303 -284.791082) (xy 286.412938 -284.754245) (xy 286.451059 -284.72312) (xy 286.49368 -284.698513)
			(xy 286.539696 -284.681061) (xy 286.587915 -284.671217) (xy 286.63709 -284.669236) (xy 286.685945 -284.675168)
			(xy 286.733216 -284.68886) (xy 286.777678 -284.709958) (xy 286.818181 -284.737914) (xy 286.853674 -284.772006)
			(xy 286.883239 -284.81135) (xy 286.90611 -284.854927) (xy 286.921694 -284.901608) (xy 286.929589 -284.950185)
			(xy 286.930084 -284.974792) (xy 287.268932 -284.974792) (xy 287.272892 -284.925738) (xy 287.284669 -284.877954)
			(xy 287.30396 -284.832678) (xy 287.330263 -284.791082) (xy 287.362898 -284.754245) (xy 287.401019 -284.72312)
			(xy 287.44364 -284.698513) (xy 287.489656 -284.681061) (xy 287.537875 -284.671217) (xy 287.58705 -284.669236)
			(xy 287.635905 -284.675168) (xy 287.683176 -284.68886) (xy 287.727638 -284.709958) (xy 287.768141 -284.737914)
			(xy 287.803634 -284.772006) (xy 287.833199 -284.81135) (xy 287.85607 -284.854927) (xy 287.871654 -284.901608)
			(xy 287.879549 -284.950185) (xy 287.880044 -284.974792) (xy 288.218892 -284.974792) (xy 288.222852 -284.925738)
			(xy 288.234629 -284.877954) (xy 288.25392 -284.832678) (xy 288.280223 -284.791082) (xy 288.312858 -284.754245)
			(xy 288.350979 -284.72312) (xy 288.3936 -284.698513) (xy 288.439616 -284.681061) (xy 288.487835 -284.671217)
			(xy 288.53701 -284.669236) (xy 288.585865 -284.675168) (xy 288.633136 -284.68886) (xy 288.677598 -284.709958)
			(xy 288.718101 -284.737914) (xy 288.753594 -284.772006) (xy 288.783159 -284.81135) (xy 288.80603 -284.854927)
			(xy 288.821614 -284.901608) (xy 288.829509 -284.950185) (xy 288.830004 -284.974792) (xy 289.169106 -284.974792)
			(xy 289.173066 -284.925738) (xy 289.184843 -284.877954) (xy 289.204134 -284.832678) (xy 289.230437 -284.791082)
			(xy 289.263072 -284.754245) (xy 289.301193 -284.72312) (xy 289.343814 -284.698513) (xy 289.38983 -284.681061)
			(xy 289.438049 -284.671217) (xy 289.487224 -284.669236) (xy 289.536079 -284.675168) (xy 289.58335 -284.68886)
			(xy 289.627812 -284.709958) (xy 289.668315 -284.737914) (xy 289.703808 -284.772006) (xy 289.733373 -284.81135)
			(xy 289.756244 -284.854927) (xy 289.771828 -284.901608) (xy 289.779723 -284.950185) (xy 289.780218 -284.974792)
			(xy 290.119066 -284.974792) (xy 290.123026 -284.925738) (xy 290.134803 -284.877954) (xy 290.154094 -284.832678)
			(xy 290.180397 -284.791082) (xy 290.213032 -284.754245) (xy 290.251153 -284.72312) (xy 290.293774 -284.698513)
			(xy 290.33979 -284.681061) (xy 290.388009 -284.671217) (xy 290.437184 -284.669236) (xy 290.486039 -284.675168)
			(xy 290.53331 -284.68886) (xy 290.577772 -284.709958) (xy 290.618275 -284.737914) (xy 290.653768 -284.772006)
			(xy 290.683333 -284.81135) (xy 290.706204 -284.854927) (xy 290.721788 -284.901608) (xy 290.729683 -284.950185)
			(xy 290.730178 -284.974792) (xy 292.018986 -284.974792) (xy 292.022946 -284.925738) (xy 292.034723 -284.877954)
			(xy 292.054014 -284.832678) (xy 292.080317 -284.791082) (xy 292.112952 -284.754245) (xy 292.151073 -284.72312)
			(xy 292.193694 -284.698513) (xy 292.23971 -284.681061) (xy 292.287929 -284.671217) (xy 292.337104 -284.669236)
			(xy 292.385959 -284.675168) (xy 292.43323 -284.68886) (xy 292.477692 -284.709958) (xy 292.518195 -284.737914)
			(xy 292.553688 -284.772006) (xy 292.583253 -284.81135) (xy 292.606124 -284.854927) (xy 292.621708 -284.901608)
			(xy 292.629603 -284.950185) (xy 292.630098 -284.974792) (xy 292.968946 -284.974792) (xy 292.972906 -284.925738)
			(xy 292.984683 -284.877954) (xy 293.003974 -284.832678) (xy 293.030277 -284.791082) (xy 293.062912 -284.754245)
			(xy 293.101033 -284.72312) (xy 293.143654 -284.698513) (xy 293.18967 -284.681061) (xy 293.237889 -284.671217)
			(xy 293.287064 -284.669236) (xy 293.335919 -284.675168) (xy 293.38319 -284.68886) (xy 293.427652 -284.709958)
			(xy 293.468155 -284.737914) (xy 293.503648 -284.772006) (xy 293.533213 -284.81135) (xy 293.556084 -284.854927)
			(xy 293.571668 -284.901608) (xy 293.579563 -284.950185) (xy 293.580058 -284.974792) (xy 293.918906 -284.974792)
			(xy 293.922866 -284.925738) (xy 293.934643 -284.877954) (xy 293.953934 -284.832678) (xy 293.980237 -284.791082)
			(xy 294.012872 -284.754245) (xy 294.050993 -284.72312) (xy 294.093614 -284.698513) (xy 294.13963 -284.681061)
			(xy 294.187849 -284.671217) (xy 294.237024 -284.669236) (xy 294.285879 -284.675168) (xy 294.33315 -284.68886)
			(xy 294.377612 -284.709958) (xy 294.418115 -284.737914) (xy 294.453608 -284.772006) (xy 294.483173 -284.81135)
			(xy 294.506044 -284.854927) (xy 294.521628 -284.901608) (xy 294.529523 -284.950185) (xy 294.530018 -284.974792)
			(xy 294.86912 -284.974792) (xy 294.87308 -284.925738) (xy 294.884857 -284.877954) (xy 294.904148 -284.832678)
			(xy 294.930451 -284.791082) (xy 294.963086 -284.754245) (xy 295.001207 -284.72312) (xy 295.043828 -284.698513)
			(xy 295.089844 -284.681061) (xy 295.138063 -284.671217) (xy 295.187238 -284.669236) (xy 295.236093 -284.675168)
			(xy 295.283364 -284.68886) (xy 295.327826 -284.709958) (xy 295.368329 -284.737914) (xy 295.403822 -284.772006)
			(xy 295.433387 -284.81135) (xy 295.456258 -284.854927) (xy 295.471842 -284.901608) (xy 295.479737 -284.950185)
			(xy 295.480232 -284.974792) (xy 295.81908 -284.974792) (xy 295.82304 -284.925738) (xy 295.834817 -284.877954)
			(xy 295.854108 -284.832678) (xy 295.880411 -284.791082) (xy 295.913046 -284.754245) (xy 295.951167 -284.72312)
			(xy 295.993788 -284.698513) (xy 296.039804 -284.681061) (xy 296.088023 -284.671217) (xy 296.137198 -284.669236)
			(xy 296.186053 -284.675168) (xy 296.233324 -284.68886) (xy 296.277786 -284.709958) (xy 296.318289 -284.737914)
			(xy 296.353782 -284.772006) (xy 296.383347 -284.81135) (xy 296.406218 -284.854927) (xy 296.421802 -284.901608)
			(xy 296.429697 -284.950185) (xy 296.430192 -284.974792) (xy 296.76904 -284.974792) (xy 296.773 -284.925738)
			(xy 296.784777 -284.877954) (xy 296.804068 -284.832678) (xy 296.830371 -284.791082) (xy 296.863006 -284.754245)
			(xy 296.901127 -284.72312) (xy 296.943748 -284.698513) (xy 296.989764 -284.681061) (xy 297.037983 -284.671217)
			(xy 297.087158 -284.669236) (xy 297.136013 -284.675168) (xy 297.183284 -284.68886) (xy 297.227746 -284.709958)
			(xy 297.268249 -284.737914) (xy 297.303742 -284.772006) (xy 297.333307 -284.81135) (xy 297.356178 -284.854927)
			(xy 297.371762 -284.901608) (xy 297.379657 -284.950185) (xy 297.380152 -284.974792) (xy 297.719 -284.974792)
			(xy 297.72296 -284.925738) (xy 297.734737 -284.877954) (xy 297.754028 -284.832678) (xy 297.780331 -284.791082)
			(xy 297.812966 -284.754245) (xy 297.851087 -284.72312) (xy 297.893708 -284.698513) (xy 297.939724 -284.681061)
			(xy 297.987943 -284.671217) (xy 298.037118 -284.669236) (xy 298.085973 -284.675168) (xy 298.133244 -284.68886)
			(xy 298.177706 -284.709958) (xy 298.218209 -284.737914) (xy 298.253702 -284.772006) (xy 298.283267 -284.81135)
			(xy 298.306138 -284.854927) (xy 298.321722 -284.901608) (xy 298.329617 -284.950185) (xy 298.330112 -284.974792)
			(xy 298.66896 -284.974792) (xy 298.67292 -284.925738) (xy 298.684697 -284.877954) (xy 298.703988 -284.832678)
			(xy 298.730291 -284.791082) (xy 298.762926 -284.754245) (xy 298.801047 -284.72312) (xy 298.843668 -284.698513)
			(xy 298.889684 -284.681061) (xy 298.937903 -284.671217) (xy 298.987078 -284.669236) (xy 299.035933 -284.675168)
			(xy 299.083204 -284.68886) (xy 299.127666 -284.709958) (xy 299.168169 -284.737914) (xy 299.203662 -284.772006)
			(xy 299.233227 -284.81135) (xy 299.256098 -284.854927) (xy 299.271682 -284.901608) (xy 299.279577 -284.950185)
			(xy 299.280072 -284.974792) (xy 299.61892 -284.974792) (xy 299.62288 -284.925738) (xy 299.634657 -284.877954)
			(xy 299.653948 -284.832678) (xy 299.680251 -284.791082) (xy 299.712886 -284.754245) (xy 299.751007 -284.72312)
			(xy 299.793628 -284.698513) (xy 299.839644 -284.681061) (xy 299.887863 -284.671217) (xy 299.937038 -284.669236)
			(xy 299.985893 -284.675168) (xy 300.033164 -284.68886) (xy 300.077626 -284.709958) (xy 300.118129 -284.737914)
			(xy 300.153622 -284.772006) (xy 300.183187 -284.81135) (xy 300.206058 -284.854927) (xy 300.221642 -284.901608)
			(xy 300.229537 -284.950185) (xy 300.230032 -284.974792) (xy 300.56888 -284.974792) (xy 300.57284 -284.925738)
			(xy 300.584617 -284.877954) (xy 300.603908 -284.832678) (xy 300.630211 -284.791082) (xy 300.662846 -284.754245)
			(xy 300.700967 -284.72312) (xy 300.743588 -284.698513) (xy 300.789604 -284.681061) (xy 300.837823 -284.671217)
			(xy 300.886998 -284.669236) (xy 300.935853 -284.675168) (xy 300.983124 -284.68886) (xy 301.027586 -284.709958)
			(xy 301.068089 -284.737914) (xy 301.103582 -284.772006) (xy 301.133147 -284.81135) (xy 301.156018 -284.854927)
			(xy 301.171602 -284.901608) (xy 301.179497 -284.950185) (xy 301.179992 -284.974792) (xy 301.519094 -284.974792)
			(xy 301.523054 -284.925738) (xy 301.534831 -284.877954) (xy 301.554122 -284.832678) (xy 301.580425 -284.791082)
			(xy 301.61306 -284.754245) (xy 301.651181 -284.72312) (xy 301.693802 -284.698513) (xy 301.739818 -284.681061)
			(xy 301.788037 -284.671217) (xy 301.837212 -284.669236) (xy 301.886067 -284.675168) (xy 301.933338 -284.68886)
			(xy 301.9778 -284.709958) (xy 302.018303 -284.737914) (xy 302.053796 -284.772006) (xy 302.083361 -284.81135)
			(xy 302.106232 -284.854927) (xy 302.121816 -284.901608) (xy 302.129711 -284.950185) (xy 302.130206 -284.974792)
			(xy 302.469054 -284.974792) (xy 302.473014 -284.925738) (xy 302.484791 -284.877954) (xy 302.504082 -284.832678)
			(xy 302.530385 -284.791082) (xy 302.56302 -284.754245) (xy 302.601141 -284.72312) (xy 302.643762 -284.698513)
			(xy 302.689778 -284.681061) (xy 302.737997 -284.671217) (xy 302.787172 -284.669236) (xy 302.836027 -284.675168)
			(xy 302.883298 -284.68886) (xy 302.92776 -284.709958) (xy 302.968263 -284.737914) (xy 303.003756 -284.772006)
			(xy 303.033321 -284.81135) (xy 303.056192 -284.854927) (xy 303.071776 -284.901608) (xy 303.079671 -284.950185)
			(xy 303.080166 -284.974792) (xy 303.079671 -284.999399) (xy 303.071776 -285.047976) (xy 303.056192 -285.094657)
			(xy 303.033321 -285.138234) (xy 303.003756 -285.177578) (xy 302.968263 -285.21167) (xy 302.92776 -285.239626)
			(xy 302.883298 -285.260724) (xy 302.836027 -285.274416) (xy 302.787172 -285.280348) (xy 302.737997 -285.278367)
			(xy 302.689778 -285.268523) (xy 302.643762 -285.251071) (xy 302.601141 -285.226464) (xy 302.56302 -285.195339)
			(xy 302.530385 -285.158502) (xy 302.504082 -285.116906) (xy 302.484791 -285.07163) (xy 302.473014 -285.023846)
			(xy 302.469054 -284.974792) (xy 302.130206 -284.974792) (xy 302.129711 -284.999399) (xy 302.121816 -285.047976)
			(xy 302.106232 -285.094657) (xy 302.083361 -285.138234) (xy 302.053796 -285.177578) (xy 302.018303 -285.21167)
			(xy 301.9778 -285.239626) (xy 301.933338 -285.260724) (xy 301.886067 -285.274416) (xy 301.837212 -285.280348)
			(xy 301.788037 -285.278367) (xy 301.739818 -285.268523) (xy 301.693802 -285.251071) (xy 301.651181 -285.226464)
			(xy 301.61306 -285.195339) (xy 301.580425 -285.158502) (xy 301.554122 -285.116906) (xy 301.534831 -285.07163)
			(xy 301.523054 -285.023846) (xy 301.519094 -284.974792) (xy 301.179992 -284.974792) (xy 301.179497 -284.999399)
			(xy 301.171602 -285.047976) (xy 301.156018 -285.094657) (xy 301.133147 -285.138234) (xy 301.103582 -285.177578)
			(xy 301.068089 -285.21167) (xy 301.027586 -285.239626) (xy 300.983124 -285.260724) (xy 300.935853 -285.274416)
			(xy 300.886998 -285.280348) (xy 300.837823 -285.278367) (xy 300.789604 -285.268523) (xy 300.743588 -285.251071)
			(xy 300.700967 -285.226464) (xy 300.662846 -285.195339) (xy 300.630211 -285.158502) (xy 300.603908 -285.116906)
			(xy 300.584617 -285.07163) (xy 300.57284 -285.023846) (xy 300.56888 -284.974792) (xy 300.230032 -284.974792)
			(xy 300.229537 -284.999399) (xy 300.221642 -285.047976) (xy 300.206058 -285.094657) (xy 300.183187 -285.138234)
			(xy 300.153622 -285.177578) (xy 300.118129 -285.21167) (xy 300.077626 -285.239626) (xy 300.033164 -285.260724)
			(xy 299.985893 -285.274416) (xy 299.937038 -285.280348) (xy 299.887863 -285.278367) (xy 299.839644 -285.268523)
			(xy 299.793628 -285.251071) (xy 299.751007 -285.226464) (xy 299.712886 -285.195339) (xy 299.680251 -285.158502)
			(xy 299.653948 -285.116906) (xy 299.634657 -285.07163) (xy 299.62288 -285.023846) (xy 299.61892 -284.974792)
			(xy 299.280072 -284.974792) (xy 299.279577 -284.999399) (xy 299.271682 -285.047976) (xy 299.256098 -285.094657)
			(xy 299.233227 -285.138234) (xy 299.203662 -285.177578) (xy 299.168169 -285.21167) (xy 299.127666 -285.239626)
			(xy 299.083204 -285.260724) (xy 299.035933 -285.274416) (xy 298.987078 -285.280348) (xy 298.937903 -285.278367)
			(xy 298.889684 -285.268523) (xy 298.843668 -285.251071) (xy 298.801047 -285.226464) (xy 298.762926 -285.195339)
			(xy 298.730291 -285.158502) (xy 298.703988 -285.116906) (xy 298.684697 -285.07163) (xy 298.67292 -285.023846)
			(xy 298.66896 -284.974792) (xy 298.330112 -284.974792) (xy 298.329617 -284.999399) (xy 298.321722 -285.047976)
			(xy 298.306138 -285.094657) (xy 298.283267 -285.138234) (xy 298.253702 -285.177578) (xy 298.218209 -285.21167)
			(xy 298.177706 -285.239626) (xy 298.133244 -285.260724) (xy 298.085973 -285.274416) (xy 298.037118 -285.280348)
			(xy 297.987943 -285.278367) (xy 297.939724 -285.268523) (xy 297.893708 -285.251071) (xy 297.851087 -285.226464)
			(xy 297.812966 -285.195339) (xy 297.780331 -285.158502) (xy 297.754028 -285.116906) (xy 297.734737 -285.07163)
			(xy 297.72296 -285.023846) (xy 297.719 -284.974792) (xy 297.380152 -284.974792) (xy 297.379657 -284.999399)
			(xy 297.371762 -285.047976) (xy 297.356178 -285.094657) (xy 297.333307 -285.138234) (xy 297.303742 -285.177578)
			(xy 297.268249 -285.21167) (xy 297.227746 -285.239626) (xy 297.183284 -285.260724) (xy 297.136013 -285.274416)
			(xy 297.087158 -285.280348) (xy 297.037983 -285.278367) (xy 296.989764 -285.268523) (xy 296.943748 -285.251071)
			(xy 296.901127 -285.226464) (xy 296.863006 -285.195339) (xy 296.830371 -285.158502) (xy 296.804068 -285.116906)
			(xy 296.784777 -285.07163) (xy 296.773 -285.023846) (xy 296.76904 -284.974792) (xy 296.430192 -284.974792)
			(xy 296.429697 -284.999399) (xy 296.421802 -285.047976) (xy 296.406218 -285.094657) (xy 296.383347 -285.138234)
			(xy 296.353782 -285.177578) (xy 296.318289 -285.21167) (xy 296.277786 -285.239626) (xy 296.233324 -285.260724)
			(xy 296.186053 -285.274416) (xy 296.137198 -285.280348) (xy 296.088023 -285.278367) (xy 296.039804 -285.268523)
			(xy 295.993788 -285.251071) (xy 295.951167 -285.226464) (xy 295.913046 -285.195339) (xy 295.880411 -285.158502)
			(xy 295.854108 -285.116906) (xy 295.834817 -285.07163) (xy 295.82304 -285.023846) (xy 295.81908 -284.974792)
			(xy 295.480232 -284.974792) (xy 295.479737 -284.999399) (xy 295.471842 -285.047976) (xy 295.456258 -285.094657)
			(xy 295.433387 -285.138234) (xy 295.403822 -285.177578) (xy 295.368329 -285.21167) (xy 295.327826 -285.239626)
			(xy 295.283364 -285.260724) (xy 295.236093 -285.274416) (xy 295.187238 -285.280348) (xy 295.138063 -285.278367)
			(xy 295.089844 -285.268523) (xy 295.043828 -285.251071) (xy 295.001207 -285.226464) (xy 294.963086 -285.195339)
			(xy 294.930451 -285.158502) (xy 294.904148 -285.116906) (xy 294.884857 -285.07163) (xy 294.87308 -285.023846)
			(xy 294.86912 -284.974792) (xy 294.530018 -284.974792) (xy 294.529523 -284.999399) (xy 294.521628 -285.047976)
			(xy 294.506044 -285.094657) (xy 294.483173 -285.138234) (xy 294.453608 -285.177578) (xy 294.418115 -285.21167)
			(xy 294.377612 -285.239626) (xy 294.33315 -285.260724) (xy 294.285879 -285.274416) (xy 294.237024 -285.280348)
			(xy 294.187849 -285.278367) (xy 294.13963 -285.268523) (xy 294.093614 -285.251071) (xy 294.050993 -285.226464)
			(xy 294.012872 -285.195339) (xy 293.980237 -285.158502) (xy 293.953934 -285.116906) (xy 293.934643 -285.07163)
			(xy 293.922866 -285.023846) (xy 293.918906 -284.974792) (xy 293.580058 -284.974792) (xy 293.579563 -284.999399)
			(xy 293.571668 -285.047976) (xy 293.556084 -285.094657) (xy 293.533213 -285.138234) (xy 293.503648 -285.177578)
			(xy 293.468155 -285.21167) (xy 293.427652 -285.239626) (xy 293.38319 -285.260724) (xy 293.335919 -285.274416)
			(xy 293.287064 -285.280348) (xy 293.237889 -285.278367) (xy 293.18967 -285.268523) (xy 293.143654 -285.251071)
			(xy 293.101033 -285.226464) (xy 293.062912 -285.195339) (xy 293.030277 -285.158502) (xy 293.003974 -285.116906)
			(xy 292.984683 -285.07163) (xy 292.972906 -285.023846) (xy 292.968946 -284.974792) (xy 292.630098 -284.974792)
			(xy 292.629603 -284.999399) (xy 292.621708 -285.047976) (xy 292.606124 -285.094657) (xy 292.583253 -285.138234)
			(xy 292.553688 -285.177578) (xy 292.518195 -285.21167) (xy 292.477692 -285.239626) (xy 292.43323 -285.260724)
			(xy 292.385959 -285.274416) (xy 292.337104 -285.280348) (xy 292.287929 -285.278367) (xy 292.23971 -285.268523)
			(xy 292.193694 -285.251071) (xy 292.151073 -285.226464) (xy 292.112952 -285.195339) (xy 292.080317 -285.158502)
			(xy 292.054014 -285.116906) (xy 292.034723 -285.07163) (xy 292.022946 -285.023846) (xy 292.018986 -284.974792)
			(xy 290.730178 -284.974792) (xy 290.729683 -284.999399) (xy 290.721788 -285.047976) (xy 290.706204 -285.094657)
			(xy 290.683333 -285.138234) (xy 290.653768 -285.177578) (xy 290.618275 -285.21167) (xy 290.577772 -285.239626)
			(xy 290.53331 -285.260724) (xy 290.486039 -285.274416) (xy 290.437184 -285.280348) (xy 290.388009 -285.278367)
			(xy 290.33979 -285.268523) (xy 290.293774 -285.251071) (xy 290.251153 -285.226464) (xy 290.213032 -285.195339)
			(xy 290.180397 -285.158502) (xy 290.154094 -285.116906) (xy 290.134803 -285.07163) (xy 290.123026 -285.023846)
			(xy 290.119066 -284.974792) (xy 289.780218 -284.974792) (xy 289.779723 -284.999399) (xy 289.771828 -285.047976)
			(xy 289.756244 -285.094657) (xy 289.733373 -285.138234) (xy 289.703808 -285.177578) (xy 289.668315 -285.21167)
			(xy 289.627812 -285.239626) (xy 289.58335 -285.260724) (xy 289.536079 -285.274416) (xy 289.487224 -285.280348)
			(xy 289.438049 -285.278367) (xy 289.38983 -285.268523) (xy 289.343814 -285.251071) (xy 289.301193 -285.226464)
			(xy 289.263072 -285.195339) (xy 289.230437 -285.158502) (xy 289.204134 -285.116906) (xy 289.184843 -285.07163)
			(xy 289.173066 -285.023846) (xy 289.169106 -284.974792) (xy 288.830004 -284.974792) (xy 288.829509 -284.999399)
			(xy 288.821614 -285.047976) (xy 288.80603 -285.094657) (xy 288.783159 -285.138234) (xy 288.753594 -285.177578)
			(xy 288.718101 -285.21167) (xy 288.677598 -285.239626) (xy 288.633136 -285.260724) (xy 288.585865 -285.274416)
			(xy 288.53701 -285.280348) (xy 288.487835 -285.278367) (xy 288.439616 -285.268523) (xy 288.3936 -285.251071)
			(xy 288.350979 -285.226464) (xy 288.312858 -285.195339) (xy 288.280223 -285.158502) (xy 288.25392 -285.116906)
			(xy 288.234629 -285.07163) (xy 288.222852 -285.023846) (xy 288.218892 -284.974792) (xy 287.880044 -284.974792)
			(xy 287.879549 -284.999399) (xy 287.871654 -285.047976) (xy 287.85607 -285.094657) (xy 287.833199 -285.138234)
			(xy 287.803634 -285.177578) (xy 287.768141 -285.21167) (xy 287.727638 -285.239626) (xy 287.683176 -285.260724)
			(xy 287.635905 -285.274416) (xy 287.58705 -285.280348) (xy 287.537875 -285.278367) (xy 287.489656 -285.268523)
			(xy 287.44364 -285.251071) (xy 287.401019 -285.226464) (xy 287.362898 -285.195339) (xy 287.330263 -285.158502)
			(xy 287.30396 -285.116906) (xy 287.284669 -285.07163) (xy 287.272892 -285.023846) (xy 287.268932 -284.974792)
			(xy 286.930084 -284.974792) (xy 286.929589 -284.999399) (xy 286.921694 -285.047976) (xy 286.90611 -285.094657)
			(xy 286.883239 -285.138234) (xy 286.853674 -285.177578) (xy 286.818181 -285.21167) (xy 286.777678 -285.239626)
			(xy 286.733216 -285.260724) (xy 286.685945 -285.274416) (xy 286.63709 -285.280348) (xy 286.587915 -285.278367)
			(xy 286.539696 -285.268523) (xy 286.49368 -285.251071) (xy 286.451059 -285.226464) (xy 286.412938 -285.195339)
			(xy 286.380303 -285.158502) (xy 286.354 -285.116906) (xy 286.334709 -285.07163) (xy 286.322932 -285.023846)
			(xy 286.318972 -284.974792) (xy 285.980124 -284.974792) (xy 285.979629 -284.999399) (xy 285.971734 -285.047976)
			(xy 285.95615 -285.094657) (xy 285.933279 -285.138234) (xy 285.903714 -285.177578) (xy 285.868221 -285.21167)
			(xy 285.827718 -285.239626) (xy 285.783256 -285.260724) (xy 285.735985 -285.274416) (xy 285.68713 -285.280348)
			(xy 285.637955 -285.278367) (xy 285.589736 -285.268523) (xy 285.54372 -285.251071) (xy 285.501099 -285.226464)
			(xy 285.462978 -285.195339) (xy 285.430343 -285.158502) (xy 285.40404 -285.116906) (xy 285.384749 -285.07163)
			(xy 285.372972 -285.023846) (xy 285.369012 -284.974792) (xy 285.030164 -284.974792) (xy 285.029669 -284.999399)
			(xy 285.021774 -285.047976) (xy 285.00619 -285.094657) (xy 284.983319 -285.138234) (xy 284.953754 -285.177578)
			(xy 284.918261 -285.21167) (xy 284.877758 -285.239626) (xy 284.833296 -285.260724) (xy 284.786025 -285.274416)
			(xy 284.73717 -285.280348) (xy 284.687995 -285.278367) (xy 284.639776 -285.268523) (xy 284.59376 -285.251071)
			(xy 284.551139 -285.226464) (xy 284.513018 -285.195339) (xy 284.480383 -285.158502) (xy 284.45408 -285.116906)
			(xy 284.434789 -285.07163) (xy 284.423012 -285.023846) (xy 284.419052 -284.974792) (xy 284.080204 -284.974792)
			(xy 284.079709 -284.999399) (xy 284.071814 -285.047976) (xy 284.05623 -285.094657) (xy 284.033359 -285.138234)
			(xy 284.003794 -285.177578) (xy 283.968301 -285.21167) (xy 283.927798 -285.239626) (xy 283.883336 -285.260724)
			(xy 283.836065 -285.274416) (xy 283.78721 -285.280348) (xy 283.738035 -285.278367) (xy 283.689816 -285.268523)
			(xy 283.6438 -285.251071) (xy 283.601179 -285.226464) (xy 283.563058 -285.195339) (xy 283.530423 -285.158502)
			(xy 283.50412 -285.116906) (xy 283.484829 -285.07163) (xy 283.473052 -285.023846) (xy 283.469092 -284.974792)
			(xy 283.130244 -284.974792) (xy 283.129749 -284.999399) (xy 283.121854 -285.047976) (xy 283.10627 -285.094657)
			(xy 283.083399 -285.138234) (xy 283.053834 -285.177578) (xy 283.018341 -285.21167) (xy 282.977838 -285.239626)
			(xy 282.933376 -285.260724) (xy 282.886105 -285.274416) (xy 282.83725 -285.280348) (xy 282.788075 -285.278367)
			(xy 282.739856 -285.268523) (xy 282.69384 -285.251071) (xy 282.651219 -285.226464) (xy 282.613098 -285.195339)
			(xy 282.580463 -285.158502) (xy 282.55416 -285.116906) (xy 282.534869 -285.07163) (xy 282.523092 -285.023846)
			(xy 282.519132 -284.974792) (xy 282.18003 -284.974792) (xy 282.179535 -284.999399) (xy 282.17164 -285.047976)
			(xy 282.156056 -285.094657) (xy 282.133185 -285.138234) (xy 282.10362 -285.177578) (xy 282.068127 -285.21167)
			(xy 282.027624 -285.239626) (xy 281.983162 -285.260724) (xy 281.935891 -285.274416) (xy 281.887036 -285.280348)
			(xy 281.837861 -285.278367) (xy 281.789642 -285.268523) (xy 281.743626 -285.251071) (xy 281.701005 -285.226464)
			(xy 281.662884 -285.195339) (xy 281.630249 -285.158502) (xy 281.603946 -285.116906) (xy 281.584655 -285.07163)
			(xy 281.572878 -285.023846) (xy 281.568918 -284.974792) (xy 281.23007 -284.974792) (xy 281.229575 -284.999399)
			(xy 281.22168 -285.047976) (xy 281.206096 -285.094657) (xy 281.183225 -285.138234) (xy 281.15366 -285.177578)
			(xy 281.118167 -285.21167) (xy 281.077664 -285.239626) (xy 281.033202 -285.260724) (xy 280.985931 -285.274416)
			(xy 280.937076 -285.280348) (xy 280.887901 -285.278367) (xy 280.839682 -285.268523) (xy 280.793666 -285.251071)
			(xy 280.751045 -285.226464) (xy 280.712924 -285.195339) (xy 280.680289 -285.158502) (xy 280.653986 -285.116906)
			(xy 280.634695 -285.07163) (xy 280.622918 -285.023846) (xy 280.618958 -284.974792) (xy 280.28011 -284.974792)
			(xy 280.28011 -284.991302) (xy 280.279602 -284.997144) (xy 280.279602 -284.997652) (xy 280.278332 -285.008574)
			(xy 280.278332 -285.008828) (xy 280.277824 -285.012892) (xy 280.275284 -285.031688) (xy 280.274268 -285.037276)
			(xy 280.270204 -285.053024) (xy 280.268426 -285.065724) (xy 280.268426 -285.449772) (xy 305.793914 -285.449772)
			(xy 305.797874 -285.400718) (xy 305.809651 -285.352934) (xy 305.828942 -285.307658) (xy 305.855245 -285.266062)
			(xy 305.88788 -285.229225) (xy 305.926001 -285.1981) (xy 305.968622 -285.173493) (xy 306.014638 -285.156041)
			(xy 306.062857 -285.146197) (xy 306.112032 -285.144216) (xy 306.160887 -285.150148) (xy 306.208158 -285.16384)
			(xy 306.25262 -285.184938) (xy 306.293123 -285.212894) (xy 306.328616 -285.246986) (xy 306.358181 -285.28633)
			(xy 306.381052 -285.329907) (xy 306.396636 -285.376588) (xy 306.404531 -285.425165) (xy 306.405026 -285.449772)
			(xy 306.743874 -285.449772) (xy 306.747834 -285.400718) (xy 306.759611 -285.352934) (xy 306.778902 -285.307658)
			(xy 306.805205 -285.266062) (xy 306.83784 -285.229225) (xy 306.875961 -285.1981) (xy 306.918582 -285.173493)
			(xy 306.964598 -285.156041) (xy 307.012817 -285.146197) (xy 307.061992 -285.144216) (xy 307.110847 -285.150148)
			(xy 307.158118 -285.16384) (xy 307.20258 -285.184938) (xy 307.243083 -285.212894) (xy 307.278576 -285.246986)
			(xy 307.308141 -285.28633) (xy 307.331012 -285.329907) (xy 307.346596 -285.376588) (xy 307.354491 -285.425165)
			(xy 307.354986 -285.449772) (xy 307.694088 -285.449772) (xy 307.698048 -285.400718) (xy 307.709825 -285.352934)
			(xy 307.729116 -285.307658) (xy 307.755419 -285.266062) (xy 307.788054 -285.229225) (xy 307.826175 -285.1981)
			(xy 307.868796 -285.173493) (xy 307.914812 -285.156041) (xy 307.963031 -285.146197) (xy 308.012206 -285.144216)
			(xy 308.061061 -285.150148) (xy 308.108332 -285.16384) (xy 308.152794 -285.184938) (xy 308.193297 -285.212894)
			(xy 308.22879 -285.246986) (xy 308.258355 -285.28633) (xy 308.281226 -285.329907) (xy 308.29681 -285.376588)
			(xy 308.304705 -285.425165) (xy 308.3052 -285.449772) (xy 308.644048 -285.449772) (xy 308.648008 -285.400718)
			(xy 308.659785 -285.352934) (xy 308.679076 -285.307658) (xy 308.705379 -285.266062) (xy 308.738014 -285.229225)
			(xy 308.776135 -285.1981) (xy 308.818756 -285.173493) (xy 308.864772 -285.156041) (xy 308.912991 -285.146197)
			(xy 308.962166 -285.144216) (xy 309.011021 -285.150148) (xy 309.058292 -285.16384) (xy 309.102754 -285.184938)
			(xy 309.143257 -285.212894) (xy 309.17875 -285.246986) (xy 309.208315 -285.28633) (xy 309.231186 -285.329907)
			(xy 309.24677 -285.376588) (xy 309.254665 -285.425165) (xy 309.25516 -285.449772) (xy 309.594008 -285.449772)
			(xy 309.597968 -285.400718) (xy 309.609745 -285.352934) (xy 309.629036 -285.307658) (xy 309.655339 -285.266062)
			(xy 309.687974 -285.229225) (xy 309.726095 -285.1981) (xy 309.768716 -285.173493) (xy 309.814732 -285.156041)
			(xy 309.862951 -285.146197) (xy 309.912126 -285.144216) (xy 309.960981 -285.150148) (xy 310.008252 -285.16384)
			(xy 310.052714 -285.184938) (xy 310.093217 -285.212894) (xy 310.12871 -285.246986) (xy 310.158275 -285.28633)
			(xy 310.181146 -285.329907) (xy 310.19673 -285.376588) (xy 310.204625 -285.425165) (xy 310.20512 -285.449772)
			(xy 310.543968 -285.449772) (xy 310.547928 -285.400718) (xy 310.559705 -285.352934) (xy 310.578996 -285.307658)
			(xy 310.605299 -285.266062) (xy 310.637934 -285.229225) (xy 310.676055 -285.1981) (xy 310.718676 -285.173493)
			(xy 310.764692 -285.156041) (xy 310.812911 -285.146197) (xy 310.862086 -285.144216) (xy 310.910941 -285.150148)
			(xy 310.958212 -285.16384) (xy 311.002674 -285.184938) (xy 311.043177 -285.212894) (xy 311.07867 -285.246986)
			(xy 311.108235 -285.28633) (xy 311.131106 -285.329907) (xy 311.14669 -285.376588) (xy 311.154585 -285.425165)
			(xy 311.15508 -285.449772) (xy 311.493928 -285.449772) (xy 311.497888 -285.400718) (xy 311.509665 -285.352934)
			(xy 311.528956 -285.307658) (xy 311.555259 -285.266062) (xy 311.587894 -285.229225) (xy 311.626015 -285.1981)
			(xy 311.668636 -285.173493) (xy 311.714652 -285.156041) (xy 311.762871 -285.146197) (xy 311.812046 -285.144216)
			(xy 311.860901 -285.150148) (xy 311.908172 -285.16384) (xy 311.952634 -285.184938) (xy 311.993137 -285.212894)
			(xy 312.02863 -285.246986) (xy 312.058195 -285.28633) (xy 312.081066 -285.329907) (xy 312.09665 -285.376588)
			(xy 312.104545 -285.425165) (xy 312.10504 -285.449772) (xy 312.443888 -285.449772) (xy 312.447848 -285.400718)
			(xy 312.459625 -285.352934) (xy 312.478916 -285.307658) (xy 312.505219 -285.266062) (xy 312.537854 -285.229225)
			(xy 312.575975 -285.1981) (xy 312.618596 -285.173493) (xy 312.664612 -285.156041) (xy 312.712831 -285.146197)
			(xy 312.762006 -285.144216) (xy 312.810861 -285.150148) (xy 312.858132 -285.16384) (xy 312.902594 -285.184938)
			(xy 312.943097 -285.212894) (xy 312.97859 -285.246986) (xy 313.008155 -285.28633) (xy 313.031026 -285.329907)
			(xy 313.04661 -285.376588) (xy 313.054505 -285.425165) (xy 313.055 -285.449772) (xy 313.054505 -285.474379)
			(xy 313.054326 -285.47548) (xy 313.373258 -285.47548) (xy 313.373258 -285.424064) (xy 313.381301 -285.373282)
			(xy 313.397189 -285.324383) (xy 313.420532 -285.278571) (xy 313.450753 -285.236975) (xy 313.487109 -285.200619)
			(xy 313.528705 -285.170398) (xy 313.574517 -285.147055) (xy 313.623416 -285.131167) (xy 313.674198 -285.123124)
			(xy 313.725614 -285.123124) (xy 313.776396 -285.131167) (xy 313.825295 -285.147055) (xy 313.871107 -285.170398)
			(xy 313.912703 -285.200619) (xy 313.949059 -285.236975) (xy 313.97928 -285.278571) (xy 314.002623 -285.324383)
			(xy 314.018511 -285.373282) (xy 314.026554 -285.424064) (xy 314.027058 -285.449772) (xy 314.026554 -285.47548)
			(xy 314.323218 -285.47548) (xy 314.323218 -285.424064) (xy 314.331261 -285.373282) (xy 314.347149 -285.324383)
			(xy 314.370492 -285.278571) (xy 314.400713 -285.236975) (xy 314.437069 -285.200619) (xy 314.478665 -285.170398)
			(xy 314.524477 -285.147055) (xy 314.573376 -285.131167) (xy 314.624158 -285.123124) (xy 314.675574 -285.123124)
			(xy 314.726356 -285.131167) (xy 314.775255 -285.147055) (xy 314.821067 -285.170398) (xy 314.862663 -285.200619)
			(xy 314.899019 -285.236975) (xy 314.92924 -285.278571) (xy 314.952583 -285.324383) (xy 314.968471 -285.373282)
			(xy 314.976514 -285.424064) (xy 314.977018 -285.449772) (xy 314.977013 -285.450026) (xy 315.294276 -285.450026)
			(xy 315.298236 -285.400972) (xy 315.310013 -285.353188) (xy 315.329304 -285.307912) (xy 315.355607 -285.266316)
			(xy 315.388242 -285.229479) (xy 315.426363 -285.198354) (xy 315.468984 -285.173747) (xy 315.515 -285.156295)
			(xy 315.563219 -285.146451) (xy 315.612394 -285.14447) (xy 315.661249 -285.150402) (xy 315.70852 -285.164094)
			(xy 315.752982 -285.185192) (xy 315.793485 -285.213148) (xy 315.828978 -285.24724) (xy 315.858543 -285.286584)
			(xy 315.881414 -285.330161) (xy 315.896998 -285.376842) (xy 315.904893 -285.425419) (xy 315.905388 -285.450026)
			(xy 315.904893 -285.474633) (xy 315.897788 -285.518352) (xy 323.668134 -285.518352) (xy 323.672205 -285.46273)
			(xy 323.684331 -285.408293) (xy 323.704254 -285.356202) (xy 323.73155 -285.307567) (xy 323.765636 -285.263424)
			(xy 323.805785 -285.224715) (xy 323.851143 -285.192264) (xy 323.900743 -285.166763) (xy 323.953527 -285.148756)
			(xy 324.00837 -285.138626) (xy 324.064104 -285.136589) (xy 324.119541 -285.142689) (xy 324.173498 -285.156795)
			(xy 324.224827 -285.178607) (xy 324.272433 -285.207661) (xy 324.315301 -285.243336) (xy 324.352518 -285.284873)
			(xy 324.383291 -285.331386) (xy 324.406963 -285.381883) (xy 324.423031 -285.43529) (xy 324.431151 -285.490466)
			(xy 324.43166 -285.518352) (xy 324.431151 -285.546238) (xy 324.423031 -285.601414) (xy 324.406963 -285.654821)
			(xy 324.383291 -285.705318) (xy 324.352518 -285.751831) (xy 324.315301 -285.793368) (xy 324.272433 -285.829043)
			(xy 324.224827 -285.858097) (xy 324.173498 -285.879909) (xy 324.119541 -285.894015) (xy 324.064104 -285.900115)
			(xy 324.00837 -285.898078) (xy 323.953527 -285.887948) (xy 323.900743 -285.869941) (xy 323.851143 -285.84444)
			(xy 323.805785 -285.811989) (xy 323.765636 -285.77328) (xy 323.73155 -285.729137) (xy 323.704254 -285.680502)
			(xy 323.684331 -285.628411) (xy 323.672205 -285.573974) (xy 323.668134 -285.518352) (xy 315.897788 -285.518352)
			(xy 315.896998 -285.52321) (xy 315.881414 -285.569891) (xy 315.858543 -285.613468) (xy 315.828978 -285.652812)
			(xy 315.793485 -285.686904) (xy 315.752982 -285.71486) (xy 315.70852 -285.735958) (xy 315.661249 -285.74965)
			(xy 315.612394 -285.755582) (xy 315.563219 -285.753601) (xy 315.515 -285.743757) (xy 315.468984 -285.726305)
			(xy 315.426363 -285.701698) (xy 315.388242 -285.670573) (xy 315.355607 -285.633736) (xy 315.329304 -285.59214)
			(xy 315.310013 -285.546864) (xy 315.298236 -285.49908) (xy 315.294276 -285.450026) (xy 314.977013 -285.450026)
			(xy 314.976514 -285.47548) (xy 314.968471 -285.526262) (xy 314.952583 -285.575161) (xy 314.92924 -285.620973)
			(xy 314.899019 -285.662569) (xy 314.862663 -285.698925) (xy 314.821067 -285.729146) (xy 314.775255 -285.752489)
			(xy 314.726356 -285.768377) (xy 314.675574 -285.77642) (xy 314.624158 -285.77642) (xy 314.573376 -285.768377)
			(xy 314.524477 -285.752489) (xy 314.478665 -285.729146) (xy 314.437069 -285.698925) (xy 314.400713 -285.662569)
			(xy 314.370492 -285.620973) (xy 314.347149 -285.575161) (xy 314.331261 -285.526262) (xy 314.323218 -285.47548)
			(xy 314.026554 -285.47548) (xy 314.018511 -285.526262) (xy 314.002623 -285.575161) (xy 313.97928 -285.620973)
			(xy 313.949059 -285.662569) (xy 313.912703 -285.698925) (xy 313.871107 -285.729146) (xy 313.825295 -285.752489)
			(xy 313.776396 -285.768377) (xy 313.725614 -285.77642) (xy 313.674198 -285.77642) (xy 313.623416 -285.768377)
			(xy 313.574517 -285.752489) (xy 313.528705 -285.729146) (xy 313.487109 -285.698925) (xy 313.450753 -285.662569)
			(xy 313.420532 -285.620973) (xy 313.397189 -285.575161) (xy 313.381301 -285.526262) (xy 313.373258 -285.47548)
			(xy 313.054326 -285.47548) (xy 313.04661 -285.522956) (xy 313.031026 -285.569637) (xy 313.008155 -285.613214)
			(xy 312.97859 -285.652558) (xy 312.943097 -285.68665) (xy 312.902594 -285.714606) (xy 312.858132 -285.735704)
			(xy 312.810861 -285.749396) (xy 312.762006 -285.755328) (xy 312.712831 -285.753347) (xy 312.664612 -285.743503)
			(xy 312.618596 -285.726051) (xy 312.575975 -285.701444) (xy 312.537854 -285.670319) (xy 312.505219 -285.633482)
			(xy 312.478916 -285.591886) (xy 312.459625 -285.54661) (xy 312.447848 -285.498826) (xy 312.443888 -285.449772)
			(xy 312.10504 -285.449772) (xy 312.104545 -285.474379) (xy 312.09665 -285.522956) (xy 312.081066 -285.569637)
			(xy 312.058195 -285.613214) (xy 312.02863 -285.652558) (xy 311.993137 -285.68665) (xy 311.952634 -285.714606)
			(xy 311.908172 -285.735704) (xy 311.860901 -285.749396) (xy 311.812046 -285.755328) (xy 311.762871 -285.753347)
			(xy 311.714652 -285.743503) (xy 311.668636 -285.726051) (xy 311.626015 -285.701444) (xy 311.587894 -285.670319)
			(xy 311.555259 -285.633482) (xy 311.528956 -285.591886) (xy 311.509665 -285.54661) (xy 311.497888 -285.498826)
			(xy 311.493928 -285.449772) (xy 311.15508 -285.449772) (xy 311.154585 -285.474379) (xy 311.14669 -285.522956)
			(xy 311.131106 -285.569637) (xy 311.108235 -285.613214) (xy 311.07867 -285.652558) (xy 311.043177 -285.68665)
			(xy 311.002674 -285.714606) (xy 310.958212 -285.735704) (xy 310.910941 -285.749396) (xy 310.862086 -285.755328)
			(xy 310.812911 -285.753347) (xy 310.764692 -285.743503) (xy 310.718676 -285.726051) (xy 310.676055 -285.701444)
			(xy 310.637934 -285.670319) (xy 310.605299 -285.633482) (xy 310.578996 -285.591886) (xy 310.559705 -285.54661)
			(xy 310.547928 -285.498826) (xy 310.543968 -285.449772) (xy 310.20512 -285.449772) (xy 310.204625 -285.474379)
			(xy 310.19673 -285.522956) (xy 310.181146 -285.569637) (xy 310.158275 -285.613214) (xy 310.12871 -285.652558)
			(xy 310.093217 -285.68665) (xy 310.052714 -285.714606) (xy 310.008252 -285.735704) (xy 309.960981 -285.749396)
			(xy 309.912126 -285.755328) (xy 309.862951 -285.753347) (xy 309.814732 -285.743503) (xy 309.768716 -285.726051)
			(xy 309.726095 -285.701444) (xy 309.687974 -285.670319) (xy 309.655339 -285.633482) (xy 309.629036 -285.591886)
			(xy 309.609745 -285.54661) (xy 309.597968 -285.498826) (xy 309.594008 -285.449772) (xy 309.25516 -285.449772)
			(xy 309.254665 -285.474379) (xy 309.24677 -285.522956) (xy 309.231186 -285.569637) (xy 309.208315 -285.613214)
			(xy 309.17875 -285.652558) (xy 309.143257 -285.68665) (xy 309.102754 -285.714606) (xy 309.058292 -285.735704)
			(xy 309.011021 -285.749396) (xy 308.962166 -285.755328) (xy 308.912991 -285.753347) (xy 308.864772 -285.743503)
			(xy 308.818756 -285.726051) (xy 308.776135 -285.701444) (xy 308.738014 -285.670319) (xy 308.705379 -285.633482)
			(xy 308.679076 -285.591886) (xy 308.659785 -285.54661) (xy 308.648008 -285.498826) (xy 308.644048 -285.449772)
			(xy 308.3052 -285.449772) (xy 308.304705 -285.474379) (xy 308.29681 -285.522956) (xy 308.281226 -285.569637)
			(xy 308.258355 -285.613214) (xy 308.22879 -285.652558) (xy 308.193297 -285.68665) (xy 308.152794 -285.714606)
			(xy 308.108332 -285.735704) (xy 308.061061 -285.749396) (xy 308.012206 -285.755328) (xy 307.963031 -285.753347)
			(xy 307.914812 -285.743503) (xy 307.868796 -285.726051) (xy 307.826175 -285.701444) (xy 307.788054 -285.670319)
			(xy 307.755419 -285.633482) (xy 307.729116 -285.591886) (xy 307.709825 -285.54661) (xy 307.698048 -285.498826)
			(xy 307.694088 -285.449772) (xy 307.354986 -285.449772) (xy 307.354491 -285.474379) (xy 307.346596 -285.522956)
			(xy 307.331012 -285.569637) (xy 307.308141 -285.613214) (xy 307.278576 -285.652558) (xy 307.243083 -285.68665)
			(xy 307.20258 -285.714606) (xy 307.158118 -285.735704) (xy 307.110847 -285.749396) (xy 307.061992 -285.755328)
			(xy 307.012817 -285.753347) (xy 306.964598 -285.743503) (xy 306.918582 -285.726051) (xy 306.875961 -285.701444)
			(xy 306.83784 -285.670319) (xy 306.805205 -285.633482) (xy 306.778902 -285.591886) (xy 306.759611 -285.54661)
			(xy 306.747834 -285.498826) (xy 306.743874 -285.449772) (xy 306.405026 -285.449772) (xy 306.404531 -285.474379)
			(xy 306.396636 -285.522956) (xy 306.381052 -285.569637) (xy 306.358181 -285.613214) (xy 306.328616 -285.652558)
			(xy 306.293123 -285.68665) (xy 306.25262 -285.714606) (xy 306.208158 -285.735704) (xy 306.160887 -285.749396)
			(xy 306.112032 -285.755328) (xy 306.062857 -285.753347) (xy 306.014638 -285.743503) (xy 305.968622 -285.726051)
			(xy 305.926001 -285.701444) (xy 305.88788 -285.670319) (xy 305.855245 -285.633482) (xy 305.828942 -285.591886)
			(xy 305.809651 -285.54661) (xy 305.797874 -285.498826) (xy 305.793914 -285.449772) (xy 280.268426 -285.449772)
			(xy 280.268426 -285.83001) (xy 280.268934 -285.836106) (xy 280.270204 -285.847282) (xy 280.270966 -285.850584)
			(xy 280.270966 -285.851092) (xy 280.27522 -285.86921) (xy 280.27981 -285.906144) (xy 280.28011 -285.924752)
			(xy 280.618958 -285.924752) (xy 280.622918 -285.875698) (xy 280.634695 -285.827914) (xy 280.653986 -285.782638)
			(xy 280.680289 -285.741042) (xy 280.712924 -285.704205) (xy 280.751045 -285.67308) (xy 280.793666 -285.648473)
			(xy 280.839682 -285.631021) (xy 280.887901 -285.621177) (xy 280.937076 -285.619196) (xy 280.985931 -285.625128)
			(xy 281.033202 -285.63882) (xy 281.077664 -285.659918) (xy 281.118167 -285.687874) (xy 281.15366 -285.721966)
			(xy 281.183225 -285.76131) (xy 281.206096 -285.804887) (xy 281.22168 -285.851568) (xy 281.229575 -285.900145)
			(xy 281.23007 -285.924752) (xy 281.568918 -285.924752) (xy 281.572878 -285.875698) (xy 281.584655 -285.827914)
			(xy 281.603946 -285.782638) (xy 281.630249 -285.741042) (xy 281.662884 -285.704205) (xy 281.701005 -285.67308)
			(xy 281.743626 -285.648473) (xy 281.789642 -285.631021) (xy 281.837861 -285.621177) (xy 281.887036 -285.619196)
			(xy 281.935891 -285.625128) (xy 281.983162 -285.63882) (xy 282.027624 -285.659918) (xy 282.068127 -285.687874)
			(xy 282.10362 -285.721966) (xy 282.133185 -285.76131) (xy 282.156056 -285.804887) (xy 282.17164 -285.851568)
			(xy 282.179535 -285.900145) (xy 282.18003 -285.924752) (xy 282.519132 -285.924752) (xy 282.523092 -285.875698)
			(xy 282.534869 -285.827914) (xy 282.55416 -285.782638) (xy 282.580463 -285.741042) (xy 282.613098 -285.704205)
			(xy 282.651219 -285.67308) (xy 282.69384 -285.648473) (xy 282.739856 -285.631021) (xy 282.788075 -285.621177)
			(xy 282.83725 -285.619196) (xy 282.886105 -285.625128) (xy 282.933376 -285.63882) (xy 282.977838 -285.659918)
			(xy 283.018341 -285.687874) (xy 283.053834 -285.721966) (xy 283.083399 -285.76131) (xy 283.10627 -285.804887)
			(xy 283.121854 -285.851568) (xy 283.129749 -285.900145) (xy 283.130244 -285.924752) (xy 283.469092 -285.924752)
			(xy 283.473052 -285.875698) (xy 283.484829 -285.827914) (xy 283.50412 -285.782638) (xy 283.530423 -285.741042)
			(xy 283.563058 -285.704205) (xy 283.601179 -285.67308) (xy 283.6438 -285.648473) (xy 283.689816 -285.631021)
			(xy 283.738035 -285.621177) (xy 283.78721 -285.619196) (xy 283.836065 -285.625128) (xy 283.883336 -285.63882)
			(xy 283.927798 -285.659918) (xy 283.968301 -285.687874) (xy 284.003794 -285.721966) (xy 284.033359 -285.76131)
			(xy 284.05623 -285.804887) (xy 284.071814 -285.851568) (xy 284.079709 -285.900145) (xy 284.080204 -285.924752)
			(xy 284.419052 -285.924752) (xy 284.423012 -285.875698) (xy 284.434789 -285.827914) (xy 284.45408 -285.782638)
			(xy 284.480383 -285.741042) (xy 284.513018 -285.704205) (xy 284.551139 -285.67308) (xy 284.59376 -285.648473)
			(xy 284.639776 -285.631021) (xy 284.687995 -285.621177) (xy 284.73717 -285.619196) (xy 284.786025 -285.625128)
			(xy 284.833296 -285.63882) (xy 284.877758 -285.659918) (xy 284.918261 -285.687874) (xy 284.953754 -285.721966)
			(xy 284.983319 -285.76131) (xy 285.00619 -285.804887) (xy 285.021774 -285.851568) (xy 285.029669 -285.900145)
			(xy 285.030164 -285.924752) (xy 285.369012 -285.924752) (xy 285.372972 -285.875698) (xy 285.384749 -285.827914)
			(xy 285.40404 -285.782638) (xy 285.430343 -285.741042) (xy 285.462978 -285.704205) (xy 285.501099 -285.67308)
			(xy 285.54372 -285.648473) (xy 285.589736 -285.631021) (xy 285.637955 -285.621177) (xy 285.68713 -285.619196)
			(xy 285.735985 -285.625128) (xy 285.783256 -285.63882) (xy 285.827718 -285.659918) (xy 285.868221 -285.687874)
			(xy 285.903714 -285.721966) (xy 285.933279 -285.76131) (xy 285.95615 -285.804887) (xy 285.971734 -285.851568)
			(xy 285.979629 -285.900145) (xy 285.980124 -285.924752) (xy 286.318972 -285.924752) (xy 286.322932 -285.875698)
			(xy 286.334709 -285.827914) (xy 286.354 -285.782638) (xy 286.380303 -285.741042) (xy 286.412938 -285.704205)
			(xy 286.451059 -285.67308) (xy 286.49368 -285.648473) (xy 286.539696 -285.631021) (xy 286.587915 -285.621177)
			(xy 286.63709 -285.619196) (xy 286.685945 -285.625128) (xy 286.733216 -285.63882) (xy 286.777678 -285.659918)
			(xy 286.818181 -285.687874) (xy 286.853674 -285.721966) (xy 286.883239 -285.76131) (xy 286.90611 -285.804887)
			(xy 286.921694 -285.851568) (xy 286.929589 -285.900145) (xy 286.930084 -285.924752) (xy 287.268932 -285.924752)
			(xy 287.272892 -285.875698) (xy 287.284669 -285.827914) (xy 287.30396 -285.782638) (xy 287.330263 -285.741042)
			(xy 287.362898 -285.704205) (xy 287.401019 -285.67308) (xy 287.44364 -285.648473) (xy 287.489656 -285.631021)
			(xy 287.537875 -285.621177) (xy 287.58705 -285.619196) (xy 287.635905 -285.625128) (xy 287.683176 -285.63882)
			(xy 287.727638 -285.659918) (xy 287.768141 -285.687874) (xy 287.803634 -285.721966) (xy 287.833199 -285.76131)
			(xy 287.85607 -285.804887) (xy 287.871654 -285.851568) (xy 287.879549 -285.900145) (xy 287.880044 -285.924752)
			(xy 288.218892 -285.924752) (xy 288.222852 -285.875698) (xy 288.234629 -285.827914) (xy 288.25392 -285.782638)
			(xy 288.280223 -285.741042) (xy 288.312858 -285.704205) (xy 288.350979 -285.67308) (xy 288.3936 -285.648473)
			(xy 288.439616 -285.631021) (xy 288.487835 -285.621177) (xy 288.53701 -285.619196) (xy 288.585865 -285.625128)
			(xy 288.633136 -285.63882) (xy 288.677598 -285.659918) (xy 288.718101 -285.687874) (xy 288.753594 -285.721966)
			(xy 288.783159 -285.76131) (xy 288.80603 -285.804887) (xy 288.821614 -285.851568) (xy 288.829509 -285.900145)
			(xy 288.830004 -285.924752) (xy 289.169106 -285.924752) (xy 289.173066 -285.875698) (xy 289.184843 -285.827914)
			(xy 289.204134 -285.782638) (xy 289.230437 -285.741042) (xy 289.263072 -285.704205) (xy 289.301193 -285.67308)
			(xy 289.343814 -285.648473) (xy 289.38983 -285.631021) (xy 289.438049 -285.621177) (xy 289.487224 -285.619196)
			(xy 289.536079 -285.625128) (xy 289.58335 -285.63882) (xy 289.627812 -285.659918) (xy 289.668315 -285.687874)
			(xy 289.703808 -285.721966) (xy 289.733373 -285.76131) (xy 289.756244 -285.804887) (xy 289.771828 -285.851568)
			(xy 289.779723 -285.900145) (xy 289.780218 -285.924752) (xy 290.119066 -285.924752) (xy 290.123026 -285.875698)
			(xy 290.134803 -285.827914) (xy 290.154094 -285.782638) (xy 290.180397 -285.741042) (xy 290.213032 -285.704205)
			(xy 290.251153 -285.67308) (xy 290.293774 -285.648473) (xy 290.33979 -285.631021) (xy 290.388009 -285.621177)
			(xy 290.437184 -285.619196) (xy 290.486039 -285.625128) (xy 290.53331 -285.63882) (xy 290.577772 -285.659918)
			(xy 290.618275 -285.687874) (xy 290.653768 -285.721966) (xy 290.683333 -285.76131) (xy 290.706204 -285.804887)
			(xy 290.721788 -285.851568) (xy 290.729683 -285.900145) (xy 290.730178 -285.924752) (xy 292.018986 -285.924752)
			(xy 292.022946 -285.875698) (xy 292.034723 -285.827914) (xy 292.054014 -285.782638) (xy 292.080317 -285.741042)
			(xy 292.112952 -285.704205) (xy 292.151073 -285.67308) (xy 292.193694 -285.648473) (xy 292.23971 -285.631021)
			(xy 292.287929 -285.621177) (xy 292.337104 -285.619196) (xy 292.385959 -285.625128) (xy 292.43323 -285.63882)
			(xy 292.477692 -285.659918) (xy 292.518195 -285.687874) (xy 292.553688 -285.721966) (xy 292.583253 -285.76131)
			(xy 292.606124 -285.804887) (xy 292.621708 -285.851568) (xy 292.629603 -285.900145) (xy 292.630098 -285.924752)
			(xy 292.968946 -285.924752) (xy 292.972906 -285.875698) (xy 292.984683 -285.827914) (xy 293.003974 -285.782638)
			(xy 293.030277 -285.741042) (xy 293.062912 -285.704205) (xy 293.101033 -285.67308) (xy 293.143654 -285.648473)
			(xy 293.18967 -285.631021) (xy 293.237889 -285.621177) (xy 293.287064 -285.619196) (xy 293.335919 -285.625128)
			(xy 293.38319 -285.63882) (xy 293.427652 -285.659918) (xy 293.468155 -285.687874) (xy 293.503648 -285.721966)
			(xy 293.533213 -285.76131) (xy 293.556084 -285.804887) (xy 293.571668 -285.851568) (xy 293.579563 -285.900145)
			(xy 293.580058 -285.924752) (xy 293.918906 -285.924752) (xy 293.922866 -285.875698) (xy 293.934643 -285.827914)
			(xy 293.953934 -285.782638) (xy 293.980237 -285.741042) (xy 294.012872 -285.704205) (xy 294.050993 -285.67308)
			(xy 294.093614 -285.648473) (xy 294.13963 -285.631021) (xy 294.187849 -285.621177) (xy 294.237024 -285.619196)
			(xy 294.285879 -285.625128) (xy 294.33315 -285.63882) (xy 294.377612 -285.659918) (xy 294.418115 -285.687874)
			(xy 294.453608 -285.721966) (xy 294.483173 -285.76131) (xy 294.506044 -285.804887) (xy 294.521628 -285.851568)
			(xy 294.529523 -285.900145) (xy 294.530018 -285.924752) (xy 294.86912 -285.924752) (xy 294.87308 -285.875698)
			(xy 294.884857 -285.827914) (xy 294.904148 -285.782638) (xy 294.930451 -285.741042) (xy 294.963086 -285.704205)
			(xy 295.001207 -285.67308) (xy 295.043828 -285.648473) (xy 295.089844 -285.631021) (xy 295.138063 -285.621177)
			(xy 295.187238 -285.619196) (xy 295.236093 -285.625128) (xy 295.283364 -285.63882) (xy 295.327826 -285.659918)
			(xy 295.368329 -285.687874) (xy 295.403822 -285.721966) (xy 295.433387 -285.76131) (xy 295.456258 -285.804887)
			(xy 295.471842 -285.851568) (xy 295.479737 -285.900145) (xy 295.480232 -285.924752) (xy 295.81908 -285.924752)
			(xy 295.82304 -285.875698) (xy 295.834817 -285.827914) (xy 295.854108 -285.782638) (xy 295.880411 -285.741042)
			(xy 295.913046 -285.704205) (xy 295.951167 -285.67308) (xy 295.993788 -285.648473) (xy 296.039804 -285.631021)
			(xy 296.088023 -285.621177) (xy 296.137198 -285.619196) (xy 296.186053 -285.625128) (xy 296.233324 -285.63882)
			(xy 296.277786 -285.659918) (xy 296.318289 -285.687874) (xy 296.353782 -285.721966) (xy 296.383347 -285.76131)
			(xy 296.406218 -285.804887) (xy 296.421802 -285.851568) (xy 296.429697 -285.900145) (xy 296.430192 -285.924752)
			(xy 296.76904 -285.924752) (xy 296.773 -285.875698) (xy 296.784777 -285.827914) (xy 296.804068 -285.782638)
			(xy 296.830371 -285.741042) (xy 296.863006 -285.704205) (xy 296.901127 -285.67308) (xy 296.943748 -285.648473)
			(xy 296.989764 -285.631021) (xy 297.037983 -285.621177) (xy 297.087158 -285.619196) (xy 297.136013 -285.625128)
			(xy 297.183284 -285.63882) (xy 297.227746 -285.659918) (xy 297.268249 -285.687874) (xy 297.303742 -285.721966)
			(xy 297.333307 -285.76131) (xy 297.356178 -285.804887) (xy 297.371762 -285.851568) (xy 297.379657 -285.900145)
			(xy 297.380152 -285.924752) (xy 297.719 -285.924752) (xy 297.72296 -285.875698) (xy 297.734737 -285.827914)
			(xy 297.754028 -285.782638) (xy 297.780331 -285.741042) (xy 297.812966 -285.704205) (xy 297.851087 -285.67308)
			(xy 297.893708 -285.648473) (xy 297.939724 -285.631021) (xy 297.987943 -285.621177) (xy 298.037118 -285.619196)
			(xy 298.085973 -285.625128) (xy 298.133244 -285.63882) (xy 298.177706 -285.659918) (xy 298.218209 -285.687874)
			(xy 298.253702 -285.721966) (xy 298.283267 -285.76131) (xy 298.306138 -285.804887) (xy 298.321722 -285.851568)
			(xy 298.329617 -285.900145) (xy 298.330112 -285.924752) (xy 298.66896 -285.924752) (xy 298.67292 -285.875698)
			(xy 298.684697 -285.827914) (xy 298.703988 -285.782638) (xy 298.730291 -285.741042) (xy 298.762926 -285.704205)
			(xy 298.801047 -285.67308) (xy 298.843668 -285.648473) (xy 298.889684 -285.631021) (xy 298.937903 -285.621177)
			(xy 298.987078 -285.619196) (xy 299.035933 -285.625128) (xy 299.083204 -285.63882) (xy 299.127666 -285.659918)
			(xy 299.168169 -285.687874) (xy 299.203662 -285.721966) (xy 299.233227 -285.76131) (xy 299.256098 -285.804887)
			(xy 299.271682 -285.851568) (xy 299.279577 -285.900145) (xy 299.280072 -285.924752) (xy 299.61892 -285.924752)
			(xy 299.62288 -285.875698) (xy 299.634657 -285.827914) (xy 299.653948 -285.782638) (xy 299.680251 -285.741042)
			(xy 299.712886 -285.704205) (xy 299.751007 -285.67308) (xy 299.793628 -285.648473) (xy 299.839644 -285.631021)
			(xy 299.887863 -285.621177) (xy 299.937038 -285.619196) (xy 299.985893 -285.625128) (xy 300.033164 -285.63882)
			(xy 300.077626 -285.659918) (xy 300.118129 -285.687874) (xy 300.153622 -285.721966) (xy 300.183187 -285.76131)
			(xy 300.206058 -285.804887) (xy 300.221642 -285.851568) (xy 300.229537 -285.900145) (xy 300.230032 -285.924752)
			(xy 300.56888 -285.924752) (xy 300.57284 -285.875698) (xy 300.584617 -285.827914) (xy 300.603908 -285.782638)
			(xy 300.630211 -285.741042) (xy 300.662846 -285.704205) (xy 300.700967 -285.67308) (xy 300.743588 -285.648473)
			(xy 300.789604 -285.631021) (xy 300.837823 -285.621177) (xy 300.886998 -285.619196) (xy 300.935853 -285.625128)
			(xy 300.983124 -285.63882) (xy 301.027586 -285.659918) (xy 301.068089 -285.687874) (xy 301.103582 -285.721966)
			(xy 301.133147 -285.76131) (xy 301.156018 -285.804887) (xy 301.171602 -285.851568) (xy 301.179497 -285.900145)
			(xy 301.179992 -285.924752) (xy 301.519094 -285.924752) (xy 301.523054 -285.875698) (xy 301.534831 -285.827914)
			(xy 301.554122 -285.782638) (xy 301.580425 -285.741042) (xy 301.61306 -285.704205) (xy 301.651181 -285.67308)
			(xy 301.693802 -285.648473) (xy 301.739818 -285.631021) (xy 301.788037 -285.621177) (xy 301.837212 -285.619196)
			(xy 301.886067 -285.625128) (xy 301.933338 -285.63882) (xy 301.9778 -285.659918) (xy 302.018303 -285.687874)
			(xy 302.053796 -285.721966) (xy 302.083361 -285.76131) (xy 302.106232 -285.804887) (xy 302.121816 -285.851568)
			(xy 302.129711 -285.900145) (xy 302.130206 -285.924752) (xy 302.469054 -285.924752) (xy 302.473014 -285.875698)
			(xy 302.484791 -285.827914) (xy 302.504082 -285.782638) (xy 302.530385 -285.741042) (xy 302.56302 -285.704205)
			(xy 302.601141 -285.67308) (xy 302.643762 -285.648473) (xy 302.689778 -285.631021) (xy 302.737997 -285.621177)
			(xy 302.787172 -285.619196) (xy 302.836027 -285.625128) (xy 302.883298 -285.63882) (xy 302.92776 -285.659918)
			(xy 302.968263 -285.687874) (xy 303.003756 -285.721966) (xy 303.033321 -285.76131) (xy 303.056192 -285.804887)
			(xy 303.071776 -285.851568) (xy 303.079671 -285.900145) (xy 303.080166 -285.924752) (xy 303.079671 -285.949359)
			(xy 303.071776 -285.997936) (xy 303.056192 -286.044617) (xy 303.033321 -286.088194) (xy 303.003756 -286.127538)
			(xy 302.968263 -286.16163) (xy 302.92776 -286.189586) (xy 302.883298 -286.210684) (xy 302.836027 -286.224376)
			(xy 302.787172 -286.230308) (xy 302.737997 -286.228327) (xy 302.689778 -286.218483) (xy 302.643762 -286.201031)
			(xy 302.601141 -286.176424) (xy 302.56302 -286.145299) (xy 302.530385 -286.108462) (xy 302.504082 -286.066866)
			(xy 302.484791 -286.02159) (xy 302.473014 -285.973806) (xy 302.469054 -285.924752) (xy 302.130206 -285.924752)
			(xy 302.129711 -285.949359) (xy 302.121816 -285.997936) (xy 302.106232 -286.044617) (xy 302.083361 -286.088194)
			(xy 302.053796 -286.127538) (xy 302.018303 -286.16163) (xy 301.9778 -286.189586) (xy 301.933338 -286.210684)
			(xy 301.886067 -286.224376) (xy 301.837212 -286.230308) (xy 301.788037 -286.228327) (xy 301.739818 -286.218483)
			(xy 301.693802 -286.201031) (xy 301.651181 -286.176424) (xy 301.61306 -286.145299) (xy 301.580425 -286.108462)
			(xy 301.554122 -286.066866) (xy 301.534831 -286.02159) (xy 301.523054 -285.973806) (xy 301.519094 -285.924752)
			(xy 301.179992 -285.924752) (xy 301.179497 -285.949359) (xy 301.171602 -285.997936) (xy 301.156018 -286.044617)
			(xy 301.133147 -286.088194) (xy 301.103582 -286.127538) (xy 301.068089 -286.16163) (xy 301.027586 -286.189586)
			(xy 300.983124 -286.210684) (xy 300.935853 -286.224376) (xy 300.886998 -286.230308) (xy 300.837823 -286.228327)
			(xy 300.789604 -286.218483) (xy 300.743588 -286.201031) (xy 300.700967 -286.176424) (xy 300.662846 -286.145299)
			(xy 300.630211 -286.108462) (xy 300.603908 -286.066866) (xy 300.584617 -286.02159) (xy 300.57284 -285.973806)
			(xy 300.56888 -285.924752) (xy 300.230032 -285.924752) (xy 300.229537 -285.949359) (xy 300.221642 -285.997936)
			(xy 300.206058 -286.044617) (xy 300.183187 -286.088194) (xy 300.153622 -286.127538) (xy 300.118129 -286.16163)
			(xy 300.077626 -286.189586) (xy 300.033164 -286.210684) (xy 299.985893 -286.224376) (xy 299.937038 -286.230308)
			(xy 299.887863 -286.228327) (xy 299.839644 -286.218483) (xy 299.793628 -286.201031) (xy 299.751007 -286.176424)
			(xy 299.712886 -286.145299) (xy 299.680251 -286.108462) (xy 299.653948 -286.066866) (xy 299.634657 -286.02159)
			(xy 299.62288 -285.973806) (xy 299.61892 -285.924752) (xy 299.280072 -285.924752) (xy 299.279577 -285.949359)
			(xy 299.271682 -285.997936) (xy 299.256098 -286.044617) (xy 299.233227 -286.088194) (xy 299.203662 -286.127538)
			(xy 299.168169 -286.16163) (xy 299.127666 -286.189586) (xy 299.083204 -286.210684) (xy 299.035933 -286.224376)
			(xy 298.987078 -286.230308) (xy 298.937903 -286.228327) (xy 298.889684 -286.218483) (xy 298.843668 -286.201031)
			(xy 298.801047 -286.176424) (xy 298.762926 -286.145299) (xy 298.730291 -286.108462) (xy 298.703988 -286.066866)
			(xy 298.684697 -286.02159) (xy 298.67292 -285.973806) (xy 298.66896 -285.924752) (xy 298.330112 -285.924752)
			(xy 298.329617 -285.949359) (xy 298.321722 -285.997936) (xy 298.306138 -286.044617) (xy 298.283267 -286.088194)
			(xy 298.253702 -286.127538) (xy 298.218209 -286.16163) (xy 298.177706 -286.189586) (xy 298.133244 -286.210684)
			(xy 298.085973 -286.224376) (xy 298.037118 -286.230308) (xy 297.987943 -286.228327) (xy 297.939724 -286.218483)
			(xy 297.893708 -286.201031) (xy 297.851087 -286.176424) (xy 297.812966 -286.145299) (xy 297.780331 -286.108462)
			(xy 297.754028 -286.066866) (xy 297.734737 -286.02159) (xy 297.72296 -285.973806) (xy 297.719 -285.924752)
			(xy 297.380152 -285.924752) (xy 297.379657 -285.949359) (xy 297.371762 -285.997936) (xy 297.356178 -286.044617)
			(xy 297.333307 -286.088194) (xy 297.303742 -286.127538) (xy 297.268249 -286.16163) (xy 297.227746 -286.189586)
			(xy 297.183284 -286.210684) (xy 297.136013 -286.224376) (xy 297.087158 -286.230308) (xy 297.037983 -286.228327)
			(xy 296.989764 -286.218483) (xy 296.943748 -286.201031) (xy 296.901127 -286.176424) (xy 296.863006 -286.145299)
			(xy 296.830371 -286.108462) (xy 296.804068 -286.066866) (xy 296.784777 -286.02159) (xy 296.773 -285.973806)
			(xy 296.76904 -285.924752) (xy 296.430192 -285.924752) (xy 296.429697 -285.949359) (xy 296.421802 -285.997936)
			(xy 296.406218 -286.044617) (xy 296.383347 -286.088194) (xy 296.353782 -286.127538) (xy 296.318289 -286.16163)
			(xy 296.277786 -286.189586) (xy 296.233324 -286.210684) (xy 296.186053 -286.224376) (xy 296.137198 -286.230308)
			(xy 296.088023 -286.228327) (xy 296.039804 -286.218483) (xy 295.993788 -286.201031) (xy 295.951167 -286.176424)
			(xy 295.913046 -286.145299) (xy 295.880411 -286.108462) (xy 295.854108 -286.066866) (xy 295.834817 -286.02159)
			(xy 295.82304 -285.973806) (xy 295.81908 -285.924752) (xy 295.480232 -285.924752) (xy 295.479737 -285.949359)
			(xy 295.471842 -285.997936) (xy 295.456258 -286.044617) (xy 295.433387 -286.088194) (xy 295.403822 -286.127538)
			(xy 295.368329 -286.16163) (xy 295.327826 -286.189586) (xy 295.283364 -286.210684) (xy 295.236093 -286.224376)
			(xy 295.187238 -286.230308) (xy 295.138063 -286.228327) (xy 295.089844 -286.218483) (xy 295.043828 -286.201031)
			(xy 295.001207 -286.176424) (xy 294.963086 -286.145299) (xy 294.930451 -286.108462) (xy 294.904148 -286.066866)
			(xy 294.884857 -286.02159) (xy 294.87308 -285.973806) (xy 294.86912 -285.924752) (xy 294.530018 -285.924752)
			(xy 294.529523 -285.949359) (xy 294.521628 -285.997936) (xy 294.506044 -286.044617) (xy 294.483173 -286.088194)
			(xy 294.453608 -286.127538) (xy 294.418115 -286.16163) (xy 294.377612 -286.189586) (xy 294.33315 -286.210684)
			(xy 294.285879 -286.224376) (xy 294.237024 -286.230308) (xy 294.187849 -286.228327) (xy 294.13963 -286.218483)
			(xy 294.093614 -286.201031) (xy 294.050993 -286.176424) (xy 294.012872 -286.145299) (xy 293.980237 -286.108462)
			(xy 293.953934 -286.066866) (xy 293.934643 -286.02159) (xy 293.922866 -285.973806) (xy 293.918906 -285.924752)
			(xy 293.580058 -285.924752) (xy 293.579563 -285.949359) (xy 293.571668 -285.997936) (xy 293.556084 -286.044617)
			(xy 293.533213 -286.088194) (xy 293.503648 -286.127538) (xy 293.468155 -286.16163) (xy 293.427652 -286.189586)
			(xy 293.38319 -286.210684) (xy 293.335919 -286.224376) (xy 293.287064 -286.230308) (xy 293.237889 -286.228327)
			(xy 293.18967 -286.218483) (xy 293.143654 -286.201031) (xy 293.101033 -286.176424) (xy 293.062912 -286.145299)
			(xy 293.030277 -286.108462) (xy 293.003974 -286.066866) (xy 292.984683 -286.02159) (xy 292.972906 -285.973806)
			(xy 292.968946 -285.924752) (xy 292.630098 -285.924752) (xy 292.629603 -285.949359) (xy 292.621708 -285.997936)
			(xy 292.606124 -286.044617) (xy 292.583253 -286.088194) (xy 292.553688 -286.127538) (xy 292.518195 -286.16163)
			(xy 292.477692 -286.189586) (xy 292.43323 -286.210684) (xy 292.385959 -286.224376) (xy 292.337104 -286.230308)
			(xy 292.287929 -286.228327) (xy 292.23971 -286.218483) (xy 292.193694 -286.201031) (xy 292.151073 -286.176424)
			(xy 292.112952 -286.145299) (xy 292.080317 -286.108462) (xy 292.054014 -286.066866) (xy 292.034723 -286.02159)
			(xy 292.022946 -285.973806) (xy 292.018986 -285.924752) (xy 290.730178 -285.924752) (xy 290.729683 -285.949359)
			(xy 290.721788 -285.997936) (xy 290.706204 -286.044617) (xy 290.683333 -286.088194) (xy 290.653768 -286.127538)
			(xy 290.618275 -286.16163) (xy 290.577772 -286.189586) (xy 290.53331 -286.210684) (xy 290.486039 -286.224376)
			(xy 290.437184 -286.230308) (xy 290.388009 -286.228327) (xy 290.33979 -286.218483) (xy 290.293774 -286.201031)
			(xy 290.251153 -286.176424) (xy 290.213032 -286.145299) (xy 290.180397 -286.108462) (xy 290.154094 -286.066866)
			(xy 290.134803 -286.02159) (xy 290.123026 -285.973806) (xy 290.119066 -285.924752) (xy 289.780218 -285.924752)
			(xy 289.779723 -285.949359) (xy 289.771828 -285.997936) (xy 289.756244 -286.044617) (xy 289.733373 -286.088194)
			(xy 289.703808 -286.127538) (xy 289.668315 -286.16163) (xy 289.627812 -286.189586) (xy 289.58335 -286.210684)
			(xy 289.536079 -286.224376) (xy 289.487224 -286.230308) (xy 289.438049 -286.228327) (xy 289.38983 -286.218483)
			(xy 289.343814 -286.201031) (xy 289.301193 -286.176424) (xy 289.263072 -286.145299) (xy 289.230437 -286.108462)
			(xy 289.204134 -286.066866) (xy 289.184843 -286.02159) (xy 289.173066 -285.973806) (xy 289.169106 -285.924752)
			(xy 288.830004 -285.924752) (xy 288.829509 -285.949359) (xy 288.821614 -285.997936) (xy 288.80603 -286.044617)
			(xy 288.783159 -286.088194) (xy 288.753594 -286.127538) (xy 288.718101 -286.16163) (xy 288.677598 -286.189586)
			(xy 288.633136 -286.210684) (xy 288.585865 -286.224376) (xy 288.53701 -286.230308) (xy 288.487835 -286.228327)
			(xy 288.439616 -286.218483) (xy 288.3936 -286.201031) (xy 288.350979 -286.176424) (xy 288.312858 -286.145299)
			(xy 288.280223 -286.108462) (xy 288.25392 -286.066866) (xy 288.234629 -286.02159) (xy 288.222852 -285.973806)
			(xy 288.218892 -285.924752) (xy 287.880044 -285.924752) (xy 287.879549 -285.949359) (xy 287.871654 -285.997936)
			(xy 287.85607 -286.044617) (xy 287.833199 -286.088194) (xy 287.803634 -286.127538) (xy 287.768141 -286.16163)
			(xy 287.727638 -286.189586) (xy 287.683176 -286.210684) (xy 287.635905 -286.224376) (xy 287.58705 -286.230308)
			(xy 287.537875 -286.228327) (xy 287.489656 -286.218483) (xy 287.44364 -286.201031) (xy 287.401019 -286.176424)
			(xy 287.362898 -286.145299) (xy 287.330263 -286.108462) (xy 287.30396 -286.066866) (xy 287.284669 -286.02159)
			(xy 287.272892 -285.973806) (xy 287.268932 -285.924752) (xy 286.930084 -285.924752) (xy 286.929589 -285.949359)
			(xy 286.921694 -285.997936) (xy 286.90611 -286.044617) (xy 286.883239 -286.088194) (xy 286.853674 -286.127538)
			(xy 286.818181 -286.16163) (xy 286.777678 -286.189586) (xy 286.733216 -286.210684) (xy 286.685945 -286.224376)
			(xy 286.63709 -286.230308) (xy 286.587915 -286.228327) (xy 286.539696 -286.218483) (xy 286.49368 -286.201031)
			(xy 286.451059 -286.176424) (xy 286.412938 -286.145299) (xy 286.380303 -286.108462) (xy 286.354 -286.066866)
			(xy 286.334709 -286.02159) (xy 286.322932 -285.973806) (xy 286.318972 -285.924752) (xy 285.980124 -285.924752)
			(xy 285.979629 -285.949359) (xy 285.971734 -285.997936) (xy 285.95615 -286.044617) (xy 285.933279 -286.088194)
			(xy 285.903714 -286.127538) (xy 285.868221 -286.16163) (xy 285.827718 -286.189586) (xy 285.783256 -286.210684)
			(xy 285.735985 -286.224376) (xy 285.68713 -286.230308) (xy 285.637955 -286.228327) (xy 285.589736 -286.218483)
			(xy 285.54372 -286.201031) (xy 285.501099 -286.176424) (xy 285.462978 -286.145299) (xy 285.430343 -286.108462)
			(xy 285.40404 -286.066866) (xy 285.384749 -286.02159) (xy 285.372972 -285.973806) (xy 285.369012 -285.924752)
			(xy 285.030164 -285.924752) (xy 285.029669 -285.949359) (xy 285.021774 -285.997936) (xy 285.00619 -286.044617)
			(xy 284.983319 -286.088194) (xy 284.953754 -286.127538) (xy 284.918261 -286.16163) (xy 284.877758 -286.189586)
			(xy 284.833296 -286.210684) (xy 284.786025 -286.224376) (xy 284.73717 -286.230308) (xy 284.687995 -286.228327)
			(xy 284.639776 -286.218483) (xy 284.59376 -286.201031) (xy 284.551139 -286.176424) (xy 284.513018 -286.145299)
			(xy 284.480383 -286.108462) (xy 284.45408 -286.066866) (xy 284.434789 -286.02159) (xy 284.423012 -285.973806)
			(xy 284.419052 -285.924752) (xy 284.080204 -285.924752) (xy 284.079709 -285.949359) (xy 284.071814 -285.997936)
			(xy 284.05623 -286.044617) (xy 284.033359 -286.088194) (xy 284.003794 -286.127538) (xy 283.968301 -286.16163)
			(xy 283.927798 -286.189586) (xy 283.883336 -286.210684) (xy 283.836065 -286.224376) (xy 283.78721 -286.230308)
			(xy 283.738035 -286.228327) (xy 283.689816 -286.218483) (xy 283.6438 -286.201031) (xy 283.601179 -286.176424)
			(xy 283.563058 -286.145299) (xy 283.530423 -286.108462) (xy 283.50412 -286.066866) (xy 283.484829 -286.02159)
			(xy 283.473052 -285.973806) (xy 283.469092 -285.924752) (xy 283.130244 -285.924752) (xy 283.129749 -285.949359)
			(xy 283.121854 -285.997936) (xy 283.10627 -286.044617) (xy 283.083399 -286.088194) (xy 283.053834 -286.127538)
			(xy 283.018341 -286.16163) (xy 282.977838 -286.189586) (xy 282.933376 -286.210684) (xy 282.886105 -286.224376)
			(xy 282.83725 -286.230308) (xy 282.788075 -286.228327) (xy 282.739856 -286.218483) (xy 282.69384 -286.201031)
			(xy 282.651219 -286.176424) (xy 282.613098 -286.145299) (xy 282.580463 -286.108462) (xy 282.55416 -286.066866)
			(xy 282.534869 -286.02159) (xy 282.523092 -285.973806) (xy 282.519132 -285.924752) (xy 282.18003 -285.924752)
			(xy 282.179535 -285.949359) (xy 282.17164 -285.997936) (xy 282.156056 -286.044617) (xy 282.133185 -286.088194)
			(xy 282.10362 -286.127538) (xy 282.068127 -286.16163) (xy 282.027624 -286.189586) (xy 281.983162 -286.210684)
			(xy 281.935891 -286.224376) (xy 281.887036 -286.230308) (xy 281.837861 -286.228327) (xy 281.789642 -286.218483)
			(xy 281.743626 -286.201031) (xy 281.701005 -286.176424) (xy 281.662884 -286.145299) (xy 281.630249 -286.108462)
			(xy 281.603946 -286.066866) (xy 281.584655 -286.02159) (xy 281.572878 -285.973806) (xy 281.568918 -285.924752)
			(xy 281.23007 -285.924752) (xy 281.229575 -285.949359) (xy 281.22168 -285.997936) (xy 281.206096 -286.044617)
			(xy 281.183225 -286.088194) (xy 281.15366 -286.127538) (xy 281.118167 -286.16163) (xy 281.077664 -286.189586)
			(xy 281.033202 -286.210684) (xy 280.985931 -286.224376) (xy 280.937076 -286.230308) (xy 280.887901 -286.228327)
			(xy 280.839682 -286.218483) (xy 280.793666 -286.201031) (xy 280.751045 -286.176424) (xy 280.712924 -286.145299)
			(xy 280.680289 -286.108462) (xy 280.653986 -286.066866) (xy 280.634695 -286.02159) (xy 280.622918 -285.973806)
			(xy 280.618958 -285.924752) (xy 280.28011 -285.924752) (xy 280.28011 -285.941262) (xy 280.279602 -285.947104)
			(xy 280.279602 -285.947612) (xy 280.278332 -285.958534) (xy 280.278332 -285.958788) (xy 280.277824 -285.962852)
			(xy 280.275284 -285.981648) (xy 280.274268 -285.987236) (xy 280.270204 -286.002984) (xy 280.268426 -286.015684)
			(xy 280.268426 -286.399732) (xy 305.793914 -286.399732) (xy 305.797874 -286.350678) (xy 305.809651 -286.302894)
			(xy 305.828942 -286.257618) (xy 305.855245 -286.216022) (xy 305.88788 -286.179185) (xy 305.926001 -286.14806)
			(xy 305.968622 -286.123453) (xy 306.014638 -286.106001) (xy 306.062857 -286.096157) (xy 306.112032 -286.094176)
			(xy 306.160887 -286.100108) (xy 306.208158 -286.1138) (xy 306.25262 -286.134898) (xy 306.293123 -286.162854)
			(xy 306.328616 -286.196946) (xy 306.358181 -286.23629) (xy 306.381052 -286.279867) (xy 306.396636 -286.326548)
			(xy 306.404531 -286.375125) (xy 306.405026 -286.399732) (xy 306.744128 -286.399732) (xy 306.748088 -286.350678)
			(xy 306.759865 -286.302894) (xy 306.779156 -286.257618) (xy 306.805459 -286.216022) (xy 306.838094 -286.179185)
			(xy 306.876215 -286.14806) (xy 306.918836 -286.123453) (xy 306.964852 -286.106001) (xy 307.013071 -286.096157)
			(xy 307.062246 -286.094176) (xy 307.111101 -286.100108) (xy 307.158372 -286.1138) (xy 307.202834 -286.134898)
			(xy 307.243337 -286.162854) (xy 307.27883 -286.196946) (xy 307.308395 -286.23629) (xy 307.331266 -286.279867)
			(xy 307.34685 -286.326548) (xy 307.354745 -286.375125) (xy 307.35524 -286.399732) (xy 307.694088 -286.399732)
			(xy 307.698048 -286.350678) (xy 307.709825 -286.302894) (xy 307.729116 -286.257618) (xy 307.755419 -286.216022)
			(xy 307.788054 -286.179185) (xy 307.826175 -286.14806) (xy 307.868796 -286.123453) (xy 307.914812 -286.106001)
			(xy 307.963031 -286.096157) (xy 308.012206 -286.094176) (xy 308.061061 -286.100108) (xy 308.108332 -286.1138)
			(xy 308.152794 -286.134898) (xy 308.193297 -286.162854) (xy 308.22879 -286.196946) (xy 308.258355 -286.23629)
			(xy 308.281226 -286.279867) (xy 308.29681 -286.326548) (xy 308.304705 -286.375125) (xy 308.3052 -286.399732)
			(xy 308.305195 -286.399986) (xy 308.644048 -286.399986) (xy 308.648008 -286.350932) (xy 308.659785 -286.303148)
			(xy 308.679076 -286.257872) (xy 308.705379 -286.216276) (xy 308.738014 -286.179439) (xy 308.776135 -286.148314)
			(xy 308.818756 -286.123707) (xy 308.864772 -286.106255) (xy 308.912991 -286.096411) (xy 308.962166 -286.09443)
			(xy 309.011021 -286.100362) (xy 309.058292 -286.114054) (xy 309.102754 -286.135152) (xy 309.143257 -286.163108)
			(xy 309.17875 -286.1972) (xy 309.208315 -286.236544) (xy 309.231186 -286.280121) (xy 309.24677 -286.326802)
			(xy 309.254665 -286.375379) (xy 309.25516 -286.399986) (xy 309.594008 -286.399986) (xy 309.597968 -286.350932)
			(xy 309.609745 -286.303148) (xy 309.629036 -286.257872) (xy 309.655339 -286.216276) (xy 309.687974 -286.179439)
			(xy 309.726095 -286.148314) (xy 309.768716 -286.123707) (xy 309.814732 -286.106255) (xy 309.862951 -286.096411)
			(xy 309.912126 -286.09443) (xy 309.960981 -286.100362) (xy 310.008252 -286.114054) (xy 310.052714 -286.135152)
			(xy 310.093217 -286.163108) (xy 310.12871 -286.1972) (xy 310.158275 -286.236544) (xy 310.181146 -286.280121)
			(xy 310.19673 -286.326802) (xy 310.204625 -286.375379) (xy 310.205115 -286.399732) (xy 310.543968 -286.399732)
			(xy 310.547928 -286.350678) (xy 310.559705 -286.302894) (xy 310.578996 -286.257618) (xy 310.605299 -286.216022)
			(xy 310.637934 -286.179185) (xy 310.676055 -286.14806) (xy 310.718676 -286.123453) (xy 310.764692 -286.106001)
			(xy 310.812911 -286.096157) (xy 310.862086 -286.094176) (xy 310.910941 -286.100108) (xy 310.958212 -286.1138)
			(xy 311.002674 -286.134898) (xy 311.043177 -286.162854) (xy 311.07867 -286.196946) (xy 311.108235 -286.23629)
			(xy 311.131106 -286.279867) (xy 311.14669 -286.326548) (xy 311.154585 -286.375125) (xy 311.15508 -286.399732)
			(xy 311.154585 -286.424339) (xy 311.154406 -286.42544) (xy 311.473084 -286.42544) (xy 311.473084 -286.374024)
			(xy 311.481127 -286.323242) (xy 311.497015 -286.274343) (xy 311.520358 -286.228531) (xy 311.550579 -286.186935)
			(xy 311.586935 -286.150579) (xy 311.628531 -286.120358) (xy 311.674343 -286.097015) (xy 311.723242 -286.081127)
			(xy 311.774024 -286.073084) (xy 311.82544 -286.073084) (xy 311.876222 -286.081127) (xy 311.925121 -286.097015)
			(xy 311.970933 -286.120358) (xy 312.012529 -286.150579) (xy 312.048885 -286.186935) (xy 312.079106 -286.228531)
			(xy 312.102449 -286.274343) (xy 312.118337 -286.323242) (xy 312.12638 -286.374024) (xy 312.126884 -286.399732)
			(xy 312.12638 -286.42544) (xy 312.423044 -286.42544) (xy 312.423044 -286.374024) (xy 312.431087 -286.323242)
			(xy 312.446975 -286.274343) (xy 312.470318 -286.228531) (xy 312.500539 -286.186935) (xy 312.536895 -286.150579)
			(xy 312.578491 -286.120358) (xy 312.624303 -286.097015) (xy 312.673202 -286.081127) (xy 312.723984 -286.073084)
			(xy 312.7754 -286.073084) (xy 312.826182 -286.081127) (xy 312.875081 -286.097015) (xy 312.920893 -286.120358)
			(xy 312.962489 -286.150579) (xy 312.998845 -286.186935) (xy 313.029066 -286.228531) (xy 313.052409 -286.274343)
			(xy 313.068297 -286.323242) (xy 313.07634 -286.374024) (xy 313.076844 -286.399732) (xy 313.394102 -286.399732)
			(xy 313.398062 -286.350678) (xy 313.409839 -286.302894) (xy 313.42913 -286.257618) (xy 313.455433 -286.216022)
			(xy 313.488068 -286.179185) (xy 313.526189 -286.14806) (xy 313.56881 -286.123453) (xy 313.614826 -286.106001)
			(xy 313.663045 -286.096157) (xy 313.71222 -286.094176) (xy 313.761075 -286.100108) (xy 313.808346 -286.1138)
			(xy 313.852808 -286.134898) (xy 313.893311 -286.162854) (xy 313.928804 -286.196946) (xy 313.958369 -286.23629)
			(xy 313.98124 -286.279867) (xy 313.996824 -286.326548) (xy 314.004719 -286.375125) (xy 314.005214 -286.399732)
			(xy 314.344062 -286.399732) (xy 314.348022 -286.350678) (xy 314.359799 -286.302894) (xy 314.37909 -286.257618)
			(xy 314.405393 -286.216022) (xy 314.438028 -286.179185) (xy 314.476149 -286.14806) (xy 314.51877 -286.123453)
			(xy 314.564786 -286.106001) (xy 314.613005 -286.096157) (xy 314.66218 -286.094176) (xy 314.711035 -286.100108)
			(xy 314.758306 -286.1138) (xy 314.802768 -286.134898) (xy 314.843271 -286.162854) (xy 314.878764 -286.196946)
			(xy 314.908329 -286.23629) (xy 314.9312 -286.279867) (xy 314.946784 -286.326548) (xy 314.954679 -286.375125)
			(xy 314.955174 -286.399732) (xy 314.954679 -286.424339) (xy 314.946784 -286.472916) (xy 314.9312 -286.519597)
			(xy 314.908329 -286.563174) (xy 314.878764 -286.602518) (xy 314.843271 -286.63661) (xy 314.802768 -286.664566)
			(xy 314.758306 -286.685664) (xy 314.711035 -286.699356) (xy 314.66218 -286.705288) (xy 314.613005 -286.703307)
			(xy 314.564786 -286.693463) (xy 314.51877 -286.676011) (xy 314.476149 -286.651404) (xy 314.438028 -286.620279)
			(xy 314.405393 -286.583442) (xy 314.37909 -286.541846) (xy 314.359799 -286.49657) (xy 314.348022 -286.448786)
			(xy 314.344062 -286.399732) (xy 314.005214 -286.399732) (xy 314.004719 -286.424339) (xy 313.996824 -286.472916)
			(xy 313.98124 -286.519597) (xy 313.958369 -286.563174) (xy 313.928804 -286.602518) (xy 313.893311 -286.63661)
			(xy 313.852808 -286.664566) (xy 313.808346 -286.685664) (xy 313.761075 -286.699356) (xy 313.71222 -286.705288)
			(xy 313.663045 -286.703307) (xy 313.614826 -286.693463) (xy 313.56881 -286.676011) (xy 313.526189 -286.651404)
			(xy 313.488068 -286.620279) (xy 313.455433 -286.583442) (xy 313.42913 -286.541846) (xy 313.409839 -286.49657)
			(xy 313.398062 -286.448786) (xy 313.394102 -286.399732) (xy 313.076844 -286.399732) (xy 313.07634 -286.42544)
			(xy 313.068297 -286.476222) (xy 313.052409 -286.525121) (xy 313.029066 -286.570933) (xy 312.998845 -286.612529)
			(xy 312.962489 -286.648885) (xy 312.920893 -286.679106) (xy 312.875081 -286.702449) (xy 312.826182 -286.718337)
			(xy 312.7754 -286.72638) (xy 312.723984 -286.72638) (xy 312.673202 -286.718337) (xy 312.624303 -286.702449)
			(xy 312.578491 -286.679106) (xy 312.536895 -286.648885) (xy 312.500539 -286.612529) (xy 312.470318 -286.570933)
			(xy 312.446975 -286.525121) (xy 312.431087 -286.476222) (xy 312.423044 -286.42544) (xy 312.12638 -286.42544)
			(xy 312.118337 -286.476222) (xy 312.102449 -286.525121) (xy 312.079106 -286.570933) (xy 312.048885 -286.612529)
			(xy 312.012529 -286.648885) (xy 311.970933 -286.679106) (xy 311.925121 -286.702449) (xy 311.876222 -286.718337)
			(xy 311.82544 -286.72638) (xy 311.774024 -286.72638) (xy 311.723242 -286.718337) (xy 311.674343 -286.702449)
			(xy 311.628531 -286.679106) (xy 311.586935 -286.648885) (xy 311.550579 -286.612529) (xy 311.520358 -286.570933)
			(xy 311.497015 -286.525121) (xy 311.481127 -286.476222) (xy 311.473084 -286.42544) (xy 311.154406 -286.42544)
			(xy 311.14669 -286.472916) (xy 311.131106 -286.519597) (xy 311.108235 -286.563174) (xy 311.07867 -286.602518)
			(xy 311.043177 -286.63661) (xy 311.002674 -286.664566) (xy 310.958212 -286.685664) (xy 310.910941 -286.699356)
			(xy 310.862086 -286.705288) (xy 310.812911 -286.703307) (xy 310.764692 -286.693463) (xy 310.718676 -286.676011)
			(xy 310.676055 -286.651404) (xy 310.637934 -286.620279) (xy 310.605299 -286.583442) (xy 310.578996 -286.541846)
			(xy 310.559705 -286.49657) (xy 310.547928 -286.448786) (xy 310.543968 -286.399732) (xy 310.205115 -286.399732)
			(xy 310.20512 -286.399986) (xy 310.204625 -286.424593) (xy 310.19673 -286.47317) (xy 310.181146 -286.519851)
			(xy 310.158275 -286.563428) (xy 310.12871 -286.602772) (xy 310.093217 -286.636864) (xy 310.052714 -286.66482)
			(xy 310.008252 -286.685918) (xy 309.960981 -286.69961) (xy 309.912126 -286.705542) (xy 309.862951 -286.703561)
			(xy 309.814732 -286.693717) (xy 309.768716 -286.676265) (xy 309.726095 -286.651658) (xy 309.687974 -286.620533)
			(xy 309.655339 -286.583696) (xy 309.629036 -286.5421) (xy 309.609745 -286.496824) (xy 309.597968 -286.44904)
			(xy 309.594008 -286.399986) (xy 309.25516 -286.399986) (xy 309.254665 -286.424593) (xy 309.24677 -286.47317)
			(xy 309.231186 -286.519851) (xy 309.208315 -286.563428) (xy 309.17875 -286.602772) (xy 309.143257 -286.636864)
			(xy 309.102754 -286.66482) (xy 309.058292 -286.685918) (xy 309.011021 -286.69961) (xy 308.962166 -286.705542)
			(xy 308.912991 -286.703561) (xy 308.864772 -286.693717) (xy 308.818756 -286.676265) (xy 308.776135 -286.651658)
			(xy 308.738014 -286.620533) (xy 308.705379 -286.583696) (xy 308.679076 -286.5421) (xy 308.659785 -286.496824)
			(xy 308.648008 -286.44904) (xy 308.644048 -286.399986) (xy 308.305195 -286.399986) (xy 308.304705 -286.424339)
			(xy 308.29681 -286.472916) (xy 308.281226 -286.519597) (xy 308.258355 -286.563174) (xy 308.22879 -286.602518)
			(xy 308.193297 -286.63661) (xy 308.152794 -286.664566) (xy 308.108332 -286.685664) (xy 308.061061 -286.699356)
			(xy 308.012206 -286.705288) (xy 307.963031 -286.703307) (xy 307.914812 -286.693463) (xy 307.868796 -286.676011)
			(xy 307.826175 -286.651404) (xy 307.788054 -286.620279) (xy 307.755419 -286.583442) (xy 307.729116 -286.541846)
			(xy 307.709825 -286.49657) (xy 307.698048 -286.448786) (xy 307.694088 -286.399732) (xy 307.35524 -286.399732)
			(xy 307.354745 -286.424339) (xy 307.34685 -286.472916) (xy 307.331266 -286.519597) (xy 307.308395 -286.563174)
			(xy 307.27883 -286.602518) (xy 307.243337 -286.63661) (xy 307.202834 -286.664566) (xy 307.158372 -286.685664)
			(xy 307.111101 -286.699356) (xy 307.062246 -286.705288) (xy 307.013071 -286.703307) (xy 306.964852 -286.693463)
			(xy 306.918836 -286.676011) (xy 306.876215 -286.651404) (xy 306.838094 -286.620279) (xy 306.805459 -286.583442)
			(xy 306.779156 -286.541846) (xy 306.759865 -286.49657) (xy 306.748088 -286.448786) (xy 306.744128 -286.399732)
			(xy 306.405026 -286.399732) (xy 306.404531 -286.424339) (xy 306.396636 -286.472916) (xy 306.381052 -286.519597)
			(xy 306.358181 -286.563174) (xy 306.328616 -286.602518) (xy 306.293123 -286.63661) (xy 306.25262 -286.664566)
			(xy 306.208158 -286.685664) (xy 306.160887 -286.699356) (xy 306.112032 -286.705288) (xy 306.062857 -286.703307)
			(xy 306.014638 -286.693463) (xy 305.968622 -286.676011) (xy 305.926001 -286.651404) (xy 305.88788 -286.620279)
			(xy 305.855245 -286.583442) (xy 305.828942 -286.541846) (xy 305.809651 -286.49657) (xy 305.797874 -286.448786)
			(xy 305.793914 -286.399732) (xy 280.268426 -286.399732) (xy 280.268426 -286.780224) (xy 280.268934 -286.78632)
			(xy 280.270204 -286.797496) (xy 280.270966 -286.800798) (xy 280.270966 -286.801306) (xy 280.275219 -286.819424)
			(xy 280.279808 -286.856358) (xy 280.28011 -286.874966) (xy 280.618958 -286.874966) (xy 280.622918 -286.825912)
			(xy 280.634695 -286.778128) (xy 280.653986 -286.732852) (xy 280.680289 -286.691256) (xy 280.712924 -286.654419)
			(xy 280.751045 -286.623294) (xy 280.793666 -286.598687) (xy 280.839682 -286.581235) (xy 280.887901 -286.571391)
			(xy 280.937076 -286.56941) (xy 280.985931 -286.575342) (xy 281.033202 -286.589034) (xy 281.077664 -286.610132)
			(xy 281.118167 -286.638088) (xy 281.15366 -286.67218) (xy 281.183225 -286.711524) (xy 281.206096 -286.755101)
			(xy 281.22168 -286.801782) (xy 281.229575 -286.850359) (xy 281.23007 -286.874966) (xy 281.568918 -286.874966)
			(xy 281.572878 -286.825912) (xy 281.584655 -286.778128) (xy 281.603946 -286.732852) (xy 281.630249 -286.691256)
			(xy 281.662884 -286.654419) (xy 281.701005 -286.623294) (xy 281.743626 -286.598687) (xy 281.789642 -286.581235)
			(xy 281.837861 -286.571391) (xy 281.887036 -286.56941) (xy 281.935891 -286.575342) (xy 281.983162 -286.589034)
			(xy 282.027624 -286.610132) (xy 282.068127 -286.638088) (xy 282.10362 -286.67218) (xy 282.133185 -286.711524)
			(xy 282.156056 -286.755101) (xy 282.17164 -286.801782) (xy 282.179535 -286.850359) (xy 282.18003 -286.874966)
			(xy 282.519132 -286.874966) (xy 282.523092 -286.825912) (xy 282.534869 -286.778128) (xy 282.55416 -286.732852)
			(xy 282.580463 -286.691256) (xy 282.613098 -286.654419) (xy 282.651219 -286.623294) (xy 282.69384 -286.598687)
			(xy 282.739856 -286.581235) (xy 282.788075 -286.571391) (xy 282.83725 -286.56941) (xy 282.886105 -286.575342)
			(xy 282.933376 -286.589034) (xy 282.977838 -286.610132) (xy 283.018341 -286.638088) (xy 283.053834 -286.67218)
			(xy 283.083399 -286.711524) (xy 283.10627 -286.755101) (xy 283.121854 -286.801782) (xy 283.129749 -286.850359)
			(xy 283.130244 -286.874966) (xy 283.469092 -286.874966) (xy 283.473052 -286.825912) (xy 283.484829 -286.778128)
			(xy 283.50412 -286.732852) (xy 283.530423 -286.691256) (xy 283.563058 -286.654419) (xy 283.601179 -286.623294)
			(xy 283.6438 -286.598687) (xy 283.689816 -286.581235) (xy 283.738035 -286.571391) (xy 283.78721 -286.56941)
			(xy 283.836065 -286.575342) (xy 283.883336 -286.589034) (xy 283.927798 -286.610132) (xy 283.968301 -286.638088)
			(xy 284.003794 -286.67218) (xy 284.033359 -286.711524) (xy 284.05623 -286.755101) (xy 284.071814 -286.801782)
			(xy 284.079709 -286.850359) (xy 284.080204 -286.874966) (xy 284.419052 -286.874966) (xy 284.423012 -286.825912)
			(xy 284.434789 -286.778128) (xy 284.45408 -286.732852) (xy 284.480383 -286.691256) (xy 284.513018 -286.654419)
			(xy 284.551139 -286.623294) (xy 284.59376 -286.598687) (xy 284.639776 -286.581235) (xy 284.687995 -286.571391)
			(xy 284.73717 -286.56941) (xy 284.786025 -286.575342) (xy 284.833296 -286.589034) (xy 284.877758 -286.610132)
			(xy 284.918261 -286.638088) (xy 284.953754 -286.67218) (xy 284.983319 -286.711524) (xy 285.00619 -286.755101)
			(xy 285.021774 -286.801782) (xy 285.029669 -286.850359) (xy 285.030164 -286.874966) (xy 285.369012 -286.874966)
			(xy 285.372972 -286.825912) (xy 285.384749 -286.778128) (xy 285.40404 -286.732852) (xy 285.430343 -286.691256)
			(xy 285.462978 -286.654419) (xy 285.501099 -286.623294) (xy 285.54372 -286.598687) (xy 285.589736 -286.581235)
			(xy 285.637955 -286.571391) (xy 285.68713 -286.56941) (xy 285.735985 -286.575342) (xy 285.783256 -286.589034)
			(xy 285.827718 -286.610132) (xy 285.868221 -286.638088) (xy 285.903714 -286.67218) (xy 285.933279 -286.711524)
			(xy 285.95615 -286.755101) (xy 285.971734 -286.801782) (xy 285.979629 -286.850359) (xy 285.980124 -286.874966)
			(xy 286.318972 -286.874966) (xy 286.322932 -286.825912) (xy 286.334709 -286.778128) (xy 286.354 -286.732852)
			(xy 286.380303 -286.691256) (xy 286.412938 -286.654419) (xy 286.451059 -286.623294) (xy 286.49368 -286.598687)
			(xy 286.539696 -286.581235) (xy 286.587915 -286.571391) (xy 286.63709 -286.56941) (xy 286.685945 -286.575342)
			(xy 286.733216 -286.589034) (xy 286.777678 -286.610132) (xy 286.818181 -286.638088) (xy 286.853674 -286.67218)
			(xy 286.883239 -286.711524) (xy 286.90611 -286.755101) (xy 286.921694 -286.801782) (xy 286.929589 -286.850359)
			(xy 286.930084 -286.874966) (xy 287.268932 -286.874966) (xy 287.272892 -286.825912) (xy 287.284669 -286.778128)
			(xy 287.30396 -286.732852) (xy 287.330263 -286.691256) (xy 287.362898 -286.654419) (xy 287.401019 -286.623294)
			(xy 287.44364 -286.598687) (xy 287.489656 -286.581235) (xy 287.537875 -286.571391) (xy 287.58705 -286.56941)
			(xy 287.635905 -286.575342) (xy 287.683176 -286.589034) (xy 287.727638 -286.610132) (xy 287.768141 -286.638088)
			(xy 287.803634 -286.67218) (xy 287.833199 -286.711524) (xy 287.85607 -286.755101) (xy 287.871654 -286.801782)
			(xy 287.879549 -286.850359) (xy 287.880044 -286.874966) (xy 288.218892 -286.874966) (xy 288.222852 -286.825912)
			(xy 288.234629 -286.778128) (xy 288.25392 -286.732852) (xy 288.280223 -286.691256) (xy 288.312858 -286.654419)
			(xy 288.350979 -286.623294) (xy 288.3936 -286.598687) (xy 288.439616 -286.581235) (xy 288.487835 -286.571391)
			(xy 288.53701 -286.56941) (xy 288.585865 -286.575342) (xy 288.633136 -286.589034) (xy 288.677598 -286.610132)
			(xy 288.718101 -286.638088) (xy 288.753594 -286.67218) (xy 288.783159 -286.711524) (xy 288.80603 -286.755101)
			(xy 288.821614 -286.801782) (xy 288.829509 -286.850359) (xy 288.830004 -286.874966) (xy 289.169106 -286.874966)
			(xy 289.173066 -286.825912) (xy 289.184843 -286.778128) (xy 289.204134 -286.732852) (xy 289.230437 -286.691256)
			(xy 289.263072 -286.654419) (xy 289.301193 -286.623294) (xy 289.343814 -286.598687) (xy 289.38983 -286.581235)
			(xy 289.438049 -286.571391) (xy 289.487224 -286.56941) (xy 289.536079 -286.575342) (xy 289.58335 -286.589034)
			(xy 289.627812 -286.610132) (xy 289.668315 -286.638088) (xy 289.703808 -286.67218) (xy 289.733373 -286.711524)
			(xy 289.756244 -286.755101) (xy 289.771828 -286.801782) (xy 289.779723 -286.850359) (xy 289.780218 -286.874966)
			(xy 290.119066 -286.874966) (xy 290.123026 -286.825912) (xy 290.134803 -286.778128) (xy 290.154094 -286.732852)
			(xy 290.180397 -286.691256) (xy 290.213032 -286.654419) (xy 290.251153 -286.623294) (xy 290.293774 -286.598687)
			(xy 290.33979 -286.581235) (xy 290.388009 -286.571391) (xy 290.437184 -286.56941) (xy 290.486039 -286.575342)
			(xy 290.53331 -286.589034) (xy 290.577772 -286.610132) (xy 290.618275 -286.638088) (xy 290.653768 -286.67218)
			(xy 290.683333 -286.711524) (xy 290.706204 -286.755101) (xy 290.721788 -286.801782) (xy 290.729683 -286.850359)
			(xy 290.730178 -286.874966) (xy 292.018986 -286.874966) (xy 292.022946 -286.825912) (xy 292.034723 -286.778128)
			(xy 292.054014 -286.732852) (xy 292.080317 -286.691256) (xy 292.112952 -286.654419) (xy 292.151073 -286.623294)
			(xy 292.193694 -286.598687) (xy 292.23971 -286.581235) (xy 292.287929 -286.571391) (xy 292.337104 -286.56941)
			(xy 292.385959 -286.575342) (xy 292.43323 -286.589034) (xy 292.477692 -286.610132) (xy 292.518195 -286.638088)
			(xy 292.553688 -286.67218) (xy 292.583253 -286.711524) (xy 292.606124 -286.755101) (xy 292.621708 -286.801782)
			(xy 292.629603 -286.850359) (xy 292.630098 -286.874966) (xy 292.968946 -286.874966) (xy 292.972906 -286.825912)
			(xy 292.984683 -286.778128) (xy 293.003974 -286.732852) (xy 293.030277 -286.691256) (xy 293.062912 -286.654419)
			(xy 293.101033 -286.623294) (xy 293.143654 -286.598687) (xy 293.18967 -286.581235) (xy 293.237889 -286.571391)
			(xy 293.287064 -286.56941) (xy 293.335919 -286.575342) (xy 293.38319 -286.589034) (xy 293.427652 -286.610132)
			(xy 293.468155 -286.638088) (xy 293.503648 -286.67218) (xy 293.533213 -286.711524) (xy 293.556084 -286.755101)
			(xy 293.571668 -286.801782) (xy 293.579563 -286.850359) (xy 293.580058 -286.874966) (xy 293.918906 -286.874966)
			(xy 293.922866 -286.825912) (xy 293.934643 -286.778128) (xy 293.953934 -286.732852) (xy 293.980237 -286.691256)
			(xy 294.012872 -286.654419) (xy 294.050993 -286.623294) (xy 294.093614 -286.598687) (xy 294.13963 -286.581235)
			(xy 294.187849 -286.571391) (xy 294.237024 -286.56941) (xy 294.285879 -286.575342) (xy 294.33315 -286.589034)
			(xy 294.377612 -286.610132) (xy 294.418115 -286.638088) (xy 294.453608 -286.67218) (xy 294.483173 -286.711524)
			(xy 294.506044 -286.755101) (xy 294.521628 -286.801782) (xy 294.529523 -286.850359) (xy 294.530018 -286.874966)
			(xy 294.86912 -286.874966) (xy 294.87308 -286.825912) (xy 294.884857 -286.778128) (xy 294.904148 -286.732852)
			(xy 294.930451 -286.691256) (xy 294.963086 -286.654419) (xy 295.001207 -286.623294) (xy 295.043828 -286.598687)
			(xy 295.089844 -286.581235) (xy 295.138063 -286.571391) (xy 295.187238 -286.56941) (xy 295.236093 -286.575342)
			(xy 295.283364 -286.589034) (xy 295.327826 -286.610132) (xy 295.368329 -286.638088) (xy 295.403822 -286.67218)
			(xy 295.433387 -286.711524) (xy 295.456258 -286.755101) (xy 295.471842 -286.801782) (xy 295.479737 -286.850359)
			(xy 295.480232 -286.874966) (xy 295.81908 -286.874966) (xy 295.82304 -286.825912) (xy 295.834817 -286.778128)
			(xy 295.854108 -286.732852) (xy 295.880411 -286.691256) (xy 295.913046 -286.654419) (xy 295.951167 -286.623294)
			(xy 295.993788 -286.598687) (xy 296.039804 -286.581235) (xy 296.088023 -286.571391) (xy 296.137198 -286.56941)
			(xy 296.186053 -286.575342) (xy 296.233324 -286.589034) (xy 296.277786 -286.610132) (xy 296.318289 -286.638088)
			(xy 296.353782 -286.67218) (xy 296.383347 -286.711524) (xy 296.406218 -286.755101) (xy 296.421802 -286.801782)
			(xy 296.429697 -286.850359) (xy 296.430192 -286.874966) (xy 296.76904 -286.874966) (xy 296.773 -286.825912)
			(xy 296.784777 -286.778128) (xy 296.804068 -286.732852) (xy 296.830371 -286.691256) (xy 296.863006 -286.654419)
			(xy 296.901127 -286.623294) (xy 296.943748 -286.598687) (xy 296.989764 -286.581235) (xy 297.037983 -286.571391)
			(xy 297.087158 -286.56941) (xy 297.136013 -286.575342) (xy 297.183284 -286.589034) (xy 297.227746 -286.610132)
			(xy 297.268249 -286.638088) (xy 297.303742 -286.67218) (xy 297.333307 -286.711524) (xy 297.356178 -286.755101)
			(xy 297.371762 -286.801782) (xy 297.379657 -286.850359) (xy 297.380152 -286.874966) (xy 297.719 -286.874966)
			(xy 297.72296 -286.825912) (xy 297.734737 -286.778128) (xy 297.754028 -286.732852) (xy 297.780331 -286.691256)
			(xy 297.812966 -286.654419) (xy 297.851087 -286.623294) (xy 297.893708 -286.598687) (xy 297.939724 -286.581235)
			(xy 297.987943 -286.571391) (xy 298.037118 -286.56941) (xy 298.085973 -286.575342) (xy 298.133244 -286.589034)
			(xy 298.177706 -286.610132) (xy 298.218209 -286.638088) (xy 298.253702 -286.67218) (xy 298.283267 -286.711524)
			(xy 298.306138 -286.755101) (xy 298.321722 -286.801782) (xy 298.329617 -286.850359) (xy 298.330112 -286.874966)
			(xy 298.66896 -286.874966) (xy 298.67292 -286.825912) (xy 298.684697 -286.778128) (xy 298.703988 -286.732852)
			(xy 298.730291 -286.691256) (xy 298.762926 -286.654419) (xy 298.801047 -286.623294) (xy 298.843668 -286.598687)
			(xy 298.889684 -286.581235) (xy 298.937903 -286.571391) (xy 298.987078 -286.56941) (xy 299.035933 -286.575342)
			(xy 299.083204 -286.589034) (xy 299.127666 -286.610132) (xy 299.168169 -286.638088) (xy 299.203662 -286.67218)
			(xy 299.233227 -286.711524) (xy 299.256098 -286.755101) (xy 299.271682 -286.801782) (xy 299.279577 -286.850359)
			(xy 299.280072 -286.874966) (xy 299.61892 -286.874966) (xy 299.62288 -286.825912) (xy 299.634657 -286.778128)
			(xy 299.653948 -286.732852) (xy 299.680251 -286.691256) (xy 299.712886 -286.654419) (xy 299.751007 -286.623294)
			(xy 299.793628 -286.598687) (xy 299.839644 -286.581235) (xy 299.887863 -286.571391) (xy 299.937038 -286.56941)
			(xy 299.985893 -286.575342) (xy 300.033164 -286.589034) (xy 300.077626 -286.610132) (xy 300.118129 -286.638088)
			(xy 300.153622 -286.67218) (xy 300.183187 -286.711524) (xy 300.206058 -286.755101) (xy 300.221642 -286.801782)
			(xy 300.229537 -286.850359) (xy 300.230032 -286.874966) (xy 300.56888 -286.874966) (xy 300.57284 -286.825912)
			(xy 300.584617 -286.778128) (xy 300.603908 -286.732852) (xy 300.630211 -286.691256) (xy 300.662846 -286.654419)
			(xy 300.700967 -286.623294) (xy 300.743588 -286.598687) (xy 300.789604 -286.581235) (xy 300.837823 -286.571391)
			(xy 300.886998 -286.56941) (xy 300.935853 -286.575342) (xy 300.983124 -286.589034) (xy 301.027586 -286.610132)
			(xy 301.068089 -286.638088) (xy 301.103582 -286.67218) (xy 301.133147 -286.711524) (xy 301.156018 -286.755101)
			(xy 301.171602 -286.801782) (xy 301.179497 -286.850359) (xy 301.179992 -286.874966) (xy 301.519094 -286.874966)
			(xy 301.523054 -286.825912) (xy 301.534831 -286.778128) (xy 301.554122 -286.732852) (xy 301.580425 -286.691256)
			(xy 301.61306 -286.654419) (xy 301.651181 -286.623294) (xy 301.693802 -286.598687) (xy 301.739818 -286.581235)
			(xy 301.788037 -286.571391) (xy 301.837212 -286.56941) (xy 301.886067 -286.575342) (xy 301.933338 -286.589034)
			(xy 301.9778 -286.610132) (xy 302.018303 -286.638088) (xy 302.053796 -286.67218) (xy 302.083361 -286.711524)
			(xy 302.106232 -286.755101) (xy 302.121816 -286.801782) (xy 302.129711 -286.850359) (xy 302.130206 -286.874966)
			(xy 302.469054 -286.874966) (xy 302.473014 -286.825912) (xy 302.484791 -286.778128) (xy 302.504082 -286.732852)
			(xy 302.530385 -286.691256) (xy 302.56302 -286.654419) (xy 302.601141 -286.623294) (xy 302.643762 -286.598687)
			(xy 302.689778 -286.581235) (xy 302.737997 -286.571391) (xy 302.787172 -286.56941) (xy 302.836027 -286.575342)
			(xy 302.883298 -286.589034) (xy 302.92776 -286.610132) (xy 302.968263 -286.638088) (xy 303.003756 -286.67218)
			(xy 303.033321 -286.711524) (xy 303.056192 -286.755101) (xy 303.071776 -286.801782) (xy 303.079671 -286.850359)
			(xy 303.080166 -286.874966) (xy 303.079671 -286.899573) (xy 303.071776 -286.94815) (xy 303.056192 -286.994831)
			(xy 303.033321 -287.038408) (xy 303.003756 -287.077752) (xy 302.968263 -287.111844) (xy 302.92776 -287.1398)
			(xy 302.883298 -287.160898) (xy 302.836027 -287.17459) (xy 302.787172 -287.180522) (xy 302.737997 -287.178541)
			(xy 302.689778 -287.168697) (xy 302.643762 -287.151245) (xy 302.601141 -287.126638) (xy 302.56302 -287.095513)
			(xy 302.530385 -287.058676) (xy 302.504082 -287.01708) (xy 302.484791 -286.971804) (xy 302.473014 -286.92402)
			(xy 302.469054 -286.874966) (xy 302.130206 -286.874966) (xy 302.129711 -286.899573) (xy 302.121816 -286.94815)
			(xy 302.106232 -286.994831) (xy 302.083361 -287.038408) (xy 302.053796 -287.077752) (xy 302.018303 -287.111844)
			(xy 301.9778 -287.1398) (xy 301.933338 -287.160898) (xy 301.886067 -287.17459) (xy 301.837212 -287.180522)
			(xy 301.788037 -287.178541) (xy 301.739818 -287.168697) (xy 301.693802 -287.151245) (xy 301.651181 -287.126638)
			(xy 301.61306 -287.095513) (xy 301.580425 -287.058676) (xy 301.554122 -287.01708) (xy 301.534831 -286.971804)
			(xy 301.523054 -286.92402) (xy 301.519094 -286.874966) (xy 301.179992 -286.874966) (xy 301.179497 -286.899573)
			(xy 301.171602 -286.94815) (xy 301.156018 -286.994831) (xy 301.133147 -287.038408) (xy 301.103582 -287.077752)
			(xy 301.068089 -287.111844) (xy 301.027586 -287.1398) (xy 300.983124 -287.160898) (xy 300.935853 -287.17459)
			(xy 300.886998 -287.180522) (xy 300.837823 -287.178541) (xy 300.789604 -287.168697) (xy 300.743588 -287.151245)
			(xy 300.700967 -287.126638) (xy 300.662846 -287.095513) (xy 300.630211 -287.058676) (xy 300.603908 -287.01708)
			(xy 300.584617 -286.971804) (xy 300.57284 -286.92402) (xy 300.56888 -286.874966) (xy 300.230032 -286.874966)
			(xy 300.229537 -286.899573) (xy 300.221642 -286.94815) (xy 300.206058 -286.994831) (xy 300.183187 -287.038408)
			(xy 300.153622 -287.077752) (xy 300.118129 -287.111844) (xy 300.077626 -287.1398) (xy 300.033164 -287.160898)
			(xy 299.985893 -287.17459) (xy 299.937038 -287.180522) (xy 299.887863 -287.178541) (xy 299.839644 -287.168697)
			(xy 299.793628 -287.151245) (xy 299.751007 -287.126638) (xy 299.712886 -287.095513) (xy 299.680251 -287.058676)
			(xy 299.653948 -287.01708) (xy 299.634657 -286.971804) (xy 299.62288 -286.92402) (xy 299.61892 -286.874966)
			(xy 299.280072 -286.874966) (xy 299.279577 -286.899573) (xy 299.271682 -286.94815) (xy 299.256098 -286.994831)
			(xy 299.233227 -287.038408) (xy 299.203662 -287.077752) (xy 299.168169 -287.111844) (xy 299.127666 -287.1398)
			(xy 299.083204 -287.160898) (xy 299.035933 -287.17459) (xy 298.987078 -287.180522) (xy 298.937903 -287.178541)
			(xy 298.889684 -287.168697) (xy 298.843668 -287.151245) (xy 298.801047 -287.126638) (xy 298.762926 -287.095513)
			(xy 298.730291 -287.058676) (xy 298.703988 -287.01708) (xy 298.684697 -286.971804) (xy 298.67292 -286.92402)
			(xy 298.66896 -286.874966) (xy 298.330112 -286.874966) (xy 298.329617 -286.899573) (xy 298.321722 -286.94815)
			(xy 298.306138 -286.994831) (xy 298.283267 -287.038408) (xy 298.253702 -287.077752) (xy 298.218209 -287.111844)
			(xy 298.177706 -287.1398) (xy 298.133244 -287.160898) (xy 298.085973 -287.17459) (xy 298.037118 -287.180522)
			(xy 297.987943 -287.178541) (xy 297.939724 -287.168697) (xy 297.893708 -287.151245) (xy 297.851087 -287.126638)
			(xy 297.812966 -287.095513) (xy 297.780331 -287.058676) (xy 297.754028 -287.01708) (xy 297.734737 -286.971804)
			(xy 297.72296 -286.92402) (xy 297.719 -286.874966) (xy 297.380152 -286.874966) (xy 297.379657 -286.899573)
			(xy 297.371762 -286.94815) (xy 297.356178 -286.994831) (xy 297.333307 -287.038408) (xy 297.303742 -287.077752)
			(xy 297.268249 -287.111844) (xy 297.227746 -287.1398) (xy 297.183284 -287.160898) (xy 297.136013 -287.17459)
			(xy 297.087158 -287.180522) (xy 297.037983 -287.178541) (xy 296.989764 -287.168697) (xy 296.943748 -287.151245)
			(xy 296.901127 -287.126638) (xy 296.863006 -287.095513) (xy 296.830371 -287.058676) (xy 296.804068 -287.01708)
			(xy 296.784777 -286.971804) (xy 296.773 -286.92402) (xy 296.76904 -286.874966) (xy 296.430192 -286.874966)
			(xy 296.429697 -286.899573) (xy 296.421802 -286.94815) (xy 296.406218 -286.994831) (xy 296.383347 -287.038408)
			(xy 296.353782 -287.077752) (xy 296.318289 -287.111844) (xy 296.277786 -287.1398) (xy 296.233324 -287.160898)
			(xy 296.186053 -287.17459) (xy 296.137198 -287.180522) (xy 296.088023 -287.178541) (xy 296.039804 -287.168697)
			(xy 295.993788 -287.151245) (xy 295.951167 -287.126638) (xy 295.913046 -287.095513) (xy 295.880411 -287.058676)
			(xy 295.854108 -287.01708) (xy 295.834817 -286.971804) (xy 295.82304 -286.92402) (xy 295.81908 -286.874966)
			(xy 295.480232 -286.874966) (xy 295.479737 -286.899573) (xy 295.471842 -286.94815) (xy 295.456258 -286.994831)
			(xy 295.433387 -287.038408) (xy 295.403822 -287.077752) (xy 295.368329 -287.111844) (xy 295.327826 -287.1398)
			(xy 295.283364 -287.160898) (xy 295.236093 -287.17459) (xy 295.187238 -287.180522) (xy 295.138063 -287.178541)
			(xy 295.089844 -287.168697) (xy 295.043828 -287.151245) (xy 295.001207 -287.126638) (xy 294.963086 -287.095513)
			(xy 294.930451 -287.058676) (xy 294.904148 -287.01708) (xy 294.884857 -286.971804) (xy 294.87308 -286.92402)
			(xy 294.86912 -286.874966) (xy 294.530018 -286.874966) (xy 294.529523 -286.899573) (xy 294.521628 -286.94815)
			(xy 294.506044 -286.994831) (xy 294.483173 -287.038408) (xy 294.453608 -287.077752) (xy 294.418115 -287.111844)
			(xy 294.377612 -287.1398) (xy 294.33315 -287.160898) (xy 294.285879 -287.17459) (xy 294.237024 -287.180522)
			(xy 294.187849 -287.178541) (xy 294.13963 -287.168697) (xy 294.093614 -287.151245) (xy 294.050993 -287.126638)
			(xy 294.012872 -287.095513) (xy 293.980237 -287.058676) (xy 293.953934 -287.01708) (xy 293.934643 -286.971804)
			(xy 293.922866 -286.92402) (xy 293.918906 -286.874966) (xy 293.580058 -286.874966) (xy 293.579563 -286.899573)
			(xy 293.571668 -286.94815) (xy 293.556084 -286.994831) (xy 293.533213 -287.038408) (xy 293.503648 -287.077752)
			(xy 293.468155 -287.111844) (xy 293.427652 -287.1398) (xy 293.38319 -287.160898) (xy 293.335919 -287.17459)
			(xy 293.287064 -287.180522) (xy 293.237889 -287.178541) (xy 293.18967 -287.168697) (xy 293.143654 -287.151245)
			(xy 293.101033 -287.126638) (xy 293.062912 -287.095513) (xy 293.030277 -287.058676) (xy 293.003974 -287.01708)
			(xy 292.984683 -286.971804) (xy 292.972906 -286.92402) (xy 292.968946 -286.874966) (xy 292.630098 -286.874966)
			(xy 292.629603 -286.899573) (xy 292.621708 -286.94815) (xy 292.606124 -286.994831) (xy 292.583253 -287.038408)
			(xy 292.553688 -287.077752) (xy 292.518195 -287.111844) (xy 292.477692 -287.1398) (xy 292.43323 -287.160898)
			(xy 292.385959 -287.17459) (xy 292.337104 -287.180522) (xy 292.287929 -287.178541) (xy 292.23971 -287.168697)
			(xy 292.193694 -287.151245) (xy 292.151073 -287.126638) (xy 292.112952 -287.095513) (xy 292.080317 -287.058676)
			(xy 292.054014 -287.01708) (xy 292.034723 -286.971804) (xy 292.022946 -286.92402) (xy 292.018986 -286.874966)
			(xy 290.730178 -286.874966) (xy 290.729683 -286.899573) (xy 290.721788 -286.94815) (xy 290.706204 -286.994831)
			(xy 290.683333 -287.038408) (xy 290.653768 -287.077752) (xy 290.618275 -287.111844) (xy 290.577772 -287.1398)
			(xy 290.53331 -287.160898) (xy 290.486039 -287.17459) (xy 290.437184 -287.180522) (xy 290.388009 -287.178541)
			(xy 290.33979 -287.168697) (xy 290.293774 -287.151245) (xy 290.251153 -287.126638) (xy 290.213032 -287.095513)
			(xy 290.180397 -287.058676) (xy 290.154094 -287.01708) (xy 290.134803 -286.971804) (xy 290.123026 -286.92402)
			(xy 290.119066 -286.874966) (xy 289.780218 -286.874966) (xy 289.779723 -286.899573) (xy 289.771828 -286.94815)
			(xy 289.756244 -286.994831) (xy 289.733373 -287.038408) (xy 289.703808 -287.077752) (xy 289.668315 -287.111844)
			(xy 289.627812 -287.1398) (xy 289.58335 -287.160898) (xy 289.536079 -287.17459) (xy 289.487224 -287.180522)
			(xy 289.438049 -287.178541) (xy 289.38983 -287.168697) (xy 289.343814 -287.151245) (xy 289.301193 -287.126638)
			(xy 289.263072 -287.095513) (xy 289.230437 -287.058676) (xy 289.204134 -287.01708) (xy 289.184843 -286.971804)
			(xy 289.173066 -286.92402) (xy 289.169106 -286.874966) (xy 288.830004 -286.874966) (xy 288.829509 -286.899573)
			(xy 288.821614 -286.94815) (xy 288.80603 -286.994831) (xy 288.783159 -287.038408) (xy 288.753594 -287.077752)
			(xy 288.718101 -287.111844) (xy 288.677598 -287.1398) (xy 288.633136 -287.160898) (xy 288.585865 -287.17459)
			(xy 288.53701 -287.180522) (xy 288.487835 -287.178541) (xy 288.439616 -287.168697) (xy 288.3936 -287.151245)
			(xy 288.350979 -287.126638) (xy 288.312858 -287.095513) (xy 288.280223 -287.058676) (xy 288.25392 -287.01708)
			(xy 288.234629 -286.971804) (xy 288.222852 -286.92402) (xy 288.218892 -286.874966) (xy 287.880044 -286.874966)
			(xy 287.879549 -286.899573) (xy 287.871654 -286.94815) (xy 287.85607 -286.994831) (xy 287.833199 -287.038408)
			(xy 287.803634 -287.077752) (xy 287.768141 -287.111844) (xy 287.727638 -287.1398) (xy 287.683176 -287.160898)
			(xy 287.635905 -287.17459) (xy 287.58705 -287.180522) (xy 287.537875 -287.178541) (xy 287.489656 -287.168697)
			(xy 287.44364 -287.151245) (xy 287.401019 -287.126638) (xy 287.362898 -287.095513) (xy 287.330263 -287.058676)
			(xy 287.30396 -287.01708) (xy 287.284669 -286.971804) (xy 287.272892 -286.92402) (xy 287.268932 -286.874966)
			(xy 286.930084 -286.874966) (xy 286.929589 -286.899573) (xy 286.921694 -286.94815) (xy 286.90611 -286.994831)
			(xy 286.883239 -287.038408) (xy 286.853674 -287.077752) (xy 286.818181 -287.111844) (xy 286.777678 -287.1398)
			(xy 286.733216 -287.160898) (xy 286.685945 -287.17459) (xy 286.63709 -287.180522) (xy 286.587915 -287.178541)
			(xy 286.539696 -287.168697) (xy 286.49368 -287.151245) (xy 286.451059 -287.126638) (xy 286.412938 -287.095513)
			(xy 286.380303 -287.058676) (xy 286.354 -287.01708) (xy 286.334709 -286.971804) (xy 286.322932 -286.92402)
			(xy 286.318972 -286.874966) (xy 285.980124 -286.874966) (xy 285.979629 -286.899573) (xy 285.971734 -286.94815)
			(xy 285.95615 -286.994831) (xy 285.933279 -287.038408) (xy 285.903714 -287.077752) (xy 285.868221 -287.111844)
			(xy 285.827718 -287.1398) (xy 285.783256 -287.160898) (xy 285.735985 -287.17459) (xy 285.68713 -287.180522)
			(xy 285.637955 -287.178541) (xy 285.589736 -287.168697) (xy 285.54372 -287.151245) (xy 285.501099 -287.126638)
			(xy 285.462978 -287.095513) (xy 285.430343 -287.058676) (xy 285.40404 -287.01708) (xy 285.384749 -286.971804)
			(xy 285.372972 -286.92402) (xy 285.369012 -286.874966) (xy 285.030164 -286.874966) (xy 285.029669 -286.899573)
			(xy 285.021774 -286.94815) (xy 285.00619 -286.994831) (xy 284.983319 -287.038408) (xy 284.953754 -287.077752)
			(xy 284.918261 -287.111844) (xy 284.877758 -287.1398) (xy 284.833296 -287.160898) (xy 284.786025 -287.17459)
			(xy 284.73717 -287.180522) (xy 284.687995 -287.178541) (xy 284.639776 -287.168697) (xy 284.59376 -287.151245)
			(xy 284.551139 -287.126638) (xy 284.513018 -287.095513) (xy 284.480383 -287.058676) (xy 284.45408 -287.01708)
			(xy 284.434789 -286.971804) (xy 284.423012 -286.92402) (xy 284.419052 -286.874966) (xy 284.080204 -286.874966)
			(xy 284.079709 -286.899573) (xy 284.071814 -286.94815) (xy 284.05623 -286.994831) (xy 284.033359 -287.038408)
			(xy 284.003794 -287.077752) (xy 283.968301 -287.111844) (xy 283.927798 -287.1398) (xy 283.883336 -287.160898)
			(xy 283.836065 -287.17459) (xy 283.78721 -287.180522) (xy 283.738035 -287.178541) (xy 283.689816 -287.168697)
			(xy 283.6438 -287.151245) (xy 283.601179 -287.126638) (xy 283.563058 -287.095513) (xy 283.530423 -287.058676)
			(xy 283.50412 -287.01708) (xy 283.484829 -286.971804) (xy 283.473052 -286.92402) (xy 283.469092 -286.874966)
			(xy 283.130244 -286.874966) (xy 283.129749 -286.899573) (xy 283.121854 -286.94815) (xy 283.10627 -286.994831)
			(xy 283.083399 -287.038408) (xy 283.053834 -287.077752) (xy 283.018341 -287.111844) (xy 282.977838 -287.1398)
			(xy 282.933376 -287.160898) (xy 282.886105 -287.17459) (xy 282.83725 -287.180522) (xy 282.788075 -287.178541)
			(xy 282.739856 -287.168697) (xy 282.69384 -287.151245) (xy 282.651219 -287.126638) (xy 282.613098 -287.095513)
			(xy 282.580463 -287.058676) (xy 282.55416 -287.01708) (xy 282.534869 -286.971804) (xy 282.523092 -286.92402)
			(xy 282.519132 -286.874966) (xy 282.18003 -286.874966) (xy 282.179535 -286.899573) (xy 282.17164 -286.94815)
			(xy 282.156056 -286.994831) (xy 282.133185 -287.038408) (xy 282.10362 -287.077752) (xy 282.068127 -287.111844)
			(xy 282.027624 -287.1398) (xy 281.983162 -287.160898) (xy 281.935891 -287.17459) (xy 281.887036 -287.180522)
			(xy 281.837861 -287.178541) (xy 281.789642 -287.168697) (xy 281.743626 -287.151245) (xy 281.701005 -287.126638)
			(xy 281.662884 -287.095513) (xy 281.630249 -287.058676) (xy 281.603946 -287.01708) (xy 281.584655 -286.971804)
			(xy 281.572878 -286.92402) (xy 281.568918 -286.874966) (xy 281.23007 -286.874966) (xy 281.229575 -286.899573)
			(xy 281.22168 -286.94815) (xy 281.206096 -286.994831) (xy 281.183225 -287.038408) (xy 281.15366 -287.077752)
			(xy 281.118167 -287.111844) (xy 281.077664 -287.1398) (xy 281.033202 -287.160898) (xy 280.985931 -287.17459)
			(xy 280.937076 -287.180522) (xy 280.887901 -287.178541) (xy 280.839682 -287.168697) (xy 280.793666 -287.151245)
			(xy 280.751045 -287.126638) (xy 280.712924 -287.095513) (xy 280.680289 -287.058676) (xy 280.653986 -287.01708)
			(xy 280.634695 -286.971804) (xy 280.622918 -286.92402) (xy 280.618958 -286.874966) (xy 280.28011 -286.874966)
			(xy 280.28011 -286.891476) (xy 280.279602 -286.897318) (xy 280.279602 -286.897826) (xy 280.278332 -286.908748)
			(xy 280.278332 -286.909002) (xy 280.277824 -286.913066) (xy 280.275284 -286.931862) (xy 280.274268 -286.93745)
			(xy 280.270204 -286.953198) (xy 280.268426 -286.965898) (xy 280.268426 -287.349946) (xy 305.793914 -287.349946)
			(xy 305.797874 -287.300892) (xy 305.809651 -287.253108) (xy 305.828942 -287.207832) (xy 305.855245 -287.166236)
			(xy 305.88788 -287.129399) (xy 305.926001 -287.098274) (xy 305.968622 -287.073667) (xy 306.014638 -287.056215)
			(xy 306.062857 -287.046371) (xy 306.112032 -287.04439) (xy 306.160887 -287.050322) (xy 306.208158 -287.064014)
			(xy 306.25262 -287.085112) (xy 306.293123 -287.113068) (xy 306.328616 -287.14716) (xy 306.358181 -287.186504)
			(xy 306.381052 -287.230081) (xy 306.396636 -287.276762) (xy 306.404531 -287.325339) (xy 306.405026 -287.349946)
			(xy 306.743874 -287.349946) (xy 306.747834 -287.300892) (xy 306.759611 -287.253108) (xy 306.778902 -287.207832)
			(xy 306.805205 -287.166236) (xy 306.83784 -287.129399) (xy 306.875961 -287.098274) (xy 306.918582 -287.073667)
			(xy 306.964598 -287.056215) (xy 307.012817 -287.046371) (xy 307.061992 -287.04439) (xy 307.110847 -287.050322)
			(xy 307.158118 -287.064014) (xy 307.20258 -287.085112) (xy 307.243083 -287.113068) (xy 307.278576 -287.14716)
			(xy 307.308141 -287.186504) (xy 307.331012 -287.230081) (xy 307.346596 -287.276762) (xy 307.354491 -287.325339)
			(xy 307.354986 -287.349946) (xy 307.694088 -287.349946) (xy 307.698048 -287.300892) (xy 307.709825 -287.253108)
			(xy 307.729116 -287.207832) (xy 307.755419 -287.166236) (xy 307.788054 -287.129399) (xy 307.826175 -287.098274)
			(xy 307.868796 -287.073667) (xy 307.914812 -287.056215) (xy 307.963031 -287.046371) (xy 308.012206 -287.04439)
			(xy 308.061061 -287.050322) (xy 308.108332 -287.064014) (xy 308.152794 -287.085112) (xy 308.193297 -287.113068)
			(xy 308.22879 -287.14716) (xy 308.258355 -287.186504) (xy 308.281226 -287.230081) (xy 308.29681 -287.276762)
			(xy 308.304705 -287.325339) (xy 308.3052 -287.349946) (xy 308.644048 -287.349946) (xy 308.648008 -287.300892)
			(xy 308.659785 -287.253108) (xy 308.679076 -287.207832) (xy 308.705379 -287.166236) (xy 308.738014 -287.129399)
			(xy 308.776135 -287.098274) (xy 308.818756 -287.073667) (xy 308.864772 -287.056215) (xy 308.912991 -287.046371)
			(xy 308.962166 -287.04439) (xy 309.011021 -287.050322) (xy 309.058292 -287.064014) (xy 309.102754 -287.085112)
			(xy 309.143257 -287.113068) (xy 309.17875 -287.14716) (xy 309.208315 -287.186504) (xy 309.231186 -287.230081)
			(xy 309.24677 -287.276762) (xy 309.254665 -287.325339) (xy 309.25516 -287.349946) (xy 309.594008 -287.349946)
			(xy 309.597968 -287.300892) (xy 309.609745 -287.253108) (xy 309.629036 -287.207832) (xy 309.655339 -287.166236)
			(xy 309.687974 -287.129399) (xy 309.726095 -287.098274) (xy 309.768716 -287.073667) (xy 309.814732 -287.056215)
			(xy 309.862951 -287.046371) (xy 309.912126 -287.04439) (xy 309.960981 -287.050322) (xy 310.008252 -287.064014)
			(xy 310.052714 -287.085112) (xy 310.093217 -287.113068) (xy 310.12871 -287.14716) (xy 310.158275 -287.186504)
			(xy 310.181146 -287.230081) (xy 310.19673 -287.276762) (xy 310.204625 -287.325339) (xy 310.20512 -287.349946)
			(xy 310.543968 -287.349946) (xy 310.547928 -287.300892) (xy 310.559705 -287.253108) (xy 310.578996 -287.207832)
			(xy 310.605299 -287.166236) (xy 310.637934 -287.129399) (xy 310.676055 -287.098274) (xy 310.718676 -287.073667)
			(xy 310.764692 -287.056215) (xy 310.812911 -287.046371) (xy 310.862086 -287.04439) (xy 310.910941 -287.050322)
			(xy 310.958212 -287.064014) (xy 311.002674 -287.085112) (xy 311.043177 -287.113068) (xy 311.07867 -287.14716)
			(xy 311.108235 -287.186504) (xy 311.131106 -287.230081) (xy 311.14669 -287.276762) (xy 311.154585 -287.325339)
			(xy 311.15508 -287.349946) (xy 311.493674 -287.349946) (xy 311.497634 -287.300892) (xy 311.509411 -287.253108)
			(xy 311.528702 -287.207832) (xy 311.555005 -287.166236) (xy 311.58764 -287.129399) (xy 311.625761 -287.098274)
			(xy 311.668382 -287.073667) (xy 311.714398 -287.056215) (xy 311.762617 -287.046371) (xy 311.811792 -287.04439)
			(xy 311.860647 -287.050322) (xy 311.907918 -287.064014) (xy 311.95238 -287.085112) (xy 311.992883 -287.113068)
			(xy 312.028376 -287.14716) (xy 312.057941 -287.186504) (xy 312.080812 -287.230081) (xy 312.096396 -287.276762)
			(xy 312.104291 -287.325339) (xy 312.104786 -287.349946) (xy 312.443888 -287.349946) (xy 312.447848 -287.300892)
			(xy 312.459625 -287.253108) (xy 312.478916 -287.207832) (xy 312.505219 -287.166236) (xy 312.537854 -287.129399)
			(xy 312.575975 -287.098274) (xy 312.618596 -287.073667) (xy 312.664612 -287.056215) (xy 312.712831 -287.046371)
			(xy 312.762006 -287.04439) (xy 312.810861 -287.050322) (xy 312.858132 -287.064014) (xy 312.902594 -287.085112)
			(xy 312.943097 -287.113068) (xy 312.97859 -287.14716) (xy 313.008155 -287.186504) (xy 313.031026 -287.230081)
			(xy 313.04661 -287.276762) (xy 313.054505 -287.325339) (xy 313.055 -287.349946) (xy 313.054505 -287.374553)
			(xy 313.054326 -287.375654) (xy 313.373258 -287.375654) (xy 313.373258 -287.324238) (xy 313.381301 -287.273456)
			(xy 313.397189 -287.224557) (xy 313.420532 -287.178745) (xy 313.450753 -287.137149) (xy 313.487109 -287.100793)
			(xy 313.528705 -287.070572) (xy 313.574517 -287.047229) (xy 313.623416 -287.031341) (xy 313.674198 -287.023298)
			(xy 313.725614 -287.023298) (xy 313.776396 -287.031341) (xy 313.825295 -287.047229) (xy 313.871107 -287.070572)
			(xy 313.912703 -287.100793) (xy 313.949059 -287.137149) (xy 313.97928 -287.178745) (xy 314.002623 -287.224557)
			(xy 314.018511 -287.273456) (xy 314.026554 -287.324238) (xy 314.027058 -287.349946) (xy 314.026554 -287.375654)
			(xy 314.323218 -287.375654) (xy 314.323218 -287.324238) (xy 314.331261 -287.273456) (xy 314.347149 -287.224557)
			(xy 314.370492 -287.178745) (xy 314.400713 -287.137149) (xy 314.437069 -287.100793) (xy 314.478665 -287.070572)
			(xy 314.524477 -287.047229) (xy 314.573376 -287.031341) (xy 314.624158 -287.023298) (xy 314.675574 -287.023298)
			(xy 314.726356 -287.031341) (xy 314.775255 -287.047229) (xy 314.821067 -287.070572) (xy 314.862663 -287.100793)
			(xy 314.899019 -287.137149) (xy 314.92924 -287.178745) (xy 314.952583 -287.224557) (xy 314.968471 -287.273456)
			(xy 314.976514 -287.324238) (xy 314.977018 -287.349946) (xy 314.977013 -287.3502) (xy 315.294276 -287.3502)
			(xy 315.298236 -287.301146) (xy 315.310013 -287.253362) (xy 315.329304 -287.208086) (xy 315.355607 -287.16649)
			(xy 315.388242 -287.129653) (xy 315.426363 -287.098528) (xy 315.468984 -287.073921) (xy 315.515 -287.056469)
			(xy 315.563219 -287.046625) (xy 315.612394 -287.044644) (xy 315.661249 -287.050576) (xy 315.70852 -287.064268)
			(xy 315.752982 -287.085366) (xy 315.793485 -287.113322) (xy 315.828978 -287.147414) (xy 315.858543 -287.186758)
			(xy 315.881414 -287.230335) (xy 315.896998 -287.277016) (xy 315.904893 -287.325593) (xy 315.905388 -287.3502)
			(xy 315.904893 -287.374807) (xy 315.896998 -287.423384) (xy 315.881414 -287.470065) (xy 315.858543 -287.513642)
			(xy 315.828978 -287.552986) (xy 315.793485 -287.587078) (xy 315.752982 -287.615034) (xy 315.70852 -287.636132)
			(xy 315.661249 -287.649824) (xy 315.612394 -287.655756) (xy 315.563219 -287.653775) (xy 315.515 -287.643931)
			(xy 315.468984 -287.626479) (xy 315.426363 -287.601872) (xy 315.388242 -287.570747) (xy 315.355607 -287.53391)
			(xy 315.329304 -287.492314) (xy 315.310013 -287.447038) (xy 315.298236 -287.399254) (xy 315.294276 -287.3502)
			(xy 314.977013 -287.3502) (xy 314.976514 -287.375654) (xy 314.968471 -287.426436) (xy 314.952583 -287.475335)
			(xy 314.92924 -287.521147) (xy 314.899019 -287.562743) (xy 314.862663 -287.599099) (xy 314.821067 -287.62932)
			(xy 314.775255 -287.652663) (xy 314.726356 -287.668551) (xy 314.675574 -287.676594) (xy 314.624158 -287.676594)
			(xy 314.573376 -287.668551) (xy 314.524477 -287.652663) (xy 314.478665 -287.62932) (xy 314.437069 -287.599099)
			(xy 314.400713 -287.562743) (xy 314.370492 -287.521147) (xy 314.347149 -287.475335) (xy 314.331261 -287.426436)
			(xy 314.323218 -287.375654) (xy 314.026554 -287.375654) (xy 314.018511 -287.426436) (xy 314.002623 -287.475335)
			(xy 313.97928 -287.521147) (xy 313.949059 -287.562743) (xy 313.912703 -287.599099) (xy 313.871107 -287.62932)
			(xy 313.825295 -287.652663) (xy 313.776396 -287.668551) (xy 313.725614 -287.676594) (xy 313.674198 -287.676594)
			(xy 313.623416 -287.668551) (xy 313.574517 -287.652663) (xy 313.528705 -287.62932) (xy 313.487109 -287.599099)
			(xy 313.450753 -287.562743) (xy 313.420532 -287.521147) (xy 313.397189 -287.475335) (xy 313.381301 -287.426436)
			(xy 313.373258 -287.375654) (xy 313.054326 -287.375654) (xy 313.04661 -287.42313) (xy 313.031026 -287.469811)
			(xy 313.008155 -287.513388) (xy 312.97859 -287.552732) (xy 312.943097 -287.586824) (xy 312.902594 -287.61478)
			(xy 312.858132 -287.635878) (xy 312.810861 -287.64957) (xy 312.762006 -287.655502) (xy 312.712831 -287.653521)
			(xy 312.664612 -287.643677) (xy 312.618596 -287.626225) (xy 312.575975 -287.601618) (xy 312.537854 -287.570493)
			(xy 312.505219 -287.533656) (xy 312.478916 -287.49206) (xy 312.459625 -287.446784) (xy 312.447848 -287.399)
			(xy 312.443888 -287.349946) (xy 312.104786 -287.349946) (xy 312.104291 -287.374553) (xy 312.096396 -287.42313)
			(xy 312.080812 -287.469811) (xy 312.057941 -287.513388) (xy 312.028376 -287.552732) (xy 311.992883 -287.586824)
			(xy 311.95238 -287.61478) (xy 311.907918 -287.635878) (xy 311.860647 -287.64957) (xy 311.811792 -287.655502)
			(xy 311.762617 -287.653521) (xy 311.714398 -287.643677) (xy 311.668382 -287.626225) (xy 311.625761 -287.601618)
			(xy 311.58764 -287.570493) (xy 311.555005 -287.533656) (xy 311.528702 -287.49206) (xy 311.509411 -287.446784)
			(xy 311.497634 -287.399) (xy 311.493674 -287.349946) (xy 311.15508 -287.349946) (xy 311.154585 -287.374553)
			(xy 311.14669 -287.42313) (xy 311.131106 -287.469811) (xy 311.108235 -287.513388) (xy 311.07867 -287.552732)
			(xy 311.043177 -287.586824) (xy 311.002674 -287.61478) (xy 310.958212 -287.635878) (xy 310.910941 -287.64957)
			(xy 310.862086 -287.655502) (xy 310.812911 -287.653521) (xy 310.764692 -287.643677) (xy 310.718676 -287.626225)
			(xy 310.676055 -287.601618) (xy 310.637934 -287.570493) (xy 310.605299 -287.533656) (xy 310.578996 -287.49206)
			(xy 310.559705 -287.446784) (xy 310.547928 -287.399) (xy 310.543968 -287.349946) (xy 310.20512 -287.349946)
			(xy 310.204625 -287.374553) (xy 310.19673 -287.42313) (xy 310.181146 -287.469811) (xy 310.158275 -287.513388)
			(xy 310.12871 -287.552732) (xy 310.093217 -287.586824) (xy 310.052714 -287.61478) (xy 310.008252 -287.635878)
			(xy 309.960981 -287.64957) (xy 309.912126 -287.655502) (xy 309.862951 -287.653521) (xy 309.814732 -287.643677)
			(xy 309.768716 -287.626225) (xy 309.726095 -287.601618) (xy 309.687974 -287.570493) (xy 309.655339 -287.533656)
			(xy 309.629036 -287.49206) (xy 309.609745 -287.446784) (xy 309.597968 -287.399) (xy 309.594008 -287.349946)
			(xy 309.25516 -287.349946) (xy 309.254665 -287.374553) (xy 309.24677 -287.42313) (xy 309.231186 -287.469811)
			(xy 309.208315 -287.513388) (xy 309.17875 -287.552732) (xy 309.143257 -287.586824) (xy 309.102754 -287.61478)
			(xy 309.058292 -287.635878) (xy 309.011021 -287.64957) (xy 308.962166 -287.655502) (xy 308.912991 -287.653521)
			(xy 308.864772 -287.643677) (xy 308.818756 -287.626225) (xy 308.776135 -287.601618) (xy 308.738014 -287.570493)
			(xy 308.705379 -287.533656) (xy 308.679076 -287.49206) (xy 308.659785 -287.446784) (xy 308.648008 -287.399)
			(xy 308.644048 -287.349946) (xy 308.3052 -287.349946) (xy 308.304705 -287.374553) (xy 308.29681 -287.42313)
			(xy 308.281226 -287.469811) (xy 308.258355 -287.513388) (xy 308.22879 -287.552732) (xy 308.193297 -287.586824)
			(xy 308.152794 -287.61478) (xy 308.108332 -287.635878) (xy 308.061061 -287.64957) (xy 308.012206 -287.655502)
			(xy 307.963031 -287.653521) (xy 307.914812 -287.643677) (xy 307.868796 -287.626225) (xy 307.826175 -287.601618)
			(xy 307.788054 -287.570493) (xy 307.755419 -287.533656) (xy 307.729116 -287.49206) (xy 307.709825 -287.446784)
			(xy 307.698048 -287.399) (xy 307.694088 -287.349946) (xy 307.354986 -287.349946) (xy 307.354491 -287.374553)
			(xy 307.346596 -287.42313) (xy 307.331012 -287.469811) (xy 307.308141 -287.513388) (xy 307.278576 -287.552732)
			(xy 307.243083 -287.586824) (xy 307.20258 -287.61478) (xy 307.158118 -287.635878) (xy 307.110847 -287.64957)
			(xy 307.061992 -287.655502) (xy 307.012817 -287.653521) (xy 306.964598 -287.643677) (xy 306.918582 -287.626225)
			(xy 306.875961 -287.601618) (xy 306.83784 -287.570493) (xy 306.805205 -287.533656) (xy 306.778902 -287.49206)
			(xy 306.759611 -287.446784) (xy 306.747834 -287.399) (xy 306.743874 -287.349946) (xy 306.405026 -287.349946)
			(xy 306.404531 -287.374553) (xy 306.396636 -287.42313) (xy 306.381052 -287.469811) (xy 306.358181 -287.513388)
			(xy 306.328616 -287.552732) (xy 306.293123 -287.586824) (xy 306.25262 -287.61478) (xy 306.208158 -287.635878)
			(xy 306.160887 -287.64957) (xy 306.112032 -287.655502) (xy 306.062857 -287.653521) (xy 306.014638 -287.643677)
			(xy 305.968622 -287.626225) (xy 305.926001 -287.601618) (xy 305.88788 -287.570493) (xy 305.855245 -287.533656)
			(xy 305.828942 -287.49206) (xy 305.809651 -287.446784) (xy 305.797874 -287.399) (xy 305.793914 -287.349946)
			(xy 280.268426 -287.349946) (xy 280.268426 -287.730184) (xy 280.268934 -287.73628) (xy 280.270204 -287.747456)
			(xy 280.270966 -287.750758) (xy 280.270966 -287.751266) (xy 280.275216 -287.769385) (xy 280.279797 -287.806318)
			(xy 280.28011 -287.824926) (xy 280.618958 -287.824926) (xy 280.622918 -287.775872) (xy 280.634695 -287.728088)
			(xy 280.653986 -287.682812) (xy 280.680289 -287.641216) (xy 280.712924 -287.604379) (xy 280.751045 -287.573254)
			(xy 280.793666 -287.548647) (xy 280.839682 -287.531195) (xy 280.887901 -287.521351) (xy 280.937076 -287.51937)
			(xy 280.985931 -287.525302) (xy 281.033202 -287.538994) (xy 281.077664 -287.560092) (xy 281.118167 -287.588048)
			(xy 281.15366 -287.62214) (xy 281.183225 -287.661484) (xy 281.206096 -287.705061) (xy 281.22168 -287.751742)
			(xy 281.229575 -287.800319) (xy 281.23007 -287.824926) (xy 281.568918 -287.824926) (xy 281.572878 -287.775872)
			(xy 281.584655 -287.728088) (xy 281.603946 -287.682812) (xy 281.630249 -287.641216) (xy 281.662884 -287.604379)
			(xy 281.701005 -287.573254) (xy 281.743626 -287.548647) (xy 281.789642 -287.531195) (xy 281.837861 -287.521351)
			(xy 281.887036 -287.51937) (xy 281.935891 -287.525302) (xy 281.983162 -287.538994) (xy 282.027624 -287.560092)
			(xy 282.068127 -287.588048) (xy 282.10362 -287.62214) (xy 282.133185 -287.661484) (xy 282.156056 -287.705061)
			(xy 282.17164 -287.751742) (xy 282.179535 -287.800319) (xy 282.18003 -287.824926) (xy 282.519132 -287.824926)
			(xy 282.523092 -287.775872) (xy 282.534869 -287.728088) (xy 282.55416 -287.682812) (xy 282.580463 -287.641216)
			(xy 282.613098 -287.604379) (xy 282.651219 -287.573254) (xy 282.69384 -287.548647) (xy 282.739856 -287.531195)
			(xy 282.788075 -287.521351) (xy 282.83725 -287.51937) (xy 282.886105 -287.525302) (xy 282.933376 -287.538994)
			(xy 282.977838 -287.560092) (xy 283.018341 -287.588048) (xy 283.053834 -287.62214) (xy 283.083399 -287.661484)
			(xy 283.10627 -287.705061) (xy 283.121854 -287.751742) (xy 283.129749 -287.800319) (xy 283.130244 -287.824926)
			(xy 283.469092 -287.824926) (xy 283.473052 -287.775872) (xy 283.484829 -287.728088) (xy 283.50412 -287.682812)
			(xy 283.530423 -287.641216) (xy 283.563058 -287.604379) (xy 283.601179 -287.573254) (xy 283.6438 -287.548647)
			(xy 283.689816 -287.531195) (xy 283.738035 -287.521351) (xy 283.78721 -287.51937) (xy 283.836065 -287.525302)
			(xy 283.883336 -287.538994) (xy 283.927798 -287.560092) (xy 283.968301 -287.588048) (xy 284.003794 -287.62214)
			(xy 284.033359 -287.661484) (xy 284.05623 -287.705061) (xy 284.071814 -287.751742) (xy 284.079709 -287.800319)
			(xy 284.080204 -287.824926) (xy 284.419052 -287.824926) (xy 284.423012 -287.775872) (xy 284.434789 -287.728088)
			(xy 284.45408 -287.682812) (xy 284.480383 -287.641216) (xy 284.513018 -287.604379) (xy 284.551139 -287.573254)
			(xy 284.59376 -287.548647) (xy 284.639776 -287.531195) (xy 284.687995 -287.521351) (xy 284.73717 -287.51937)
			(xy 284.786025 -287.525302) (xy 284.833296 -287.538994) (xy 284.877758 -287.560092) (xy 284.918261 -287.588048)
			(xy 284.953754 -287.62214) (xy 284.983319 -287.661484) (xy 285.00619 -287.705061) (xy 285.021774 -287.751742)
			(xy 285.029669 -287.800319) (xy 285.030164 -287.824926) (xy 285.369012 -287.824926) (xy 285.372972 -287.775872)
			(xy 285.384749 -287.728088) (xy 285.40404 -287.682812) (xy 285.430343 -287.641216) (xy 285.462978 -287.604379)
			(xy 285.501099 -287.573254) (xy 285.54372 -287.548647) (xy 285.589736 -287.531195) (xy 285.637955 -287.521351)
			(xy 285.68713 -287.51937) (xy 285.735985 -287.525302) (xy 285.783256 -287.538994) (xy 285.827718 -287.560092)
			(xy 285.868221 -287.588048) (xy 285.903714 -287.62214) (xy 285.933279 -287.661484) (xy 285.95615 -287.705061)
			(xy 285.971734 -287.751742) (xy 285.979629 -287.800319) (xy 285.980124 -287.824926) (xy 286.318972 -287.824926)
			(xy 286.322932 -287.775872) (xy 286.334709 -287.728088) (xy 286.354 -287.682812) (xy 286.380303 -287.641216)
			(xy 286.412938 -287.604379) (xy 286.451059 -287.573254) (xy 286.49368 -287.548647) (xy 286.539696 -287.531195)
			(xy 286.587915 -287.521351) (xy 286.63709 -287.51937) (xy 286.685945 -287.525302) (xy 286.733216 -287.538994)
			(xy 286.777678 -287.560092) (xy 286.818181 -287.588048) (xy 286.853674 -287.62214) (xy 286.883239 -287.661484)
			(xy 286.90611 -287.705061) (xy 286.921694 -287.751742) (xy 286.929589 -287.800319) (xy 286.930084 -287.824926)
			(xy 287.268932 -287.824926) (xy 287.272892 -287.775872) (xy 287.284669 -287.728088) (xy 287.30396 -287.682812)
			(xy 287.330263 -287.641216) (xy 287.362898 -287.604379) (xy 287.401019 -287.573254) (xy 287.44364 -287.548647)
			(xy 287.489656 -287.531195) (xy 287.537875 -287.521351) (xy 287.58705 -287.51937) (xy 287.635905 -287.525302)
			(xy 287.683176 -287.538994) (xy 287.727638 -287.560092) (xy 287.768141 -287.588048) (xy 287.803634 -287.62214)
			(xy 287.833199 -287.661484) (xy 287.85607 -287.705061) (xy 287.871654 -287.751742) (xy 287.879549 -287.800319)
			(xy 287.880044 -287.824926) (xy 288.218892 -287.824926) (xy 288.222852 -287.775872) (xy 288.234629 -287.728088)
			(xy 288.25392 -287.682812) (xy 288.280223 -287.641216) (xy 288.312858 -287.604379) (xy 288.350979 -287.573254)
			(xy 288.3936 -287.548647) (xy 288.439616 -287.531195) (xy 288.487835 -287.521351) (xy 288.53701 -287.51937)
			(xy 288.585865 -287.525302) (xy 288.633136 -287.538994) (xy 288.677598 -287.560092) (xy 288.718101 -287.588048)
			(xy 288.753594 -287.62214) (xy 288.783159 -287.661484) (xy 288.80603 -287.705061) (xy 288.821614 -287.751742)
			(xy 288.829509 -287.800319) (xy 288.830004 -287.824926) (xy 289.169106 -287.824926) (xy 289.173066 -287.775872)
			(xy 289.184843 -287.728088) (xy 289.204134 -287.682812) (xy 289.230437 -287.641216) (xy 289.263072 -287.604379)
			(xy 289.301193 -287.573254) (xy 289.343814 -287.548647) (xy 289.38983 -287.531195) (xy 289.438049 -287.521351)
			(xy 289.487224 -287.51937) (xy 289.536079 -287.525302) (xy 289.58335 -287.538994) (xy 289.627812 -287.560092)
			(xy 289.668315 -287.588048) (xy 289.703808 -287.62214) (xy 289.733373 -287.661484) (xy 289.753566 -287.699958)
			(xy 290.143958 -287.699958) (xy 290.147918 -287.650904) (xy 290.159695 -287.60312) (xy 290.178986 -287.557844)
			(xy 290.205289 -287.516248) (xy 290.237924 -287.479411) (xy 290.276045 -287.448286) (xy 290.318666 -287.423679)
			(xy 290.364682 -287.406227) (xy 290.412901 -287.396383) (xy 290.462076 -287.394402) (xy 290.510931 -287.400334)
			(xy 290.558202 -287.414026) (xy 290.602664 -287.435124) (xy 290.643167 -287.46308) (xy 290.67866 -287.497172)
			(xy 290.708225 -287.536516) (xy 290.731096 -287.580093) (xy 290.74668 -287.626774) (xy 290.754575 -287.675351)
			(xy 290.75507 -287.699958) (xy 290.754575 -287.724565) (xy 290.74668 -287.773142) (xy 290.731096 -287.819823)
			(xy 290.708225 -287.8634) (xy 290.68083 -287.899856) (xy 292.018986 -287.899856) (xy 292.022946 -287.850802)
			(xy 292.034723 -287.803018) (xy 292.054014 -287.757742) (xy 292.080317 -287.716146) (xy 292.112952 -287.679309)
			(xy 292.151073 -287.648184) (xy 292.193694 -287.623577) (xy 292.23971 -287.606125) (xy 292.287929 -287.596281)
			(xy 292.337104 -287.5943) (xy 292.385959 -287.600232) (xy 292.43323 -287.613924) (xy 292.477692 -287.635022)
			(xy 292.518195 -287.662978) (xy 292.553688 -287.69707) (xy 292.583253 -287.736414) (xy 292.606124 -287.779991)
			(xy 292.621125 -287.824926) (xy 292.968946 -287.824926) (xy 292.972906 -287.775872) (xy 292.984683 -287.728088)
			(xy 293.003974 -287.682812) (xy 293.030277 -287.641216) (xy 293.062912 -287.604379) (xy 293.101033 -287.573254)
			(xy 293.143654 -287.548647) (xy 293.18967 -287.531195) (xy 293.237889 -287.521351) (xy 293.287064 -287.51937)
			(xy 293.335919 -287.525302) (xy 293.38319 -287.538994) (xy 293.427652 -287.560092) (xy 293.468155 -287.588048)
			(xy 293.503648 -287.62214) (xy 293.533213 -287.661484) (xy 293.556084 -287.705061) (xy 293.571668 -287.751742)
			(xy 293.579563 -287.800319) (xy 293.580058 -287.824926) (xy 293.918906 -287.824926) (xy 293.922866 -287.775872)
			(xy 293.934643 -287.728088) (xy 293.953934 -287.682812) (xy 293.980237 -287.641216) (xy 294.012872 -287.604379)
			(xy 294.050993 -287.573254) (xy 294.093614 -287.548647) (xy 294.13963 -287.531195) (xy 294.187849 -287.521351)
			(xy 294.237024 -287.51937) (xy 294.285879 -287.525302) (xy 294.33315 -287.538994) (xy 294.377612 -287.560092)
			(xy 294.418115 -287.588048) (xy 294.453608 -287.62214) (xy 294.483173 -287.661484) (xy 294.506044 -287.705061)
			(xy 294.521628 -287.751742) (xy 294.529523 -287.800319) (xy 294.530018 -287.824926) (xy 294.86912 -287.824926)
			(xy 294.87308 -287.775872) (xy 294.884857 -287.728088) (xy 294.904148 -287.682812) (xy 294.930451 -287.641216)
			(xy 294.963086 -287.604379) (xy 295.001207 -287.573254) (xy 295.043828 -287.548647) (xy 295.089844 -287.531195)
			(xy 295.138063 -287.521351) (xy 295.187238 -287.51937) (xy 295.236093 -287.525302) (xy 295.283364 -287.538994)
			(xy 295.327826 -287.560092) (xy 295.368329 -287.588048) (xy 295.403822 -287.62214) (xy 295.433387 -287.661484)
			(xy 295.456258 -287.705061) (xy 295.471842 -287.751742) (xy 295.479737 -287.800319) (xy 295.480232 -287.824926)
			(xy 295.81908 -287.824926) (xy 295.82304 -287.775872) (xy 295.834817 -287.728088) (xy 295.854108 -287.682812)
			(xy 295.880411 -287.641216) (xy 295.913046 -287.604379) (xy 295.951167 -287.573254) (xy 295.993788 -287.548647)
			(xy 296.039804 -287.531195) (xy 296.088023 -287.521351) (xy 296.137198 -287.51937) (xy 296.186053 -287.525302)
			(xy 296.233324 -287.538994) (xy 296.277786 -287.560092) (xy 296.318289 -287.588048) (xy 296.353782 -287.62214)
			(xy 296.383347 -287.661484) (xy 296.406218 -287.705061) (xy 296.421802 -287.751742) (xy 296.429697 -287.800319)
			(xy 296.430192 -287.824926) (xy 296.76904 -287.824926) (xy 296.773 -287.775872) (xy 296.784777 -287.728088)
			(xy 296.804068 -287.682812) (xy 296.830371 -287.641216) (xy 296.863006 -287.604379) (xy 296.901127 -287.573254)
			(xy 296.943748 -287.548647) (xy 296.989764 -287.531195) (xy 297.037983 -287.521351) (xy 297.087158 -287.51937)
			(xy 297.136013 -287.525302) (xy 297.183284 -287.538994) (xy 297.227746 -287.560092) (xy 297.268249 -287.588048)
			(xy 297.303742 -287.62214) (xy 297.333307 -287.661484) (xy 297.356178 -287.705061) (xy 297.371762 -287.751742)
			(xy 297.379657 -287.800319) (xy 297.380152 -287.824926) (xy 297.719 -287.824926) (xy 297.72296 -287.775872)
			(xy 297.734737 -287.728088) (xy 297.754028 -287.682812) (xy 297.780331 -287.641216) (xy 297.812966 -287.604379)
			(xy 297.851087 -287.573254) (xy 297.893708 -287.548647) (xy 297.939724 -287.531195) (xy 297.987943 -287.521351)
			(xy 298.037118 -287.51937) (xy 298.085973 -287.525302) (xy 298.133244 -287.538994) (xy 298.177706 -287.560092)
			(xy 298.218209 -287.588048) (xy 298.253702 -287.62214) (xy 298.283267 -287.661484) (xy 298.306138 -287.705061)
			(xy 298.321722 -287.751742) (xy 298.329617 -287.800319) (xy 298.330112 -287.824926) (xy 298.66896 -287.824926)
			(xy 298.67292 -287.775872) (xy 298.684697 -287.728088) (xy 298.703988 -287.682812) (xy 298.730291 -287.641216)
			(xy 298.762926 -287.604379) (xy 298.801047 -287.573254) (xy 298.843668 -287.548647) (xy 298.889684 -287.531195)
			(xy 298.937903 -287.521351) (xy 298.987078 -287.51937) (xy 299.035933 -287.525302) (xy 299.083204 -287.538994)
			(xy 299.127666 -287.560092) (xy 299.168169 -287.588048) (xy 299.203662 -287.62214) (xy 299.233227 -287.661484)
			(xy 299.256098 -287.705061) (xy 299.271682 -287.751742) (xy 299.279577 -287.800319) (xy 299.280072 -287.824926)
			(xy 299.61892 -287.824926) (xy 299.62288 -287.775872) (xy 299.634657 -287.728088) (xy 299.653948 -287.682812)
			(xy 299.680251 -287.641216) (xy 299.712886 -287.604379) (xy 299.751007 -287.573254) (xy 299.793628 -287.548647)
			(xy 299.839644 -287.531195) (xy 299.887863 -287.521351) (xy 299.937038 -287.51937) (xy 299.985893 -287.525302)
			(xy 300.033164 -287.538994) (xy 300.077626 -287.560092) (xy 300.118129 -287.588048) (xy 300.153622 -287.62214)
			(xy 300.183187 -287.661484) (xy 300.206058 -287.705061) (xy 300.221642 -287.751742) (xy 300.229537 -287.800319)
			(xy 300.230032 -287.824926) (xy 300.56888 -287.824926) (xy 300.57284 -287.775872) (xy 300.584617 -287.728088)
			(xy 300.603908 -287.682812) (xy 300.630211 -287.641216) (xy 300.662846 -287.604379) (xy 300.700967 -287.573254)
			(xy 300.743588 -287.548647) (xy 300.789604 -287.531195) (xy 300.837823 -287.521351) (xy 300.886998 -287.51937)
			(xy 300.935853 -287.525302) (xy 300.983124 -287.538994) (xy 301.027586 -287.560092) (xy 301.068089 -287.588048)
			(xy 301.103582 -287.62214) (xy 301.133147 -287.661484) (xy 301.156018 -287.705061) (xy 301.171602 -287.751742)
			(xy 301.179497 -287.800319) (xy 301.179992 -287.824926) (xy 302.469054 -287.824926) (xy 302.473014 -287.775872)
			(xy 302.484791 -287.728088) (xy 302.504082 -287.682812) (xy 302.530385 -287.641216) (xy 302.56302 -287.604379)
			(xy 302.601141 -287.573254) (xy 302.643762 -287.548647) (xy 302.689778 -287.531195) (xy 302.737997 -287.521351)
			(xy 302.787172 -287.51937) (xy 302.836027 -287.525302) (xy 302.883298 -287.538994) (xy 302.92776 -287.560092)
			(xy 302.968263 -287.588048) (xy 303.003756 -287.62214) (xy 303.033321 -287.661484) (xy 303.056192 -287.705061)
			(xy 303.071776 -287.751742) (xy 303.079671 -287.800319) (xy 303.080166 -287.824926) (xy 303.079671 -287.849533)
			(xy 303.071776 -287.89811) (xy 303.056192 -287.944791) (xy 303.033321 -287.988368) (xy 303.003756 -288.027712)
			(xy 302.968263 -288.061804) (xy 302.92776 -288.08976) (xy 302.883298 -288.110858) (xy 302.836027 -288.12455)
			(xy 302.787172 -288.130482) (xy 302.737997 -288.128501) (xy 302.689778 -288.118657) (xy 302.643762 -288.101205)
			(xy 302.601141 -288.076598) (xy 302.56302 -288.045473) (xy 302.530385 -288.008636) (xy 302.504082 -287.96704)
			(xy 302.484791 -287.921764) (xy 302.473014 -287.87398) (xy 302.469054 -287.824926) (xy 301.179992 -287.824926)
			(xy 301.179497 -287.849533) (xy 301.171602 -287.89811) (xy 301.156018 -287.944791) (xy 301.133147 -287.988368)
			(xy 301.103582 -288.027712) (xy 301.068089 -288.061804) (xy 301.027586 -288.08976) (xy 300.983124 -288.110858)
			(xy 300.935853 -288.12455) (xy 300.886998 -288.130482) (xy 300.837823 -288.128501) (xy 300.789604 -288.118657)
			(xy 300.743588 -288.101205) (xy 300.700967 -288.076598) (xy 300.662846 -288.045473) (xy 300.630211 -288.008636)
			(xy 300.603908 -287.96704) (xy 300.584617 -287.921764) (xy 300.57284 -287.87398) (xy 300.56888 -287.824926)
			(xy 300.230032 -287.824926) (xy 300.229537 -287.849533) (xy 300.221642 -287.89811) (xy 300.206058 -287.944791)
			(xy 300.183187 -287.988368) (xy 300.153622 -288.027712) (xy 300.118129 -288.061804) (xy 300.077626 -288.08976)
			(xy 300.033164 -288.110858) (xy 299.985893 -288.12455) (xy 299.937038 -288.130482) (xy 299.887863 -288.128501)
			(xy 299.839644 -288.118657) (xy 299.793628 -288.101205) (xy 299.751007 -288.076598) (xy 299.712886 -288.045473)
			(xy 299.680251 -288.008636) (xy 299.653948 -287.96704) (xy 299.634657 -287.921764) (xy 299.62288 -287.87398)
			(xy 299.61892 -287.824926) (xy 299.280072 -287.824926) (xy 299.279577 -287.849533) (xy 299.271682 -287.89811)
			(xy 299.256098 -287.944791) (xy 299.233227 -287.988368) (xy 299.203662 -288.027712) (xy 299.168169 -288.061804)
			(xy 299.127666 -288.08976) (xy 299.083204 -288.110858) (xy 299.035933 -288.12455) (xy 298.987078 -288.130482)
			(xy 298.937903 -288.128501) (xy 298.889684 -288.118657) (xy 298.843668 -288.101205) (xy 298.801047 -288.076598)
			(xy 298.762926 -288.045473) (xy 298.730291 -288.008636) (xy 298.703988 -287.96704) (xy 298.684697 -287.921764)
			(xy 298.67292 -287.87398) (xy 298.66896 -287.824926) (xy 298.330112 -287.824926) (xy 298.329617 -287.849533)
			(xy 298.321722 -287.89811) (xy 298.306138 -287.944791) (xy 298.283267 -287.988368) (xy 298.253702 -288.027712)
			(xy 298.218209 -288.061804) (xy 298.177706 -288.08976) (xy 298.133244 -288.110858) (xy 298.085973 -288.12455)
			(xy 298.037118 -288.130482) (xy 297.987943 -288.128501) (xy 297.939724 -288.118657) (xy 297.893708 -288.101205)
			(xy 297.851087 -288.076598) (xy 297.812966 -288.045473) (xy 297.780331 -288.008636) (xy 297.754028 -287.96704)
			(xy 297.734737 -287.921764) (xy 297.72296 -287.87398) (xy 297.719 -287.824926) (xy 297.380152 -287.824926)
			(xy 297.379657 -287.849533) (xy 297.371762 -287.89811) (xy 297.356178 -287.944791) (xy 297.333307 -287.988368)
			(xy 297.303742 -288.027712) (xy 297.268249 -288.061804) (xy 297.227746 -288.08976) (xy 297.183284 -288.110858)
			(xy 297.136013 -288.12455) (xy 297.087158 -288.130482) (xy 297.037983 -288.128501) (xy 296.989764 -288.118657)
			(xy 296.943748 -288.101205) (xy 296.901127 -288.076598) (xy 296.863006 -288.045473) (xy 296.830371 -288.008636)
			(xy 296.804068 -287.96704) (xy 296.784777 -287.921764) (xy 296.773 -287.87398) (xy 296.76904 -287.824926)
			(xy 296.430192 -287.824926) (xy 296.429697 -287.849533) (xy 296.421802 -287.89811) (xy 296.406218 -287.944791)
			(xy 296.383347 -287.988368) (xy 296.353782 -288.027712) (xy 296.318289 -288.061804) (xy 296.277786 -288.08976)
			(xy 296.233324 -288.110858) (xy 296.186053 -288.12455) (xy 296.137198 -288.130482) (xy 296.088023 -288.128501)
			(xy 296.039804 -288.118657) (xy 295.993788 -288.101205) (xy 295.951167 -288.076598) (xy 295.913046 -288.045473)
			(xy 295.880411 -288.008636) (xy 295.854108 -287.96704) (xy 295.834817 -287.921764) (xy 295.82304 -287.87398)
			(xy 295.81908 -287.824926) (xy 295.480232 -287.824926) (xy 295.479737 -287.849533) (xy 295.471842 -287.89811)
			(xy 295.456258 -287.944791) (xy 295.433387 -287.988368) (xy 295.403822 -288.027712) (xy 295.368329 -288.061804)
			(xy 295.327826 -288.08976) (xy 295.283364 -288.110858) (xy 295.236093 -288.12455) (xy 295.187238 -288.130482)
			(xy 295.138063 -288.128501) (xy 295.089844 -288.118657) (xy 295.043828 -288.101205) (xy 295.001207 -288.076598)
			(xy 294.963086 -288.045473) (xy 294.930451 -288.008636) (xy 294.904148 -287.96704) (xy 294.884857 -287.921764)
			(xy 294.87308 -287.87398) (xy 294.86912 -287.824926) (xy 294.530018 -287.824926) (xy 294.529523 -287.849533)
			(xy 294.521628 -287.89811) (xy 294.506044 -287.944791) (xy 294.483173 -287.988368) (xy 294.453608 -288.027712)
			(xy 294.418115 -288.061804) (xy 294.377612 -288.08976) (xy 294.33315 -288.110858) (xy 294.285879 -288.12455)
			(xy 294.237024 -288.130482) (xy 294.187849 -288.128501) (xy 294.13963 -288.118657) (xy 294.093614 -288.101205)
			(xy 294.050993 -288.076598) (xy 294.012872 -288.045473) (xy 293.980237 -288.008636) (xy 293.953934 -287.96704)
			(xy 293.934643 -287.921764) (xy 293.922866 -287.87398) (xy 293.918906 -287.824926) (xy 293.580058 -287.824926)
			(xy 293.579563 -287.849533) (xy 293.571668 -287.89811) (xy 293.556084 -287.944791) (xy 293.533213 -287.988368)
			(xy 293.503648 -288.027712) (xy 293.468155 -288.061804) (xy 293.427652 -288.08976) (xy 293.38319 -288.110858)
			(xy 293.335919 -288.12455) (xy 293.287064 -288.130482) (xy 293.237889 -288.128501) (xy 293.18967 -288.118657)
			(xy 293.143654 -288.101205) (xy 293.101033 -288.076598) (xy 293.062912 -288.045473) (xy 293.030277 -288.008636)
			(xy 293.003974 -287.96704) (xy 292.984683 -287.921764) (xy 292.972906 -287.87398) (xy 292.968946 -287.824926)
			(xy 292.621125 -287.824926) (xy 292.621708 -287.826672) (xy 292.629603 -287.875249) (xy 292.630098 -287.899856)
			(xy 292.629603 -287.924463) (xy 292.621708 -287.97304) (xy 292.606124 -288.019721) (xy 292.583253 -288.063298)
			(xy 292.553688 -288.102642) (xy 292.518195 -288.136734) (xy 292.477692 -288.16469) (xy 292.43323 -288.185788)
			(xy 292.385959 -288.19948) (xy 292.337104 -288.205412) (xy 292.287929 -288.203431) (xy 292.23971 -288.193587)
			(xy 292.193694 -288.176135) (xy 292.151073 -288.151528) (xy 292.112952 -288.120403) (xy 292.080317 -288.083566)
			(xy 292.054014 -288.04197) (xy 292.034723 -287.996694) (xy 292.022946 -287.94891) (xy 292.018986 -287.899856)
			(xy 290.68083 -287.899856) (xy 290.67866 -287.902744) (xy 290.643167 -287.936836) (xy 290.602664 -287.964792)
			(xy 290.558202 -287.98589) (xy 290.510931 -287.999582) (xy 290.462076 -288.005514) (xy 290.412901 -288.003533)
			(xy 290.364682 -287.993689) (xy 290.318666 -287.976237) (xy 290.276045 -287.95163) (xy 290.237924 -287.920505)
			(xy 290.205289 -287.883668) (xy 290.178986 -287.842072) (xy 290.159695 -287.796796) (xy 290.147918 -287.749012)
			(xy 290.143958 -287.699958) (xy 289.753566 -287.699958) (xy 289.756244 -287.705061) (xy 289.771828 -287.751742)
			(xy 289.779723 -287.800319) (xy 289.780218 -287.824926) (xy 289.779723 -287.849533) (xy 289.771828 -287.89811)
			(xy 289.756244 -287.944791) (xy 289.733373 -287.988368) (xy 289.703808 -288.027712) (xy 289.668315 -288.061804)
			(xy 289.627812 -288.08976) (xy 289.58335 -288.110858) (xy 289.536079 -288.12455) (xy 289.487224 -288.130482)
			(xy 289.438049 -288.128501) (xy 289.38983 -288.118657) (xy 289.343814 -288.101205) (xy 289.301193 -288.076598)
			(xy 289.263072 -288.045473) (xy 289.230437 -288.008636) (xy 289.204134 -287.96704) (xy 289.184843 -287.921764)
			(xy 289.173066 -287.87398) (xy 289.169106 -287.824926) (xy 288.830004 -287.824926) (xy 288.829509 -287.849533)
			(xy 288.821614 -287.89811) (xy 288.80603 -287.944791) (xy 288.783159 -287.988368) (xy 288.753594 -288.027712)
			(xy 288.718101 -288.061804) (xy 288.677598 -288.08976) (xy 288.633136 -288.110858) (xy 288.585865 -288.12455)
			(xy 288.53701 -288.130482) (xy 288.487835 -288.128501) (xy 288.439616 -288.118657) (xy 288.3936 -288.101205)
			(xy 288.350979 -288.076598) (xy 288.312858 -288.045473) (xy 288.280223 -288.008636) (xy 288.25392 -287.96704)
			(xy 288.234629 -287.921764) (xy 288.222852 -287.87398) (xy 288.218892 -287.824926) (xy 287.880044 -287.824926)
			(xy 287.879549 -287.849533) (xy 287.871654 -287.89811) (xy 287.85607 -287.944791) (xy 287.833199 -287.988368)
			(xy 287.803634 -288.027712) (xy 287.768141 -288.061804) (xy 287.727638 -288.08976) (xy 287.683176 -288.110858)
			(xy 287.635905 -288.12455) (xy 287.58705 -288.130482) (xy 287.537875 -288.128501) (xy 287.489656 -288.118657)
			(xy 287.44364 -288.101205) (xy 287.401019 -288.076598) (xy 287.362898 -288.045473) (xy 287.330263 -288.008636)
			(xy 287.30396 -287.96704) (xy 287.284669 -287.921764) (xy 287.272892 -287.87398) (xy 287.268932 -287.824926)
			(xy 286.930084 -287.824926) (xy 286.929589 -287.849533) (xy 286.921694 -287.89811) (xy 286.90611 -287.944791)
			(xy 286.883239 -287.988368) (xy 286.853674 -288.027712) (xy 286.818181 -288.061804) (xy 286.777678 -288.08976)
			(xy 286.733216 -288.110858) (xy 286.685945 -288.12455) (xy 286.63709 -288.130482) (xy 286.587915 -288.128501)
			(xy 286.539696 -288.118657) (xy 286.49368 -288.101205) (xy 286.451059 -288.076598) (xy 286.412938 -288.045473)
			(xy 286.380303 -288.008636) (xy 286.354 -287.96704) (xy 286.334709 -287.921764) (xy 286.322932 -287.87398)
			(xy 286.318972 -287.824926) (xy 285.980124 -287.824926) (xy 285.979629 -287.849533) (xy 285.971734 -287.89811)
			(xy 285.95615 -287.944791) (xy 285.933279 -287.988368) (xy 285.903714 -288.027712) (xy 285.868221 -288.061804)
			(xy 285.827718 -288.08976) (xy 285.783256 -288.110858) (xy 285.735985 -288.12455) (xy 285.68713 -288.130482)
			(xy 285.637955 -288.128501) (xy 285.589736 -288.118657) (xy 285.54372 -288.101205) (xy 285.501099 -288.076598)
			(xy 285.462978 -288.045473) (xy 285.430343 -288.008636) (xy 285.40404 -287.96704) (xy 285.384749 -287.921764)
			(xy 285.372972 -287.87398) (xy 285.369012 -287.824926) (xy 285.030164 -287.824926) (xy 285.029669 -287.849533)
			(xy 285.021774 -287.89811) (xy 285.00619 -287.944791) (xy 284.983319 -287.988368) (xy 284.953754 -288.027712)
			(xy 284.918261 -288.061804) (xy 284.877758 -288.08976) (xy 284.833296 -288.110858) (xy 284.786025 -288.12455)
			(xy 284.73717 -288.130482) (xy 284.687995 -288.128501) (xy 284.639776 -288.118657) (xy 284.59376 -288.101205)
			(xy 284.551139 -288.076598) (xy 284.513018 -288.045473) (xy 284.480383 -288.008636) (xy 284.45408 -287.96704)
			(xy 284.434789 -287.921764) (xy 284.423012 -287.87398) (xy 284.419052 -287.824926) (xy 284.080204 -287.824926)
			(xy 284.079709 -287.849533) (xy 284.071814 -287.89811) (xy 284.05623 -287.944791) (xy 284.033359 -287.988368)
			(xy 284.003794 -288.027712) (xy 283.968301 -288.061804) (xy 283.927798 -288.08976) (xy 283.883336 -288.110858)
			(xy 283.836065 -288.12455) (xy 283.78721 -288.130482) (xy 283.738035 -288.128501) (xy 283.689816 -288.118657)
			(xy 283.6438 -288.101205) (xy 283.601179 -288.076598) (xy 283.563058 -288.045473) (xy 283.530423 -288.008636)
			(xy 283.50412 -287.96704) (xy 283.484829 -287.921764) (xy 283.473052 -287.87398) (xy 283.469092 -287.824926)
			(xy 283.130244 -287.824926) (xy 283.129749 -287.849533) (xy 283.121854 -287.89811) (xy 283.10627 -287.944791)
			(xy 283.083399 -287.988368) (xy 283.053834 -288.027712) (xy 283.018341 -288.061804) (xy 282.977838 -288.08976)
			(xy 282.933376 -288.110858) (xy 282.886105 -288.12455) (xy 282.83725 -288.130482) (xy 282.788075 -288.128501)
			(xy 282.739856 -288.118657) (xy 282.69384 -288.101205) (xy 282.651219 -288.076598) (xy 282.613098 -288.045473)
			(xy 282.580463 -288.008636) (xy 282.55416 -287.96704) (xy 282.534869 -287.921764) (xy 282.523092 -287.87398)
			(xy 282.519132 -287.824926) (xy 282.18003 -287.824926) (xy 282.179535 -287.849533) (xy 282.17164 -287.89811)
			(xy 282.156056 -287.944791) (xy 282.133185 -287.988368) (xy 282.10362 -288.027712) (xy 282.068127 -288.061804)
			(xy 282.027624 -288.08976) (xy 281.983162 -288.110858) (xy 281.935891 -288.12455) (xy 281.887036 -288.130482)
			(xy 281.837861 -288.128501) (xy 281.789642 -288.118657) (xy 281.743626 -288.101205) (xy 281.701005 -288.076598)
			(xy 281.662884 -288.045473) (xy 281.630249 -288.008636) (xy 281.603946 -287.96704) (xy 281.584655 -287.921764)
			(xy 281.572878 -287.87398) (xy 281.568918 -287.824926) (xy 281.23007 -287.824926) (xy 281.229575 -287.849533)
			(xy 281.22168 -287.89811) (xy 281.206096 -287.944791) (xy 281.183225 -287.988368) (xy 281.15366 -288.027712)
			(xy 281.118167 -288.061804) (xy 281.077664 -288.08976) (xy 281.033202 -288.110858) (xy 280.985931 -288.12455)
			(xy 280.937076 -288.130482) (xy 280.887901 -288.128501) (xy 280.839682 -288.118657) (xy 280.793666 -288.101205)
			(xy 280.751045 -288.076598) (xy 280.712924 -288.045473) (xy 280.680289 -288.008636) (xy 280.653986 -287.96704)
			(xy 280.634695 -287.921764) (xy 280.622918 -287.87398) (xy 280.618958 -287.824926) (xy 280.28011 -287.824926)
			(xy 280.28011 -287.841436) (xy 280.279602 -287.847278) (xy 280.279602 -287.847786) (xy 280.278332 -287.858708)
			(xy 280.278332 -287.858962) (xy 280.277824 -287.863026) (xy 280.275284 -287.881822) (xy 280.274268 -287.88741)
			(xy 280.270204 -287.903158) (xy 280.268426 -287.915858) (xy 280.268426 -288.308192) (xy 305.793963 -288.308192)
			(xy 305.79665 -288.25862) (xy 305.80732 -288.210135) (xy 305.825695 -288.164015) (xy 305.851289 -288.121475)
			(xy 305.883428 -288.083636) (xy 305.921265 -288.051496) (xy 305.963804 -288.0259) (xy 306.009923 -288.007524)
			(xy 306.058408 -287.996851) (xy 306.10798 -287.994163) (xy 306.157335 -287.99953) (xy 306.205171 -288.012812)
			(xy 306.250228 -288.033658) (xy 306.291319 -288.061518) (xy 306.327361 -288.095659) (xy 306.357405 -288.135182)
			(xy 306.380658 -288.179045) (xy 306.39651 -288.226092) (xy 306.404541 -288.275083) (xy 306.405026 -288.299906)
			(xy 306.40485 -288.314089) (xy 306.402177 -288.342329) (xy 306.399692 -288.356294) (xy 306.397406 -288.36874)
			(xy 306.404772 -288.392362) (xy 306.482242 -288.469832) (xy 306.505864 -288.477198) (xy 306.51831 -288.474912)
			(xy 306.532276 -288.472438) (xy 306.560516 -288.469765) (xy 306.574698 -288.469578) (xy 306.588945 -288.469746)
			(xy 306.617313 -288.472414) (xy 306.63134 -288.474912) (xy 306.643532 -288.477198) (xy 306.667662 -288.469832)
			(xy 306.744878 -288.392616) (xy 306.752244 -288.36874) (xy 306.749958 -288.356294) (xy 306.747485 -288.342328)
			(xy 306.744811 -288.314088) (xy 306.744624 -288.299906) (xy 306.745071 -288.275085) (xy 306.753101 -288.226097)
			(xy 306.768951 -288.179053) (xy 306.792202 -288.135194) (xy 306.822243 -288.095673) (xy 306.858282 -288.061533)
			(xy 306.899368 -288.033674) (xy 306.944421 -288.012828) (xy 306.992253 -287.999545) (xy 307.041604 -287.994176)
			(xy 307.091173 -287.996861) (xy 307.139654 -288.00753) (xy 307.185772 -288.025901) (xy 307.228309 -288.051492)
			(xy 307.266146 -288.083627) (xy 307.298286 -288.12146) (xy 307.323882 -288.163994) (xy 307.342259 -288.210109)
			(xy 307.352934 -288.25859) (xy 307.355177 -288.299906) (xy 307.694088 -288.299906) (xy 307.698048 -288.250852)
			(xy 307.709825 -288.203068) (xy 307.729116 -288.157792) (xy 307.755419 -288.116196) (xy 307.788054 -288.079359)
			(xy 307.826175 -288.048234) (xy 307.868796 -288.023627) (xy 307.914812 -288.006175) (xy 307.963031 -287.996331)
			(xy 308.012206 -287.99435) (xy 308.061061 -288.000282) (xy 308.108332 -288.013974) (xy 308.152794 -288.035072)
			(xy 308.193297 -288.063028) (xy 308.22879 -288.09712) (xy 308.258355 -288.136464) (xy 308.281226 -288.180041)
			(xy 308.29681 -288.226722) (xy 308.304705 -288.275299) (xy 308.3052 -288.299906) (xy 308.644048 -288.299906)
			(xy 308.648008 -288.250852) (xy 308.659785 -288.203068) (xy 308.679076 -288.157792) (xy 308.705379 -288.116196)
			(xy 308.738014 -288.079359) (xy 308.776135 -288.048234) (xy 308.818756 -288.023627) (xy 308.864772 -288.006175)
			(xy 308.912991 -287.996331) (xy 308.962166 -287.99435) (xy 309.011021 -288.000282) (xy 309.058292 -288.013974)
			(xy 309.102754 -288.035072) (xy 309.143257 -288.063028) (xy 309.17875 -288.09712) (xy 309.208315 -288.136464)
			(xy 309.231186 -288.180041) (xy 309.24677 -288.226722) (xy 309.254665 -288.275299) (xy 309.25516 -288.299906)
			(xy 309.594008 -288.299906) (xy 309.597968 -288.250852) (xy 309.609745 -288.203068) (xy 309.629036 -288.157792)
			(xy 309.655339 -288.116196) (xy 309.687974 -288.079359) (xy 309.726095 -288.048234) (xy 309.768716 -288.023627)
			(xy 309.814732 -288.006175) (xy 309.862951 -287.996331) (xy 309.912126 -287.99435) (xy 309.960981 -288.000282)
			(xy 310.008252 -288.013974) (xy 310.052714 -288.035072) (xy 310.093217 -288.063028) (xy 310.12871 -288.09712)
			(xy 310.158275 -288.136464) (xy 310.181146 -288.180041) (xy 310.19673 -288.226722) (xy 310.204625 -288.275299)
			(xy 310.20512 -288.299906) (xy 310.543968 -288.299906) (xy 310.547928 -288.250852) (xy 310.559705 -288.203068)
			(xy 310.578996 -288.157792) (xy 310.605299 -288.116196) (xy 310.637934 -288.079359) (xy 310.676055 -288.048234)
			(xy 310.718676 -288.023627) (xy 310.764692 -288.006175) (xy 310.812911 -287.996331) (xy 310.862086 -287.99435)
			(xy 310.910941 -288.000282) (xy 310.958212 -288.013974) (xy 311.002674 -288.035072) (xy 311.043177 -288.063028)
			(xy 311.07867 -288.09712) (xy 311.108235 -288.136464) (xy 311.131106 -288.180041) (xy 311.14669 -288.226722)
			(xy 311.154585 -288.275299) (xy 311.15508 -288.299906) (xy 311.154585 -288.324513) (xy 311.154446 -288.325369)
			(xy 311.472991 -288.325369) (xy 311.472998 -288.273936) (xy 311.481053 -288.223139) (xy 311.496956 -288.174226)
			(xy 311.520315 -288.128405) (xy 311.550557 -288.086802) (xy 311.586935 -288.050444) (xy 311.628553 -288.020224)
			(xy 311.674387 -287.996889) (xy 311.723308 -287.981012) (xy 311.77411 -287.972985) (xy 311.825543 -287.973004)
			(xy 311.876339 -287.981071) (xy 311.925247 -287.996986) (xy 311.971063 -288.020357) (xy 312.012658 -288.050608)
			(xy 312.049008 -288.086995) (xy 312.079217 -288.128621) (xy 312.102541 -288.174461) (xy 312.118407 -288.223385)
			(xy 312.126422 -288.274189) (xy 312.126884 -288.299906) (xy 312.126671 -288.313629) (xy 312.124258 -288.340969)
			(xy 312.122058 -288.354516) (xy 312.12028 -288.366454) (xy 312.127138 -288.389314) (xy 312.200798 -288.465768)
			(xy 312.223404 -288.473642) (xy 312.235342 -288.472118) (xy 312.245141 -288.470931) (xy 312.264841 -288.469659)
			(xy 312.274712 -288.469578) (xy 312.284583 -288.469649) (xy 312.304284 -288.470922) (xy 312.314082 -288.472118)
			(xy 312.32602 -288.473642) (xy 312.348626 -288.465768) (xy 312.422286 -288.389314) (xy 312.429144 -288.366454)
			(xy 312.427366 -288.354516) (xy 312.425145 -288.340972) (xy 312.422731 -288.31363) (xy 312.42254 -288.299906)
			(xy 312.423044 -288.274198) (xy 312.431087 -288.223416) (xy 312.446975 -288.174517) (xy 312.470318 -288.128705)
			(xy 312.500539 -288.087109) (xy 312.536895 -288.050753) (xy 312.578491 -288.020532) (xy 312.624303 -287.997189)
			(xy 312.673202 -287.981301) (xy 312.723984 -287.973258) (xy 312.7754 -287.973258) (xy 312.826182 -287.981301)
			(xy 312.875081 -287.997189) (xy 312.920893 -288.020532) (xy 312.962489 -288.050753) (xy 312.998845 -288.087109)
			(xy 313.029066 -288.128705) (xy 313.052409 -288.174517) (xy 313.068297 -288.223416) (xy 313.07634 -288.274198)
			(xy 313.076844 -288.299906) (xy 313.076631 -288.313629) (xy 313.074218 -288.340969) (xy 313.072018 -288.354516)
			(xy 313.069986 -288.366454) (xy 313.077098 -288.389314) (xy 313.150758 -288.465768) (xy 313.173364 -288.473642)
			(xy 313.185556 -288.472118) (xy 313.195355 -288.470929) (xy 313.215055 -288.469658) (xy 313.224926 -288.469578)
			(xy 313.239109 -288.469751) (xy 313.267349 -288.472426) (xy 313.281314 -288.474912) (xy 313.29376 -288.477198)
			(xy 313.317382 -288.469832) (xy 313.394852 -288.392362) (xy 313.402218 -288.36874) (xy 313.399932 -288.356294)
			(xy 313.397459 -288.342328) (xy 313.394785 -288.314088) (xy 313.394598 -288.299906) (xy 313.39512 -288.274651)
			(xy 313.403433 -288.224829) (xy 313.419834 -288.177055) (xy 313.443875 -288.132632) (xy 313.474899 -288.092772)
			(xy 313.512061 -288.058562) (xy 313.554347 -288.030936) (xy 313.600603 -288.010646) (xy 313.649568 -287.998246)
			(xy 313.699906 -287.994075) (xy 313.750244 -287.998246) (xy 313.799209 -288.010646) (xy 313.845465 -288.030936)
			(xy 313.887751 -288.058562) (xy 313.924913 -288.092772) (xy 313.955937 -288.132632) (xy 313.979978 -288.177055)
			(xy 313.996379 -288.224829) (xy 314.004692 -288.274651) (xy 314.005214 -288.299906) (xy 314.005038 -288.314089)
			(xy 314.002365 -288.342329) (xy 313.99988 -288.356294) (xy 313.997594 -288.36874) (xy 314.00496 -288.392362)
			(xy 314.08243 -288.469832) (xy 314.106052 -288.477198) (xy 314.118498 -288.474912) (xy 314.132465 -288.47244)
			(xy 314.160704 -288.469765) (xy 314.174886 -288.469578) (xy 314.189069 -288.469757) (xy 314.217309 -288.472427)
			(xy 314.231274 -288.474912) (xy 314.24372 -288.477198) (xy 314.267342 -288.469832) (xy 314.344812 -288.392362)
			(xy 314.352178 -288.36874) (xy 314.349892 -288.356294) (xy 314.347419 -288.342328) (xy 314.344745 -288.314088)
			(xy 314.344558 -288.299906) (xy 314.34508 -288.274651) (xy 314.353393 -288.224829) (xy 314.369794 -288.177055)
			(xy 314.393835 -288.132632) (xy 314.424859 -288.092772) (xy 314.462021 -288.058562) (xy 314.504307 -288.030936)
			(xy 314.550563 -288.010646) (xy 314.599528 -287.998246) (xy 314.649866 -287.994075) (xy 314.700204 -287.998246)
			(xy 314.749169 -288.010646) (xy 314.795425 -288.030936) (xy 314.837711 -288.058562) (xy 314.874873 -288.092772)
			(xy 314.905897 -288.132632) (xy 314.929938 -288.177055) (xy 314.946339 -288.224829) (xy 314.950281 -288.248456)
			(xy 319.795821 -288.248456) (xy 319.795821 -288.193944) (xy 319.803579 -288.139988) (xy 319.818936 -288.087685)
			(xy 319.841581 -288.0381) (xy 319.871053 -287.992243) (xy 319.90675 -287.951046) (xy 319.947947 -287.915349)
			(xy 319.993805 -287.885879) (xy 320.043391 -287.863234) (xy 320.095694 -287.847877) (xy 320.14965 -287.840121)
			(xy 320.176906 -287.839658) (xy 320.203022 -287.840108) (xy 320.254766 -287.847246) (xy 320.305052 -287.861374)
			(xy 320.352941 -287.882229) (xy 320.397539 -287.90942) (xy 320.438012 -287.942439) (xy 320.473603 -287.98067)
			(xy 320.503648 -288.023397) (xy 320.515996 -288.046414) (xy 320.522763 -288.058628) (xy 320.541766 -288.079074)
			(xy 320.565592 -288.093616) (xy 320.592463 -288.101168) (xy 320.620377 -288.101168) (xy 320.647248 -288.093616)
			(xy 320.671074 -288.079074) (xy 320.690077 -288.058628) (xy 320.696844 -288.046414) (xy 320.709203 -288.0234)
			(xy 320.739231 -287.980657) (xy 320.774814 -287.942413) (xy 320.815283 -287.909383) (xy 320.859881 -287.882187)
			(xy 320.907775 -287.861332) (xy 320.958067 -287.84721) (xy 321.009815 -287.840085) (xy 321.035934 -287.839658)
			(xy 321.063181 -287.840215) (xy 321.11712 -287.847974) (xy 321.169406 -287.863331) (xy 321.218975 -287.885972)
			(xy 321.264817 -287.915437) (xy 321.305999 -287.951125) (xy 321.341684 -287.99231) (xy 321.371144 -288.038155)
			(xy 321.393781 -288.087726) (xy 321.409133 -288.140013) (xy 321.416888 -288.193953) (xy 321.416888 -288.248445)
			(xy 321.67082 -288.248445) (xy 321.670822 -288.193932) (xy 321.678582 -288.139975) (xy 321.693942 -288.087671)
			(xy 321.716589 -288.038085) (xy 321.746064 -287.992228) (xy 321.781764 -287.951032) (xy 321.822964 -287.915336)
			(xy 321.868825 -287.885868) (xy 321.918413 -287.863226) (xy 321.970719 -287.847872) (xy 322.024678 -287.840119)
			(xy 322.051934 -287.839658) (xy 322.076572 -287.84042) (xy 322.089272 -287.841182) (xy 322.11137 -287.83153)
			(xy 322.179442 -287.74771) (xy 322.184522 -287.723834) (xy 322.180966 -287.711642) (xy 322.17443 -287.686493)
			(xy 322.16742 -287.635007) (xy 322.166996 -287.609026) (xy 322.167482 -287.581775) (xy 322.175238 -287.527827)
			(xy 322.190593 -287.475532) (xy 322.213235 -287.425955) (xy 322.242701 -287.380105) (xy 322.278392 -287.338914)
			(xy 322.319583 -287.303223) (xy 322.365433 -287.273757) (xy 322.41501 -287.251115) (xy 322.467305 -287.23576)
			(xy 322.521253 -287.228004) (xy 322.575755 -287.228004) (xy 322.629703 -287.23576) (xy 322.681998 -287.251115)
			(xy 322.731575 -287.273757) (xy 322.777425 -287.303223) (xy 322.818616 -287.338914) (xy 322.854307 -287.380105)
			(xy 322.883773 -287.425955) (xy 322.906415 -287.475532) (xy 322.92177 -287.527827) (xy 322.929526 -287.581775)
			(xy 322.930012 -287.609026) (xy 322.929581 -287.63547) (xy 322.922318 -287.687857) (xy 322.915534 -287.71342)
			(xy 322.911978 -287.725866) (xy 322.917312 -287.75025) (xy 322.988432 -287.834324) (xy 323.0118 -287.843468)
			(xy 323.024754 -287.842198) (xy 323.035511 -287.841027) (xy 323.057114 -287.839756) (xy 323.067934 -287.839658)
			(xy 323.082158 -287.839912) (xy 323.093842 -287.84042) (xy 323.114924 -287.831276) (xy 323.18198 -287.75406)
			(xy 323.188076 -287.732216) (xy 323.186044 -287.720786) (xy 323.183307 -287.704285) (xy 323.180382 -287.670963)
			(xy 323.180202 -287.654238) (xy 323.180688 -287.626987) (xy 323.188444 -287.573039) (xy 323.203799 -287.520744)
			(xy 323.226441 -287.471167) (xy 323.255907 -287.425317) (xy 323.291598 -287.384126) (xy 323.332789 -287.348435)
			(xy 323.378639 -287.318969) (xy 323.428216 -287.296327) (xy 323.480511 -287.280972) (xy 323.534459 -287.273216)
			(xy 323.588961 -287.273216) (xy 323.642909 -287.280972) (xy 323.695204 -287.296327) (xy 323.744781 -287.318969)
			(xy 323.790631 -287.348435) (xy 323.831822 -287.384126) (xy 323.867513 -287.425317) (xy 323.896979 -287.471167)
			(xy 323.919621 -287.520744) (xy 323.934976 -287.573039) (xy 323.942732 -287.626987) (xy 323.943218 -287.654238)
			(xy 323.943035 -287.6709) (xy 323.940109 -287.704095) (xy 323.937376 -287.720532) (xy 323.935344 -287.732216)
			(xy 323.94144 -287.753806) (xy 324.008242 -287.831022) (xy 324.028816 -287.840166) (xy 324.0405 -287.839912)
			(xy 324.051676 -287.839658) (xy 324.078932 -287.840129) (xy 324.132888 -287.847884) (xy 324.185192 -287.863239)
			(xy 324.234778 -287.885881) (xy 324.280637 -287.91535) (xy 324.321835 -287.951045) (xy 324.357533 -287.99224)
			(xy 324.387005 -288.038097) (xy 324.409651 -288.087681) (xy 324.42501 -288.139984) (xy 324.432769 -288.19394)
			(xy 324.432769 -288.248451) (xy 324.425012 -288.302407) (xy 324.409655 -288.35471) (xy 324.38701 -288.404295)
			(xy 324.357539 -288.450152) (xy 324.321841 -288.491348) (xy 324.280644 -288.527045) (xy 324.234786 -288.556515)
			(xy 324.185201 -288.579158) (xy 324.132897 -288.594514) (xy 324.078941 -288.60227) (xy 324.02443 -288.602268)
			(xy 323.970474 -288.594508) (xy 323.918172 -288.579148) (xy 323.868588 -288.556501) (xy 323.822732 -288.527027)
			(xy 323.781538 -288.491328) (xy 323.745844 -288.450129) (xy 323.716376 -288.404269) (xy 323.693735 -288.354682)
			(xy 323.678382 -288.302378) (xy 323.670629 -288.248422) (xy 323.670168 -288.221166) (xy 323.670351 -288.204504)
			(xy 323.673277 -288.171309) (xy 323.67601 -288.154872) (xy 323.678042 -288.143188) (xy 323.671946 -288.121598)
			(xy 323.605144 -288.044382) (xy 323.58457 -288.035238) (xy 323.572886 -288.035492) (xy 323.56171 -288.035746)
			(xy 323.547486 -288.035492) (xy 323.535802 -288.034984) (xy 323.51472 -288.044128) (xy 323.447664 -288.121344)
			(xy 323.441568 -288.143188) (xy 323.4436 -288.154618) (xy 323.446338 -288.171119) (xy 323.449262 -288.204441)
			(xy 323.449442 -288.221166) (xy 323.448956 -288.248417) (xy 323.4412 -288.302365) (xy 323.425845 -288.35466)
			(xy 323.403203 -288.404237) (xy 323.373737 -288.450087) (xy 323.338046 -288.491278) (xy 323.296855 -288.526969)
			(xy 323.251005 -288.556435) (xy 323.201428 -288.579077) (xy 323.149133 -288.594432) (xy 323.095185 -288.602188)
			(xy 323.040683 -288.602188) (xy 322.986735 -288.594432) (xy 322.93444 -288.579077) (xy 322.884863 -288.556435)
			(xy 322.839013 -288.526969) (xy 322.797822 -288.491278) (xy 322.762131 -288.450087) (xy 322.732665 -288.404237)
			(xy 322.710023 -288.35466) (xy 322.694668 -288.302365) (xy 322.686912 -288.248417) (xy 322.686426 -288.221166)
			(xy 322.686854 -288.194722) (xy 322.694119 -288.142335) (xy 322.700904 -288.116772) (xy 322.70446 -288.104326)
			(xy 322.699126 -288.079942) (xy 322.628006 -287.995868) (xy 322.604638 -287.986724) (xy 322.591684 -287.987994)
			(xy 322.580927 -287.989162) (xy 322.559324 -287.990435) (xy 322.548504 -287.990534) (xy 322.523866 -287.989772)
			(xy 322.511166 -287.98901) (xy 322.489068 -287.998662) (xy 322.420996 -288.082482) (xy 322.415916 -288.106358)
			(xy 322.419472 -288.11855) (xy 322.426007 -288.143699) (xy 322.433018 -288.195185) (xy 322.433442 -288.221166)
			(xy 322.432981 -288.248422) (xy 322.425228 -288.302381) (xy 322.409874 -288.354687) (xy 322.387232 -288.404275)
			(xy 322.357764 -288.450136) (xy 322.322068 -288.491336) (xy 322.280872 -288.527036) (xy 322.235015 -288.556511)
			(xy 322.185429 -288.579158) (xy 322.133125 -288.594518) (xy 322.079168 -288.602278) (xy 322.024655 -288.60228)
			(xy 321.970697 -288.594523) (xy 321.918392 -288.579166) (xy 321.868805 -288.556521) (xy 321.822946 -288.52705)
			(xy 321.781748 -288.491352) (xy 321.74605 -288.450154) (xy 321.716579 -288.404295) (xy 321.693934 -288.354708)
			(xy 321.678577 -288.302403) (xy 321.67082 -288.248445) (xy 321.416888 -288.248445) (xy 321.416888 -288.248447)
			(xy 321.409133 -288.302387) (xy 321.393781 -288.354674) (xy 321.371144 -288.404245) (xy 321.341684 -288.45009)
			(xy 321.305999 -288.491275) (xy 321.264817 -288.526963) (xy 321.218975 -288.556428) (xy 321.169406 -288.579069)
			(xy 321.11712 -288.594426) (xy 321.063181 -288.602185) (xy 321.035934 -288.602674) (xy 321.009817 -288.602228)
			(xy 320.958072 -288.595094) (xy 320.907784 -288.580968) (xy 320.859893 -288.560114) (xy 320.815294 -288.532922)
			(xy 320.774822 -288.499901) (xy 320.739232 -288.461667) (xy 320.70919 -288.418937) (xy 320.696844 -288.395918)
			(xy 320.690077 -288.383704) (xy 320.671074 -288.363258) (xy 320.647248 -288.348716) (xy 320.620377 -288.341164)
			(xy 320.592463 -288.341164) (xy 320.565592 -288.348716) (xy 320.541766 -288.363258) (xy 320.522763 -288.383704)
			(xy 320.515996 -288.395918) (xy 320.503621 -288.418923) (xy 320.473593 -288.461664) (xy 320.438012 -288.499907)
			(xy 320.397545 -288.532936) (xy 320.352949 -288.560133) (xy 320.305059 -288.58099) (xy 320.25477 -288.595115)
			(xy 320.203024 -288.602245) (xy 320.176906 -288.602674) (xy 320.14965 -288.602279) (xy 320.095694 -288.594523)
			(xy 320.043391 -288.579166) (xy 319.993805 -288.556521) (xy 319.947947 -288.527051) (xy 319.90675 -288.491354)
			(xy 319.871053 -288.450157) (xy 319.841581 -288.4043) (xy 319.818936 -288.354715) (xy 319.803579 -288.302412)
			(xy 319.795821 -288.248456) (xy 314.950281 -288.248456) (xy 314.954652 -288.274651) (xy 314.955174 -288.299906)
			(xy 314.954999 -288.314089) (xy 314.952326 -288.342329) (xy 314.94984 -288.356294) (xy 314.947554 -288.36874)
			(xy 314.95492 -288.392362) (xy 315.03239 -288.469832) (xy 315.056012 -288.477198) (xy 315.068458 -288.474912)
			(xy 315.082423 -288.472432) (xy 315.110663 -288.469762) (xy 315.124846 -288.469578) (xy 315.147629 -288.469993)
			(xy 315.192686 -288.476777) (xy 315.236238 -288.490173) (xy 315.277319 -288.509884) (xy 315.31502 -288.535474)
			(xy 315.348506 -288.566376) (xy 315.363098 -288.583878) (xy 315.370664 -288.592477) (xy 315.391281 -288.602401)
			(xy 315.402722 -288.602928) (xy 315.48197 -288.602928) (xy 315.493383 -288.60227) (xy 315.51396 -288.592386)
			(xy 315.521594 -288.583878) (xy 315.53619 -288.566378) (xy 315.569664 -288.535461) (xy 315.607361 -288.509862)
			(xy 315.648444 -288.49015) (xy 315.692 -288.476762) (xy 315.737062 -288.469997) (xy 315.759846 -288.469578)
			(xy 315.785098 -288.470131) (xy 315.834911 -288.47845) (xy 315.882676 -288.494855) (xy 315.92709 -288.518896)
			(xy 315.966942 -288.54992) (xy 316.001145 -288.587079) (xy 316.028765 -288.62936) (xy 316.04905 -288.675611)
			(xy 316.061447 -288.724569) (xy 316.065617 -288.7749) (xy 316.061447 -288.825231) (xy 316.04905 -288.874189)
			(xy 316.028765 -288.92044) (xy 316.001145 -288.962721) (xy 315.966942 -288.99988) (xy 315.92709 -289.030904)
			(xy 315.882676 -289.054945) (xy 315.834911 -289.07135) (xy 315.785098 -289.079669) (xy 315.759846 -289.080194)
			(xy 315.737063 -289.079795) (xy 315.692004 -289.073009) (xy 315.648451 -289.059611) (xy 315.60737 -289.039896)
			(xy 315.569669 -289.014303) (xy 315.536185 -288.983397) (xy 315.521594 -288.965894) (xy 315.514036 -288.957287)
			(xy 315.493412 -288.947369) (xy 315.48197 -288.946844) (xy 315.402722 -288.946844) (xy 315.39131 -288.947507)
			(xy 315.370733 -288.957388) (xy 315.363098 -288.965894) (xy 315.348524 -288.983413) (xy 315.315044 -289.014326)
			(xy 315.277341 -289.03992) (xy 315.236254 -289.059629) (xy 315.192695 -289.073013) (xy 315.147631 -289.079776)
			(xy 315.124846 -289.080194) (xy 315.100853 -289.079719) (xy 315.053458 -289.072219) (xy 315.00782 -289.057396)
			(xy 314.965063 -289.035615) (xy 314.92624 -289.007413) (xy 314.892308 -288.973484) (xy 314.864102 -288.934664)
			(xy 314.842316 -288.89191) (xy 314.827488 -288.846273) (xy 314.819983 -288.798879) (xy 314.819538 -288.774886)
			(xy 314.819712 -288.760703) (xy 314.822386 -288.732463) (xy 314.824872 -288.718498) (xy 314.827158 -288.706052)
			(xy 314.819792 -288.68243) (xy 314.742322 -288.60496) (xy 314.7187 -288.597594) (xy 314.706254 -288.59988)
			(xy 314.692288 -288.602359) (xy 314.664049 -288.605029) (xy 314.649866 -288.605214) (xy 314.635683 -288.605042)
			(xy 314.607443 -288.602367) (xy 314.593478 -288.59988) (xy 314.581032 -288.597594) (xy 314.55741 -288.60496)
			(xy 314.47994 -288.68243) (xy 314.472574 -288.706052) (xy 314.47486 -288.718498) (xy 314.477332 -288.732465)
			(xy 314.480007 -288.760704) (xy 314.480194 -288.774886) (xy 314.479672 -288.800141) (xy 314.471359 -288.849963)
			(xy 314.454958 -288.897737) (xy 314.430917 -288.94216) (xy 314.399893 -288.98202) (xy 314.362731 -289.01623)
			(xy 314.320445 -289.043856) (xy 314.274189 -289.064146) (xy 314.225224 -289.076546) (xy 314.174886 -289.080717)
			(xy 314.124548 -289.076546) (xy 314.075583 -289.064146) (xy 314.029327 -289.043856) (xy 313.987041 -289.01623)
			(xy 313.949879 -288.98202) (xy 313.918855 -288.94216) (xy 313.894814 -288.897737) (xy 313.878413 -288.849963)
			(xy 313.8701 -288.800141) (xy 313.869578 -288.774886) (xy 313.869753 -288.760703) (xy 313.872426 -288.732463)
			(xy 313.874912 -288.718498) (xy 313.877198 -288.706052) (xy 313.869832 -288.68243) (xy 313.792362 -288.60496)
			(xy 313.76874 -288.597594) (xy 313.756294 -288.59988) (xy 313.742328 -288.602353) (xy 313.714088 -288.605027)
			(xy 313.699906 -288.605214) (xy 313.685723 -288.605036) (xy 313.657483 -288.602365) (xy 313.643518 -288.59988)
			(xy 313.631072 -288.597594) (xy 313.60745 -288.60496) (xy 313.52998 -288.68243) (xy 313.522614 -288.706052)
			(xy 313.5249 -288.718498) (xy 313.527372 -288.732465) (xy 313.530047 -288.760704) (xy 313.530234 -288.774886)
			(xy 313.529712 -288.800141) (xy 313.521399 -288.849963) (xy 313.504998 -288.897737) (xy 313.480957 -288.94216)
			(xy 313.449933 -288.98202) (xy 313.412771 -289.01623) (xy 313.370485 -289.043856) (xy 313.324229 -289.064146)
			(xy 313.275264 -289.076546) (xy 313.224926 -289.080717) (xy 313.174588 -289.076546) (xy 313.125623 -289.064146)
			(xy 313.079367 -289.043856) (xy 313.037081 -289.01623) (xy 312.999919 -288.98202) (xy 312.968895 -288.94216)
			(xy 312.944854 -288.897737) (xy 312.928453 -288.849963) (xy 312.92014 -288.800141) (xy 312.919618 -288.774886)
			(xy 312.919689 -288.765015) (xy 312.920961 -288.745314) (xy 312.922158 -288.735516) (xy 312.923682 -288.723578)
			(xy 312.915808 -288.700718) (xy 312.839354 -288.627312) (xy 312.816494 -288.6202) (xy 312.804302 -288.622232)
			(xy 312.790753 -288.62439) (xy 312.763411 -288.626677) (xy 312.749692 -288.626804) (xy 312.735974 -288.626658)
			(xy 312.708633 -288.62437) (xy 312.695082 -288.622232) (xy 312.683144 -288.620454) (xy 312.660284 -288.627312)
			(xy 312.58383 -288.700972) (xy 312.575956 -288.723578) (xy 312.57748 -288.735516) (xy 312.578665 -288.745316)
			(xy 312.579938 -288.765015) (xy 312.58002 -288.774886) (xy 312.579498 -288.800141) (xy 312.571185 -288.849963)
			(xy 312.554784 -288.897737) (xy 312.530743 -288.94216) (xy 312.499719 -288.98202) (xy 312.462557 -289.01623)
			(xy 312.420271 -289.043856) (xy 312.374015 -289.064146) (xy 312.32505 -289.076546) (xy 312.274712 -289.080717)
			(xy 312.224374 -289.076546) (xy 312.175409 -289.064146) (xy 312.129153 -289.043856) (xy 312.086867 -289.01623)
			(xy 312.049705 -288.98202) (xy 312.018681 -288.94216) (xy 311.99464 -288.897737) (xy 311.978239 -288.849963)
			(xy 311.969926 -288.800141) (xy 311.969404 -288.774886) (xy 311.969475 -288.765015) (xy 311.970747 -288.745314)
			(xy 311.971944 -288.735516) (xy 311.973468 -288.723578) (xy 311.965594 -288.700972) (xy 311.88914 -288.627312)
			(xy 311.86628 -288.620454) (xy 311.854342 -288.622232) (xy 311.840793 -288.624385) (xy 311.813451 -288.626675)
			(xy 311.799732 -288.626804) (xy 311.774016 -288.626408) (xy 311.723216 -288.618366) (xy 311.6743 -288.602475)
			(xy 311.628472 -288.579126) (xy 311.586863 -288.548895) (xy 311.550495 -288.512526) (xy 311.520266 -288.470914)
			(xy 311.496919 -288.425086) (xy 311.48103 -288.376169) (xy 311.472991 -288.325369) (xy 311.154446 -288.325369)
			(xy 311.14669 -288.37309) (xy 311.131106 -288.419771) (xy 311.108235 -288.463348) (xy 311.07867 -288.502692)
			(xy 311.043177 -288.536784) (xy 311.002674 -288.56474) (xy 310.958212 -288.585838) (xy 310.910941 -288.59953)
			(xy 310.862086 -288.605462) (xy 310.812911 -288.603481) (xy 310.764692 -288.593637) (xy 310.718676 -288.576185)
			(xy 310.676055 -288.551578) (xy 310.637934 -288.520453) (xy 310.605299 -288.483616) (xy 310.578996 -288.44202)
			(xy 310.559705 -288.396744) (xy 310.547928 -288.34896) (xy 310.543968 -288.299906) (xy 310.20512 -288.299906)
			(xy 310.204625 -288.324513) (xy 310.19673 -288.37309) (xy 310.181146 -288.419771) (xy 310.158275 -288.463348)
			(xy 310.12871 -288.502692) (xy 310.093217 -288.536784) (xy 310.052714 -288.56474) (xy 310.008252 -288.585838)
			(xy 309.960981 -288.59953) (xy 309.912126 -288.605462) (xy 309.862951 -288.603481) (xy 309.814732 -288.593637)
			(xy 309.768716 -288.576185) (xy 309.726095 -288.551578) (xy 309.687974 -288.520453) (xy 309.655339 -288.483616)
			(xy 309.629036 -288.44202) (xy 309.609745 -288.396744) (xy 309.597968 -288.34896) (xy 309.594008 -288.299906)
			(xy 309.25516 -288.299906) (xy 309.254665 -288.324513) (xy 309.24677 -288.37309) (xy 309.231186 -288.419771)
			(xy 309.208315 -288.463348) (xy 309.17875 -288.502692) (xy 309.143257 -288.536784) (xy 309.102754 -288.56474)
			(xy 309.058292 -288.585838) (xy 309.011021 -288.59953) (xy 308.962166 -288.605462) (xy 308.912991 -288.603481)
			(xy 308.864772 -288.593637) (xy 308.818756 -288.576185) (xy 308.776135 -288.551578) (xy 308.738014 -288.520453)
			(xy 308.705379 -288.483616) (xy 308.679076 -288.44202) (xy 308.659785 -288.396744) (xy 308.648008 -288.34896)
			(xy 308.644048 -288.299906) (xy 308.3052 -288.299906) (xy 308.304705 -288.324513) (xy 308.29681 -288.37309)
			(xy 308.281226 -288.419771) (xy 308.258355 -288.463348) (xy 308.22879 -288.502692) (xy 308.193297 -288.536784)
			(xy 308.152794 -288.56474) (xy 308.108332 -288.585838) (xy 308.061061 -288.59953) (xy 308.012206 -288.605462)
			(xy 307.963031 -288.603481) (xy 307.914812 -288.593637) (xy 307.868796 -288.576185) (xy 307.826175 -288.551578)
			(xy 307.788054 -288.520453) (xy 307.755419 -288.483616) (xy 307.729116 -288.44202) (xy 307.709825 -288.396744)
			(xy 307.698048 -288.34896) (xy 307.694088 -288.299906) (xy 307.355177 -288.299906) (xy 307.355625 -288.308158)
			(xy 307.350262 -288.35751) (xy 307.336985 -288.405343) (xy 307.316145 -288.450398) (xy 307.28829 -288.491489)
			(xy 307.254155 -288.527532) (xy 307.214638 -288.557577) (xy 307.170781 -288.580834) (xy 307.12374 -288.596689)
			(xy 307.074753 -288.604726) (xy 307.049932 -288.605214) (xy 307.035685 -288.605049) (xy 307.007318 -288.602375)
			(xy 306.99329 -288.59988) (xy 306.981098 -288.597594) (xy 306.956968 -288.60496) (xy 306.879752 -288.682176)
			(xy 306.872386 -288.706052) (xy 306.874672 -288.718498) (xy 306.877144 -288.732465) (xy 306.879819 -288.760704)
			(xy 306.880006 -288.774886) (xy 306.879484 -288.800141) (xy 306.871171 -288.849963) (xy 306.85477 -288.897737)
			(xy 306.830729 -288.94216) (xy 306.799705 -288.98202) (xy 306.762543 -289.01623) (xy 306.720257 -289.043856)
			(xy 306.674001 -289.064146) (xy 306.625036 -289.076546) (xy 306.574698 -289.080717) (xy 306.52436 -289.076546)
			(xy 306.475395 -289.064146) (xy 306.429139 -289.043856) (xy 306.386853 -289.01623) (xy 306.349691 -288.98202)
			(xy 306.318667 -288.94216) (xy 306.294626 -288.897737) (xy 306.278225 -288.849963) (xy 306.269912 -288.800141)
			(xy 306.26939 -288.774886) (xy 306.269565 -288.760703) (xy 306.272238 -288.732463) (xy 306.274724 -288.718498)
			(xy 306.27701 -288.706052) (xy 306.269644 -288.68243) (xy 306.192174 -288.60496) (xy 306.168552 -288.597594)
			(xy 306.156106 -288.59988) (xy 306.142139 -288.602352) (xy 306.1139 -288.605027) (xy 306.099718 -288.605214)
			(xy 306.074895 -288.604741) (xy 306.025903 -288.596713) (xy 305.978856 -288.580863) (xy 305.934992 -288.557611)
			(xy 305.895468 -288.527569) (xy 305.861326 -288.491528) (xy 305.833463 -288.450438) (xy 305.812616 -288.405382)
			(xy 305.799333 -288.357547) (xy 305.793963 -288.308192) (xy 280.268426 -288.308192) (xy 280.268426 -288.680144)
			(xy 280.268934 -288.68624) (xy 280.270204 -288.697416) (xy 280.270966 -288.700718) (xy 280.270966 -288.701226)
			(xy 280.275218 -288.719344) (xy 280.279804 -288.756278) (xy 280.28011 -288.774886) (xy 280.618958 -288.774886)
			(xy 280.622918 -288.725832) (xy 280.634695 -288.678048) (xy 280.653986 -288.632772) (xy 280.680289 -288.591176)
			(xy 280.712924 -288.554339) (xy 280.751045 -288.523214) (xy 280.793666 -288.498607) (xy 280.839682 -288.481155)
			(xy 280.887901 -288.471311) (xy 280.937076 -288.46933) (xy 280.985931 -288.475262) (xy 281.033202 -288.488954)
			(xy 281.077664 -288.510052) (xy 281.118167 -288.538008) (xy 281.15366 -288.5721) (xy 281.183225 -288.611444)
			(xy 281.206096 -288.655021) (xy 281.22168 -288.701702) (xy 281.229575 -288.750279) (xy 281.23007 -288.774886)
			(xy 281.568918 -288.774886) (xy 281.572878 -288.725832) (xy 281.584655 -288.678048) (xy 281.603946 -288.632772)
			(xy 281.630249 -288.591176) (xy 281.662884 -288.554339) (xy 281.701005 -288.523214) (xy 281.743626 -288.498607)
			(xy 281.789642 -288.481155) (xy 281.837861 -288.471311) (xy 281.887036 -288.46933) (xy 281.935891 -288.475262)
			(xy 281.983162 -288.488954) (xy 282.027624 -288.510052) (xy 282.068127 -288.538008) (xy 282.10362 -288.5721)
			(xy 282.133185 -288.611444) (xy 282.156056 -288.655021) (xy 282.17164 -288.701702) (xy 282.179535 -288.750279)
			(xy 282.18003 -288.774886) (xy 282.519132 -288.774886) (xy 282.523092 -288.725832) (xy 282.534869 -288.678048)
			(xy 282.55416 -288.632772) (xy 282.580463 -288.591176) (xy 282.613098 -288.554339) (xy 282.651219 -288.523214)
			(xy 282.69384 -288.498607) (xy 282.739856 -288.481155) (xy 282.788075 -288.471311) (xy 282.83725 -288.46933)
			(xy 282.886105 -288.475262) (xy 282.933376 -288.488954) (xy 282.977838 -288.510052) (xy 283.018341 -288.538008)
			(xy 283.053834 -288.5721) (xy 283.083399 -288.611444) (xy 283.10627 -288.655021) (xy 283.121854 -288.701702)
			(xy 283.129749 -288.750279) (xy 283.130244 -288.774886) (xy 283.469092 -288.774886) (xy 283.473052 -288.725832)
			(xy 283.484829 -288.678048) (xy 283.50412 -288.632772) (xy 283.530423 -288.591176) (xy 283.563058 -288.554339)
			(xy 283.601179 -288.523214) (xy 283.6438 -288.498607) (xy 283.689816 -288.481155) (xy 283.738035 -288.471311)
			(xy 283.78721 -288.46933) (xy 283.836065 -288.475262) (xy 283.883336 -288.488954) (xy 283.927798 -288.510052)
			(xy 283.968301 -288.538008) (xy 284.003794 -288.5721) (xy 284.033359 -288.611444) (xy 284.05623 -288.655021)
			(xy 284.071814 -288.701702) (xy 284.079709 -288.750279) (xy 284.080204 -288.774886) (xy 284.419052 -288.774886)
			(xy 284.423012 -288.725832) (xy 284.434789 -288.678048) (xy 284.45408 -288.632772) (xy 284.480383 -288.591176)
			(xy 284.513018 -288.554339) (xy 284.551139 -288.523214) (xy 284.59376 -288.498607) (xy 284.639776 -288.481155)
			(xy 284.687995 -288.471311) (xy 284.73717 -288.46933) (xy 284.786025 -288.475262) (xy 284.833296 -288.488954)
			(xy 284.877758 -288.510052) (xy 284.918261 -288.538008) (xy 284.953754 -288.5721) (xy 284.983319 -288.611444)
			(xy 285.00619 -288.655021) (xy 285.021774 -288.701702) (xy 285.029669 -288.750279) (xy 285.030164 -288.774886)
			(xy 285.369012 -288.774886) (xy 285.372972 -288.725832) (xy 285.384749 -288.678048) (xy 285.40404 -288.632772)
			(xy 285.430343 -288.591176) (xy 285.462978 -288.554339) (xy 285.501099 -288.523214) (xy 285.54372 -288.498607)
			(xy 285.589736 -288.481155) (xy 285.637955 -288.471311) (xy 285.68713 -288.46933) (xy 285.735985 -288.475262)
			(xy 285.783256 -288.488954) (xy 285.827718 -288.510052) (xy 285.868221 -288.538008) (xy 285.903714 -288.5721)
			(xy 285.933279 -288.611444) (xy 285.95615 -288.655021) (xy 285.971734 -288.701702) (xy 285.979629 -288.750279)
			(xy 285.980124 -288.774886) (xy 286.318972 -288.774886) (xy 286.322932 -288.725832) (xy 286.334709 -288.678048)
			(xy 286.354 -288.632772) (xy 286.380303 -288.591176) (xy 286.412938 -288.554339) (xy 286.451059 -288.523214)
			(xy 286.49368 -288.498607) (xy 286.539696 -288.481155) (xy 286.587915 -288.471311) (xy 286.63709 -288.46933)
			(xy 286.685945 -288.475262) (xy 286.733216 -288.488954) (xy 286.777678 -288.510052) (xy 286.818181 -288.538008)
			(xy 286.853674 -288.5721) (xy 286.883239 -288.611444) (xy 286.90611 -288.655021) (xy 286.921694 -288.701702)
			(xy 286.929589 -288.750279) (xy 286.930084 -288.774886) (xy 287.268932 -288.774886) (xy 287.272892 -288.725832)
			(xy 287.284669 -288.678048) (xy 287.30396 -288.632772) (xy 287.330263 -288.591176) (xy 287.362898 -288.554339)
			(xy 287.401019 -288.523214) (xy 287.44364 -288.498607) (xy 287.489656 -288.481155) (xy 287.537875 -288.471311)
			(xy 287.58705 -288.46933) (xy 287.635905 -288.475262) (xy 287.683176 -288.488954) (xy 287.727638 -288.510052)
			(xy 287.768141 -288.538008) (xy 287.803634 -288.5721) (xy 287.833199 -288.611444) (xy 287.85607 -288.655021)
			(xy 287.871654 -288.701702) (xy 287.879549 -288.750279) (xy 287.880044 -288.774886) (xy 288.218892 -288.774886)
			(xy 288.222852 -288.725832) (xy 288.234629 -288.678048) (xy 288.25392 -288.632772) (xy 288.280223 -288.591176)
			(xy 288.312858 -288.554339) (xy 288.350979 -288.523214) (xy 288.3936 -288.498607) (xy 288.439616 -288.481155)
			(xy 288.487835 -288.471311) (xy 288.53701 -288.46933) (xy 288.585865 -288.475262) (xy 288.633136 -288.488954)
			(xy 288.677598 -288.510052) (xy 288.718101 -288.538008) (xy 288.753594 -288.5721) (xy 288.783159 -288.611444)
			(xy 288.80603 -288.655021) (xy 288.821614 -288.701702) (xy 288.829509 -288.750279) (xy 288.830004 -288.774886)
			(xy 289.169106 -288.774886) (xy 289.173066 -288.725832) (xy 289.184843 -288.678048) (xy 289.204134 -288.632772)
			(xy 289.230437 -288.591176) (xy 289.263072 -288.554339) (xy 289.301193 -288.523214) (xy 289.343814 -288.498607)
			(xy 289.38983 -288.481155) (xy 289.438049 -288.471311) (xy 289.487224 -288.46933) (xy 289.536079 -288.475262)
			(xy 289.58335 -288.488954) (xy 289.627812 -288.510052) (xy 289.668315 -288.538008) (xy 289.703808 -288.5721)
			(xy 289.733373 -288.611444) (xy 289.756244 -288.655021) (xy 289.771828 -288.701702) (xy 289.779723 -288.750279)
			(xy 289.780218 -288.774886) (xy 290.119066 -288.774886) (xy 290.123026 -288.725832) (xy 290.134803 -288.678048)
			(xy 290.154094 -288.632772) (xy 290.180397 -288.591176) (xy 290.213032 -288.554339) (xy 290.251153 -288.523214)
			(xy 290.293774 -288.498607) (xy 290.33979 -288.481155) (xy 290.388009 -288.471311) (xy 290.437184 -288.46933)
			(xy 290.486039 -288.475262) (xy 290.53331 -288.488954) (xy 290.577772 -288.510052) (xy 290.618275 -288.538008)
			(xy 290.653768 -288.5721) (xy 290.683333 -288.611444) (xy 290.706204 -288.655021) (xy 290.721788 -288.701702)
			(xy 290.729683 -288.750279) (xy 290.730178 -288.774886) (xy 292.018986 -288.774886) (xy 292.022946 -288.725832)
			(xy 292.034723 -288.678048) (xy 292.054014 -288.632772) (xy 292.080317 -288.591176) (xy 292.112952 -288.554339)
			(xy 292.151073 -288.523214) (xy 292.193694 -288.498607) (xy 292.23971 -288.481155) (xy 292.287929 -288.471311)
			(xy 292.337104 -288.46933) (xy 292.385959 -288.475262) (xy 292.43323 -288.488954) (xy 292.477692 -288.510052)
			(xy 292.518195 -288.538008) (xy 292.553688 -288.5721) (xy 292.583253 -288.611444) (xy 292.606124 -288.655021)
			(xy 292.621708 -288.701702) (xy 292.629603 -288.750279) (xy 292.630098 -288.774886) (xy 292.968946 -288.774886)
			(xy 292.972906 -288.725832) (xy 292.984683 -288.678048) (xy 293.003974 -288.632772) (xy 293.030277 -288.591176)
			(xy 293.062912 -288.554339) (xy 293.101033 -288.523214) (xy 293.143654 -288.498607) (xy 293.18967 -288.481155)
			(xy 293.237889 -288.471311) (xy 293.287064 -288.46933) (xy 293.335919 -288.475262) (xy 293.38319 -288.488954)
			(xy 293.427652 -288.510052) (xy 293.468155 -288.538008) (xy 293.503648 -288.5721) (xy 293.533213 -288.611444)
			(xy 293.556084 -288.655021) (xy 293.571668 -288.701702) (xy 293.579563 -288.750279) (xy 293.580058 -288.774886)
			(xy 293.918906 -288.774886) (xy 293.922866 -288.725832) (xy 293.934643 -288.678048) (xy 293.953934 -288.632772)
			(xy 293.980237 -288.591176) (xy 294.012872 -288.554339) (xy 294.050993 -288.523214) (xy 294.093614 -288.498607)
			(xy 294.13963 -288.481155) (xy 294.187849 -288.471311) (xy 294.237024 -288.46933) (xy 294.285879 -288.475262)
			(xy 294.33315 -288.488954) (xy 294.377612 -288.510052) (xy 294.418115 -288.538008) (xy 294.453608 -288.5721)
			(xy 294.483173 -288.611444) (xy 294.506044 -288.655021) (xy 294.521628 -288.701702) (xy 294.529523 -288.750279)
			(xy 294.530018 -288.774886) (xy 294.86912 -288.774886) (xy 294.87308 -288.725832) (xy 294.884857 -288.678048)
			(xy 294.904148 -288.632772) (xy 294.930451 -288.591176) (xy 294.963086 -288.554339) (xy 295.001207 -288.523214)
			(xy 295.043828 -288.498607) (xy 295.089844 -288.481155) (xy 295.138063 -288.471311) (xy 295.187238 -288.46933)
			(xy 295.236093 -288.475262) (xy 295.283364 -288.488954) (xy 295.327826 -288.510052) (xy 295.368329 -288.538008)
			(xy 295.403822 -288.5721) (xy 295.433387 -288.611444) (xy 295.456258 -288.655021) (xy 295.471842 -288.701702)
			(xy 295.479737 -288.750279) (xy 295.480232 -288.774886) (xy 295.81908 -288.774886) (xy 295.82304 -288.725832)
			(xy 295.834817 -288.678048) (xy 295.854108 -288.632772) (xy 295.880411 -288.591176) (xy 295.913046 -288.554339)
			(xy 295.951167 -288.523214) (xy 295.993788 -288.498607) (xy 296.039804 -288.481155) (xy 296.088023 -288.471311)
			(xy 296.137198 -288.46933) (xy 296.186053 -288.475262) (xy 296.233324 -288.488954) (xy 296.277786 -288.510052)
			(xy 296.318289 -288.538008) (xy 296.353782 -288.5721) (xy 296.383347 -288.611444) (xy 296.406218 -288.655021)
			(xy 296.421802 -288.701702) (xy 296.429697 -288.750279) (xy 296.430192 -288.774886) (xy 296.76904 -288.774886)
			(xy 296.773 -288.725832) (xy 296.784777 -288.678048) (xy 296.804068 -288.632772) (xy 296.830371 -288.591176)
			(xy 296.863006 -288.554339) (xy 296.901127 -288.523214) (xy 296.943748 -288.498607) (xy 296.989764 -288.481155)
			(xy 297.037983 -288.471311) (xy 297.087158 -288.46933) (xy 297.136013 -288.475262) (xy 297.183284 -288.488954)
			(xy 297.227746 -288.510052) (xy 297.268249 -288.538008) (xy 297.303742 -288.5721) (xy 297.333307 -288.611444)
			(xy 297.356178 -288.655021) (xy 297.371762 -288.701702) (xy 297.379657 -288.750279) (xy 297.380152 -288.774886)
			(xy 297.719 -288.774886) (xy 297.72296 -288.725832) (xy 297.734737 -288.678048) (xy 297.754028 -288.632772)
			(xy 297.780331 -288.591176) (xy 297.812966 -288.554339) (xy 297.851087 -288.523214) (xy 297.893708 -288.498607)
			(xy 297.939724 -288.481155) (xy 297.987943 -288.471311) (xy 298.037118 -288.46933) (xy 298.085973 -288.475262)
			(xy 298.133244 -288.488954) (xy 298.177706 -288.510052) (xy 298.218209 -288.538008) (xy 298.253702 -288.5721)
			(xy 298.283267 -288.611444) (xy 298.306138 -288.655021) (xy 298.321722 -288.701702) (xy 298.329617 -288.750279)
			(xy 298.330112 -288.774886) (xy 298.66896 -288.774886) (xy 298.67292 -288.725832) (xy 298.684697 -288.678048)
			(xy 298.703988 -288.632772) (xy 298.730291 -288.591176) (xy 298.762926 -288.554339) (xy 298.801047 -288.523214)
			(xy 298.843668 -288.498607) (xy 298.889684 -288.481155) (xy 298.937903 -288.471311) (xy 298.987078 -288.46933)
			(xy 299.035933 -288.475262) (xy 299.083204 -288.488954) (xy 299.127666 -288.510052) (xy 299.168169 -288.538008)
			(xy 299.203662 -288.5721) (xy 299.233227 -288.611444) (xy 299.256098 -288.655021) (xy 299.271682 -288.701702)
			(xy 299.279577 -288.750279) (xy 299.280072 -288.774886) (xy 299.61892 -288.774886) (xy 299.62288 -288.725832)
			(xy 299.634657 -288.678048) (xy 299.653948 -288.632772) (xy 299.680251 -288.591176) (xy 299.712886 -288.554339)
			(xy 299.751007 -288.523214) (xy 299.793628 -288.498607) (xy 299.839644 -288.481155) (xy 299.887863 -288.471311)
			(xy 299.937038 -288.46933) (xy 299.985893 -288.475262) (xy 300.033164 -288.488954) (xy 300.077626 -288.510052)
			(xy 300.118129 -288.538008) (xy 300.153622 -288.5721) (xy 300.183187 -288.611444) (xy 300.206058 -288.655021)
			(xy 300.221642 -288.701702) (xy 300.229537 -288.750279) (xy 300.230032 -288.774886) (xy 300.56888 -288.774886)
			(xy 300.57284 -288.725832) (xy 300.584617 -288.678048) (xy 300.603908 -288.632772) (xy 300.630211 -288.591176)
			(xy 300.662846 -288.554339) (xy 300.700967 -288.523214) (xy 300.743588 -288.498607) (xy 300.789604 -288.481155)
			(xy 300.837823 -288.471311) (xy 300.886998 -288.46933) (xy 300.935853 -288.475262) (xy 300.983124 -288.488954)
			(xy 301.027586 -288.510052) (xy 301.068089 -288.538008) (xy 301.103582 -288.5721) (xy 301.133147 -288.611444)
			(xy 301.156018 -288.655021) (xy 301.171602 -288.701702) (xy 301.179497 -288.750279) (xy 301.179992 -288.774886)
			(xy 301.519094 -288.774886) (xy 301.523054 -288.725832) (xy 301.534831 -288.678048) (xy 301.554122 -288.632772)
			(xy 301.580425 -288.591176) (xy 301.61306 -288.554339) (xy 301.651181 -288.523214) (xy 301.693802 -288.498607)
			(xy 301.739818 -288.481155) (xy 301.788037 -288.471311) (xy 301.837212 -288.46933) (xy 301.886067 -288.475262)
			(xy 301.933338 -288.488954) (xy 301.9778 -288.510052) (xy 302.018303 -288.538008) (xy 302.053796 -288.5721)
			(xy 302.083361 -288.611444) (xy 302.106232 -288.655021) (xy 302.121816 -288.701702) (xy 302.129711 -288.750279)
			(xy 302.130206 -288.774886) (xy 302.469054 -288.774886) (xy 302.473014 -288.725832) (xy 302.484791 -288.678048)
			(xy 302.504082 -288.632772) (xy 302.530385 -288.591176) (xy 302.56302 -288.554339) (xy 302.601141 -288.523214)
			(xy 302.643762 -288.498607) (xy 302.689778 -288.481155) (xy 302.737997 -288.471311) (xy 302.787172 -288.46933)
			(xy 302.836027 -288.475262) (xy 302.883298 -288.488954) (xy 302.92776 -288.510052) (xy 302.968263 -288.538008)
			(xy 303.003756 -288.5721) (xy 303.033321 -288.611444) (xy 303.056192 -288.655021) (xy 303.071776 -288.701702)
			(xy 303.079671 -288.750279) (xy 303.080166 -288.774886) (xy 303.419014 -288.774886) (xy 303.422974 -288.725832)
			(xy 303.434751 -288.678048) (xy 303.454042 -288.632772) (xy 303.480345 -288.591176) (xy 303.51298 -288.554339)
			(xy 303.551101 -288.523214) (xy 303.593722 -288.498607) (xy 303.639738 -288.481155) (xy 303.687957 -288.471311)
			(xy 303.737132 -288.46933) (xy 303.785987 -288.475262) (xy 303.833258 -288.488954) (xy 303.87772 -288.510052)
			(xy 303.918223 -288.538008) (xy 303.953716 -288.5721) (xy 303.983281 -288.611444) (xy 304.006152 -288.655021)
			(xy 304.021736 -288.701702) (xy 304.029631 -288.750279) (xy 304.030126 -288.774886) (xy 304.368974 -288.774886)
			(xy 304.372934 -288.725832) (xy 304.384711 -288.678048) (xy 304.404002 -288.632772) (xy 304.430305 -288.591176)
			(xy 304.46294 -288.554339) (xy 304.501061 -288.523214) (xy 304.543682 -288.498607) (xy 304.589698 -288.481155)
			(xy 304.637917 -288.471311) (xy 304.687092 -288.46933) (xy 304.735947 -288.475262) (xy 304.783218 -288.488954)
			(xy 304.82768 -288.510052) (xy 304.868183 -288.538008) (xy 304.903676 -288.5721) (xy 304.933241 -288.611444)
			(xy 304.956112 -288.655021) (xy 304.971696 -288.701702) (xy 304.979591 -288.750279) (xy 304.980086 -288.774886)
			(xy 304.979591 -288.799493) (xy 304.971696 -288.84807) (xy 304.956112 -288.894751) (xy 304.933241 -288.938328)
			(xy 304.903676 -288.977672) (xy 304.868183 -289.011764) (xy 304.82768 -289.03972) (xy 304.783218 -289.060818)
			(xy 304.735947 -289.07451) (xy 304.687092 -289.080442) (xy 304.637917 -289.078461) (xy 304.589698 -289.068617)
			(xy 304.543682 -289.051165) (xy 304.501061 -289.026558) (xy 304.46294 -288.995433) (xy 304.430305 -288.958596)
			(xy 304.404002 -288.917) (xy 304.384711 -288.871724) (xy 304.372934 -288.82394) (xy 304.368974 -288.774886)
			(xy 304.030126 -288.774886) (xy 304.029631 -288.799493) (xy 304.021736 -288.84807) (xy 304.006152 -288.894751)
			(xy 303.983281 -288.938328) (xy 303.953716 -288.977672) (xy 303.918223 -289.011764) (xy 303.87772 -289.03972)
			(xy 303.833258 -289.060818) (xy 303.785987 -289.07451) (xy 303.737132 -289.080442) (xy 303.687957 -289.078461)
			(xy 303.639738 -289.068617) (xy 303.593722 -289.051165) (xy 303.551101 -289.026558) (xy 303.51298 -288.995433)
			(xy 303.480345 -288.958596) (xy 303.454042 -288.917) (xy 303.434751 -288.871724) (xy 303.422974 -288.82394)
			(xy 303.419014 -288.774886) (xy 303.080166 -288.774886) (xy 303.079671 -288.799493) (xy 303.071776 -288.84807)
			(xy 303.056192 -288.894751) (xy 303.033321 -288.938328) (xy 303.003756 -288.977672) (xy 302.968263 -289.011764)
			(xy 302.92776 -289.03972) (xy 302.883298 -289.060818) (xy 302.836027 -289.07451) (xy 302.787172 -289.080442)
			(xy 302.737997 -289.078461) (xy 302.689778 -289.068617) (xy 302.643762 -289.051165) (xy 302.601141 -289.026558)
			(xy 302.56302 -288.995433) (xy 302.530385 -288.958596) (xy 302.504082 -288.917) (xy 302.484791 -288.871724)
			(xy 302.473014 -288.82394) (xy 302.469054 -288.774886) (xy 302.130206 -288.774886) (xy 302.129711 -288.799493)
			(xy 302.121816 -288.84807) (xy 302.106232 -288.894751) (xy 302.083361 -288.938328) (xy 302.053796 -288.977672)
			(xy 302.018303 -289.011764) (xy 301.9778 -289.03972) (xy 301.933338 -289.060818) (xy 301.886067 -289.07451)
			(xy 301.837212 -289.080442) (xy 301.788037 -289.078461) (xy 301.739818 -289.068617) (xy 301.693802 -289.051165)
			(xy 301.651181 -289.026558) (xy 301.61306 -288.995433) (xy 301.580425 -288.958596) (xy 301.554122 -288.917)
			(xy 301.534831 -288.871724) (xy 301.523054 -288.82394) (xy 301.519094 -288.774886) (xy 301.179992 -288.774886)
			(xy 301.179497 -288.799493) (xy 301.171602 -288.84807) (xy 301.156018 -288.894751) (xy 301.133147 -288.938328)
			(xy 301.103582 -288.977672) (xy 301.068089 -289.011764) (xy 301.027586 -289.03972) (xy 300.983124 -289.060818)
			(xy 300.935853 -289.07451) (xy 300.886998 -289.080442) (xy 300.837823 -289.078461) (xy 300.789604 -289.068617)
			(xy 300.743588 -289.051165) (xy 300.700967 -289.026558) (xy 300.662846 -288.995433) (xy 300.630211 -288.958596)
			(xy 300.603908 -288.917) (xy 300.584617 -288.871724) (xy 300.57284 -288.82394) (xy 300.56888 -288.774886)
			(xy 300.230032 -288.774886) (xy 300.229537 -288.799493) (xy 300.221642 -288.84807) (xy 300.206058 -288.894751)
			(xy 300.183187 -288.938328) (xy 300.153622 -288.977672) (xy 300.118129 -289.011764) (xy 300.077626 -289.03972)
			(xy 300.033164 -289.060818) (xy 299.985893 -289.07451) (xy 299.937038 -289.080442) (xy 299.887863 -289.078461)
			(xy 299.839644 -289.068617) (xy 299.793628 -289.051165) (xy 299.751007 -289.026558) (xy 299.712886 -288.995433)
			(xy 299.680251 -288.958596) (xy 299.653948 -288.917) (xy 299.634657 -288.871724) (xy 299.62288 -288.82394)
			(xy 299.61892 -288.774886) (xy 299.280072 -288.774886) (xy 299.279577 -288.799493) (xy 299.271682 -288.84807)
			(xy 299.256098 -288.894751) (xy 299.233227 -288.938328) (xy 299.203662 -288.977672) (xy 299.168169 -289.011764)
			(xy 299.127666 -289.03972) (xy 299.083204 -289.060818) (xy 299.035933 -289.07451) (xy 298.987078 -289.080442)
			(xy 298.937903 -289.078461) (xy 298.889684 -289.068617) (xy 298.843668 -289.051165) (xy 298.801047 -289.026558)
			(xy 298.762926 -288.995433) (xy 298.730291 -288.958596) (xy 298.703988 -288.917) (xy 298.684697 -288.871724)
			(xy 298.67292 -288.82394) (xy 298.66896 -288.774886) (xy 298.330112 -288.774886) (xy 298.329617 -288.799493)
			(xy 298.321722 -288.84807) (xy 298.306138 -288.894751) (xy 298.283267 -288.938328) (xy 298.253702 -288.977672)
			(xy 298.218209 -289.011764) (xy 298.177706 -289.03972) (xy 298.133244 -289.060818) (xy 298.085973 -289.07451)
			(xy 298.037118 -289.080442) (xy 297.987943 -289.078461) (xy 297.939724 -289.068617) (xy 297.893708 -289.051165)
			(xy 297.851087 -289.026558) (xy 297.812966 -288.995433) (xy 297.780331 -288.958596) (xy 297.754028 -288.917)
			(xy 297.734737 -288.871724) (xy 297.72296 -288.82394) (xy 297.719 -288.774886) (xy 297.380152 -288.774886)
			(xy 297.379657 -288.799493) (xy 297.371762 -288.84807) (xy 297.356178 -288.894751) (xy 297.333307 -288.938328)
			(xy 297.303742 -288.977672) (xy 297.268249 -289.011764) (xy 297.227746 -289.03972) (xy 297.183284 -289.060818)
			(xy 297.136013 -289.07451) (xy 297.087158 -289.080442) (xy 297.037983 -289.078461) (xy 296.989764 -289.068617)
			(xy 296.943748 -289.051165) (xy 296.901127 -289.026558) (xy 296.863006 -288.995433) (xy 296.830371 -288.958596)
			(xy 296.804068 -288.917) (xy 296.784777 -288.871724) (xy 296.773 -288.82394) (xy 296.76904 -288.774886)
			(xy 296.430192 -288.774886) (xy 296.429697 -288.799493) (xy 296.421802 -288.84807) (xy 296.406218 -288.894751)
			(xy 296.383347 -288.938328) (xy 296.353782 -288.977672) (xy 296.318289 -289.011764) (xy 296.277786 -289.03972)
			(xy 296.233324 -289.060818) (xy 296.186053 -289.07451) (xy 296.137198 -289.080442) (xy 296.088023 -289.078461)
			(xy 296.039804 -289.068617) (xy 295.993788 -289.051165) (xy 295.951167 -289.026558) (xy 295.913046 -288.995433)
			(xy 295.880411 -288.958596) (xy 295.854108 -288.917) (xy 295.834817 -288.871724) (xy 295.82304 -288.82394)
			(xy 295.81908 -288.774886) (xy 295.480232 -288.774886) (xy 295.479737 -288.799493) (xy 295.471842 -288.84807)
			(xy 295.456258 -288.894751) (xy 295.433387 -288.938328) (xy 295.403822 -288.977672) (xy 295.368329 -289.011764)
			(xy 295.327826 -289.03972) (xy 295.283364 -289.060818) (xy 295.236093 -289.07451) (xy 295.187238 -289.080442)
			(xy 295.138063 -289.078461) (xy 295.089844 -289.068617) (xy 295.043828 -289.051165) (xy 295.001207 -289.026558)
			(xy 294.963086 -288.995433) (xy 294.930451 -288.958596) (xy 294.904148 -288.917) (xy 294.884857 -288.871724)
			(xy 294.87308 -288.82394) (xy 294.86912 -288.774886) (xy 294.530018 -288.774886) (xy 294.529523 -288.799493)
			(xy 294.521628 -288.84807) (xy 294.506044 -288.894751) (xy 294.483173 -288.938328) (xy 294.453608 -288.977672)
			(xy 294.418115 -289.011764) (xy 294.377612 -289.03972) (xy 294.33315 -289.060818) (xy 294.285879 -289.07451)
			(xy 294.237024 -289.080442) (xy 294.187849 -289.078461) (xy 294.13963 -289.068617) (xy 294.093614 -289.051165)
			(xy 294.050993 -289.026558) (xy 294.012872 -288.995433) (xy 293.980237 -288.958596) (xy 293.953934 -288.917)
			(xy 293.934643 -288.871724) (xy 293.922866 -288.82394) (xy 293.918906 -288.774886) (xy 293.580058 -288.774886)
			(xy 293.579563 -288.799493) (xy 293.571668 -288.84807) (xy 293.556084 -288.894751) (xy 293.533213 -288.938328)
			(xy 293.503648 -288.977672) (xy 293.468155 -289.011764) (xy 293.427652 -289.03972) (xy 293.38319 -289.060818)
			(xy 293.335919 -289.07451) (xy 293.287064 -289.080442) (xy 293.237889 -289.078461) (xy 293.18967 -289.068617)
			(xy 293.143654 -289.051165) (xy 293.101033 -289.026558) (xy 293.062912 -288.995433) (xy 293.030277 -288.958596)
			(xy 293.003974 -288.917) (xy 292.984683 -288.871724) (xy 292.972906 -288.82394) (xy 292.968946 -288.774886)
			(xy 292.630098 -288.774886) (xy 292.629603 -288.799493) (xy 292.621708 -288.84807) (xy 292.606124 -288.894751)
			(xy 292.583253 -288.938328) (xy 292.553688 -288.977672) (xy 292.518195 -289.011764) (xy 292.477692 -289.03972)
			(xy 292.43323 -289.060818) (xy 292.385959 -289.07451) (xy 292.337104 -289.080442) (xy 292.287929 -289.078461)
			(xy 292.23971 -289.068617) (xy 292.193694 -289.051165) (xy 292.151073 -289.026558) (xy 292.112952 -288.995433)
			(xy 292.080317 -288.958596) (xy 292.054014 -288.917) (xy 292.034723 -288.871724) (xy 292.022946 -288.82394)
			(xy 292.018986 -288.774886) (xy 290.730178 -288.774886) (xy 290.729683 -288.799493) (xy 290.721788 -288.84807)
			(xy 290.706204 -288.894751) (xy 290.683333 -288.938328) (xy 290.653768 -288.977672) (xy 290.618275 -289.011764)
			(xy 290.577772 -289.03972) (xy 290.53331 -289.060818) (xy 290.486039 -289.07451) (xy 290.437184 -289.080442)
			(xy 290.388009 -289.078461) (xy 290.33979 -289.068617) (xy 290.293774 -289.051165) (xy 290.251153 -289.026558)
			(xy 290.213032 -288.995433) (xy 290.180397 -288.958596) (xy 290.154094 -288.917) (xy 290.134803 -288.871724)
			(xy 290.123026 -288.82394) (xy 290.119066 -288.774886) (xy 289.780218 -288.774886) (xy 289.779723 -288.799493)
			(xy 289.771828 -288.84807) (xy 289.756244 -288.894751) (xy 289.733373 -288.938328) (xy 289.703808 -288.977672)
			(xy 289.668315 -289.011764) (xy 289.627812 -289.03972) (xy 289.58335 -289.060818) (xy 289.536079 -289.07451)
			(xy 289.487224 -289.080442) (xy 289.438049 -289.078461) (xy 289.38983 -289.068617) (xy 289.343814 -289.051165)
			(xy 289.301193 -289.026558) (xy 289.263072 -288.995433) (xy 289.230437 -288.958596) (xy 289.204134 -288.917)
			(xy 289.184843 -288.871724) (xy 289.173066 -288.82394) (xy 289.169106 -288.774886) (xy 288.830004 -288.774886)
			(xy 288.829509 -288.799493) (xy 288.821614 -288.84807) (xy 288.80603 -288.894751) (xy 288.783159 -288.938328)
			(xy 288.753594 -288.977672) (xy 288.718101 -289.011764) (xy 288.677598 -289.03972) (xy 288.633136 -289.060818)
			(xy 288.585865 -289.07451) (xy 288.53701 -289.080442) (xy 288.487835 -289.078461) (xy 288.439616 -289.068617)
			(xy 288.3936 -289.051165) (xy 288.350979 -289.026558) (xy 288.312858 -288.995433) (xy 288.280223 -288.958596)
			(xy 288.25392 -288.917) (xy 288.234629 -288.871724) (xy 288.222852 -288.82394) (xy 288.218892 -288.774886)
			(xy 287.880044 -288.774886) (xy 287.879549 -288.799493) (xy 287.871654 -288.84807) (xy 287.85607 -288.894751)
			(xy 287.833199 -288.938328) (xy 287.803634 -288.977672) (xy 287.768141 -289.011764) (xy 287.727638 -289.03972)
			(xy 287.683176 -289.060818) (xy 287.635905 -289.07451) (xy 287.58705 -289.080442) (xy 287.537875 -289.078461)
			(xy 287.489656 -289.068617) (xy 287.44364 -289.051165) (xy 287.401019 -289.026558) (xy 287.362898 -288.995433)
			(xy 287.330263 -288.958596) (xy 287.30396 -288.917) (xy 287.284669 -288.871724) (xy 287.272892 -288.82394)
			(xy 287.268932 -288.774886) (xy 286.930084 -288.774886) (xy 286.929589 -288.799493) (xy 286.921694 -288.84807)
			(xy 286.90611 -288.894751) (xy 286.883239 -288.938328) (xy 286.853674 -288.977672) (xy 286.818181 -289.011764)
			(xy 286.777678 -289.03972) (xy 286.733216 -289.060818) (xy 286.685945 -289.07451) (xy 286.63709 -289.080442)
			(xy 286.587915 -289.078461) (xy 286.539696 -289.068617) (xy 286.49368 -289.051165) (xy 286.451059 -289.026558)
			(xy 286.412938 -288.995433) (xy 286.380303 -288.958596) (xy 286.354 -288.917) (xy 286.334709 -288.871724)
			(xy 286.322932 -288.82394) (xy 286.318972 -288.774886) (xy 285.980124 -288.774886) (xy 285.979629 -288.799493)
			(xy 285.971734 -288.84807) (xy 285.95615 -288.894751) (xy 285.933279 -288.938328) (xy 285.903714 -288.977672)
			(xy 285.868221 -289.011764) (xy 285.827718 -289.03972) (xy 285.783256 -289.060818) (xy 285.735985 -289.07451)
			(xy 285.68713 -289.080442) (xy 285.637955 -289.078461) (xy 285.589736 -289.068617) (xy 285.54372 -289.051165)
			(xy 285.501099 -289.026558) (xy 285.462978 -288.995433) (xy 285.430343 -288.958596) (xy 285.40404 -288.917)
			(xy 285.384749 -288.871724) (xy 285.372972 -288.82394) (xy 285.369012 -288.774886) (xy 285.030164 -288.774886)
			(xy 285.029669 -288.799493) (xy 285.021774 -288.84807) (xy 285.00619 -288.894751) (xy 284.983319 -288.938328)
			(xy 284.953754 -288.977672) (xy 284.918261 -289.011764) (xy 284.877758 -289.03972) (xy 284.833296 -289.060818)
			(xy 284.786025 -289.07451) (xy 284.73717 -289.080442) (xy 284.687995 -289.078461) (xy 284.639776 -289.068617)
			(xy 284.59376 -289.051165) (xy 284.551139 -289.026558) (xy 284.513018 -288.995433) (xy 284.480383 -288.958596)
			(xy 284.45408 -288.917) (xy 284.434789 -288.871724) (xy 284.423012 -288.82394) (xy 284.419052 -288.774886)
			(xy 284.080204 -288.774886) (xy 284.079709 -288.799493) (xy 284.071814 -288.84807) (xy 284.05623 -288.894751)
			(xy 284.033359 -288.938328) (xy 284.003794 -288.977672) (xy 283.968301 -289.011764) (xy 283.927798 -289.03972)
			(xy 283.883336 -289.060818) (xy 283.836065 -289.07451) (xy 283.78721 -289.080442) (xy 283.738035 -289.078461)
			(xy 283.689816 -289.068617) (xy 283.6438 -289.051165) (xy 283.601179 -289.026558) (xy 283.563058 -288.995433)
			(xy 283.530423 -288.958596) (xy 283.50412 -288.917) (xy 283.484829 -288.871724) (xy 283.473052 -288.82394)
			(xy 283.469092 -288.774886) (xy 283.130244 -288.774886) (xy 283.129749 -288.799493) (xy 283.121854 -288.84807)
			(xy 283.10627 -288.894751) (xy 283.083399 -288.938328) (xy 283.053834 -288.977672) (xy 283.018341 -289.011764)
			(xy 282.977838 -289.03972) (xy 282.933376 -289.060818) (xy 282.886105 -289.07451) (xy 282.83725 -289.080442)
			(xy 282.788075 -289.078461) (xy 282.739856 -289.068617) (xy 282.69384 -289.051165) (xy 282.651219 -289.026558)
			(xy 282.613098 -288.995433) (xy 282.580463 -288.958596) (xy 282.55416 -288.917) (xy 282.534869 -288.871724)
			(xy 282.523092 -288.82394) (xy 282.519132 -288.774886) (xy 282.18003 -288.774886) (xy 282.179535 -288.799493)
			(xy 282.17164 -288.84807) (xy 282.156056 -288.894751) (xy 282.133185 -288.938328) (xy 282.10362 -288.977672)
			(xy 282.068127 -289.011764) (xy 282.027624 -289.03972) (xy 281.983162 -289.060818) (xy 281.935891 -289.07451)
			(xy 281.887036 -289.080442) (xy 281.837861 -289.078461) (xy 281.789642 -289.068617) (xy 281.743626 -289.051165)
			(xy 281.701005 -289.026558) (xy 281.662884 -288.995433) (xy 281.630249 -288.958596) (xy 281.603946 -288.917)
			(xy 281.584655 -288.871724) (xy 281.572878 -288.82394) (xy 281.568918 -288.774886) (xy 281.23007 -288.774886)
			(xy 281.229575 -288.799493) (xy 281.22168 -288.84807) (xy 281.206096 -288.894751) (xy 281.183225 -288.938328)
			(xy 281.15366 -288.977672) (xy 281.118167 -289.011764) (xy 281.077664 -289.03972) (xy 281.033202 -289.060818)
			(xy 280.985931 -289.07451) (xy 280.937076 -289.080442) (xy 280.887901 -289.078461) (xy 280.839682 -289.068617)
			(xy 280.793666 -289.051165) (xy 280.751045 -289.026558) (xy 280.712924 -288.995433) (xy 280.680289 -288.958596)
			(xy 280.653986 -288.917) (xy 280.634695 -288.871724) (xy 280.622918 -288.82394) (xy 280.618958 -288.774886)
			(xy 280.28011 -288.774886) (xy 280.28011 -288.791396) (xy 280.279602 -288.797238) (xy 280.279602 -288.797746)
			(xy 280.278332 -288.808668) (xy 280.278332 -288.808922) (xy 280.277824 -288.812986) (xy 280.275284 -288.831782)
			(xy 280.274268 -288.83737) (xy 280.270204 -288.853118) (xy 280.268426 -288.865818) (xy 280.268426 -289.08502)
			(xy 317.987678 -289.08502) (xy 317.991749 -289.029398) (xy 318.003875 -288.974961) (xy 318.023798 -288.92287)
			(xy 318.051094 -288.874235) (xy 318.08518 -288.830092) (xy 318.125329 -288.791383) (xy 318.170687 -288.758932)
			(xy 318.220287 -288.733431) (xy 318.273071 -288.715424) (xy 318.327914 -288.705294) (xy 318.383648 -288.703257)
			(xy 318.439085 -288.709357) (xy 318.493042 -288.723463) (xy 318.544371 -288.745275) (xy 318.591977 -288.774329)
			(xy 318.634845 -288.810004) (xy 318.653448 -288.830766) (xy 325.352916 -288.830766) (xy 325.356987 -288.775144)
			(xy 325.369113 -288.720707) (xy 325.389036 -288.668616) (xy 325.416332 -288.619981) (xy 325.450418 -288.575838)
			(xy 325.490567 -288.537129) (xy 325.535925 -288.504678) (xy 325.585525 -288.479177) (xy 325.638309 -288.46117)
			(xy 325.693152 -288.45104) (xy 325.748886 -288.449003) (xy 325.804323 -288.455103) (xy 325.85828 -288.469209)
			(xy 325.909609 -288.491021) (xy 325.957215 -288.520075) (xy 326.000083 -288.55575) (xy 326.0373 -288.597287)
			(xy 326.068073 -288.6438) (xy 326.091745 -288.694297) (xy 326.107813 -288.747704) (xy 326.115933 -288.80288)
			(xy 326.116442 -288.830766) (xy 326.115933 -288.858652) (xy 326.107813 -288.913828) (xy 326.091745 -288.967235)
			(xy 326.068073 -289.017732) (xy 326.0373 -289.064245) (xy 326.000083 -289.105782) (xy 325.957215 -289.141457)
			(xy 325.909609 -289.170511) (xy 325.85828 -289.192323) (xy 325.804323 -289.206429) (xy 325.748886 -289.212529)
			(xy 325.693152 -289.210492) (xy 325.638309 -289.200362) (xy 325.585525 -289.182355) (xy 325.535925 -289.156854)
			(xy 325.490567 -289.124403) (xy 325.450418 -289.085694) (xy 325.416332 -289.041551) (xy 325.389036 -288.992916)
			(xy 325.369113 -288.940825) (xy 325.356987 -288.886388) (xy 325.352916 -288.830766) (xy 318.653448 -288.830766)
			(xy 318.672062 -288.851541) (xy 318.702835 -288.898054) (xy 318.726507 -288.948551) (xy 318.742575 -289.001958)
			(xy 318.750695 -289.057134) (xy 318.751204 -289.08502) (xy 318.750695 -289.112906) (xy 318.742575 -289.168082)
			(xy 318.726507 -289.221489) (xy 318.702835 -289.271986) (xy 318.672062 -289.318499) (xy 318.634845 -289.360036)
			(xy 318.591977 -289.395711) (xy 318.544371 -289.424765) (xy 318.493042 -289.446577) (xy 318.439085 -289.460683)
			(xy 318.383648 -289.466783) (xy 318.327914 -289.464746) (xy 318.273071 -289.454616) (xy 318.220287 -289.436609)
			(xy 318.170687 -289.411108) (xy 318.125329 -289.378657) (xy 318.08518 -289.339948) (xy 318.051094 -289.295805)
			(xy 318.023798 -289.24717) (xy 318.003875 -289.195079) (xy 317.991749 -289.140642) (xy 317.987678 -289.08502)
			(xy 280.268426 -289.08502) (xy 280.268426 -289.630104) (xy 280.268934 -289.6362) (xy 280.270204 -289.647376)
			(xy 280.270966 -289.650678) (xy 280.270966 -289.651186) (xy 280.275215 -289.669305) (xy 280.279793 -289.706238)
			(xy 280.28011 -289.724846) (xy 280.618958 -289.724846) (xy 280.622918 -289.675792) (xy 280.634695 -289.628008)
			(xy 280.653986 -289.582732) (xy 280.680289 -289.541136) (xy 280.712924 -289.504299) (xy 280.751045 -289.473174)
			(xy 280.793666 -289.448567) (xy 280.839682 -289.431115) (xy 280.887901 -289.421271) (xy 280.937076 -289.41929)
			(xy 280.985931 -289.425222) (xy 281.033202 -289.438914) (xy 281.077664 -289.460012) (xy 281.118167 -289.487968)
			(xy 281.15366 -289.52206) (xy 281.183225 -289.561404) (xy 281.206096 -289.604981) (xy 281.22168 -289.651662)
			(xy 281.229575 -289.700239) (xy 281.23007 -289.724846) (xy 281.568918 -289.724846) (xy 281.572878 -289.675792)
			(xy 281.584655 -289.628008) (xy 281.603946 -289.582732) (xy 281.630249 -289.541136) (xy 281.662884 -289.504299)
			(xy 281.701005 -289.473174) (xy 281.743626 -289.448567) (xy 281.789642 -289.431115) (xy 281.837861 -289.421271)
			(xy 281.887036 -289.41929) (xy 281.935891 -289.425222) (xy 281.983162 -289.438914) (xy 282.027624 -289.460012)
			(xy 282.068127 -289.487968) (xy 282.10362 -289.52206) (xy 282.133185 -289.561404) (xy 282.156056 -289.604981)
			(xy 282.17164 -289.651662) (xy 282.179535 -289.700239) (xy 282.18003 -289.724846) (xy 282.519132 -289.724846)
			(xy 282.523092 -289.675792) (xy 282.534869 -289.628008) (xy 282.55416 -289.582732) (xy 282.580463 -289.541136)
			(xy 282.613098 -289.504299) (xy 282.651219 -289.473174) (xy 282.69384 -289.448567) (xy 282.739856 -289.431115)
			(xy 282.788075 -289.421271) (xy 282.83725 -289.41929) (xy 282.886105 -289.425222) (xy 282.933376 -289.438914)
			(xy 282.977838 -289.460012) (xy 283.018341 -289.487968) (xy 283.053834 -289.52206) (xy 283.083399 -289.561404)
			(xy 283.10627 -289.604981) (xy 283.121854 -289.651662) (xy 283.129749 -289.700239) (xy 283.130244 -289.724846)
			(xy 283.469092 -289.724846) (xy 283.473052 -289.675792) (xy 283.484829 -289.628008) (xy 283.50412 -289.582732)
			(xy 283.530423 -289.541136) (xy 283.563058 -289.504299) (xy 283.601179 -289.473174) (xy 283.6438 -289.448567)
			(xy 283.689816 -289.431115) (xy 283.738035 -289.421271) (xy 283.78721 -289.41929) (xy 283.836065 -289.425222)
			(xy 283.883336 -289.438914) (xy 283.927798 -289.460012) (xy 283.968301 -289.487968) (xy 284.003794 -289.52206)
			(xy 284.033359 -289.561404) (xy 284.05623 -289.604981) (xy 284.071814 -289.651662) (xy 284.079709 -289.700239)
			(xy 284.080204 -289.724846) (xy 284.419052 -289.724846) (xy 284.423012 -289.675792) (xy 284.434789 -289.628008)
			(xy 284.45408 -289.582732) (xy 284.480383 -289.541136) (xy 284.513018 -289.504299) (xy 284.551139 -289.473174)
			(xy 284.59376 -289.448567) (xy 284.639776 -289.431115) (xy 284.687995 -289.421271) (xy 284.73717 -289.41929)
			(xy 284.786025 -289.425222) (xy 284.833296 -289.438914) (xy 284.877758 -289.460012) (xy 284.918261 -289.487968)
			(xy 284.953754 -289.52206) (xy 284.983319 -289.561404) (xy 285.00619 -289.604981) (xy 285.021774 -289.651662)
			(xy 285.029669 -289.700239) (xy 285.030164 -289.724846) (xy 285.369012 -289.724846) (xy 285.372972 -289.675792)
			(xy 285.384749 -289.628008) (xy 285.40404 -289.582732) (xy 285.430343 -289.541136) (xy 285.462978 -289.504299)
			(xy 285.501099 -289.473174) (xy 285.54372 -289.448567) (xy 285.589736 -289.431115) (xy 285.637955 -289.421271)
			(xy 285.68713 -289.41929) (xy 285.735985 -289.425222) (xy 285.783256 -289.438914) (xy 285.827718 -289.460012)
			(xy 285.868221 -289.487968) (xy 285.903714 -289.52206) (xy 285.933279 -289.561404) (xy 285.95615 -289.604981)
			(xy 285.971734 -289.651662) (xy 285.979629 -289.700239) (xy 285.980124 -289.724846) (xy 286.318972 -289.724846)
			(xy 286.322932 -289.675792) (xy 286.334709 -289.628008) (xy 286.354 -289.582732) (xy 286.380303 -289.541136)
			(xy 286.412938 -289.504299) (xy 286.451059 -289.473174) (xy 286.49368 -289.448567) (xy 286.539696 -289.431115)
			(xy 286.587915 -289.421271) (xy 286.63709 -289.41929) (xy 286.685945 -289.425222) (xy 286.733216 -289.438914)
			(xy 286.777678 -289.460012) (xy 286.818181 -289.487968) (xy 286.853674 -289.52206) (xy 286.883239 -289.561404)
			(xy 286.90611 -289.604981) (xy 286.921694 -289.651662) (xy 286.929589 -289.700239) (xy 286.930084 -289.724846)
			(xy 287.268932 -289.724846) (xy 287.272892 -289.675792) (xy 287.284669 -289.628008) (xy 287.30396 -289.582732)
			(xy 287.330263 -289.541136) (xy 287.362898 -289.504299) (xy 287.401019 -289.473174) (xy 287.44364 -289.448567)
			(xy 287.489656 -289.431115) (xy 287.537875 -289.421271) (xy 287.58705 -289.41929) (xy 287.635905 -289.425222)
			(xy 287.683176 -289.438914) (xy 287.727638 -289.460012) (xy 287.768141 -289.487968) (xy 287.803634 -289.52206)
			(xy 287.833199 -289.561404) (xy 287.85607 -289.604981) (xy 287.871654 -289.651662) (xy 287.879549 -289.700239)
			(xy 287.880044 -289.724846) (xy 288.218892 -289.724846) (xy 288.222852 -289.675792) (xy 288.234629 -289.628008)
			(xy 288.25392 -289.582732) (xy 288.280223 -289.541136) (xy 288.312858 -289.504299) (xy 288.350979 -289.473174)
			(xy 288.3936 -289.448567) (xy 288.439616 -289.431115) (xy 288.487835 -289.421271) (xy 288.53701 -289.41929)
			(xy 288.585865 -289.425222) (xy 288.633136 -289.438914) (xy 288.677598 -289.460012) (xy 288.718101 -289.487968)
			(xy 288.753594 -289.52206) (xy 288.783159 -289.561404) (xy 288.80603 -289.604981) (xy 288.821614 -289.651662)
			(xy 288.829509 -289.700239) (xy 288.830004 -289.724846) (xy 289.169106 -289.724846) (xy 289.173066 -289.675792)
			(xy 289.184843 -289.628008) (xy 289.204134 -289.582732) (xy 289.230437 -289.541136) (xy 289.263072 -289.504299)
			(xy 289.301193 -289.473174) (xy 289.343814 -289.448567) (xy 289.38983 -289.431115) (xy 289.438049 -289.421271)
			(xy 289.487224 -289.41929) (xy 289.536079 -289.425222) (xy 289.58335 -289.438914) (xy 289.627812 -289.460012)
			(xy 289.668315 -289.487968) (xy 289.703808 -289.52206) (xy 289.733373 -289.561404) (xy 289.756244 -289.604981)
			(xy 289.771828 -289.651662) (xy 289.779723 -289.700239) (xy 289.780218 -289.724846) (xy 290.119066 -289.724846)
			(xy 290.123026 -289.675792) (xy 290.134803 -289.628008) (xy 290.154094 -289.582732) (xy 290.180397 -289.541136)
			(xy 290.213032 -289.504299) (xy 290.251153 -289.473174) (xy 290.293774 -289.448567) (xy 290.33979 -289.431115)
			(xy 290.388009 -289.421271) (xy 290.437184 -289.41929) (xy 290.486039 -289.425222) (xy 290.53331 -289.438914)
			(xy 290.577772 -289.460012) (xy 290.618275 -289.487968) (xy 290.653768 -289.52206) (xy 290.683333 -289.561404)
			(xy 290.706204 -289.604981) (xy 290.721788 -289.651662) (xy 290.729683 -289.700239) (xy 290.730178 -289.724846)
			(xy 292.018986 -289.724846) (xy 292.022946 -289.675792) (xy 292.034723 -289.628008) (xy 292.054014 -289.582732)
			(xy 292.080317 -289.541136) (xy 292.112952 -289.504299) (xy 292.151073 -289.473174) (xy 292.193694 -289.448567)
			(xy 292.23971 -289.431115) (xy 292.287929 -289.421271) (xy 292.337104 -289.41929) (xy 292.385959 -289.425222)
			(xy 292.43323 -289.438914) (xy 292.477692 -289.460012) (xy 292.518195 -289.487968) (xy 292.553688 -289.52206)
			(xy 292.583253 -289.561404) (xy 292.606124 -289.604981) (xy 292.621708 -289.651662) (xy 292.629603 -289.700239)
			(xy 292.630098 -289.724846) (xy 292.968946 -289.724846) (xy 292.972906 -289.675792) (xy 292.984683 -289.628008)
			(xy 293.003974 -289.582732) (xy 293.030277 -289.541136) (xy 293.062912 -289.504299) (xy 293.101033 -289.473174)
			(xy 293.143654 -289.448567) (xy 293.18967 -289.431115) (xy 293.237889 -289.421271) (xy 293.287064 -289.41929)
			(xy 293.335919 -289.425222) (xy 293.38319 -289.438914) (xy 293.427652 -289.460012) (xy 293.468155 -289.487968)
			(xy 293.503648 -289.52206) (xy 293.533213 -289.561404) (xy 293.556084 -289.604981) (xy 293.571668 -289.651662)
			(xy 293.579563 -289.700239) (xy 293.580058 -289.724846) (xy 293.918906 -289.724846) (xy 293.922866 -289.675792)
			(xy 293.934643 -289.628008) (xy 293.953934 -289.582732) (xy 293.980237 -289.541136) (xy 294.012872 -289.504299)
			(xy 294.050993 -289.473174) (xy 294.093614 -289.448567) (xy 294.13963 -289.431115) (xy 294.187849 -289.421271)
			(xy 294.237024 -289.41929) (xy 294.285879 -289.425222) (xy 294.33315 -289.438914) (xy 294.377612 -289.460012)
			(xy 294.418115 -289.487968) (xy 294.453608 -289.52206) (xy 294.483173 -289.561404) (xy 294.506044 -289.604981)
			(xy 294.521628 -289.651662) (xy 294.529523 -289.700239) (xy 294.530018 -289.724846) (xy 294.86912 -289.724846)
			(xy 294.87308 -289.675792) (xy 294.884857 -289.628008) (xy 294.904148 -289.582732) (xy 294.930451 -289.541136)
			(xy 294.963086 -289.504299) (xy 295.001207 -289.473174) (xy 295.043828 -289.448567) (xy 295.089844 -289.431115)
			(xy 295.138063 -289.421271) (xy 295.187238 -289.41929) (xy 295.236093 -289.425222) (xy 295.283364 -289.438914)
			(xy 295.327826 -289.460012) (xy 295.368329 -289.487968) (xy 295.403822 -289.52206) (xy 295.433387 -289.561404)
			(xy 295.456258 -289.604981) (xy 295.471842 -289.651662) (xy 295.479737 -289.700239) (xy 295.480232 -289.724846)
			(xy 295.81908 -289.724846) (xy 295.82304 -289.675792) (xy 295.834817 -289.628008) (xy 295.854108 -289.582732)
			(xy 295.880411 -289.541136) (xy 295.913046 -289.504299) (xy 295.951167 -289.473174) (xy 295.993788 -289.448567)
			(xy 296.039804 -289.431115) (xy 296.088023 -289.421271) (xy 296.137198 -289.41929) (xy 296.186053 -289.425222)
			(xy 296.233324 -289.438914) (xy 296.277786 -289.460012) (xy 296.318289 -289.487968) (xy 296.353782 -289.52206)
			(xy 296.383347 -289.561404) (xy 296.406218 -289.604981) (xy 296.421802 -289.651662) (xy 296.429697 -289.700239)
			(xy 296.430192 -289.724846) (xy 296.76904 -289.724846) (xy 296.773 -289.675792) (xy 296.784777 -289.628008)
			(xy 296.804068 -289.582732) (xy 296.830371 -289.541136) (xy 296.863006 -289.504299) (xy 296.901127 -289.473174)
			(xy 296.943748 -289.448567) (xy 296.989764 -289.431115) (xy 297.037983 -289.421271) (xy 297.087158 -289.41929)
			(xy 297.136013 -289.425222) (xy 297.183284 -289.438914) (xy 297.227746 -289.460012) (xy 297.268249 -289.487968)
			(xy 297.303742 -289.52206) (xy 297.333307 -289.561404) (xy 297.356178 -289.604981) (xy 297.371762 -289.651662)
			(xy 297.379657 -289.700239) (xy 297.380152 -289.724846) (xy 297.719 -289.724846) (xy 297.72296 -289.675792)
			(xy 297.734737 -289.628008) (xy 297.754028 -289.582732) (xy 297.780331 -289.541136) (xy 297.812966 -289.504299)
			(xy 297.851087 -289.473174) (xy 297.893708 -289.448567) (xy 297.939724 -289.431115) (xy 297.987943 -289.421271)
			(xy 298.037118 -289.41929) (xy 298.085973 -289.425222) (xy 298.133244 -289.438914) (xy 298.177706 -289.460012)
			(xy 298.218209 -289.487968) (xy 298.253702 -289.52206) (xy 298.283267 -289.561404) (xy 298.306138 -289.604981)
			(xy 298.321722 -289.651662) (xy 298.329617 -289.700239) (xy 298.330112 -289.724846) (xy 298.66896 -289.724846)
			(xy 298.67292 -289.675792) (xy 298.684697 -289.628008) (xy 298.703988 -289.582732) (xy 298.730291 -289.541136)
			(xy 298.762926 -289.504299) (xy 298.801047 -289.473174) (xy 298.843668 -289.448567) (xy 298.889684 -289.431115)
			(xy 298.937903 -289.421271) (xy 298.987078 -289.41929) (xy 299.035933 -289.425222) (xy 299.083204 -289.438914)
			(xy 299.127666 -289.460012) (xy 299.168169 -289.487968) (xy 299.203662 -289.52206) (xy 299.233227 -289.561404)
			(xy 299.256098 -289.604981) (xy 299.271682 -289.651662) (xy 299.279577 -289.700239) (xy 299.280072 -289.724846)
			(xy 299.61892 -289.724846) (xy 299.62288 -289.675792) (xy 299.634657 -289.628008) (xy 299.653948 -289.582732)
			(xy 299.680251 -289.541136) (xy 299.712886 -289.504299) (xy 299.751007 -289.473174) (xy 299.793628 -289.448567)
			(xy 299.839644 -289.431115) (xy 299.887863 -289.421271) (xy 299.937038 -289.41929) (xy 299.985893 -289.425222)
			(xy 300.033164 -289.438914) (xy 300.077626 -289.460012) (xy 300.118129 -289.487968) (xy 300.153622 -289.52206)
			(xy 300.183187 -289.561404) (xy 300.206058 -289.604981) (xy 300.221642 -289.651662) (xy 300.229537 -289.700239)
			(xy 300.230032 -289.724846) (xy 300.56888 -289.724846) (xy 300.57284 -289.675792) (xy 300.584617 -289.628008)
			(xy 300.603908 -289.582732) (xy 300.630211 -289.541136) (xy 300.662846 -289.504299) (xy 300.700967 -289.473174)
			(xy 300.743588 -289.448567) (xy 300.789604 -289.431115) (xy 300.837823 -289.421271) (xy 300.886998 -289.41929)
			(xy 300.935853 -289.425222) (xy 300.983124 -289.438914) (xy 301.027586 -289.460012) (xy 301.068089 -289.487968)
			(xy 301.103582 -289.52206) (xy 301.133147 -289.561404) (xy 301.156018 -289.604981) (xy 301.171602 -289.651662)
			(xy 301.179497 -289.700239) (xy 301.179992 -289.724846) (xy 301.519094 -289.724846) (xy 301.523054 -289.675792)
			(xy 301.534831 -289.628008) (xy 301.554122 -289.582732) (xy 301.580425 -289.541136) (xy 301.61306 -289.504299)
			(xy 301.651181 -289.473174) (xy 301.693802 -289.448567) (xy 301.739818 -289.431115) (xy 301.788037 -289.421271)
			(xy 301.837212 -289.41929) (xy 301.886067 -289.425222) (xy 301.933338 -289.438914) (xy 301.9778 -289.460012)
			(xy 302.018303 -289.487968) (xy 302.053796 -289.52206) (xy 302.083361 -289.561404) (xy 302.106232 -289.604981)
			(xy 302.121816 -289.651662) (xy 302.129711 -289.700239) (xy 302.130206 -289.724846) (xy 302.469054 -289.724846)
			(xy 302.473014 -289.675792) (xy 302.484791 -289.628008) (xy 302.504082 -289.582732) (xy 302.530385 -289.541136)
			(xy 302.56302 -289.504299) (xy 302.601141 -289.473174) (xy 302.643762 -289.448567) (xy 302.689778 -289.431115)
			(xy 302.737997 -289.421271) (xy 302.787172 -289.41929) (xy 302.836027 -289.425222) (xy 302.883298 -289.438914)
			(xy 302.92776 -289.460012) (xy 302.968263 -289.487968) (xy 303.003756 -289.52206) (xy 303.033321 -289.561404)
			(xy 303.056192 -289.604981) (xy 303.071776 -289.651662) (xy 303.079671 -289.700239) (xy 303.080166 -289.724846)
			(xy 303.419014 -289.724846) (xy 303.422974 -289.675792) (xy 303.434751 -289.628008) (xy 303.454042 -289.582732)
			(xy 303.480345 -289.541136) (xy 303.51298 -289.504299) (xy 303.551101 -289.473174) (xy 303.593722 -289.448567)
			(xy 303.639738 -289.431115) (xy 303.687957 -289.421271) (xy 303.737132 -289.41929) (xy 303.785987 -289.425222)
			(xy 303.833258 -289.438914) (xy 303.87772 -289.460012) (xy 303.918223 -289.487968) (xy 303.953716 -289.52206)
			(xy 303.983281 -289.561404) (xy 304.006152 -289.604981) (xy 304.021736 -289.651662) (xy 304.029631 -289.700239)
			(xy 304.030126 -289.724846) (xy 304.368974 -289.724846) (xy 304.372934 -289.675792) (xy 304.384711 -289.628008)
			(xy 304.404002 -289.582732) (xy 304.430305 -289.541136) (xy 304.46294 -289.504299) (xy 304.501061 -289.473174)
			(xy 304.543682 -289.448567) (xy 304.589698 -289.431115) (xy 304.637917 -289.421271) (xy 304.687092 -289.41929)
			(xy 304.735947 -289.425222) (xy 304.783218 -289.438914) (xy 304.82768 -289.460012) (xy 304.868183 -289.487968)
			(xy 304.903676 -289.52206) (xy 304.933241 -289.561404) (xy 304.956112 -289.604981) (xy 304.971696 -289.651662)
			(xy 304.979591 -289.700239) (xy 304.980086 -289.724846) (xy 305.318934 -289.724846) (xy 305.322894 -289.675792)
			(xy 305.334671 -289.628008) (xy 305.353962 -289.582732) (xy 305.380265 -289.541136) (xy 305.4129 -289.504299)
			(xy 305.451021 -289.473174) (xy 305.493642 -289.448567) (xy 305.539658 -289.431115) (xy 305.587877 -289.421271)
			(xy 305.637052 -289.41929) (xy 305.685907 -289.425222) (xy 305.733178 -289.438914) (xy 305.77764 -289.460012)
			(xy 305.818143 -289.487968) (xy 305.853636 -289.52206) (xy 305.883201 -289.561404) (xy 305.906072 -289.604981)
			(xy 305.921656 -289.651662) (xy 305.929551 -289.700239) (xy 305.930046 -289.724846) (xy 306.269148 -289.724846)
			(xy 306.273108 -289.675792) (xy 306.284885 -289.628008) (xy 306.304176 -289.582732) (xy 306.330479 -289.541136)
			(xy 306.363114 -289.504299) (xy 306.401235 -289.473174) (xy 306.443856 -289.448567) (xy 306.489872 -289.431115)
			(xy 306.538091 -289.421271) (xy 306.587266 -289.41929) (xy 306.636121 -289.425222) (xy 306.683392 -289.438914)
			(xy 306.727854 -289.460012) (xy 306.768357 -289.487968) (xy 306.80385 -289.52206) (xy 306.833415 -289.561404)
			(xy 306.856286 -289.604981) (xy 306.87187 -289.651662) (xy 306.879765 -289.700239) (xy 306.88026 -289.724846)
			(xy 308.169068 -289.724846) (xy 308.173028 -289.675792) (xy 308.184805 -289.628008) (xy 308.204096 -289.582732)
			(xy 308.230399 -289.541136) (xy 308.263034 -289.504299) (xy 308.301155 -289.473174) (xy 308.343776 -289.448567)
			(xy 308.389792 -289.431115) (xy 308.438011 -289.421271) (xy 308.487186 -289.41929) (xy 308.536041 -289.425222)
			(xy 308.583312 -289.438914) (xy 308.627774 -289.460012) (xy 308.668277 -289.487968) (xy 308.70377 -289.52206)
			(xy 308.733335 -289.561404) (xy 308.756206 -289.604981) (xy 308.77179 -289.651662) (xy 308.779685 -289.700239)
			(xy 308.78018 -289.724846) (xy 309.119028 -289.724846) (xy 309.122988 -289.675792) (xy 309.134765 -289.628008)
			(xy 309.154056 -289.582732) (xy 309.180359 -289.541136) (xy 309.212994 -289.504299) (xy 309.251115 -289.473174)
			(xy 309.293736 -289.448567) (xy 309.339752 -289.431115) (xy 309.387971 -289.421271) (xy 309.437146 -289.41929)
			(xy 309.486001 -289.425222) (xy 309.533272 -289.438914) (xy 309.577734 -289.460012) (xy 309.618237 -289.487968)
			(xy 309.65373 -289.52206) (xy 309.683295 -289.561404) (xy 309.706166 -289.604981) (xy 309.72175 -289.651662)
			(xy 309.729645 -289.700239) (xy 309.73014 -289.724846) (xy 310.068988 -289.724846) (xy 310.072948 -289.675792)
			(xy 310.084725 -289.628008) (xy 310.104016 -289.582732) (xy 310.130319 -289.541136) (xy 310.162954 -289.504299)
			(xy 310.201075 -289.473174) (xy 310.243696 -289.448567) (xy 310.289712 -289.431115) (xy 310.337931 -289.421271)
			(xy 310.387106 -289.41929) (xy 310.435961 -289.425222) (xy 310.483232 -289.438914) (xy 310.527694 -289.460012)
			(xy 310.568197 -289.487968) (xy 310.60369 -289.52206) (xy 310.633255 -289.561404) (xy 310.656126 -289.604981)
			(xy 310.67171 -289.651662) (xy 310.679605 -289.700239) (xy 310.6801 -289.724846) (xy 311.018948 -289.724846)
			(xy 311.022908 -289.675792) (xy 311.034685 -289.628008) (xy 311.053976 -289.582732) (xy 311.080279 -289.541136)
			(xy 311.112914 -289.504299) (xy 311.151035 -289.473174) (xy 311.193656 -289.448567) (xy 311.239672 -289.431115)
			(xy 311.287891 -289.421271) (xy 311.337066 -289.41929) (xy 311.385921 -289.425222) (xy 311.433192 -289.438914)
			(xy 311.477654 -289.460012) (xy 311.518157 -289.487968) (xy 311.55365 -289.52206) (xy 311.583215 -289.561404)
			(xy 311.606086 -289.604981) (xy 311.62167 -289.651662) (xy 311.629565 -289.700239) (xy 311.63006 -289.724846)
			(xy 311.968908 -289.724846) (xy 311.972868 -289.675792) (xy 311.984645 -289.628008) (xy 312.003936 -289.582732)
			(xy 312.030239 -289.541136) (xy 312.062874 -289.504299) (xy 312.100995 -289.473174) (xy 312.143616 -289.448567)
			(xy 312.189632 -289.431115) (xy 312.237851 -289.421271) (xy 312.287026 -289.41929) (xy 312.335881 -289.425222)
			(xy 312.383152 -289.438914) (xy 312.427614 -289.460012) (xy 312.468117 -289.487968) (xy 312.50361 -289.52206)
			(xy 312.533175 -289.561404) (xy 312.556046 -289.604981) (xy 312.57163 -289.651662) (xy 312.579525 -289.700239)
			(xy 312.58002 -289.724846) (xy 312.919122 -289.724846) (xy 312.923082 -289.675792) (xy 312.934859 -289.628008)
			(xy 312.95415 -289.582732) (xy 312.980453 -289.541136) (xy 313.013088 -289.504299) (xy 313.051209 -289.473174)
			(xy 313.09383 -289.448567) (xy 313.139846 -289.431115) (xy 313.188065 -289.421271) (xy 313.23724 -289.41929)
			(xy 313.286095 -289.425222) (xy 313.333366 -289.438914) (xy 313.377828 -289.460012) (xy 313.418331 -289.487968)
			(xy 313.453824 -289.52206) (xy 313.483389 -289.561404) (xy 313.50626 -289.604981) (xy 313.521844 -289.651662)
			(xy 313.529739 -289.700239) (xy 313.530234 -289.724846) (xy 313.869082 -289.724846) (xy 313.873042 -289.675792)
			(xy 313.884819 -289.628008) (xy 313.90411 -289.582732) (xy 313.930413 -289.541136) (xy 313.963048 -289.504299)
			(xy 314.001169 -289.473174) (xy 314.04379 -289.448567) (xy 314.089806 -289.431115) (xy 314.138025 -289.421271)
			(xy 314.1872 -289.41929) (xy 314.236055 -289.425222) (xy 314.283326 -289.438914) (xy 314.327788 -289.460012)
			(xy 314.368291 -289.487968) (xy 314.403784 -289.52206) (xy 314.433349 -289.561404) (xy 314.45622 -289.604981)
			(xy 314.471804 -289.651662) (xy 314.479699 -289.700239) (xy 314.480194 -289.724846) (xy 314.819042 -289.724846)
			(xy 314.823002 -289.675792) (xy 314.834779 -289.628008) (xy 314.85407 -289.582732) (xy 314.880373 -289.541136)
			(xy 314.913008 -289.504299) (xy 314.951129 -289.473174) (xy 314.99375 -289.448567) (xy 315.039766 -289.431115)
			(xy 315.087985 -289.421271) (xy 315.13716 -289.41929) (xy 315.186015 -289.425222) (xy 315.233286 -289.438914)
			(xy 315.277748 -289.460012) (xy 315.318251 -289.487968) (xy 315.353744 -289.52206) (xy 315.383309 -289.561404)
			(xy 315.40618 -289.604981) (xy 315.421764 -289.651662) (xy 315.429659 -289.700239) (xy 315.430154 -289.724846)
			(xy 315.429659 -289.749453) (xy 315.421764 -289.79803) (xy 315.40618 -289.844711) (xy 315.383309 -289.888288)
			(xy 315.353744 -289.927632) (xy 315.318251 -289.961724) (xy 315.277748 -289.98968) (xy 315.233286 -290.010778)
			(xy 315.186015 -290.02447) (xy 315.13716 -290.030402) (xy 315.087985 -290.028421) (xy 315.039766 -290.018577)
			(xy 314.99375 -290.001125) (xy 314.951129 -289.976518) (xy 314.913008 -289.945393) (xy 314.880373 -289.908556)
			(xy 314.85407 -289.86696) (xy 314.834779 -289.821684) (xy 314.823002 -289.7739) (xy 314.819042 -289.724846)
			(xy 314.480194 -289.724846) (xy 314.479699 -289.749453) (xy 314.471804 -289.79803) (xy 314.45622 -289.844711)
			(xy 314.433349 -289.888288) (xy 314.403784 -289.927632) (xy 314.368291 -289.961724) (xy 314.327788 -289.98968)
			(xy 314.283326 -290.010778) (xy 314.236055 -290.02447) (xy 314.1872 -290.030402) (xy 314.138025 -290.028421)
			(xy 314.089806 -290.018577) (xy 314.04379 -290.001125) (xy 314.001169 -289.976518) (xy 313.963048 -289.945393)
			(xy 313.930413 -289.908556) (xy 313.90411 -289.86696) (xy 313.884819 -289.821684) (xy 313.873042 -289.7739)
			(xy 313.869082 -289.724846) (xy 313.530234 -289.724846) (xy 313.529739 -289.749453) (xy 313.521844 -289.79803)
			(xy 313.50626 -289.844711) (xy 313.483389 -289.888288) (xy 313.453824 -289.927632) (xy 313.418331 -289.961724)
			(xy 313.377828 -289.98968) (xy 313.333366 -290.010778) (xy 313.286095 -290.02447) (xy 313.23724 -290.030402)
			(xy 313.188065 -290.028421) (xy 313.139846 -290.018577) (xy 313.09383 -290.001125) (xy 313.051209 -289.976518)
			(xy 313.013088 -289.945393) (xy 312.980453 -289.908556) (xy 312.95415 -289.86696) (xy 312.934859 -289.821684)
			(xy 312.923082 -289.7739) (xy 312.919122 -289.724846) (xy 312.58002 -289.724846) (xy 312.579525 -289.749453)
			(xy 312.57163 -289.79803) (xy 312.556046 -289.844711) (xy 312.533175 -289.888288) (xy 312.50361 -289.927632)
			(xy 312.468117 -289.961724) (xy 312.427614 -289.98968) (xy 312.383152 -290.010778) (xy 312.335881 -290.02447)
			(xy 312.287026 -290.030402) (xy 312.237851 -290.028421) (xy 312.189632 -290.018577) (xy 312.143616 -290.001125)
			(xy 312.100995 -289.976518) (xy 312.062874 -289.945393) (xy 312.030239 -289.908556) (xy 312.003936 -289.86696)
			(xy 311.984645 -289.821684) (xy 311.972868 -289.7739) (xy 311.968908 -289.724846) (xy 311.63006 -289.724846)
			(xy 311.629565 -289.749453) (xy 311.62167 -289.79803) (xy 311.606086 -289.844711) (xy 311.583215 -289.888288)
			(xy 311.55365 -289.927632) (xy 311.518157 -289.961724) (xy 311.477654 -289.98968) (xy 311.433192 -290.010778)
			(xy 311.385921 -290.02447) (xy 311.337066 -290.030402) (xy 311.287891 -290.028421) (xy 311.239672 -290.018577)
			(xy 311.193656 -290.001125) (xy 311.151035 -289.976518) (xy 311.112914 -289.945393) (xy 311.080279 -289.908556)
			(xy 311.053976 -289.86696) (xy 311.034685 -289.821684) (xy 311.022908 -289.7739) (xy 311.018948 -289.724846)
			(xy 310.6801 -289.724846) (xy 310.679605 -289.749453) (xy 310.67171 -289.79803) (xy 310.656126 -289.844711)
			(xy 310.633255 -289.888288) (xy 310.60369 -289.927632) (xy 310.568197 -289.961724) (xy 310.527694 -289.98968)
			(xy 310.483232 -290.010778) (xy 310.435961 -290.02447) (xy 310.387106 -290.030402) (xy 310.337931 -290.028421)
			(xy 310.289712 -290.018577) (xy 310.243696 -290.001125) (xy 310.201075 -289.976518) (xy 310.162954 -289.945393)
			(xy 310.130319 -289.908556) (xy 310.104016 -289.86696) (xy 310.084725 -289.821684) (xy 310.072948 -289.7739)
			(xy 310.068988 -289.724846) (xy 309.73014 -289.724846) (xy 309.729645 -289.749453) (xy 309.72175 -289.79803)
			(xy 309.706166 -289.844711) (xy 309.683295 -289.888288) (xy 309.65373 -289.927632) (xy 309.618237 -289.961724)
			(xy 309.577734 -289.98968) (xy 309.533272 -290.010778) (xy 309.486001 -290.02447) (xy 309.437146 -290.030402)
			(xy 309.387971 -290.028421) (xy 309.339752 -290.018577) (xy 309.293736 -290.001125) (xy 309.251115 -289.976518)
			(xy 309.212994 -289.945393) (xy 309.180359 -289.908556) (xy 309.154056 -289.86696) (xy 309.134765 -289.821684)
			(xy 309.122988 -289.7739) (xy 309.119028 -289.724846) (xy 308.78018 -289.724846) (xy 308.779685 -289.749453)
			(xy 308.77179 -289.79803) (xy 308.756206 -289.844711) (xy 308.733335 -289.888288) (xy 308.70377 -289.927632)
			(xy 308.668277 -289.961724) (xy 308.627774 -289.98968) (xy 308.583312 -290.010778) (xy 308.536041 -290.02447)
			(xy 308.487186 -290.030402) (xy 308.438011 -290.028421) (xy 308.389792 -290.018577) (xy 308.343776 -290.001125)
			(xy 308.301155 -289.976518) (xy 308.263034 -289.945393) (xy 308.230399 -289.908556) (xy 308.204096 -289.86696)
			(xy 308.184805 -289.821684) (xy 308.173028 -289.7739) (xy 308.169068 -289.724846) (xy 306.88026 -289.724846)
			(xy 306.879765 -289.749453) (xy 306.87187 -289.79803) (xy 306.856286 -289.844711) (xy 306.833415 -289.888288)
			(xy 306.80385 -289.927632) (xy 306.768357 -289.961724) (xy 306.727854 -289.98968) (xy 306.683392 -290.010778)
			(xy 306.636121 -290.02447) (xy 306.587266 -290.030402) (xy 306.538091 -290.028421) (xy 306.489872 -290.018577)
			(xy 306.443856 -290.001125) (xy 306.401235 -289.976518) (xy 306.363114 -289.945393) (xy 306.330479 -289.908556)
			(xy 306.304176 -289.86696) (xy 306.284885 -289.821684) (xy 306.273108 -289.7739) (xy 306.269148 -289.724846)
			(xy 305.930046 -289.724846) (xy 305.929551 -289.749453) (xy 305.921656 -289.79803) (xy 305.906072 -289.844711)
			(xy 305.883201 -289.888288) (xy 305.853636 -289.927632) (xy 305.818143 -289.961724) (xy 305.77764 -289.98968)
			(xy 305.733178 -290.010778) (xy 305.685907 -290.02447) (xy 305.637052 -290.030402) (xy 305.587877 -290.028421)
			(xy 305.539658 -290.018577) (xy 305.493642 -290.001125) (xy 305.451021 -289.976518) (xy 305.4129 -289.945393)
			(xy 305.380265 -289.908556) (xy 305.353962 -289.86696) (xy 305.334671 -289.821684) (xy 305.322894 -289.7739)
			(xy 305.318934 -289.724846) (xy 304.980086 -289.724846) (xy 304.979591 -289.749453) (xy 304.971696 -289.79803)
			(xy 304.956112 -289.844711) (xy 304.933241 -289.888288) (xy 304.903676 -289.927632) (xy 304.868183 -289.961724)
			(xy 304.82768 -289.98968) (xy 304.783218 -290.010778) (xy 304.735947 -290.02447) (xy 304.687092 -290.030402)
			(xy 304.637917 -290.028421) (xy 304.589698 -290.018577) (xy 304.543682 -290.001125) (xy 304.501061 -289.976518)
			(xy 304.46294 -289.945393) (xy 304.430305 -289.908556) (xy 304.404002 -289.86696) (xy 304.384711 -289.821684)
			(xy 304.372934 -289.7739) (xy 304.368974 -289.724846) (xy 304.030126 -289.724846) (xy 304.029631 -289.749453)
			(xy 304.021736 -289.79803) (xy 304.006152 -289.844711) (xy 303.983281 -289.888288) (xy 303.953716 -289.927632)
			(xy 303.918223 -289.961724) (xy 303.87772 -289.98968) (xy 303.833258 -290.010778) (xy 303.785987 -290.02447)
			(xy 303.737132 -290.030402) (xy 303.687957 -290.028421) (xy 303.639738 -290.018577) (xy 303.593722 -290.001125)
			(xy 303.551101 -289.976518) (xy 303.51298 -289.945393) (xy 303.480345 -289.908556) (xy 303.454042 -289.86696)
			(xy 303.434751 -289.821684) (xy 303.422974 -289.7739) (xy 303.419014 -289.724846) (xy 303.080166 -289.724846)
			(xy 303.079671 -289.749453) (xy 303.071776 -289.79803) (xy 303.056192 -289.844711) (xy 303.033321 -289.888288)
			(xy 303.003756 -289.927632) (xy 302.968263 -289.961724) (xy 302.92776 -289.98968) (xy 302.883298 -290.010778)
			(xy 302.836027 -290.02447) (xy 302.787172 -290.030402) (xy 302.737997 -290.028421) (xy 302.689778 -290.018577)
			(xy 302.643762 -290.001125) (xy 302.601141 -289.976518) (xy 302.56302 -289.945393) (xy 302.530385 -289.908556)
			(xy 302.504082 -289.86696) (xy 302.484791 -289.821684) (xy 302.473014 -289.7739) (xy 302.469054 -289.724846)
			(xy 302.130206 -289.724846) (xy 302.129711 -289.749453) (xy 302.121816 -289.79803) (xy 302.106232 -289.844711)
			(xy 302.083361 -289.888288) (xy 302.053796 -289.927632) (xy 302.018303 -289.961724) (xy 301.9778 -289.98968)
			(xy 301.933338 -290.010778) (xy 301.886067 -290.02447) (xy 301.837212 -290.030402) (xy 301.788037 -290.028421)
			(xy 301.739818 -290.018577) (xy 301.693802 -290.001125) (xy 301.651181 -289.976518) (xy 301.61306 -289.945393)
			(xy 301.580425 -289.908556) (xy 301.554122 -289.86696) (xy 301.534831 -289.821684) (xy 301.523054 -289.7739)
			(xy 301.519094 -289.724846) (xy 301.179992 -289.724846) (xy 301.179497 -289.749453) (xy 301.171602 -289.79803)
			(xy 301.156018 -289.844711) (xy 301.133147 -289.888288) (xy 301.103582 -289.927632) (xy 301.068089 -289.961724)
			(xy 301.027586 -289.98968) (xy 300.983124 -290.010778) (xy 300.935853 -290.02447) (xy 300.886998 -290.030402)
			(xy 300.837823 -290.028421) (xy 300.789604 -290.018577) (xy 300.743588 -290.001125) (xy 300.700967 -289.976518)
			(xy 300.662846 -289.945393) (xy 300.630211 -289.908556) (xy 300.603908 -289.86696) (xy 300.584617 -289.821684)
			(xy 300.57284 -289.7739) (xy 300.56888 -289.724846) (xy 300.230032 -289.724846) (xy 300.229537 -289.749453)
			(xy 300.221642 -289.79803) (xy 300.206058 -289.844711) (xy 300.183187 -289.888288) (xy 300.153622 -289.927632)
			(xy 300.118129 -289.961724) (xy 300.077626 -289.98968) (xy 300.033164 -290.010778) (xy 299.985893 -290.02447)
			(xy 299.937038 -290.030402) (xy 299.887863 -290.028421) (xy 299.839644 -290.018577) (xy 299.793628 -290.001125)
			(xy 299.751007 -289.976518) (xy 299.712886 -289.945393) (xy 299.680251 -289.908556) (xy 299.653948 -289.86696)
			(xy 299.634657 -289.821684) (xy 299.62288 -289.7739) (xy 299.61892 -289.724846) (xy 299.280072 -289.724846)
			(xy 299.279577 -289.749453) (xy 299.271682 -289.79803) (xy 299.256098 -289.844711) (xy 299.233227 -289.888288)
			(xy 299.203662 -289.927632) (xy 299.168169 -289.961724) (xy 299.127666 -289.98968) (xy 299.083204 -290.010778)
			(xy 299.035933 -290.02447) (xy 298.987078 -290.030402) (xy 298.937903 -290.028421) (xy 298.889684 -290.018577)
			(xy 298.843668 -290.001125) (xy 298.801047 -289.976518) (xy 298.762926 -289.945393) (xy 298.730291 -289.908556)
			(xy 298.703988 -289.86696) (xy 298.684697 -289.821684) (xy 298.67292 -289.7739) (xy 298.66896 -289.724846)
			(xy 298.330112 -289.724846) (xy 298.329617 -289.749453) (xy 298.321722 -289.79803) (xy 298.306138 -289.844711)
			(xy 298.283267 -289.888288) (xy 298.253702 -289.927632) (xy 298.218209 -289.961724) (xy 298.177706 -289.98968)
			(xy 298.133244 -290.010778) (xy 298.085973 -290.02447) (xy 298.037118 -290.030402) (xy 297.987943 -290.028421)
			(xy 297.939724 -290.018577) (xy 297.893708 -290.001125) (xy 297.851087 -289.976518) (xy 297.812966 -289.945393)
			(xy 297.780331 -289.908556) (xy 297.754028 -289.86696) (xy 297.734737 -289.821684) (xy 297.72296 -289.7739)
			(xy 297.719 -289.724846) (xy 297.380152 -289.724846) (xy 297.379657 -289.749453) (xy 297.371762 -289.79803)
			(xy 297.356178 -289.844711) (xy 297.333307 -289.888288) (xy 297.303742 -289.927632) (xy 297.268249 -289.961724)
			(xy 297.227746 -289.98968) (xy 297.183284 -290.010778) (xy 297.136013 -290.02447) (xy 297.087158 -290.030402)
			(xy 297.037983 -290.028421) (xy 296.989764 -290.018577) (xy 296.943748 -290.001125) (xy 296.901127 -289.976518)
			(xy 296.863006 -289.945393) (xy 296.830371 -289.908556) (xy 296.804068 -289.86696) (xy 296.784777 -289.821684)
			(xy 296.773 -289.7739) (xy 296.76904 -289.724846) (xy 296.430192 -289.724846) (xy 296.429697 -289.749453)
			(xy 296.421802 -289.79803) (xy 296.406218 -289.844711) (xy 296.383347 -289.888288) (xy 296.353782 -289.927632)
			(xy 296.318289 -289.961724) (xy 296.277786 -289.98968) (xy 296.233324 -290.010778) (xy 296.186053 -290.02447)
			(xy 296.137198 -290.030402) (xy 296.088023 -290.028421) (xy 296.039804 -290.018577) (xy 295.993788 -290.001125)
			(xy 295.951167 -289.976518) (xy 295.913046 -289.945393) (xy 295.880411 -289.908556) (xy 295.854108 -289.86696)
			(xy 295.834817 -289.821684) (xy 295.82304 -289.7739) (xy 295.81908 -289.724846) (xy 295.480232 -289.724846)
			(xy 295.479737 -289.749453) (xy 295.471842 -289.79803) (xy 295.456258 -289.844711) (xy 295.433387 -289.888288)
			(xy 295.403822 -289.927632) (xy 295.368329 -289.961724) (xy 295.327826 -289.98968) (xy 295.283364 -290.010778)
			(xy 295.236093 -290.02447) (xy 295.187238 -290.030402) (xy 295.138063 -290.028421) (xy 295.089844 -290.018577)
			(xy 295.043828 -290.001125) (xy 295.001207 -289.976518) (xy 294.963086 -289.945393) (xy 294.930451 -289.908556)
			(xy 294.904148 -289.86696) (xy 294.884857 -289.821684) (xy 294.87308 -289.7739) (xy 294.86912 -289.724846)
			(xy 294.530018 -289.724846) (xy 294.529523 -289.749453) (xy 294.521628 -289.79803) (xy 294.506044 -289.844711)
			(xy 294.483173 -289.888288) (xy 294.453608 -289.927632) (xy 294.418115 -289.961724) (xy 294.377612 -289.98968)
			(xy 294.33315 -290.010778) (xy 294.285879 -290.02447) (xy 294.237024 -290.030402) (xy 294.187849 -290.028421)
			(xy 294.13963 -290.018577) (xy 294.093614 -290.001125) (xy 294.050993 -289.976518) (xy 294.012872 -289.945393)
			(xy 293.980237 -289.908556) (xy 293.953934 -289.86696) (xy 293.934643 -289.821684) (xy 293.922866 -289.7739)
			(xy 293.918906 -289.724846) (xy 293.580058 -289.724846) (xy 293.579563 -289.749453) (xy 293.571668 -289.79803)
			(xy 293.556084 -289.844711) (xy 293.533213 -289.888288) (xy 293.503648 -289.927632) (xy 293.468155 -289.961724)
			(xy 293.427652 -289.98968) (xy 293.38319 -290.010778) (xy 293.335919 -290.02447) (xy 293.287064 -290.030402)
			(xy 293.237889 -290.028421) (xy 293.18967 -290.018577) (xy 293.143654 -290.001125) (xy 293.101033 -289.976518)
			(xy 293.062912 -289.945393) (xy 293.030277 -289.908556) (xy 293.003974 -289.86696) (xy 292.984683 -289.821684)
			(xy 292.972906 -289.7739) (xy 292.968946 -289.724846) (xy 292.630098 -289.724846) (xy 292.629603 -289.749453)
			(xy 292.621708 -289.79803) (xy 292.606124 -289.844711) (xy 292.583253 -289.888288) (xy 292.553688 -289.927632)
			(xy 292.518195 -289.961724) (xy 292.477692 -289.98968) (xy 292.43323 -290.010778) (xy 292.385959 -290.02447)
			(xy 292.337104 -290.030402) (xy 292.287929 -290.028421) (xy 292.23971 -290.018577) (xy 292.193694 -290.001125)
			(xy 292.151073 -289.976518) (xy 292.112952 -289.945393) (xy 292.080317 -289.908556) (xy 292.054014 -289.86696)
			(xy 292.034723 -289.821684) (xy 292.022946 -289.7739) (xy 292.018986 -289.724846) (xy 290.730178 -289.724846)
			(xy 290.729683 -289.749453) (xy 290.721788 -289.79803) (xy 290.706204 -289.844711) (xy 290.683333 -289.888288)
			(xy 290.653768 -289.927632) (xy 290.618275 -289.961724) (xy 290.577772 -289.98968) (xy 290.53331 -290.010778)
			(xy 290.486039 -290.02447) (xy 290.437184 -290.030402) (xy 290.388009 -290.028421) (xy 290.33979 -290.018577)
			(xy 290.293774 -290.001125) (xy 290.251153 -289.976518) (xy 290.213032 -289.945393) (xy 290.180397 -289.908556)
			(xy 290.154094 -289.86696) (xy 290.134803 -289.821684) (xy 290.123026 -289.7739) (xy 290.119066 -289.724846)
			(xy 289.780218 -289.724846) (xy 289.779723 -289.749453) (xy 289.771828 -289.79803) (xy 289.756244 -289.844711)
			(xy 289.733373 -289.888288) (xy 289.703808 -289.927632) (xy 289.668315 -289.961724) (xy 289.627812 -289.98968)
			(xy 289.58335 -290.010778) (xy 289.536079 -290.02447) (xy 289.487224 -290.030402) (xy 289.438049 -290.028421)
			(xy 289.38983 -290.018577) (xy 289.343814 -290.001125) (xy 289.301193 -289.976518) (xy 289.263072 -289.945393)
			(xy 289.230437 -289.908556) (xy 289.204134 -289.86696) (xy 289.184843 -289.821684) (xy 289.173066 -289.7739)
			(xy 289.169106 -289.724846) (xy 288.830004 -289.724846) (xy 288.829509 -289.749453) (xy 288.821614 -289.79803)
			(xy 288.80603 -289.844711) (xy 288.783159 -289.888288) (xy 288.753594 -289.927632) (xy 288.718101 -289.961724)
			(xy 288.677598 -289.98968) (xy 288.633136 -290.010778) (xy 288.585865 -290.02447) (xy 288.53701 -290.030402)
			(xy 288.487835 -290.028421) (xy 288.439616 -290.018577) (xy 288.3936 -290.001125) (xy 288.350979 -289.976518)
			(xy 288.312858 -289.945393) (xy 288.280223 -289.908556) (xy 288.25392 -289.86696) (xy 288.234629 -289.821684)
			(xy 288.222852 -289.7739) (xy 288.218892 -289.724846) (xy 287.880044 -289.724846) (xy 287.879549 -289.749453)
			(xy 287.871654 -289.79803) (xy 287.85607 -289.844711) (xy 287.833199 -289.888288) (xy 287.803634 -289.927632)
			(xy 287.768141 -289.961724) (xy 287.727638 -289.98968) (xy 287.683176 -290.010778) (xy 287.635905 -290.02447)
			(xy 287.58705 -290.030402) (xy 287.537875 -290.028421) (xy 287.489656 -290.018577) (xy 287.44364 -290.001125)
			(xy 287.401019 -289.976518) (xy 287.362898 -289.945393) (xy 287.330263 -289.908556) (xy 287.30396 -289.86696)
			(xy 287.284669 -289.821684) (xy 287.272892 -289.7739) (xy 287.268932 -289.724846) (xy 286.930084 -289.724846)
			(xy 286.929589 -289.749453) (xy 286.921694 -289.79803) (xy 286.90611 -289.844711) (xy 286.883239 -289.888288)
			(xy 286.853674 -289.927632) (xy 286.818181 -289.961724) (xy 286.777678 -289.98968) (xy 286.733216 -290.010778)
			(xy 286.685945 -290.02447) (xy 286.63709 -290.030402) (xy 286.587915 -290.028421) (xy 286.539696 -290.018577)
			(xy 286.49368 -290.001125) (xy 286.451059 -289.976518) (xy 286.412938 -289.945393) (xy 286.380303 -289.908556)
			(xy 286.354 -289.86696) (xy 286.334709 -289.821684) (xy 286.322932 -289.7739) (xy 286.318972 -289.724846)
			(xy 285.980124 -289.724846) (xy 285.979629 -289.749453) (xy 285.971734 -289.79803) (xy 285.95615 -289.844711)
			(xy 285.933279 -289.888288) (xy 285.903714 -289.927632) (xy 285.868221 -289.961724) (xy 285.827718 -289.98968)
			(xy 285.783256 -290.010778) (xy 285.735985 -290.02447) (xy 285.68713 -290.030402) (xy 285.637955 -290.028421)
			(xy 285.589736 -290.018577) (xy 285.54372 -290.001125) (xy 285.501099 -289.976518) (xy 285.462978 -289.945393)
			(xy 285.430343 -289.908556) (xy 285.40404 -289.86696) (xy 285.384749 -289.821684) (xy 285.372972 -289.7739)
			(xy 285.369012 -289.724846) (xy 285.030164 -289.724846) (xy 285.029669 -289.749453) (xy 285.021774 -289.79803)
			(xy 285.00619 -289.844711) (xy 284.983319 -289.888288) (xy 284.953754 -289.927632) (xy 284.918261 -289.961724)
			(xy 284.877758 -289.98968) (xy 284.833296 -290.010778) (xy 284.786025 -290.02447) (xy 284.73717 -290.030402)
			(xy 284.687995 -290.028421) (xy 284.639776 -290.018577) (xy 284.59376 -290.001125) (xy 284.551139 -289.976518)
			(xy 284.513018 -289.945393) (xy 284.480383 -289.908556) (xy 284.45408 -289.86696) (xy 284.434789 -289.821684)
			(xy 284.423012 -289.7739) (xy 284.419052 -289.724846) (xy 284.080204 -289.724846) (xy 284.079709 -289.749453)
			(xy 284.071814 -289.79803) (xy 284.05623 -289.844711) (xy 284.033359 -289.888288) (xy 284.003794 -289.927632)
			(xy 283.968301 -289.961724) (xy 283.927798 -289.98968) (xy 283.883336 -290.010778) (xy 283.836065 -290.02447)
			(xy 283.78721 -290.030402) (xy 283.738035 -290.028421) (xy 283.689816 -290.018577) (xy 283.6438 -290.001125)
			(xy 283.601179 -289.976518) (xy 283.563058 -289.945393) (xy 283.530423 -289.908556) (xy 283.50412 -289.86696)
			(xy 283.484829 -289.821684) (xy 283.473052 -289.7739) (xy 283.469092 -289.724846) (xy 283.130244 -289.724846)
			(xy 283.129749 -289.749453) (xy 283.121854 -289.79803) (xy 283.10627 -289.844711) (xy 283.083399 -289.888288)
			(xy 283.053834 -289.927632) (xy 283.018341 -289.961724) (xy 282.977838 -289.98968) (xy 282.933376 -290.010778)
			(xy 282.886105 -290.02447) (xy 282.83725 -290.030402) (xy 282.788075 -290.028421) (xy 282.739856 -290.018577)
			(xy 282.69384 -290.001125) (xy 282.651219 -289.976518) (xy 282.613098 -289.945393) (xy 282.580463 -289.908556)
			(xy 282.55416 -289.86696) (xy 282.534869 -289.821684) (xy 282.523092 -289.7739) (xy 282.519132 -289.724846)
			(xy 282.18003 -289.724846) (xy 282.179535 -289.749453) (xy 282.17164 -289.79803) (xy 282.156056 -289.844711)
			(xy 282.133185 -289.888288) (xy 282.10362 -289.927632) (xy 282.068127 -289.961724) (xy 282.027624 -289.98968)
			(xy 281.983162 -290.010778) (xy 281.935891 -290.02447) (xy 281.887036 -290.030402) (xy 281.837861 -290.028421)
			(xy 281.789642 -290.018577) (xy 281.743626 -290.001125) (xy 281.701005 -289.976518) (xy 281.662884 -289.945393)
			(xy 281.630249 -289.908556) (xy 281.603946 -289.86696) (xy 281.584655 -289.821684) (xy 281.572878 -289.7739)
			(xy 281.568918 -289.724846) (xy 281.23007 -289.724846) (xy 281.229575 -289.749453) (xy 281.22168 -289.79803)
			(xy 281.206096 -289.844711) (xy 281.183225 -289.888288) (xy 281.15366 -289.927632) (xy 281.118167 -289.961724)
			(xy 281.077664 -289.98968) (xy 281.033202 -290.010778) (xy 280.985931 -290.02447) (xy 280.937076 -290.030402)
			(xy 280.887901 -290.028421) (xy 280.839682 -290.018577) (xy 280.793666 -290.001125) (xy 280.751045 -289.976518)
			(xy 280.712924 -289.945393) (xy 280.680289 -289.908556) (xy 280.653986 -289.86696) (xy 280.634695 -289.821684)
			(xy 280.622918 -289.7739) (xy 280.618958 -289.724846) (xy 280.28011 -289.724846) (xy 280.279837 -289.742994)
			(xy 280.275512 -289.779033) (xy 280.271474 -289.796728) (xy 280.270966 -289.799014) (xy 280.270712 -289.800792)
			(xy 280.26995 -289.804856) (xy 280.268426 -289.815524) (xy 280.268426 -289.820096) (xy 280.268849 -289.830166)
			(xy 280.276565 -289.848769) (xy 280.283412 -289.856164) (xy 280.387552 -289.96005) (xy 280.399851 -289.97275)
			(xy 280.421753 -290.000504) (xy 280.43124 -290.015422) (xy 280.434796 -290.021264) (xy 280.435558 -290.022534)
			(xy 280.444702 -290.039298) (xy 280.444702 -290.039552) (xy 280.444956 -290.039806) (xy 280.44521 -290.040314)
			(xy 280.44775 -290.045394) (xy 280.44902 -290.048442) (xy 280.449782 -290.049458) (xy 280.453846 -290.05911)
			(xy 280.4541 -290.059872) (xy 280.454608 -290.061396) (xy 280.464006 -290.088066) (xy 280.46426 -290.088828)
			(xy 280.4668 -290.096956) (xy 280.467054 -290.097972) (xy 280.467054 -290.09848) (xy 280.468324 -290.102798)
			(xy 280.468832 -290.105846) (xy 280.469086 -290.107116) (xy 280.472034 -290.120346) (xy 280.47585 -290.147183)
			(xy 280.476706 -290.16071) (xy 280.47696 -290.16579) (xy 280.47696 -290.277042) (xy 280.476896 -290.278312)
			(xy 317.353694 -290.278312) (xy 317.357765 -290.22269) (xy 317.369891 -290.168253) (xy 317.389814 -290.116162)
			(xy 317.41711 -290.067527) (xy 317.451196 -290.023384) (xy 317.491345 -289.984675) (xy 317.536703 -289.952224)
			(xy 317.586303 -289.926723) (xy 317.639087 -289.908716) (xy 317.69393 -289.898586) (xy 317.749664 -289.896549)
			(xy 317.805101 -289.902649) (xy 317.859058 -289.916755) (xy 317.910387 -289.938567) (xy 317.957993 -289.967621)
			(xy 318.000861 -290.003296) (xy 318.038078 -290.044833) (xy 318.068851 -290.091346) (xy 318.092523 -290.141843)
			(xy 318.108591 -290.19525) (xy 318.114759 -290.237164) (xy 321.364354 -290.237164) (xy 321.368425 -290.181542)
			(xy 321.380551 -290.127105) (xy 321.400474 -290.075014) (xy 321.42777 -290.026379) (xy 321.461856 -289.982236)
			(xy 321.502005 -289.943527) (xy 321.547363 -289.911076) (xy 321.596963 -289.885575) (xy 321.649747 -289.867568)
			(xy 321.70459 -289.857438) (xy 321.760324 -289.855401) (xy 321.815761 -289.861501) (xy 321.869718 -289.875607)
			(xy 321.921047 -289.897419) (xy 321.968653 -289.926473) (xy 322.011521 -289.962148) (xy 322.048738 -290.003685)
			(xy 322.079511 -290.050198) (xy 322.103183 -290.100695) (xy 322.119251 -290.154102) (xy 322.127371 -290.209278)
			(xy 322.12788 -290.237164) (xy 322.127371 -290.26505) (xy 322.119251 -290.320226) (xy 322.103183 -290.373633)
			(xy 322.079511 -290.42413) (xy 322.048738 -290.470643) (xy 322.011521 -290.51218) (xy 321.968653 -290.547855)
			(xy 321.921047 -290.576909) (xy 321.869718 -290.598721) (xy 321.815761 -290.612827) (xy 321.760324 -290.618927)
			(xy 321.70459 -290.61689) (xy 321.649747 -290.60676) (xy 321.596963 -290.588753) (xy 321.547363 -290.563252)
			(xy 321.502005 -290.530801) (xy 321.461856 -290.492092) (xy 321.42777 -290.447949) (xy 321.400474 -290.399314)
			(xy 321.380551 -290.347223) (xy 321.368425 -290.292786) (xy 321.364354 -290.237164) (xy 318.114759 -290.237164)
			(xy 318.116711 -290.250426) (xy 318.11722 -290.278312) (xy 318.116711 -290.306198) (xy 318.108591 -290.361374)
			(xy 318.092523 -290.414781) (xy 318.068851 -290.465278) (xy 318.038078 -290.511791) (xy 318.000861 -290.553328)
			(xy 317.957993 -290.589003) (xy 317.910387 -290.618057) (xy 317.859058 -290.639869) (xy 317.805101 -290.653975)
			(xy 317.749664 -290.660075) (xy 317.69393 -290.658038) (xy 317.639087 -290.647908) (xy 317.586303 -290.629901)
			(xy 317.536703 -290.6044) (xy 317.491345 -290.571949) (xy 317.451196 -290.53324) (xy 317.41711 -290.489097)
			(xy 317.389814 -290.440462) (xy 317.369891 -290.388371) (xy 317.357765 -290.333934) (xy 317.353694 -290.278312)
			(xy 280.476896 -290.278312) (xy 280.475577 -290.304446) (xy 280.464197 -290.358119) (xy 280.44341 -290.408895)
			(xy 280.413886 -290.45514) (xy 280.39568 -290.47567) (xy 280.393902 -290.477448) (xy 280.393394 -290.477956)
			(xy 280.38806 -290.483544) (xy 280.38425 -290.487354) (xy 280.378916 -290.492434) (xy 280.368502 -290.50234)
			(xy 280.362152 -290.50742) (xy 280.361898 -290.507674) (xy 280.355802 -290.511992) (xy 280.35504 -290.512754)
			(xy 280.354278 -290.513262) (xy 280.31948 -290.537392) (xy 280.318972 -290.537392) (xy 280.303224 -290.548568)
			(xy 280.30043 -290.5506) (xy 280.280364 -290.564824) (xy 280.269442 -290.593018) (xy 280.272744 -290.60775)
			(xy 280.272744 -290.608004) (xy 280.27376 -290.613084) (xy 280.276599 -290.627655) (xy 280.27978 -290.657171)
			(xy 280.28011 -290.672012) (xy 280.28011 -290.674806) (xy 281.568918 -290.674806) (xy 281.572878 -290.625752)
			(xy 281.584655 -290.577968) (xy 281.603946 -290.532692) (xy 281.630249 -290.491096) (xy 281.662884 -290.454259)
			(xy 281.701005 -290.423134) (xy 281.743626 -290.398527) (xy 281.789642 -290.381075) (xy 281.837861 -290.371231)
			(xy 281.887036 -290.36925) (xy 281.935891 -290.375182) (xy 281.983162 -290.388874) (xy 282.027624 -290.409972)
			(xy 282.068127 -290.437928) (xy 282.10362 -290.47202) (xy 282.133185 -290.511364) (xy 282.156056 -290.554941)
			(xy 282.17164 -290.601622) (xy 282.179535 -290.650199) (xy 282.18003 -290.674806) (xy 282.519132 -290.674806)
			(xy 282.523092 -290.625752) (xy 282.534869 -290.577968) (xy 282.55416 -290.532692) (xy 282.580463 -290.491096)
			(xy 282.613098 -290.454259) (xy 282.651219 -290.423134) (xy 282.69384 -290.398527) (xy 282.739856 -290.381075)
			(xy 282.788075 -290.371231) (xy 282.83725 -290.36925) (xy 282.886105 -290.375182) (xy 282.933376 -290.388874)
			(xy 282.977838 -290.409972) (xy 283.018341 -290.437928) (xy 283.053834 -290.47202) (xy 283.083399 -290.511364)
			(xy 283.10627 -290.554941) (xy 283.121854 -290.601622) (xy 283.129749 -290.650199) (xy 283.130244 -290.674806)
			(xy 283.469092 -290.674806) (xy 283.473052 -290.625752) (xy 283.484829 -290.577968) (xy 283.50412 -290.532692)
			(xy 283.530423 -290.491096) (xy 283.563058 -290.454259) (xy 283.601179 -290.423134) (xy 283.6438 -290.398527)
			(xy 283.689816 -290.381075) (xy 283.738035 -290.371231) (xy 283.78721 -290.36925) (xy 283.836065 -290.375182)
			(xy 283.883336 -290.388874) (xy 283.927798 -290.409972) (xy 283.968301 -290.437928) (xy 284.003794 -290.47202)
			(xy 284.033359 -290.511364) (xy 284.05623 -290.554941) (xy 284.071814 -290.601622) (xy 284.079709 -290.650199)
			(xy 284.080204 -290.674806) (xy 284.419052 -290.674806) (xy 284.423012 -290.625752) (xy 284.434789 -290.577968)
			(xy 284.45408 -290.532692) (xy 284.480383 -290.491096) (xy 284.513018 -290.454259) (xy 284.551139 -290.423134)
			(xy 284.59376 -290.398527) (xy 284.639776 -290.381075) (xy 284.687995 -290.371231) (xy 284.73717 -290.36925)
			(xy 284.786025 -290.375182) (xy 284.833296 -290.388874) (xy 284.877758 -290.409972) (xy 284.918261 -290.437928)
			(xy 284.953754 -290.47202) (xy 284.983319 -290.511364) (xy 285.00619 -290.554941) (xy 285.021774 -290.601622)
			(xy 285.029669 -290.650199) (xy 285.030164 -290.674806) (xy 285.369012 -290.674806) (xy 285.372972 -290.625752)
			(xy 285.384749 -290.577968) (xy 285.40404 -290.532692) (xy 285.430343 -290.491096) (xy 285.462978 -290.454259)
			(xy 285.501099 -290.423134) (xy 285.54372 -290.398527) (xy 285.589736 -290.381075) (xy 285.637955 -290.371231)
			(xy 285.68713 -290.36925) (xy 285.735985 -290.375182) (xy 285.783256 -290.388874) (xy 285.827718 -290.409972)
			(xy 285.868221 -290.437928) (xy 285.903714 -290.47202) (xy 285.933279 -290.511364) (xy 285.95615 -290.554941)
			(xy 285.971734 -290.601622) (xy 285.979629 -290.650199) (xy 285.980124 -290.674806) (xy 286.318972 -290.674806)
			(xy 286.322932 -290.625752) (xy 286.334709 -290.577968) (xy 286.354 -290.532692) (xy 286.380303 -290.491096)
			(xy 286.412938 -290.454259) (xy 286.451059 -290.423134) (xy 286.49368 -290.398527) (xy 286.539696 -290.381075)
			(xy 286.587915 -290.371231) (xy 286.63709 -290.36925) (xy 286.685945 -290.375182) (xy 286.733216 -290.388874)
			(xy 286.777678 -290.409972) (xy 286.818181 -290.437928) (xy 286.853674 -290.47202) (xy 286.883239 -290.511364)
			(xy 286.90611 -290.554941) (xy 286.921694 -290.601622) (xy 286.929589 -290.650199) (xy 286.930084 -290.674806)
			(xy 287.268932 -290.674806) (xy 287.272892 -290.625752) (xy 287.284669 -290.577968) (xy 287.30396 -290.532692)
			(xy 287.330263 -290.491096) (xy 287.362898 -290.454259) (xy 287.401019 -290.423134) (xy 287.44364 -290.398527)
			(xy 287.489656 -290.381075) (xy 287.537875 -290.371231) (xy 287.58705 -290.36925) (xy 287.635905 -290.375182)
			(xy 287.683176 -290.388874) (xy 287.727638 -290.409972) (xy 287.768141 -290.437928) (xy 287.803634 -290.47202)
			(xy 287.833199 -290.511364) (xy 287.85607 -290.554941) (xy 287.871654 -290.601622) (xy 287.879549 -290.650199)
			(xy 287.880044 -290.674806) (xy 288.218892 -290.674806) (xy 288.222852 -290.625752) (xy 288.234629 -290.577968)
			(xy 288.25392 -290.532692) (xy 288.280223 -290.491096) (xy 288.312858 -290.454259) (xy 288.350979 -290.423134)
			(xy 288.3936 -290.398527) (xy 288.439616 -290.381075) (xy 288.487835 -290.371231) (xy 288.53701 -290.36925)
			(xy 288.585865 -290.375182) (xy 288.633136 -290.388874) (xy 288.677598 -290.409972) (xy 288.718101 -290.437928)
			(xy 288.753594 -290.47202) (xy 288.783159 -290.511364) (xy 288.80603 -290.554941) (xy 288.821614 -290.601622)
			(xy 288.829509 -290.650199) (xy 288.830004 -290.674806) (xy 289.169106 -290.674806) (xy 289.173066 -290.625752)
			(xy 289.184843 -290.577968) (xy 289.204134 -290.532692) (xy 289.230437 -290.491096) (xy 289.263072 -290.454259)
			(xy 289.301193 -290.423134) (xy 289.343814 -290.398527) (xy 289.38983 -290.381075) (xy 289.438049 -290.371231)
			(xy 289.487224 -290.36925) (xy 289.536079 -290.375182) (xy 289.58335 -290.388874) (xy 289.627812 -290.409972)
			(xy 289.668315 -290.437928) (xy 289.703808 -290.47202) (xy 289.733373 -290.511364) (xy 289.756244 -290.554941)
			(xy 289.771828 -290.601622) (xy 289.779723 -290.650199) (xy 289.780218 -290.674806) (xy 290.119066 -290.674806)
			(xy 290.123026 -290.625752) (xy 290.134803 -290.577968) (xy 290.154094 -290.532692) (xy 290.180397 -290.491096)
			(xy 290.213032 -290.454259) (xy 290.251153 -290.423134) (xy 290.293774 -290.398527) (xy 290.33979 -290.381075)
			(xy 290.388009 -290.371231) (xy 290.437184 -290.36925) (xy 290.486039 -290.375182) (xy 290.53331 -290.388874)
			(xy 290.577772 -290.409972) (xy 290.618275 -290.437928) (xy 290.653768 -290.47202) (xy 290.683333 -290.511364)
			(xy 290.706204 -290.554941) (xy 290.721788 -290.601622) (xy 290.729683 -290.650199) (xy 290.730178 -290.674806)
			(xy 292.018986 -290.674806) (xy 292.022946 -290.625752) (xy 292.034723 -290.577968) (xy 292.054014 -290.532692)
			(xy 292.080317 -290.491096) (xy 292.112952 -290.454259) (xy 292.151073 -290.423134) (xy 292.193694 -290.398527)
			(xy 292.23971 -290.381075) (xy 292.287929 -290.371231) (xy 292.337104 -290.36925) (xy 292.385959 -290.375182)
			(xy 292.43323 -290.388874) (xy 292.477692 -290.409972) (xy 292.518195 -290.437928) (xy 292.553688 -290.47202)
			(xy 292.583253 -290.511364) (xy 292.606124 -290.554941) (xy 292.621708 -290.601622) (xy 292.629603 -290.650199)
			(xy 292.630098 -290.674806) (xy 292.968946 -290.674806) (xy 292.972906 -290.625752) (xy 292.984683 -290.577968)
			(xy 293.003974 -290.532692) (xy 293.030277 -290.491096) (xy 293.062912 -290.454259) (xy 293.101033 -290.423134)
			(xy 293.143654 -290.398527) (xy 293.18967 -290.381075) (xy 293.237889 -290.371231) (xy 293.287064 -290.36925)
			(xy 293.335919 -290.375182) (xy 293.38319 -290.388874) (xy 293.427652 -290.409972) (xy 293.468155 -290.437928)
			(xy 293.503648 -290.47202) (xy 293.533213 -290.511364) (xy 293.556084 -290.554941) (xy 293.571668 -290.601622)
			(xy 293.579563 -290.650199) (xy 293.580058 -290.674806) (xy 293.918906 -290.674806) (xy 293.922866 -290.625752)
			(xy 293.934643 -290.577968) (xy 293.953934 -290.532692) (xy 293.980237 -290.491096) (xy 294.012872 -290.454259)
			(xy 294.050993 -290.423134) (xy 294.093614 -290.398527) (xy 294.13963 -290.381075) (xy 294.187849 -290.371231)
			(xy 294.237024 -290.36925) (xy 294.285879 -290.375182) (xy 294.33315 -290.388874) (xy 294.377612 -290.409972)
			(xy 294.418115 -290.437928) (xy 294.453608 -290.47202) (xy 294.483173 -290.511364) (xy 294.506044 -290.554941)
			(xy 294.521628 -290.601622) (xy 294.529523 -290.650199) (xy 294.530018 -290.674806) (xy 294.86912 -290.674806)
			(xy 294.87308 -290.625752) (xy 294.884857 -290.577968) (xy 294.904148 -290.532692) (xy 294.930451 -290.491096)
			(xy 294.963086 -290.454259) (xy 295.001207 -290.423134) (xy 295.043828 -290.398527) (xy 295.089844 -290.381075)
			(xy 295.138063 -290.371231) (xy 295.187238 -290.36925) (xy 295.236093 -290.375182) (xy 295.283364 -290.388874)
			(xy 295.327826 -290.409972) (xy 295.368329 -290.437928) (xy 295.403822 -290.47202) (xy 295.433387 -290.511364)
			(xy 295.456258 -290.554941) (xy 295.471842 -290.601622) (xy 295.479737 -290.650199) (xy 295.480232 -290.674806)
			(xy 295.81908 -290.674806) (xy 295.82304 -290.625752) (xy 295.834817 -290.577968) (xy 295.854108 -290.532692)
			(xy 295.880411 -290.491096) (xy 295.913046 -290.454259) (xy 295.951167 -290.423134) (xy 295.993788 -290.398527)
			(xy 296.039804 -290.381075) (xy 296.088023 -290.371231) (xy 296.137198 -290.36925) (xy 296.186053 -290.375182)
			(xy 296.233324 -290.388874) (xy 296.277786 -290.409972) (xy 296.318289 -290.437928) (xy 296.353782 -290.47202)
			(xy 296.383347 -290.511364) (xy 296.406218 -290.554941) (xy 296.421802 -290.601622) (xy 296.429697 -290.650199)
			(xy 296.430192 -290.674806) (xy 296.76904 -290.674806) (xy 296.773 -290.625752) (xy 296.784777 -290.577968)
			(xy 296.804068 -290.532692) (xy 296.830371 -290.491096) (xy 296.863006 -290.454259) (xy 296.901127 -290.423134)
			(xy 296.943748 -290.398527) (xy 296.989764 -290.381075) (xy 297.037983 -290.371231) (xy 297.087158 -290.36925)
			(xy 297.136013 -290.375182) (xy 297.183284 -290.388874) (xy 297.227746 -290.409972) (xy 297.268249 -290.437928)
			(xy 297.303742 -290.47202) (xy 297.333307 -290.511364) (xy 297.356178 -290.554941) (xy 297.371762 -290.601622)
			(xy 297.379657 -290.650199) (xy 297.380152 -290.674806) (xy 297.719 -290.674806) (xy 297.72296 -290.625752)
			(xy 297.734737 -290.577968) (xy 297.754028 -290.532692) (xy 297.780331 -290.491096) (xy 297.812966 -290.454259)
			(xy 297.851087 -290.423134) (xy 297.893708 -290.398527) (xy 297.939724 -290.381075) (xy 297.987943 -290.371231)
			(xy 298.037118 -290.36925) (xy 298.085973 -290.375182) (xy 298.133244 -290.388874) (xy 298.177706 -290.409972)
			(xy 298.218209 -290.437928) (xy 298.253702 -290.47202) (xy 298.283267 -290.511364) (xy 298.306138 -290.554941)
			(xy 298.321722 -290.601622) (xy 298.329617 -290.650199) (xy 298.330112 -290.674806) (xy 298.66896 -290.674806)
			(xy 298.67292 -290.625752) (xy 298.684697 -290.577968) (xy 298.703988 -290.532692) (xy 298.730291 -290.491096)
			(xy 298.762926 -290.454259) (xy 298.801047 -290.423134) (xy 298.843668 -290.398527) (xy 298.889684 -290.381075)
			(xy 298.937903 -290.371231) (xy 298.987078 -290.36925) (xy 299.035933 -290.375182) (xy 299.083204 -290.388874)
			(xy 299.127666 -290.409972) (xy 299.168169 -290.437928) (xy 299.203662 -290.47202) (xy 299.233227 -290.511364)
			(xy 299.256098 -290.554941) (xy 299.271682 -290.601622) (xy 299.279577 -290.650199) (xy 299.280072 -290.674806)
			(xy 299.61892 -290.674806) (xy 299.62288 -290.625752) (xy 299.634657 -290.577968) (xy 299.653948 -290.532692)
			(xy 299.680251 -290.491096) (xy 299.712886 -290.454259) (xy 299.751007 -290.423134) (xy 299.793628 -290.398527)
			(xy 299.839644 -290.381075) (xy 299.887863 -290.371231) (xy 299.937038 -290.36925) (xy 299.985893 -290.375182)
			(xy 300.033164 -290.388874) (xy 300.077626 -290.409972) (xy 300.118129 -290.437928) (xy 300.153622 -290.47202)
			(xy 300.183187 -290.511364) (xy 300.206058 -290.554941) (xy 300.221642 -290.601622) (xy 300.229537 -290.650199)
			(xy 300.230032 -290.674806) (xy 300.56888 -290.674806) (xy 300.57284 -290.625752) (xy 300.584617 -290.577968)
			(xy 300.603908 -290.532692) (xy 300.630211 -290.491096) (xy 300.662846 -290.454259) (xy 300.700967 -290.423134)
			(xy 300.743588 -290.398527) (xy 300.789604 -290.381075) (xy 300.837823 -290.371231) (xy 300.886998 -290.36925)
			(xy 300.935853 -290.375182) (xy 300.983124 -290.388874) (xy 301.027586 -290.409972) (xy 301.068089 -290.437928)
			(xy 301.103582 -290.47202) (xy 301.133147 -290.511364) (xy 301.156018 -290.554941) (xy 301.171602 -290.601622)
			(xy 301.179497 -290.650199) (xy 301.179992 -290.674806) (xy 301.519094 -290.674806) (xy 301.523054 -290.625752)
			(xy 301.534831 -290.577968) (xy 301.554122 -290.532692) (xy 301.580425 -290.491096) (xy 301.61306 -290.454259)
			(xy 301.651181 -290.423134) (xy 301.693802 -290.398527) (xy 301.739818 -290.381075) (xy 301.788037 -290.371231)
			(xy 301.837212 -290.36925) (xy 301.886067 -290.375182) (xy 301.933338 -290.388874) (xy 301.9778 -290.409972)
			(xy 302.018303 -290.437928) (xy 302.053796 -290.47202) (xy 302.083361 -290.511364) (xy 302.106232 -290.554941)
			(xy 302.121816 -290.601622) (xy 302.129711 -290.650199) (xy 302.130206 -290.674806) (xy 302.469054 -290.674806)
			(xy 302.473014 -290.625752) (xy 302.484791 -290.577968) (xy 302.504082 -290.532692) (xy 302.530385 -290.491096)
			(xy 302.56302 -290.454259) (xy 302.601141 -290.423134) (xy 302.643762 -290.398527) (xy 302.689778 -290.381075)
			(xy 302.737997 -290.371231) (xy 302.787172 -290.36925) (xy 302.836027 -290.375182) (xy 302.883298 -290.388874)
			(xy 302.92776 -290.409972) (xy 302.968263 -290.437928) (xy 303.003756 -290.47202) (xy 303.033321 -290.511364)
			(xy 303.056192 -290.554941) (xy 303.071776 -290.601622) (xy 303.079671 -290.650199) (xy 303.080166 -290.674806)
			(xy 303.419014 -290.674806) (xy 303.422974 -290.625752) (xy 303.434751 -290.577968) (xy 303.454042 -290.532692)
			(xy 303.480345 -290.491096) (xy 303.51298 -290.454259) (xy 303.551101 -290.423134) (xy 303.593722 -290.398527)
			(xy 303.639738 -290.381075) (xy 303.687957 -290.371231) (xy 303.737132 -290.36925) (xy 303.785987 -290.375182)
			(xy 303.833258 -290.388874) (xy 303.87772 -290.409972) (xy 303.918223 -290.437928) (xy 303.953716 -290.47202)
			(xy 303.983281 -290.511364) (xy 304.006152 -290.554941) (xy 304.021736 -290.601622) (xy 304.029631 -290.650199)
			(xy 304.030126 -290.674806) (xy 304.368974 -290.674806) (xy 304.372934 -290.625752) (xy 304.384711 -290.577968)
			(xy 304.404002 -290.532692) (xy 304.430305 -290.491096) (xy 304.46294 -290.454259) (xy 304.501061 -290.423134)
			(xy 304.543682 -290.398527) (xy 304.589698 -290.381075) (xy 304.637917 -290.371231) (xy 304.687092 -290.36925)
			(xy 304.735947 -290.375182) (xy 304.783218 -290.388874) (xy 304.82768 -290.409972) (xy 304.868183 -290.437928)
			(xy 304.903676 -290.47202) (xy 304.933241 -290.511364) (xy 304.956112 -290.554941) (xy 304.971696 -290.601622)
			(xy 304.979591 -290.650199) (xy 304.980086 -290.674806) (xy 305.318934 -290.674806) (xy 305.322894 -290.625752)
			(xy 305.334671 -290.577968) (xy 305.353962 -290.532692) (xy 305.380265 -290.491096) (xy 305.4129 -290.454259)
			(xy 305.451021 -290.423134) (xy 305.493642 -290.398527) (xy 305.539658 -290.381075) (xy 305.587877 -290.371231)
			(xy 305.637052 -290.36925) (xy 305.685907 -290.375182) (xy 305.733178 -290.388874) (xy 305.77764 -290.409972)
			(xy 305.818143 -290.437928) (xy 305.853636 -290.47202) (xy 305.883201 -290.511364) (xy 305.906072 -290.554941)
			(xy 305.921656 -290.601622) (xy 305.929551 -290.650199) (xy 305.930046 -290.674806) (xy 306.268894 -290.674806)
			(xy 306.272854 -290.625752) (xy 306.284631 -290.577968) (xy 306.303922 -290.532692) (xy 306.330225 -290.491096)
			(xy 306.36286 -290.454259) (xy 306.400981 -290.423134) (xy 306.443602 -290.398527) (xy 306.489618 -290.381075)
			(xy 306.537837 -290.371231) (xy 306.587012 -290.36925) (xy 306.635867 -290.375182) (xy 306.683138 -290.388874)
			(xy 306.7276 -290.409972) (xy 306.768103 -290.437928) (xy 306.803596 -290.47202) (xy 306.833161 -290.511364)
			(xy 306.856032 -290.554941) (xy 306.871616 -290.601622) (xy 306.879511 -290.650199) (xy 306.880006 -290.674806)
			(xy 307.219108 -290.674806) (xy 307.223068 -290.625752) (xy 307.234845 -290.577968) (xy 307.254136 -290.532692)
			(xy 307.280439 -290.491096) (xy 307.313074 -290.454259) (xy 307.351195 -290.423134) (xy 307.393816 -290.398527)
			(xy 307.439832 -290.381075) (xy 307.488051 -290.371231) (xy 307.537226 -290.36925) (xy 307.586081 -290.375182)
			(xy 307.633352 -290.388874) (xy 307.677814 -290.409972) (xy 307.718317 -290.437928) (xy 307.75381 -290.47202)
			(xy 307.783375 -290.511364) (xy 307.806246 -290.554941) (xy 307.82183 -290.601622) (xy 307.829725 -290.650199)
			(xy 307.83022 -290.674806) (xy 308.169068 -290.674806) (xy 308.173028 -290.625752) (xy 308.184805 -290.577968)
			(xy 308.204096 -290.532692) (xy 308.230399 -290.491096) (xy 308.263034 -290.454259) (xy 308.301155 -290.423134)
			(xy 308.343776 -290.398527) (xy 308.389792 -290.381075) (xy 308.438011 -290.371231) (xy 308.487186 -290.36925)
			(xy 308.536041 -290.375182) (xy 308.583312 -290.388874) (xy 308.627774 -290.409972) (xy 308.668277 -290.437928)
			(xy 308.70377 -290.47202) (xy 308.733335 -290.511364) (xy 308.756206 -290.554941) (xy 308.77179 -290.601622)
			(xy 308.779685 -290.650199) (xy 308.78018 -290.674806) (xy 309.119028 -290.674806) (xy 309.122988 -290.625752)
			(xy 309.134765 -290.577968) (xy 309.154056 -290.532692) (xy 309.180359 -290.491096) (xy 309.212994 -290.454259)
			(xy 309.251115 -290.423134) (xy 309.293736 -290.398527) (xy 309.339752 -290.381075) (xy 309.387971 -290.371231)
			(xy 309.437146 -290.36925) (xy 309.486001 -290.375182) (xy 309.533272 -290.388874) (xy 309.577734 -290.409972)
			(xy 309.618237 -290.437928) (xy 309.65373 -290.47202) (xy 309.683295 -290.511364) (xy 309.706166 -290.554941)
			(xy 309.72175 -290.601622) (xy 309.729645 -290.650199) (xy 309.73014 -290.674806) (xy 310.068988 -290.674806)
			(xy 310.072948 -290.625752) (xy 310.084725 -290.577968) (xy 310.104016 -290.532692) (xy 310.130319 -290.491096)
			(xy 310.162954 -290.454259) (xy 310.201075 -290.423134) (xy 310.243696 -290.398527) (xy 310.289712 -290.381075)
			(xy 310.337931 -290.371231) (xy 310.387106 -290.36925) (xy 310.435961 -290.375182) (xy 310.483232 -290.388874)
			(xy 310.527694 -290.409972) (xy 310.568197 -290.437928) (xy 310.60369 -290.47202) (xy 310.633255 -290.511364)
			(xy 310.656126 -290.554941) (xy 310.67171 -290.601622) (xy 310.679605 -290.650199) (xy 310.6801 -290.674806)
			(xy 311.018948 -290.674806) (xy 311.022908 -290.625752) (xy 311.034685 -290.577968) (xy 311.053976 -290.532692)
			(xy 311.080279 -290.491096) (xy 311.112914 -290.454259) (xy 311.151035 -290.423134) (xy 311.193656 -290.398527)
			(xy 311.239672 -290.381075) (xy 311.287891 -290.371231) (xy 311.337066 -290.36925) (xy 311.385921 -290.375182)
			(xy 311.433192 -290.388874) (xy 311.477654 -290.409972) (xy 311.518157 -290.437928) (xy 311.55365 -290.47202)
			(xy 311.583215 -290.511364) (xy 311.606086 -290.554941) (xy 311.62167 -290.601622) (xy 311.629565 -290.650199)
			(xy 311.63006 -290.674806) (xy 311.968908 -290.674806) (xy 311.972868 -290.625752) (xy 311.984645 -290.577968)
			(xy 312.003936 -290.532692) (xy 312.030239 -290.491096) (xy 312.062874 -290.454259) (xy 312.100995 -290.423134)
			(xy 312.143616 -290.398527) (xy 312.189632 -290.381075) (xy 312.237851 -290.371231) (xy 312.287026 -290.36925)
			(xy 312.335881 -290.375182) (xy 312.383152 -290.388874) (xy 312.427614 -290.409972) (xy 312.468117 -290.437928)
			(xy 312.50361 -290.47202) (xy 312.533175 -290.511364) (xy 312.556046 -290.554941) (xy 312.57163 -290.601622)
			(xy 312.579525 -290.650199) (xy 312.58002 -290.674806) (xy 312.919122 -290.674806) (xy 312.923082 -290.625752)
			(xy 312.934859 -290.577968) (xy 312.95415 -290.532692) (xy 312.980453 -290.491096) (xy 313.013088 -290.454259)
			(xy 313.051209 -290.423134) (xy 313.09383 -290.398527) (xy 313.139846 -290.381075) (xy 313.188065 -290.371231)
			(xy 313.23724 -290.36925) (xy 313.286095 -290.375182) (xy 313.333366 -290.388874) (xy 313.377828 -290.409972)
			(xy 313.418331 -290.437928) (xy 313.453824 -290.47202) (xy 313.483389 -290.511364) (xy 313.50626 -290.554941)
			(xy 313.521844 -290.601622) (xy 313.529739 -290.650199) (xy 313.530234 -290.674806) (xy 313.869082 -290.674806)
			(xy 313.873042 -290.625752) (xy 313.884819 -290.577968) (xy 313.90411 -290.532692) (xy 313.930413 -290.491096)
			(xy 313.963048 -290.454259) (xy 314.001169 -290.423134) (xy 314.04379 -290.398527) (xy 314.089806 -290.381075)
			(xy 314.138025 -290.371231) (xy 314.1872 -290.36925) (xy 314.236055 -290.375182) (xy 314.283326 -290.388874)
			(xy 314.327788 -290.409972) (xy 314.368291 -290.437928) (xy 314.403784 -290.47202) (xy 314.433349 -290.511364)
			(xy 314.45622 -290.554941) (xy 314.471804 -290.601622) (xy 314.479699 -290.650199) (xy 314.480194 -290.674806)
			(xy 314.819042 -290.674806) (xy 314.823002 -290.625752) (xy 314.834779 -290.577968) (xy 314.85407 -290.532692)
			(xy 314.880373 -290.491096) (xy 314.913008 -290.454259) (xy 314.951129 -290.423134) (xy 314.99375 -290.398527)
			(xy 315.039766 -290.381075) (xy 315.087985 -290.371231) (xy 315.13716 -290.36925) (xy 315.186015 -290.375182)
			(xy 315.233286 -290.388874) (xy 315.277748 -290.409972) (xy 315.318251 -290.437928) (xy 315.353744 -290.47202)
			(xy 315.383309 -290.511364) (xy 315.40618 -290.554941) (xy 315.421764 -290.601622) (xy 315.429659 -290.650199)
			(xy 315.430154 -290.674806) (xy 315.429659 -290.699413) (xy 315.421764 -290.74799) (xy 315.40618 -290.794671)
			(xy 315.383309 -290.838248) (xy 315.353744 -290.877592) (xy 315.318251 -290.911684) (xy 315.277748 -290.93964)
			(xy 315.233286 -290.960738) (xy 315.186015 -290.97443) (xy 315.13716 -290.980362) (xy 315.087985 -290.978381)
			(xy 315.039766 -290.968537) (xy 314.99375 -290.951085) (xy 314.951129 -290.926478) (xy 314.913008 -290.895353)
			(xy 314.880373 -290.858516) (xy 314.85407 -290.81692) (xy 314.834779 -290.771644) (xy 314.823002 -290.72386)
			(xy 314.819042 -290.674806) (xy 314.480194 -290.674806) (xy 314.479699 -290.699413) (xy 314.471804 -290.74799)
			(xy 314.45622 -290.794671) (xy 314.433349 -290.838248) (xy 314.403784 -290.877592) (xy 314.368291 -290.911684)
			(xy 314.327788 -290.93964) (xy 314.283326 -290.960738) (xy 314.236055 -290.97443) (xy 314.1872 -290.980362)
			(xy 314.138025 -290.978381) (xy 314.089806 -290.968537) (xy 314.04379 -290.951085) (xy 314.001169 -290.926478)
			(xy 313.963048 -290.895353) (xy 313.930413 -290.858516) (xy 313.90411 -290.81692) (xy 313.884819 -290.771644)
			(xy 313.873042 -290.72386) (xy 313.869082 -290.674806) (xy 313.530234 -290.674806) (xy 313.529739 -290.699413)
			(xy 313.521844 -290.74799) (xy 313.50626 -290.794671) (xy 313.483389 -290.838248) (xy 313.453824 -290.877592)
			(xy 313.418331 -290.911684) (xy 313.377828 -290.93964) (xy 313.333366 -290.960738) (xy 313.286095 -290.97443)
			(xy 313.23724 -290.980362) (xy 313.188065 -290.978381) (xy 313.139846 -290.968537) (xy 313.09383 -290.951085)
			(xy 313.051209 -290.926478) (xy 313.013088 -290.895353) (xy 312.980453 -290.858516) (xy 312.95415 -290.81692)
			(xy 312.934859 -290.771644) (xy 312.923082 -290.72386) (xy 312.919122 -290.674806) (xy 312.58002 -290.674806)
			(xy 312.579525 -290.699413) (xy 312.57163 -290.74799) (xy 312.556046 -290.794671) (xy 312.533175 -290.838248)
			(xy 312.50361 -290.877592) (xy 312.468117 -290.911684) (xy 312.427614 -290.93964) (xy 312.383152 -290.960738)
			(xy 312.335881 -290.97443) (xy 312.287026 -290.980362) (xy 312.237851 -290.978381) (xy 312.189632 -290.968537)
			(xy 312.143616 -290.951085) (xy 312.100995 -290.926478) (xy 312.062874 -290.895353) (xy 312.030239 -290.858516)
			(xy 312.003936 -290.81692) (xy 311.984645 -290.771644) (xy 311.972868 -290.72386) (xy 311.968908 -290.674806)
			(xy 311.63006 -290.674806) (xy 311.629565 -290.699413) (xy 311.62167 -290.74799) (xy 311.606086 -290.794671)
			(xy 311.583215 -290.838248) (xy 311.55365 -290.877592) (xy 311.518157 -290.911684) (xy 311.477654 -290.93964)
			(xy 311.433192 -290.960738) (xy 311.385921 -290.97443) (xy 311.337066 -290.980362) (xy 311.287891 -290.978381)
			(xy 311.239672 -290.968537) (xy 311.193656 -290.951085) (xy 311.151035 -290.926478) (xy 311.112914 -290.895353)
			(xy 311.080279 -290.858516) (xy 311.053976 -290.81692) (xy 311.034685 -290.771644) (xy 311.022908 -290.72386)
			(xy 311.018948 -290.674806) (xy 310.6801 -290.674806) (xy 310.679605 -290.699413) (xy 310.67171 -290.74799)
			(xy 310.656126 -290.794671) (xy 310.633255 -290.838248) (xy 310.60369 -290.877592) (xy 310.568197 -290.911684)
			(xy 310.527694 -290.93964) (xy 310.483232 -290.960738) (xy 310.435961 -290.97443) (xy 310.387106 -290.980362)
			(xy 310.337931 -290.978381) (xy 310.289712 -290.968537) (xy 310.243696 -290.951085) (xy 310.201075 -290.926478)
			(xy 310.162954 -290.895353) (xy 310.130319 -290.858516) (xy 310.104016 -290.81692) (xy 310.084725 -290.771644)
			(xy 310.072948 -290.72386) (xy 310.068988 -290.674806) (xy 309.73014 -290.674806) (xy 309.729645 -290.699413)
			(xy 309.72175 -290.74799) (xy 309.706166 -290.794671) (xy 309.683295 -290.838248) (xy 309.65373 -290.877592)
			(xy 309.618237 -290.911684) (xy 309.577734 -290.93964) (xy 309.533272 -290.960738) (xy 309.486001 -290.97443)
			(xy 309.437146 -290.980362) (xy 309.387971 -290.978381) (xy 309.339752 -290.968537) (xy 309.293736 -290.951085)
			(xy 309.251115 -290.926478) (xy 309.212994 -290.895353) (xy 309.180359 -290.858516) (xy 309.154056 -290.81692)
			(xy 309.134765 -290.771644) (xy 309.122988 -290.72386) (xy 309.119028 -290.674806) (xy 308.78018 -290.674806)
			(xy 308.779685 -290.699413) (xy 308.77179 -290.74799) (xy 308.756206 -290.794671) (xy 308.733335 -290.838248)
			(xy 308.70377 -290.877592) (xy 308.668277 -290.911684) (xy 308.627774 -290.93964) (xy 308.583312 -290.960738)
			(xy 308.536041 -290.97443) (xy 308.487186 -290.980362) (xy 308.438011 -290.978381) (xy 308.389792 -290.968537)
			(xy 308.343776 -290.951085) (xy 308.301155 -290.926478) (xy 308.263034 -290.895353) (xy 308.230399 -290.858516)
			(xy 308.204096 -290.81692) (xy 308.184805 -290.771644) (xy 308.173028 -290.72386) (xy 308.169068 -290.674806)
			(xy 307.83022 -290.674806) (xy 307.829725 -290.699413) (xy 307.82183 -290.74799) (xy 307.806246 -290.794671)
			(xy 307.783375 -290.838248) (xy 307.75381 -290.877592) (xy 307.718317 -290.911684) (xy 307.677814 -290.93964)
			(xy 307.633352 -290.960738) (xy 307.586081 -290.97443) (xy 307.537226 -290.980362) (xy 307.488051 -290.978381)
			(xy 307.439832 -290.968537) (xy 307.393816 -290.951085) (xy 307.351195 -290.926478) (xy 307.313074 -290.895353)
			(xy 307.280439 -290.858516) (xy 307.254136 -290.81692) (xy 307.234845 -290.771644) (xy 307.223068 -290.72386)
			(xy 307.219108 -290.674806) (xy 306.880006 -290.674806) (xy 306.879511 -290.699413) (xy 306.871616 -290.74799)
			(xy 306.856032 -290.794671) (xy 306.833161 -290.838248) (xy 306.803596 -290.877592) (xy 306.768103 -290.911684)
			(xy 306.7276 -290.93964) (xy 306.683138 -290.960738) (xy 306.635867 -290.97443) (xy 306.587012 -290.980362)
			(xy 306.537837 -290.978381) (xy 306.489618 -290.968537) (xy 306.443602 -290.951085) (xy 306.400981 -290.926478)
			(xy 306.36286 -290.895353) (xy 306.330225 -290.858516) (xy 306.303922 -290.81692) (xy 306.284631 -290.771644)
			(xy 306.272854 -290.72386) (xy 306.268894 -290.674806) (xy 305.930046 -290.674806) (xy 305.929551 -290.699413)
			(xy 305.921656 -290.74799) (xy 305.906072 -290.794671) (xy 305.883201 -290.838248) (xy 305.853636 -290.877592)
			(xy 305.818143 -290.911684) (xy 305.77764 -290.93964) (xy 305.733178 -290.960738) (xy 305.685907 -290.97443)
			(xy 305.637052 -290.980362) (xy 305.587877 -290.978381) (xy 305.539658 -290.968537) (xy 305.493642 -290.951085)
			(xy 305.451021 -290.926478) (xy 305.4129 -290.895353) (xy 305.380265 -290.858516) (xy 305.353962 -290.81692)
			(xy 305.334671 -290.771644) (xy 305.322894 -290.72386) (xy 305.318934 -290.674806) (xy 304.980086 -290.674806)
			(xy 304.979591 -290.699413) (xy 304.971696 -290.74799) (xy 304.956112 -290.794671) (xy 304.933241 -290.838248)
			(xy 304.903676 -290.877592) (xy 304.868183 -290.911684) (xy 304.82768 -290.93964) (xy 304.783218 -290.960738)
			(xy 304.735947 -290.97443) (xy 304.687092 -290.980362) (xy 304.637917 -290.978381) (xy 304.589698 -290.968537)
			(xy 304.543682 -290.951085) (xy 304.501061 -290.926478) (xy 304.46294 -290.895353) (xy 304.430305 -290.858516)
			(xy 304.404002 -290.81692) (xy 304.384711 -290.771644) (xy 304.372934 -290.72386) (xy 304.368974 -290.674806)
			(xy 304.030126 -290.674806) (xy 304.029631 -290.699413) (xy 304.021736 -290.74799) (xy 304.006152 -290.794671)
			(xy 303.983281 -290.838248) (xy 303.953716 -290.877592) (xy 303.918223 -290.911684) (xy 303.87772 -290.93964)
			(xy 303.833258 -290.960738) (xy 303.785987 -290.97443) (xy 303.737132 -290.980362) (xy 303.687957 -290.978381)
			(xy 303.639738 -290.968537) (xy 303.593722 -290.951085) (xy 303.551101 -290.926478) (xy 303.51298 -290.895353)
			(xy 303.480345 -290.858516) (xy 303.454042 -290.81692) (xy 303.434751 -290.771644) (xy 303.422974 -290.72386)
			(xy 303.419014 -290.674806) (xy 303.080166 -290.674806) (xy 303.079671 -290.699413) (xy 303.071776 -290.74799)
			(xy 303.056192 -290.794671) (xy 303.033321 -290.838248) (xy 303.003756 -290.877592) (xy 302.968263 -290.911684)
			(xy 302.92776 -290.93964) (xy 302.883298 -290.960738) (xy 302.836027 -290.97443) (xy 302.787172 -290.980362)
			(xy 302.737997 -290.978381) (xy 302.689778 -290.968537) (xy 302.643762 -290.951085) (xy 302.601141 -290.926478)
			(xy 302.56302 -290.895353) (xy 302.530385 -290.858516) (xy 302.504082 -290.81692) (xy 302.484791 -290.771644)
			(xy 302.473014 -290.72386) (xy 302.469054 -290.674806) (xy 302.130206 -290.674806) (xy 302.129711 -290.699413)
			(xy 302.121816 -290.74799) (xy 302.106232 -290.794671) (xy 302.083361 -290.838248) (xy 302.053796 -290.877592)
			(xy 302.018303 -290.911684) (xy 301.9778 -290.93964) (xy 301.933338 -290.960738) (xy 301.886067 -290.97443)
			(xy 301.837212 -290.980362) (xy 301.788037 -290.978381) (xy 301.739818 -290.968537) (xy 301.693802 -290.951085)
			(xy 301.651181 -290.926478) (xy 301.61306 -290.895353) (xy 301.580425 -290.858516) (xy 301.554122 -290.81692)
			(xy 301.534831 -290.771644) (xy 301.523054 -290.72386) (xy 301.519094 -290.674806) (xy 301.179992 -290.674806)
			(xy 301.179497 -290.699413) (xy 301.171602 -290.74799) (xy 301.156018 -290.794671) (xy 301.133147 -290.838248)
			(xy 301.103582 -290.877592) (xy 301.068089 -290.911684) (xy 301.027586 -290.93964) (xy 300.983124 -290.960738)
			(xy 300.935853 -290.97443) (xy 300.886998 -290.980362) (xy 300.837823 -290.978381) (xy 300.789604 -290.968537)
			(xy 300.743588 -290.951085) (xy 300.700967 -290.926478) (xy 300.662846 -290.895353) (xy 300.630211 -290.858516)
			(xy 300.603908 -290.81692) (xy 300.584617 -290.771644) (xy 300.57284 -290.72386) (xy 300.56888 -290.674806)
			(xy 300.230032 -290.674806) (xy 300.229537 -290.699413) (xy 300.221642 -290.74799) (xy 300.206058 -290.794671)
			(xy 300.183187 -290.838248) (xy 300.153622 -290.877592) (xy 300.118129 -290.911684) (xy 300.077626 -290.93964)
			(xy 300.033164 -290.960738) (xy 299.985893 -290.97443) (xy 299.937038 -290.980362) (xy 299.887863 -290.978381)
			(xy 299.839644 -290.968537) (xy 299.793628 -290.951085) (xy 299.751007 -290.926478) (xy 299.712886 -290.895353)
			(xy 299.680251 -290.858516) (xy 299.653948 -290.81692) (xy 299.634657 -290.771644) (xy 299.62288 -290.72386)
			(xy 299.61892 -290.674806) (xy 299.280072 -290.674806) (xy 299.279577 -290.699413) (xy 299.271682 -290.74799)
			(xy 299.256098 -290.794671) (xy 299.233227 -290.838248) (xy 299.203662 -290.877592) (xy 299.168169 -290.911684)
			(xy 299.127666 -290.93964) (xy 299.083204 -290.960738) (xy 299.035933 -290.97443) (xy 298.987078 -290.980362)
			(xy 298.937903 -290.978381) (xy 298.889684 -290.968537) (xy 298.843668 -290.951085) (xy 298.801047 -290.926478)
			(xy 298.762926 -290.895353) (xy 298.730291 -290.858516) (xy 298.703988 -290.81692) (xy 298.684697 -290.771644)
			(xy 298.67292 -290.72386) (xy 298.66896 -290.674806) (xy 298.330112 -290.674806) (xy 298.329617 -290.699413)
			(xy 298.321722 -290.74799) (xy 298.306138 -290.794671) (xy 298.283267 -290.838248) (xy 298.253702 -290.877592)
			(xy 298.218209 -290.911684) (xy 298.177706 -290.93964) (xy 298.133244 -290.960738) (xy 298.085973 -290.97443)
			(xy 298.037118 -290.980362) (xy 297.987943 -290.978381) (xy 297.939724 -290.968537) (xy 297.893708 -290.951085)
			(xy 297.851087 -290.926478) (xy 297.812966 -290.895353) (xy 297.780331 -290.858516) (xy 297.754028 -290.81692)
			(xy 297.734737 -290.771644) (xy 297.72296 -290.72386) (xy 297.719 -290.674806) (xy 297.380152 -290.674806)
			(xy 297.379657 -290.699413) (xy 297.371762 -290.74799) (xy 297.356178 -290.794671) (xy 297.333307 -290.838248)
			(xy 297.303742 -290.877592) (xy 297.268249 -290.911684) (xy 297.227746 -290.93964) (xy 297.183284 -290.960738)
			(xy 297.136013 -290.97443) (xy 297.087158 -290.980362) (xy 297.037983 -290.978381) (xy 296.989764 -290.968537)
			(xy 296.943748 -290.951085) (xy 296.901127 -290.926478) (xy 296.863006 -290.895353) (xy 296.830371 -290.858516)
			(xy 296.804068 -290.81692) (xy 296.784777 -290.771644) (xy 296.773 -290.72386) (xy 296.76904 -290.674806)
			(xy 296.430192 -290.674806) (xy 296.429697 -290.699413) (xy 296.421802 -290.74799) (xy 296.406218 -290.794671)
			(xy 296.383347 -290.838248) (xy 296.353782 -290.877592) (xy 296.318289 -290.911684) (xy 296.277786 -290.93964)
			(xy 296.233324 -290.960738) (xy 296.186053 -290.97443) (xy 296.137198 -290.980362) (xy 296.088023 -290.978381)
			(xy 296.039804 -290.968537) (xy 295.993788 -290.951085) (xy 295.951167 -290.926478) (xy 295.913046 -290.895353)
			(xy 295.880411 -290.858516) (xy 295.854108 -290.81692) (xy 295.834817 -290.771644) (xy 295.82304 -290.72386)
			(xy 295.81908 -290.674806) (xy 295.480232 -290.674806) (xy 295.479737 -290.699413) (xy 295.471842 -290.74799)
			(xy 295.456258 -290.794671) (xy 295.433387 -290.838248) (xy 295.403822 -290.877592) (xy 295.368329 -290.911684)
			(xy 295.327826 -290.93964) (xy 295.283364 -290.960738) (xy 295.236093 -290.97443) (xy 295.187238 -290.980362)
			(xy 295.138063 -290.978381) (xy 295.089844 -290.968537) (xy 295.043828 -290.951085) (xy 295.001207 -290.926478)
			(xy 294.963086 -290.895353) (xy 294.930451 -290.858516) (xy 294.904148 -290.81692) (xy 294.884857 -290.771644)
			(xy 294.87308 -290.72386) (xy 294.86912 -290.674806) (xy 294.530018 -290.674806) (xy 294.529523 -290.699413)
			(xy 294.521628 -290.74799) (xy 294.506044 -290.794671) (xy 294.483173 -290.838248) (xy 294.453608 -290.877592)
			(xy 294.418115 -290.911684) (xy 294.377612 -290.93964) (xy 294.33315 -290.960738) (xy 294.285879 -290.97443)
			(xy 294.237024 -290.980362) (xy 294.187849 -290.978381) (xy 294.13963 -290.968537) (xy 294.093614 -290.951085)
			(xy 294.050993 -290.926478) (xy 294.012872 -290.895353) (xy 293.980237 -290.858516) (xy 293.953934 -290.81692)
			(xy 293.934643 -290.771644) (xy 293.922866 -290.72386) (xy 293.918906 -290.674806) (xy 293.580058 -290.674806)
			(xy 293.579563 -290.699413) (xy 293.571668 -290.74799) (xy 293.556084 -290.794671) (xy 293.533213 -290.838248)
			(xy 293.503648 -290.877592) (xy 293.468155 -290.911684) (xy 293.427652 -290.93964) (xy 293.38319 -290.960738)
			(xy 293.335919 -290.97443) (xy 293.287064 -290.980362) (xy 293.237889 -290.978381) (xy 293.18967 -290.968537)
			(xy 293.143654 -290.951085) (xy 293.101033 -290.926478) (xy 293.062912 -290.895353) (xy 293.030277 -290.858516)
			(xy 293.003974 -290.81692) (xy 292.984683 -290.771644) (xy 292.972906 -290.72386) (xy 292.968946 -290.674806)
			(xy 292.630098 -290.674806) (xy 292.629603 -290.699413) (xy 292.621708 -290.74799) (xy 292.606124 -290.794671)
			(xy 292.583253 -290.838248) (xy 292.553688 -290.877592) (xy 292.518195 -290.911684) (xy 292.477692 -290.93964)
			(xy 292.43323 -290.960738) (xy 292.385959 -290.97443) (xy 292.337104 -290.980362) (xy 292.287929 -290.978381)
			(xy 292.23971 -290.968537) (xy 292.193694 -290.951085) (xy 292.151073 -290.926478) (xy 292.112952 -290.895353)
			(xy 292.080317 -290.858516) (xy 292.054014 -290.81692) (xy 292.034723 -290.771644) (xy 292.022946 -290.72386)
			(xy 292.018986 -290.674806) (xy 290.730178 -290.674806) (xy 290.729683 -290.699413) (xy 290.721788 -290.74799)
			(xy 290.706204 -290.794671) (xy 290.683333 -290.838248) (xy 290.653768 -290.877592) (xy 290.618275 -290.911684)
			(xy 290.577772 -290.93964) (xy 290.53331 -290.960738) (xy 290.486039 -290.97443) (xy 290.437184 -290.980362)
			(xy 290.388009 -290.978381) (xy 290.33979 -290.968537) (xy 290.293774 -290.951085) (xy 290.251153 -290.926478)
			(xy 290.213032 -290.895353) (xy 290.180397 -290.858516) (xy 290.154094 -290.81692) (xy 290.134803 -290.771644)
			(xy 290.123026 -290.72386) (xy 290.119066 -290.674806) (xy 289.780218 -290.674806) (xy 289.779723 -290.699413)
			(xy 289.771828 -290.74799) (xy 289.756244 -290.794671) (xy 289.733373 -290.838248) (xy 289.703808 -290.877592)
			(xy 289.668315 -290.911684) (xy 289.627812 -290.93964) (xy 289.58335 -290.960738) (xy 289.536079 -290.97443)
			(xy 289.487224 -290.980362) (xy 289.438049 -290.978381) (xy 289.38983 -290.968537) (xy 289.343814 -290.951085)
			(xy 289.301193 -290.926478) (xy 289.263072 -290.895353) (xy 289.230437 -290.858516) (xy 289.204134 -290.81692)
			(xy 289.184843 -290.771644) (xy 289.173066 -290.72386) (xy 289.169106 -290.674806) (xy 288.830004 -290.674806)
			(xy 288.829509 -290.699413) (xy 288.821614 -290.74799) (xy 288.80603 -290.794671) (xy 288.783159 -290.838248)
			(xy 288.753594 -290.877592) (xy 288.718101 -290.911684) (xy 288.677598 -290.93964) (xy 288.633136 -290.960738)
			(xy 288.585865 -290.97443) (xy 288.53701 -290.980362) (xy 288.487835 -290.978381) (xy 288.439616 -290.968537)
			(xy 288.3936 -290.951085) (xy 288.350979 -290.926478) (xy 288.312858 -290.895353) (xy 288.280223 -290.858516)
			(xy 288.25392 -290.81692) (xy 288.234629 -290.771644) (xy 288.222852 -290.72386) (xy 288.218892 -290.674806)
			(xy 287.880044 -290.674806) (xy 287.879549 -290.699413) (xy 287.871654 -290.74799) (xy 287.85607 -290.794671)
			(xy 287.833199 -290.838248) (xy 287.803634 -290.877592) (xy 287.768141 -290.911684) (xy 287.727638 -290.93964)
			(xy 287.683176 -290.960738) (xy 287.635905 -290.97443) (xy 287.58705 -290.980362) (xy 287.537875 -290.978381)
			(xy 287.489656 -290.968537) (xy 287.44364 -290.951085) (xy 287.401019 -290.926478) (xy 287.362898 -290.895353)
			(xy 287.330263 -290.858516) (xy 287.30396 -290.81692) (xy 287.284669 -290.771644) (xy 287.272892 -290.72386)
			(xy 287.268932 -290.674806) (xy 286.930084 -290.674806) (xy 286.929589 -290.699413) (xy 286.921694 -290.74799)
			(xy 286.90611 -290.794671) (xy 286.883239 -290.838248) (xy 286.853674 -290.877592) (xy 286.818181 -290.911684)
			(xy 286.777678 -290.93964) (xy 286.733216 -290.960738) (xy 286.685945 -290.97443) (xy 286.63709 -290.980362)
			(xy 286.587915 -290.978381) (xy 286.539696 -290.968537) (xy 286.49368 -290.951085) (xy 286.451059 -290.926478)
			(xy 286.412938 -290.895353) (xy 286.380303 -290.858516) (xy 286.354 -290.81692) (xy 286.334709 -290.771644)
			(xy 286.322932 -290.72386) (xy 286.318972 -290.674806) (xy 285.980124 -290.674806) (xy 285.979629 -290.699413)
			(xy 285.971734 -290.74799) (xy 285.95615 -290.794671) (xy 285.933279 -290.838248) (xy 285.903714 -290.877592)
			(xy 285.868221 -290.911684) (xy 285.827718 -290.93964) (xy 285.783256 -290.960738) (xy 285.735985 -290.97443)
			(xy 285.68713 -290.980362) (xy 285.637955 -290.978381) (xy 285.589736 -290.968537) (xy 285.54372 -290.951085)
			(xy 285.501099 -290.926478) (xy 285.462978 -290.895353) (xy 285.430343 -290.858516) (xy 285.40404 -290.81692)
			(xy 285.384749 -290.771644) (xy 285.372972 -290.72386) (xy 285.369012 -290.674806) (xy 285.030164 -290.674806)
			(xy 285.029669 -290.699413) (xy 285.021774 -290.74799) (xy 285.00619 -290.794671) (xy 284.983319 -290.838248)
			(xy 284.953754 -290.877592) (xy 284.918261 -290.911684) (xy 284.877758 -290.93964) (xy 284.833296 -290.960738)
			(xy 284.786025 -290.97443) (xy 284.73717 -290.980362) (xy 284.687995 -290.978381) (xy 284.639776 -290.968537)
			(xy 284.59376 -290.951085) (xy 284.551139 -290.926478) (xy 284.513018 -290.895353) (xy 284.480383 -290.858516)
			(xy 284.45408 -290.81692) (xy 284.434789 -290.771644) (xy 284.423012 -290.72386) (xy 284.419052 -290.674806)
			(xy 284.080204 -290.674806) (xy 284.079709 -290.699413) (xy 284.071814 -290.74799) (xy 284.05623 -290.794671)
			(xy 284.033359 -290.838248) (xy 284.003794 -290.877592) (xy 283.968301 -290.911684) (xy 283.927798 -290.93964)
			(xy 283.883336 -290.960738) (xy 283.836065 -290.97443) (xy 283.78721 -290.980362) (xy 283.738035 -290.978381)
			(xy 283.689816 -290.968537) (xy 283.6438 -290.951085) (xy 283.601179 -290.926478) (xy 283.563058 -290.895353)
			(xy 283.530423 -290.858516) (xy 283.50412 -290.81692) (xy 283.484829 -290.771644) (xy 283.473052 -290.72386)
			(xy 283.469092 -290.674806) (xy 283.130244 -290.674806) (xy 283.129749 -290.699413) (xy 283.121854 -290.74799)
			(xy 283.10627 -290.794671) (xy 283.083399 -290.838248) (xy 283.053834 -290.877592) (xy 283.018341 -290.911684)
			(xy 282.977838 -290.93964) (xy 282.933376 -290.960738) (xy 282.886105 -290.97443) (xy 282.83725 -290.980362)
			(xy 282.788075 -290.978381) (xy 282.739856 -290.968537) (xy 282.69384 -290.951085) (xy 282.651219 -290.926478)
			(xy 282.613098 -290.895353) (xy 282.580463 -290.858516) (xy 282.55416 -290.81692) (xy 282.534869 -290.771644)
			(xy 282.523092 -290.72386) (xy 282.519132 -290.674806) (xy 282.18003 -290.674806) (xy 282.179535 -290.699413)
			(xy 282.17164 -290.74799) (xy 282.156056 -290.794671) (xy 282.133185 -290.838248) (xy 282.10362 -290.877592)
			(xy 282.068127 -290.911684) (xy 282.027624 -290.93964) (xy 281.983162 -290.960738) (xy 281.935891 -290.97443)
			(xy 281.887036 -290.980362) (xy 281.837861 -290.978381) (xy 281.789642 -290.968537) (xy 281.743626 -290.951085)
			(xy 281.701005 -290.926478) (xy 281.662884 -290.895353) (xy 281.630249 -290.858516) (xy 281.603946 -290.81692)
			(xy 281.584655 -290.771644) (xy 281.572878 -290.72386) (xy 281.568918 -290.674806) (xy 280.28011 -290.674806)
			(xy 280.28011 -290.684966) (xy 280.28011 -290.686744) (xy 280.279856 -290.68776) (xy 280.279602 -290.694618)
			(xy 280.279348 -290.694872) (xy 280.279348 -290.695888) (xy 280.27884 -290.707826) (xy 280.277824 -290.715192)
			(xy 280.277824 -290.715446) (xy 280.276046 -290.724336) (xy 280.276046 -290.72459) (xy 280.276046 -290.725098)
			(xy 280.275284 -290.728908) (xy 280.274776 -290.73221) (xy 280.272744 -290.7411) (xy 280.269442 -290.756086)
			(xy 280.280364 -290.784534) (xy 280.304748 -290.80206) (xy 280.312622 -290.807648) (xy 280.319226 -290.81222)
			(xy 280.325322 -290.816284) (xy 280.333704 -290.82238) (xy 280.343864 -290.829492) (xy 280.349452 -290.833302)
			(xy 280.370788 -290.850066) (xy 280.371296 -290.850574) (xy 280.37155 -290.850828) (xy 280.38044 -290.858956)
			(xy 280.382472 -290.860988) (xy 280.386282 -290.863782) (xy 280.391362 -290.869116) (xy 280.392378 -290.870386)
			(xy 280.394664 -290.872926) (xy 280.395426 -290.873688) (xy 280.395934 -290.87445) (xy 280.404316 -290.883848)
			(xy 280.40457 -290.884102) (xy 280.405078 -290.88461) (xy 280.407872 -290.888166) (xy 280.408634 -290.889436)
			(xy 280.415746 -290.898072) (xy 280.416 -290.898326) (xy 280.417016 -290.899596) (xy 280.41727 -290.900104)
			(xy 280.419556 -290.903152) (xy 280.43305 -290.922734) (xy 280.454461 -290.965196) (xy 280.469048 -291.010457)
			(xy 280.476462 -291.05743) (xy 280.47696 -291.081206) (xy 280.47696 -291.227002) (xy 280.476487 -291.2364)
			(xy 318.184782 -291.2364) (xy 318.188853 -291.180778) (xy 318.200979 -291.126341) (xy 318.220902 -291.07425)
			(xy 318.248198 -291.025615) (xy 318.282284 -290.981472) (xy 318.322433 -290.942763) (xy 318.367791 -290.910312)
			(xy 318.417391 -290.884811) (xy 318.470175 -290.866804) (xy 318.525018 -290.856674) (xy 318.580752 -290.854637)
			(xy 318.636189 -290.860737) (xy 318.690146 -290.874843) (xy 318.741475 -290.896655) (xy 318.789081 -290.925709)
			(xy 318.831949 -290.961384) (xy 318.869166 -291.002921) (xy 318.899939 -291.049434) (xy 318.923611 -291.099931)
			(xy 318.939679 -291.153338) (xy 318.947799 -291.208514) (xy 318.948308 -291.2364) (xy 318.947799 -291.264286)
			(xy 318.939679 -291.319462) (xy 318.923611 -291.372869) (xy 318.899939 -291.423366) (xy 318.869166 -291.469879)
			(xy 318.831949 -291.511416) (xy 318.789081 -291.547091) (xy 318.741475 -291.576145) (xy 318.704164 -291.592)
			(xy 320.641724 -291.592) (xy 320.645795 -291.536378) (xy 320.657921 -291.481941) (xy 320.677844 -291.42985)
			(xy 320.70514 -291.381215) (xy 320.739226 -291.337072) (xy 320.779375 -291.298363) (xy 320.824733 -291.265912)
			(xy 320.874333 -291.240411) (xy 320.927117 -291.222404) (xy 320.98196 -291.212274) (xy 321.037694 -291.210237)
			(xy 321.093131 -291.216337) (xy 321.147088 -291.230443) (xy 321.198417 -291.252255) (xy 321.246023 -291.281309)
			(xy 321.288891 -291.316984) (xy 321.326108 -291.358521) (xy 321.356881 -291.405034) (xy 321.380553 -291.455531)
			(xy 321.396621 -291.508938) (xy 321.404741 -291.564114) (xy 321.40525 -291.592) (xy 321.404741 -291.619886)
			(xy 321.396621 -291.675062) (xy 321.380553 -291.728469) (xy 321.356881 -291.778966) (xy 321.326108 -291.825479)
			(xy 321.288891 -291.867016) (xy 321.246023 -291.902691) (xy 321.198417 -291.931745) (xy 321.147088 -291.953557)
			(xy 321.093131 -291.967663) (xy 321.037694 -291.973763) (xy 320.98196 -291.971726) (xy 320.927117 -291.961596)
			(xy 320.874333 -291.943589) (xy 320.824733 -291.918088) (xy 320.779375 -291.885637) (xy 320.739226 -291.846928)
			(xy 320.70514 -291.802785) (xy 320.677844 -291.75415) (xy 320.657921 -291.702059) (xy 320.645795 -291.647622)
			(xy 320.641724 -291.592) (xy 318.704164 -291.592) (xy 318.690146 -291.597957) (xy 318.636189 -291.612063)
			(xy 318.580752 -291.618163) (xy 318.525018 -291.616126) (xy 318.470175 -291.605996) (xy 318.417391 -291.587989)
			(xy 318.367791 -291.562488) (xy 318.322433 -291.530037) (xy 318.282284 -291.491328) (xy 318.248198 -291.447185)
			(xy 318.220902 -291.39855) (xy 318.200979 -291.346459) (xy 318.188853 -291.292022) (xy 318.184782 -291.2364)
			(xy 280.476487 -291.2364) (xy 280.475581 -291.254408) (xy 280.464206 -291.308084) (xy 280.443424 -291.358865)
			(xy 280.413904 -291.405115) (xy 280.39568 -291.42563) (xy 280.393902 -291.427408) (xy 280.393394 -291.427916)
			(xy 280.38806 -291.433504) (xy 280.38425 -291.437314) (xy 280.378916 -291.442394) (xy 280.368502 -291.4523)
			(xy 280.362152 -291.45738) (xy 280.361898 -291.457634) (xy 280.355802 -291.461952) (xy 280.35504 -291.462714)
			(xy 280.354278 -291.463222) (xy 280.31948 -291.487352) (xy 280.318972 -291.487352) (xy 280.303224 -291.498528)
			(xy 280.30043 -291.50056) (xy 280.280364 -291.514784) (xy 280.269442 -291.542978) (xy 280.272744 -291.55771)
			(xy 280.272744 -291.557964) (xy 280.27376 -291.563044) (xy 280.276601 -291.577614) (xy 280.279785 -291.607131)
			(xy 280.28011 -291.621972) (xy 280.28011 -291.624766) (xy 280.618958 -291.624766) (xy 280.622918 -291.575712)
			(xy 280.634695 -291.527928) (xy 280.653986 -291.482652) (xy 280.680289 -291.441056) (xy 280.712924 -291.404219)
			(xy 280.751045 -291.373094) (xy 280.793666 -291.348487) (xy 280.839682 -291.331035) (xy 280.887901 -291.321191)
			(xy 280.937076 -291.31921) (xy 280.985931 -291.325142) (xy 281.033202 -291.338834) (xy 281.077664 -291.359932)
			(xy 281.118167 -291.387888) (xy 281.15366 -291.42198) (xy 281.183225 -291.461324) (xy 281.206096 -291.504901)
			(xy 281.22168 -291.551582) (xy 281.229575 -291.600159) (xy 281.23007 -291.624766) (xy 282.519132 -291.624766)
			(xy 282.523092 -291.575712) (xy 282.534869 -291.527928) (xy 282.55416 -291.482652) (xy 282.580463 -291.441056)
			(xy 282.613098 -291.404219) (xy 282.651219 -291.373094) (xy 282.69384 -291.348487) (xy 282.739856 -291.331035)
			(xy 282.788075 -291.321191) (xy 282.83725 -291.31921) (xy 282.886105 -291.325142) (xy 282.933376 -291.338834)
			(xy 282.977838 -291.359932) (xy 283.018341 -291.387888) (xy 283.053834 -291.42198) (xy 283.083399 -291.461324)
			(xy 283.10627 -291.504901) (xy 283.121854 -291.551582) (xy 283.129749 -291.600159) (xy 283.130244 -291.624766)
			(xy 283.469092 -291.624766) (xy 283.473052 -291.575712) (xy 283.484829 -291.527928) (xy 283.50412 -291.482652)
			(xy 283.530423 -291.441056) (xy 283.563058 -291.404219) (xy 283.601179 -291.373094) (xy 283.6438 -291.348487)
			(xy 283.689816 -291.331035) (xy 283.738035 -291.321191) (xy 283.78721 -291.31921) (xy 283.836065 -291.325142)
			(xy 283.883336 -291.338834) (xy 283.927798 -291.359932) (xy 283.968301 -291.387888) (xy 284.003794 -291.42198)
			(xy 284.033359 -291.461324) (xy 284.05623 -291.504901) (xy 284.071814 -291.551582) (xy 284.079709 -291.600159)
			(xy 284.080204 -291.624766) (xy 284.419052 -291.624766) (xy 284.423012 -291.575712) (xy 284.434789 -291.527928)
			(xy 284.45408 -291.482652) (xy 284.480383 -291.441056) (xy 284.513018 -291.404219) (xy 284.551139 -291.373094)
			(xy 284.59376 -291.348487) (xy 284.639776 -291.331035) (xy 284.687995 -291.321191) (xy 284.73717 -291.31921)
			(xy 284.786025 -291.325142) (xy 284.833296 -291.338834) (xy 284.877758 -291.359932) (xy 284.918261 -291.387888)
			(xy 284.953754 -291.42198) (xy 284.983319 -291.461324) (xy 285.00619 -291.504901) (xy 285.021774 -291.551582)
			(xy 285.029669 -291.600159) (xy 285.030164 -291.624766) (xy 285.369012 -291.624766) (xy 285.372972 -291.575712)
			(xy 285.384749 -291.527928) (xy 285.40404 -291.482652) (xy 285.430343 -291.441056) (xy 285.462978 -291.404219)
			(xy 285.501099 -291.373094) (xy 285.54372 -291.348487) (xy 285.589736 -291.331035) (xy 285.637955 -291.321191)
			(xy 285.68713 -291.31921) (xy 285.735985 -291.325142) (xy 285.783256 -291.338834) (xy 285.827718 -291.359932)
			(xy 285.868221 -291.387888) (xy 285.903714 -291.42198) (xy 285.933279 -291.461324) (xy 285.95615 -291.504901)
			(xy 285.971734 -291.551582) (xy 285.979629 -291.600159) (xy 285.980124 -291.624766) (xy 286.318972 -291.624766)
			(xy 286.322932 -291.575712) (xy 286.334709 -291.527928) (xy 286.354 -291.482652) (xy 286.380303 -291.441056)
			(xy 286.412938 -291.404219) (xy 286.451059 -291.373094) (xy 286.49368 -291.348487) (xy 286.539696 -291.331035)
			(xy 286.587915 -291.321191) (xy 286.63709 -291.31921) (xy 286.685945 -291.325142) (xy 286.733216 -291.338834)
			(xy 286.777678 -291.359932) (xy 286.818181 -291.387888) (xy 286.853674 -291.42198) (xy 286.883239 -291.461324)
			(xy 286.90611 -291.504901) (xy 286.921694 -291.551582) (xy 286.929589 -291.600159) (xy 286.930084 -291.624766)
			(xy 287.268932 -291.624766) (xy 287.272892 -291.575712) (xy 287.284669 -291.527928) (xy 287.30396 -291.482652)
			(xy 287.330263 -291.441056) (xy 287.362898 -291.404219) (xy 287.401019 -291.373094) (xy 287.44364 -291.348487)
			(xy 287.489656 -291.331035) (xy 287.537875 -291.321191) (xy 287.58705 -291.31921) (xy 287.635905 -291.325142)
			(xy 287.683176 -291.338834) (xy 287.727638 -291.359932) (xy 287.768141 -291.387888) (xy 287.803634 -291.42198)
			(xy 287.833199 -291.461324) (xy 287.85607 -291.504901) (xy 287.871654 -291.551582) (xy 287.879549 -291.600159)
			(xy 287.880044 -291.624766) (xy 288.218892 -291.624766) (xy 288.222852 -291.575712) (xy 288.234629 -291.527928)
			(xy 288.25392 -291.482652) (xy 288.280223 -291.441056) (xy 288.312858 -291.404219) (xy 288.350979 -291.373094)
			(xy 288.3936 -291.348487) (xy 288.439616 -291.331035) (xy 288.487835 -291.321191) (xy 288.53701 -291.31921)
			(xy 288.585865 -291.325142) (xy 288.633136 -291.338834) (xy 288.677598 -291.359932) (xy 288.718101 -291.387888)
			(xy 288.753594 -291.42198) (xy 288.783159 -291.461324) (xy 288.80603 -291.504901) (xy 288.821614 -291.551582)
			(xy 288.829509 -291.600159) (xy 288.830004 -291.624766) (xy 289.169106 -291.624766) (xy 289.173066 -291.575712)
			(xy 289.184843 -291.527928) (xy 289.204134 -291.482652) (xy 289.230437 -291.441056) (xy 289.263072 -291.404219)
			(xy 289.301193 -291.373094) (xy 289.343814 -291.348487) (xy 289.38983 -291.331035) (xy 289.438049 -291.321191)
			(xy 289.487224 -291.31921) (xy 289.536079 -291.325142) (xy 289.58335 -291.338834) (xy 289.627812 -291.359932)
			(xy 289.668315 -291.387888) (xy 289.703808 -291.42198) (xy 289.733373 -291.461324) (xy 289.756244 -291.504901)
			(xy 289.771828 -291.551582) (xy 289.779723 -291.600159) (xy 289.780218 -291.624766) (xy 290.119066 -291.624766)
			(xy 290.123026 -291.575712) (xy 290.134803 -291.527928) (xy 290.154094 -291.482652) (xy 290.180397 -291.441056)
			(xy 290.213032 -291.404219) (xy 290.251153 -291.373094) (xy 290.293774 -291.348487) (xy 290.33979 -291.331035)
			(xy 290.388009 -291.321191) (xy 290.437184 -291.31921) (xy 290.486039 -291.325142) (xy 290.53331 -291.338834)
			(xy 290.577772 -291.359932) (xy 290.618275 -291.387888) (xy 290.653768 -291.42198) (xy 290.683333 -291.461324)
			(xy 290.706204 -291.504901) (xy 290.721788 -291.551582) (xy 290.729683 -291.600159) (xy 290.730178 -291.624766)
			(xy 292.018986 -291.624766) (xy 292.022946 -291.575712) (xy 292.034723 -291.527928) (xy 292.054014 -291.482652)
			(xy 292.080317 -291.441056) (xy 292.112952 -291.404219) (xy 292.151073 -291.373094) (xy 292.193694 -291.348487)
			(xy 292.23971 -291.331035) (xy 292.287929 -291.321191) (xy 292.337104 -291.31921) (xy 292.385959 -291.325142)
			(xy 292.43323 -291.338834) (xy 292.477692 -291.359932) (xy 292.518195 -291.387888) (xy 292.553688 -291.42198)
			(xy 292.583253 -291.461324) (xy 292.606124 -291.504901) (xy 292.621708 -291.551582) (xy 292.629603 -291.600159)
			(xy 292.630098 -291.624766) (xy 292.968946 -291.624766) (xy 292.972906 -291.575712) (xy 292.984683 -291.527928)
			(xy 293.003974 -291.482652) (xy 293.030277 -291.441056) (xy 293.062912 -291.404219) (xy 293.101033 -291.373094)
			(xy 293.143654 -291.348487) (xy 293.18967 -291.331035) (xy 293.237889 -291.321191) (xy 293.287064 -291.31921)
			(xy 293.335919 -291.325142) (xy 293.38319 -291.338834) (xy 293.427652 -291.359932) (xy 293.468155 -291.387888)
			(xy 293.503648 -291.42198) (xy 293.533213 -291.461324) (xy 293.556084 -291.504901) (xy 293.571668 -291.551582)
			(xy 293.579563 -291.600159) (xy 293.580058 -291.624766) (xy 293.918906 -291.624766) (xy 293.922866 -291.575712)
			(xy 293.934643 -291.527928) (xy 293.953934 -291.482652) (xy 293.980237 -291.441056) (xy 294.012872 -291.404219)
			(xy 294.050993 -291.373094) (xy 294.093614 -291.348487) (xy 294.13963 -291.331035) (xy 294.187849 -291.321191)
			(xy 294.237024 -291.31921) (xy 294.285879 -291.325142) (xy 294.33315 -291.338834) (xy 294.377612 -291.359932)
			(xy 294.418115 -291.387888) (xy 294.453608 -291.42198) (xy 294.483173 -291.461324) (xy 294.506044 -291.504901)
			(xy 294.521628 -291.551582) (xy 294.529523 -291.600159) (xy 294.530018 -291.624766) (xy 294.86912 -291.624766)
			(xy 294.87308 -291.575712) (xy 294.884857 -291.527928) (xy 294.904148 -291.482652) (xy 294.930451 -291.441056)
			(xy 294.963086 -291.404219) (xy 295.001207 -291.373094) (xy 295.043828 -291.348487) (xy 295.089844 -291.331035)
			(xy 295.138063 -291.321191) (xy 295.187238 -291.31921) (xy 295.236093 -291.325142) (xy 295.283364 -291.338834)
			(xy 295.327826 -291.359932) (xy 295.368329 -291.387888) (xy 295.403822 -291.42198) (xy 295.433387 -291.461324)
			(xy 295.456258 -291.504901) (xy 295.471842 -291.551582) (xy 295.479737 -291.600159) (xy 295.480232 -291.624766)
			(xy 295.81908 -291.624766) (xy 295.82304 -291.575712) (xy 295.834817 -291.527928) (xy 295.854108 -291.482652)
			(xy 295.880411 -291.441056) (xy 295.913046 -291.404219) (xy 295.951167 -291.373094) (xy 295.993788 -291.348487)
			(xy 296.039804 -291.331035) (xy 296.088023 -291.321191) (xy 296.137198 -291.31921) (xy 296.186053 -291.325142)
			(xy 296.233324 -291.338834) (xy 296.277786 -291.359932) (xy 296.318289 -291.387888) (xy 296.353782 -291.42198)
			(xy 296.383347 -291.461324) (xy 296.406218 -291.504901) (xy 296.421802 -291.551582) (xy 296.429697 -291.600159)
			(xy 296.430192 -291.624766) (xy 296.76904 -291.624766) (xy 296.773 -291.575712) (xy 296.784777 -291.527928)
			(xy 296.804068 -291.482652) (xy 296.830371 -291.441056) (xy 296.863006 -291.404219) (xy 296.901127 -291.373094)
			(xy 296.943748 -291.348487) (xy 296.989764 -291.331035) (xy 297.037983 -291.321191) (xy 297.087158 -291.31921)
			(xy 297.136013 -291.325142) (xy 297.183284 -291.338834) (xy 297.227746 -291.359932) (xy 297.268249 -291.387888)
			(xy 297.303742 -291.42198) (xy 297.333307 -291.461324) (xy 297.356178 -291.504901) (xy 297.371762 -291.551582)
			(xy 297.379657 -291.600159) (xy 297.380152 -291.624766) (xy 297.719 -291.624766) (xy 297.72296 -291.575712)
			(xy 297.734737 -291.527928) (xy 297.754028 -291.482652) (xy 297.780331 -291.441056) (xy 297.812966 -291.404219)
			(xy 297.851087 -291.373094) (xy 297.893708 -291.348487) (xy 297.939724 -291.331035) (xy 297.987943 -291.321191)
			(xy 298.037118 -291.31921) (xy 298.085973 -291.325142) (xy 298.133244 -291.338834) (xy 298.177706 -291.359932)
			(xy 298.218209 -291.387888) (xy 298.253702 -291.42198) (xy 298.283267 -291.461324) (xy 298.306138 -291.504901)
			(xy 298.321722 -291.551582) (xy 298.329617 -291.600159) (xy 298.330112 -291.624766) (xy 298.66896 -291.624766)
			(xy 298.67292 -291.575712) (xy 298.684697 -291.527928) (xy 298.703988 -291.482652) (xy 298.730291 -291.441056)
			(xy 298.762926 -291.404219) (xy 298.801047 -291.373094) (xy 298.843668 -291.348487) (xy 298.889684 -291.331035)
			(xy 298.937903 -291.321191) (xy 298.987078 -291.31921) (xy 299.035933 -291.325142) (xy 299.083204 -291.338834)
			(xy 299.127666 -291.359932) (xy 299.168169 -291.387888) (xy 299.203662 -291.42198) (xy 299.233227 -291.461324)
			(xy 299.256098 -291.504901) (xy 299.271682 -291.551582) (xy 299.279577 -291.600159) (xy 299.280072 -291.624766)
			(xy 299.61892 -291.624766) (xy 299.62288 -291.575712) (xy 299.634657 -291.527928) (xy 299.653948 -291.482652)
			(xy 299.680251 -291.441056) (xy 299.712886 -291.404219) (xy 299.751007 -291.373094) (xy 299.793628 -291.348487)
			(xy 299.839644 -291.331035) (xy 299.887863 -291.321191) (xy 299.937038 -291.31921) (xy 299.985893 -291.325142)
			(xy 300.033164 -291.338834) (xy 300.077626 -291.359932) (xy 300.118129 -291.387888) (xy 300.153622 -291.42198)
			(xy 300.183187 -291.461324) (xy 300.206058 -291.504901) (xy 300.221642 -291.551582) (xy 300.229537 -291.600159)
			(xy 300.230032 -291.624766) (xy 300.56888 -291.624766) (xy 300.57284 -291.575712) (xy 300.584617 -291.527928)
			(xy 300.603908 -291.482652) (xy 300.630211 -291.441056) (xy 300.662846 -291.404219) (xy 300.700967 -291.373094)
			(xy 300.743588 -291.348487) (xy 300.789604 -291.331035) (xy 300.837823 -291.321191) (xy 300.886998 -291.31921)
			(xy 300.935853 -291.325142) (xy 300.983124 -291.338834) (xy 301.027586 -291.359932) (xy 301.068089 -291.387888)
			(xy 301.103582 -291.42198) (xy 301.133147 -291.461324) (xy 301.156018 -291.504901) (xy 301.171602 -291.551582)
			(xy 301.179497 -291.600159) (xy 301.179992 -291.624766) (xy 301.519094 -291.624766) (xy 301.523054 -291.575712)
			(xy 301.534831 -291.527928) (xy 301.554122 -291.482652) (xy 301.580425 -291.441056) (xy 301.61306 -291.404219)
			(xy 301.651181 -291.373094) (xy 301.693802 -291.348487) (xy 301.739818 -291.331035) (xy 301.788037 -291.321191)
			(xy 301.837212 -291.31921) (xy 301.886067 -291.325142) (xy 301.933338 -291.338834) (xy 301.9778 -291.359932)
			(xy 302.018303 -291.387888) (xy 302.053796 -291.42198) (xy 302.083361 -291.461324) (xy 302.106232 -291.504901)
			(xy 302.121816 -291.551582) (xy 302.129711 -291.600159) (xy 302.130206 -291.624766) (xy 302.469054 -291.624766)
			(xy 302.473014 -291.575712) (xy 302.484791 -291.527928) (xy 302.504082 -291.482652) (xy 302.530385 -291.441056)
			(xy 302.56302 -291.404219) (xy 302.601141 -291.373094) (xy 302.643762 -291.348487) (xy 302.689778 -291.331035)
			(xy 302.737997 -291.321191) (xy 302.787172 -291.31921) (xy 302.836027 -291.325142) (xy 302.883298 -291.338834)
			(xy 302.92776 -291.359932) (xy 302.968263 -291.387888) (xy 303.003756 -291.42198) (xy 303.033321 -291.461324)
			(xy 303.056192 -291.504901) (xy 303.071776 -291.551582) (xy 303.079671 -291.600159) (xy 303.080166 -291.624766)
			(xy 303.419014 -291.624766) (xy 303.422974 -291.575712) (xy 303.434751 -291.527928) (xy 303.454042 -291.482652)
			(xy 303.480345 -291.441056) (xy 303.51298 -291.404219) (xy 303.551101 -291.373094) (xy 303.593722 -291.348487)
			(xy 303.639738 -291.331035) (xy 303.687957 -291.321191) (xy 303.737132 -291.31921) (xy 303.785987 -291.325142)
			(xy 303.833258 -291.338834) (xy 303.87772 -291.359932) (xy 303.918223 -291.387888) (xy 303.953716 -291.42198)
			(xy 303.983281 -291.461324) (xy 304.006152 -291.504901) (xy 304.021736 -291.551582) (xy 304.029631 -291.600159)
			(xy 304.030126 -291.624766) (xy 304.368974 -291.624766) (xy 304.372934 -291.575712) (xy 304.384711 -291.527928)
			(xy 304.404002 -291.482652) (xy 304.430305 -291.441056) (xy 304.46294 -291.404219) (xy 304.501061 -291.373094)
			(xy 304.543682 -291.348487) (xy 304.589698 -291.331035) (xy 304.637917 -291.321191) (xy 304.687092 -291.31921)
			(xy 304.735947 -291.325142) (xy 304.783218 -291.338834) (xy 304.82768 -291.359932) (xy 304.868183 -291.387888)
			(xy 304.903676 -291.42198) (xy 304.933241 -291.461324) (xy 304.956112 -291.504901) (xy 304.971696 -291.551582)
			(xy 304.979591 -291.600159) (xy 304.980086 -291.624766) (xy 305.318934 -291.624766) (xy 305.322894 -291.575712)
			(xy 305.334671 -291.527928) (xy 305.353962 -291.482652) (xy 305.380265 -291.441056) (xy 305.4129 -291.404219)
			(xy 305.451021 -291.373094) (xy 305.493642 -291.348487) (xy 305.539658 -291.331035) (xy 305.587877 -291.321191)
			(xy 305.637052 -291.31921) (xy 305.685907 -291.325142) (xy 305.733178 -291.338834) (xy 305.77764 -291.359932)
			(xy 305.818143 -291.387888) (xy 305.853636 -291.42198) (xy 305.883201 -291.461324) (xy 305.906072 -291.504901)
			(xy 305.921656 -291.551582) (xy 305.929551 -291.600159) (xy 305.930046 -291.624766) (xy 306.269148 -291.624766)
			(xy 306.273108 -291.575712) (xy 306.284885 -291.527928) (xy 306.304176 -291.482652) (xy 306.330479 -291.441056)
			(xy 306.363114 -291.404219) (xy 306.401235 -291.373094) (xy 306.443856 -291.348487) (xy 306.489872 -291.331035)
			(xy 306.538091 -291.321191) (xy 306.587266 -291.31921) (xy 306.636121 -291.325142) (xy 306.683392 -291.338834)
			(xy 306.727854 -291.359932) (xy 306.768357 -291.387888) (xy 306.80385 -291.42198) (xy 306.833415 -291.461324)
			(xy 306.856286 -291.504901) (xy 306.87187 -291.551582) (xy 306.879765 -291.600159) (xy 306.88026 -291.624766)
			(xy 308.169068 -291.624766) (xy 308.173028 -291.575712) (xy 308.184805 -291.527928) (xy 308.204096 -291.482652)
			(xy 308.230399 -291.441056) (xy 308.263034 -291.404219) (xy 308.301155 -291.373094) (xy 308.343776 -291.348487)
			(xy 308.389792 -291.331035) (xy 308.438011 -291.321191) (xy 308.487186 -291.31921) (xy 308.536041 -291.325142)
			(xy 308.583312 -291.338834) (xy 308.627774 -291.359932) (xy 308.668277 -291.387888) (xy 308.70377 -291.42198)
			(xy 308.733335 -291.461324) (xy 308.756206 -291.504901) (xy 308.77179 -291.551582) (xy 308.779685 -291.600159)
			(xy 308.78018 -291.624766) (xy 309.119028 -291.624766) (xy 309.122988 -291.575712) (xy 309.134765 -291.527928)
			(xy 309.154056 -291.482652) (xy 309.180359 -291.441056) (xy 309.212994 -291.404219) (xy 309.251115 -291.373094)
			(xy 309.293736 -291.348487) (xy 309.339752 -291.331035) (xy 309.387971 -291.321191) (xy 309.437146 -291.31921)
			(xy 309.486001 -291.325142) (xy 309.533272 -291.338834) (xy 309.577734 -291.359932) (xy 309.618237 -291.387888)
			(xy 309.65373 -291.42198) (xy 309.683295 -291.461324) (xy 309.706166 -291.504901) (xy 309.72175 -291.551582)
			(xy 309.729645 -291.600159) (xy 309.73014 -291.624766) (xy 310.068988 -291.624766) (xy 310.072948 -291.575712)
			(xy 310.084725 -291.527928) (xy 310.104016 -291.482652) (xy 310.130319 -291.441056) (xy 310.162954 -291.404219)
			(xy 310.201075 -291.373094) (xy 310.243696 -291.348487) (xy 310.289712 -291.331035) (xy 310.337931 -291.321191)
			(xy 310.387106 -291.31921) (xy 310.435961 -291.325142) (xy 310.483232 -291.338834) (xy 310.527694 -291.359932)
			(xy 310.568197 -291.387888) (xy 310.60369 -291.42198) (xy 310.633255 -291.461324) (xy 310.656126 -291.504901)
			(xy 310.67171 -291.551582) (xy 310.679605 -291.600159) (xy 310.6801 -291.624766) (xy 311.018948 -291.624766)
			(xy 311.022908 -291.575712) (xy 311.034685 -291.527928) (xy 311.053976 -291.482652) (xy 311.080279 -291.441056)
			(xy 311.112914 -291.404219) (xy 311.151035 -291.373094) (xy 311.193656 -291.348487) (xy 311.239672 -291.331035)
			(xy 311.287891 -291.321191) (xy 311.337066 -291.31921) (xy 311.385921 -291.325142) (xy 311.433192 -291.338834)
			(xy 311.477654 -291.359932) (xy 311.518157 -291.387888) (xy 311.55365 -291.42198) (xy 311.583215 -291.461324)
			(xy 311.606086 -291.504901) (xy 311.62167 -291.551582) (xy 311.629565 -291.600159) (xy 311.63006 -291.624766)
			(xy 311.968908 -291.624766) (xy 311.972868 -291.575712) (xy 311.984645 -291.527928) (xy 312.003936 -291.482652)
			(xy 312.030239 -291.441056) (xy 312.062874 -291.404219) (xy 312.100995 -291.373094) (xy 312.143616 -291.348487)
			(xy 312.189632 -291.331035) (xy 312.237851 -291.321191) (xy 312.287026 -291.31921) (xy 312.335881 -291.325142)
			(xy 312.383152 -291.338834) (xy 312.427614 -291.359932) (xy 312.468117 -291.387888) (xy 312.50361 -291.42198)
			(xy 312.533175 -291.461324) (xy 312.556046 -291.504901) (xy 312.57163 -291.551582) (xy 312.579525 -291.600159)
			(xy 312.58002 -291.624766) (xy 312.919122 -291.624766) (xy 312.923082 -291.575712) (xy 312.934859 -291.527928)
			(xy 312.95415 -291.482652) (xy 312.980453 -291.441056) (xy 313.013088 -291.404219) (xy 313.051209 -291.373094)
			(xy 313.09383 -291.348487) (xy 313.139846 -291.331035) (xy 313.188065 -291.321191) (xy 313.23724 -291.31921)
			(xy 313.286095 -291.325142) (xy 313.333366 -291.338834) (xy 313.377828 -291.359932) (xy 313.418331 -291.387888)
			(xy 313.453824 -291.42198) (xy 313.483389 -291.461324) (xy 313.50626 -291.504901) (xy 313.521844 -291.551582)
			(xy 313.529739 -291.600159) (xy 313.530234 -291.624766) (xy 313.869082 -291.624766) (xy 313.873042 -291.575712)
			(xy 313.884819 -291.527928) (xy 313.90411 -291.482652) (xy 313.930413 -291.441056) (xy 313.963048 -291.404219)
			(xy 314.001169 -291.373094) (xy 314.04379 -291.348487) (xy 314.089806 -291.331035) (xy 314.138025 -291.321191)
			(xy 314.1872 -291.31921) (xy 314.236055 -291.325142) (xy 314.283326 -291.338834) (xy 314.327788 -291.359932)
			(xy 314.368291 -291.387888) (xy 314.403784 -291.42198) (xy 314.433349 -291.461324) (xy 314.45622 -291.504901)
			(xy 314.471804 -291.551582) (xy 314.479699 -291.600159) (xy 314.480194 -291.624766) (xy 314.819042 -291.624766)
			(xy 314.823002 -291.575712) (xy 314.834779 -291.527928) (xy 314.85407 -291.482652) (xy 314.880373 -291.441056)
			(xy 314.913008 -291.404219) (xy 314.951129 -291.373094) (xy 314.99375 -291.348487) (xy 315.039766 -291.331035)
			(xy 315.087985 -291.321191) (xy 315.13716 -291.31921) (xy 315.186015 -291.325142) (xy 315.233286 -291.338834)
			(xy 315.277748 -291.359932) (xy 315.318251 -291.387888) (xy 315.353744 -291.42198) (xy 315.383309 -291.461324)
			(xy 315.40618 -291.504901) (xy 315.421764 -291.551582) (xy 315.429659 -291.600159) (xy 315.430154 -291.624766)
			(xy 315.429659 -291.649373) (xy 315.421764 -291.69795) (xy 315.40618 -291.744631) (xy 315.383309 -291.788208)
			(xy 315.353744 -291.827552) (xy 315.318251 -291.861644) (xy 315.277748 -291.8896) (xy 315.233286 -291.910698)
			(xy 315.186015 -291.92439) (xy 315.13716 -291.930322) (xy 315.087985 -291.928341) (xy 315.039766 -291.918497)
			(xy 314.99375 -291.901045) (xy 314.951129 -291.876438) (xy 314.913008 -291.845313) (xy 314.880373 -291.808476)
			(xy 314.85407 -291.76688) (xy 314.834779 -291.721604) (xy 314.823002 -291.67382) (xy 314.819042 -291.624766)
			(xy 314.480194 -291.624766) (xy 314.479699 -291.649373) (xy 314.471804 -291.69795) (xy 314.45622 -291.744631)
			(xy 314.433349 -291.788208) (xy 314.403784 -291.827552) (xy 314.368291 -291.861644) (xy 314.327788 -291.8896)
			(xy 314.283326 -291.910698) (xy 314.236055 -291.92439) (xy 314.1872 -291.930322) (xy 314.138025 -291.928341)
			(xy 314.089806 -291.918497) (xy 314.04379 -291.901045) (xy 314.001169 -291.876438) (xy 313.963048 -291.845313)
			(xy 313.930413 -291.808476) (xy 313.90411 -291.76688) (xy 313.884819 -291.721604) (xy 313.873042 -291.67382)
			(xy 313.869082 -291.624766) (xy 313.530234 -291.624766) (xy 313.529739 -291.649373) (xy 313.521844 -291.69795)
			(xy 313.50626 -291.744631) (xy 313.483389 -291.788208) (xy 313.453824 -291.827552) (xy 313.418331 -291.861644)
			(xy 313.377828 -291.8896) (xy 313.333366 -291.910698) (xy 313.286095 -291.92439) (xy 313.23724 -291.930322)
			(xy 313.188065 -291.928341) (xy 313.139846 -291.918497) (xy 313.09383 -291.901045) (xy 313.051209 -291.876438)
			(xy 313.013088 -291.845313) (xy 312.980453 -291.808476) (xy 312.95415 -291.76688) (xy 312.934859 -291.721604)
			(xy 312.923082 -291.67382) (xy 312.919122 -291.624766) (xy 312.58002 -291.624766) (xy 312.579525 -291.649373)
			(xy 312.57163 -291.69795) (xy 312.556046 -291.744631) (xy 312.533175 -291.788208) (xy 312.50361 -291.827552)
			(xy 312.468117 -291.861644) (xy 312.427614 -291.8896) (xy 312.383152 -291.910698) (xy 312.335881 -291.92439)
			(xy 312.287026 -291.930322) (xy 312.237851 -291.928341) (xy 312.189632 -291.918497) (xy 312.143616 -291.901045)
			(xy 312.100995 -291.876438) (xy 312.062874 -291.845313) (xy 312.030239 -291.808476) (xy 312.003936 -291.76688)
			(xy 311.984645 -291.721604) (xy 311.972868 -291.67382) (xy 311.968908 -291.624766) (xy 311.63006 -291.624766)
			(xy 311.629565 -291.649373) (xy 311.62167 -291.69795) (xy 311.606086 -291.744631) (xy 311.583215 -291.788208)
			(xy 311.55365 -291.827552) (xy 311.518157 -291.861644) (xy 311.477654 -291.8896) (xy 311.433192 -291.910698)
			(xy 311.385921 -291.92439) (xy 311.337066 -291.930322) (xy 311.287891 -291.928341) (xy 311.239672 -291.918497)
			(xy 311.193656 -291.901045) (xy 311.151035 -291.876438) (xy 311.112914 -291.845313) (xy 311.080279 -291.808476)
			(xy 311.053976 -291.76688) (xy 311.034685 -291.721604) (xy 311.022908 -291.67382) (xy 311.018948 -291.624766)
			(xy 310.6801 -291.624766) (xy 310.679605 -291.649373) (xy 310.67171 -291.69795) (xy 310.656126 -291.744631)
			(xy 310.633255 -291.788208) (xy 310.60369 -291.827552) (xy 310.568197 -291.861644) (xy 310.527694 -291.8896)
			(xy 310.483232 -291.910698) (xy 310.435961 -291.92439) (xy 310.387106 -291.930322) (xy 310.337931 -291.928341)
			(xy 310.289712 -291.918497) (xy 310.243696 -291.901045) (xy 310.201075 -291.876438) (xy 310.162954 -291.845313)
			(xy 310.130319 -291.808476) (xy 310.104016 -291.76688) (xy 310.084725 -291.721604) (xy 310.072948 -291.67382)
			(xy 310.068988 -291.624766) (xy 309.73014 -291.624766) (xy 309.729645 -291.649373) (xy 309.72175 -291.69795)
			(xy 309.706166 -291.744631) (xy 309.683295 -291.788208) (xy 309.65373 -291.827552) (xy 309.618237 -291.861644)
			(xy 309.577734 -291.8896) (xy 309.533272 -291.910698) (xy 309.486001 -291.92439) (xy 309.437146 -291.930322)
			(xy 309.387971 -291.928341) (xy 309.339752 -291.918497) (xy 309.293736 -291.901045) (xy 309.251115 -291.876438)
			(xy 309.212994 -291.845313) (xy 309.180359 -291.808476) (xy 309.154056 -291.76688) (xy 309.134765 -291.721604)
			(xy 309.122988 -291.67382) (xy 309.119028 -291.624766) (xy 308.78018 -291.624766) (xy 308.779685 -291.649373)
			(xy 308.77179 -291.69795) (xy 308.756206 -291.744631) (xy 308.733335 -291.788208) (xy 308.70377 -291.827552)
			(xy 308.668277 -291.861644) (xy 308.627774 -291.8896) (xy 308.583312 -291.910698) (xy 308.536041 -291.92439)
			(xy 308.487186 -291.930322) (xy 308.438011 -291.928341) (xy 308.389792 -291.918497) (xy 308.343776 -291.901045)
			(xy 308.301155 -291.876438) (xy 308.263034 -291.845313) (xy 308.230399 -291.808476) (xy 308.204096 -291.76688)
			(xy 308.184805 -291.721604) (xy 308.173028 -291.67382) (xy 308.169068 -291.624766) (xy 306.88026 -291.624766)
			(xy 306.879765 -291.649373) (xy 306.87187 -291.69795) (xy 306.856286 -291.744631) (xy 306.833415 -291.788208)
			(xy 306.80385 -291.827552) (xy 306.768357 -291.861644) (xy 306.727854 -291.8896) (xy 306.683392 -291.910698)
			(xy 306.636121 -291.92439) (xy 306.587266 -291.930322) (xy 306.538091 -291.928341) (xy 306.489872 -291.918497)
			(xy 306.443856 -291.901045) (xy 306.401235 -291.876438) (xy 306.363114 -291.845313) (xy 306.330479 -291.808476)
			(xy 306.304176 -291.76688) (xy 306.284885 -291.721604) (xy 306.273108 -291.67382) (xy 306.269148 -291.624766)
			(xy 305.930046 -291.624766) (xy 305.929551 -291.649373) (xy 305.921656 -291.69795) (xy 305.906072 -291.744631)
			(xy 305.883201 -291.788208) (xy 305.853636 -291.827552) (xy 305.818143 -291.861644) (xy 305.77764 -291.8896)
			(xy 305.733178 -291.910698) (xy 305.685907 -291.92439) (xy 305.637052 -291.930322) (xy 305.587877 -291.928341)
			(xy 305.539658 -291.918497) (xy 305.493642 -291.901045) (xy 305.451021 -291.876438) (xy 305.4129 -291.845313)
			(xy 305.380265 -291.808476) (xy 305.353962 -291.76688) (xy 305.334671 -291.721604) (xy 305.322894 -291.67382)
			(xy 305.318934 -291.624766) (xy 304.980086 -291.624766) (xy 304.979591 -291.649373) (xy 304.971696 -291.69795)
			(xy 304.956112 -291.744631) (xy 304.933241 -291.788208) (xy 304.903676 -291.827552) (xy 304.868183 -291.861644)
			(xy 304.82768 -291.8896) (xy 304.783218 -291.910698) (xy 304.735947 -291.92439) (xy 304.687092 -291.930322)
			(xy 304.637917 -291.928341) (xy 304.589698 -291.918497) (xy 304.543682 -291.901045) (xy 304.501061 -291.876438)
			(xy 304.46294 -291.845313) (xy 304.430305 -291.808476) (xy 304.404002 -291.76688) (xy 304.384711 -291.721604)
			(xy 304.372934 -291.67382) (xy 304.368974 -291.624766) (xy 304.030126 -291.624766) (xy 304.029631 -291.649373)
			(xy 304.021736 -291.69795) (xy 304.006152 -291.744631) (xy 303.983281 -291.788208) (xy 303.953716 -291.827552)
			(xy 303.918223 -291.861644) (xy 303.87772 -291.8896) (xy 303.833258 -291.910698) (xy 303.785987 -291.92439)
			(xy 303.737132 -291.930322) (xy 303.687957 -291.928341) (xy 303.639738 -291.918497) (xy 303.593722 -291.901045)
			(xy 303.551101 -291.876438) (xy 303.51298 -291.845313) (xy 303.480345 -291.808476) (xy 303.454042 -291.76688)
			(xy 303.434751 -291.721604) (xy 303.422974 -291.67382) (xy 303.419014 -291.624766) (xy 303.080166 -291.624766)
			(xy 303.079671 -291.649373) (xy 303.071776 -291.69795) (xy 303.056192 -291.744631) (xy 303.033321 -291.788208)
			(xy 303.003756 -291.827552) (xy 302.968263 -291.861644) (xy 302.92776 -291.8896) (xy 302.883298 -291.910698)
			(xy 302.836027 -291.92439) (xy 302.787172 -291.930322) (xy 302.737997 -291.928341) (xy 302.689778 -291.918497)
			(xy 302.643762 -291.901045) (xy 302.601141 -291.876438) (xy 302.56302 -291.845313) (xy 302.530385 -291.808476)
			(xy 302.504082 -291.76688) (xy 302.484791 -291.721604) (xy 302.473014 -291.67382) (xy 302.469054 -291.624766)
			(xy 302.130206 -291.624766) (xy 302.129711 -291.649373) (xy 302.121816 -291.69795) (xy 302.106232 -291.744631)
			(xy 302.083361 -291.788208) (xy 302.053796 -291.827552) (xy 302.018303 -291.861644) (xy 301.9778 -291.8896)
			(xy 301.933338 -291.910698) (xy 301.886067 -291.92439) (xy 301.837212 -291.930322) (xy 301.788037 -291.928341)
			(xy 301.739818 -291.918497) (xy 301.693802 -291.901045) (xy 301.651181 -291.876438) (xy 301.61306 -291.845313)
			(xy 301.580425 -291.808476) (xy 301.554122 -291.76688) (xy 301.534831 -291.721604) (xy 301.523054 -291.67382)
			(xy 301.519094 -291.624766) (xy 301.179992 -291.624766) (xy 301.179497 -291.649373) (xy 301.171602 -291.69795)
			(xy 301.156018 -291.744631) (xy 301.133147 -291.788208) (xy 301.103582 -291.827552) (xy 301.068089 -291.861644)
			(xy 301.027586 -291.8896) (xy 300.983124 -291.910698) (xy 300.935853 -291.92439) (xy 300.886998 -291.930322)
			(xy 300.837823 -291.928341) (xy 300.789604 -291.918497) (xy 300.743588 -291.901045) (xy 300.700967 -291.876438)
			(xy 300.662846 -291.845313) (xy 300.630211 -291.808476) (xy 300.603908 -291.76688) (xy 300.584617 -291.721604)
			(xy 300.57284 -291.67382) (xy 300.56888 -291.624766) (xy 300.230032 -291.624766) (xy 300.229537 -291.649373)
			(xy 300.221642 -291.69795) (xy 300.206058 -291.744631) (xy 300.183187 -291.788208) (xy 300.153622 -291.827552)
			(xy 300.118129 -291.861644) (xy 300.077626 -291.8896) (xy 300.033164 -291.910698) (xy 299.985893 -291.92439)
			(xy 299.937038 -291.930322) (xy 299.887863 -291.928341) (xy 299.839644 -291.918497) (xy 299.793628 -291.901045)
			(xy 299.751007 -291.876438) (xy 299.712886 -291.845313) (xy 299.680251 -291.808476) (xy 299.653948 -291.76688)
			(xy 299.634657 -291.721604) (xy 299.62288 -291.67382) (xy 299.61892 -291.624766) (xy 299.280072 -291.624766)
			(xy 299.279577 -291.649373) (xy 299.271682 -291.69795) (xy 299.256098 -291.744631) (xy 299.233227 -291.788208)
			(xy 299.203662 -291.827552) (xy 299.168169 -291.861644) (xy 299.127666 -291.8896) (xy 299.083204 -291.910698)
			(xy 299.035933 -291.92439) (xy 298.987078 -291.930322) (xy 298.937903 -291.928341) (xy 298.889684 -291.918497)
			(xy 298.843668 -291.901045) (xy 298.801047 -291.876438) (xy 298.762926 -291.845313) (xy 298.730291 -291.808476)
			(xy 298.703988 -291.76688) (xy 298.684697 -291.721604) (xy 298.67292 -291.67382) (xy 298.66896 -291.624766)
			(xy 298.330112 -291.624766) (xy 298.329617 -291.649373) (xy 298.321722 -291.69795) (xy 298.306138 -291.744631)
			(xy 298.283267 -291.788208) (xy 298.253702 -291.827552) (xy 298.218209 -291.861644) (xy 298.177706 -291.8896)
			(xy 298.133244 -291.910698) (xy 298.085973 -291.92439) (xy 298.037118 -291.930322) (xy 297.987943 -291.928341)
			(xy 297.939724 -291.918497) (xy 297.893708 -291.901045) (xy 297.851087 -291.876438) (xy 297.812966 -291.845313)
			(xy 297.780331 -291.808476) (xy 297.754028 -291.76688) (xy 297.734737 -291.721604) (xy 297.72296 -291.67382)
			(xy 297.719 -291.624766) (xy 297.380152 -291.624766) (xy 297.379657 -291.649373) (xy 297.371762 -291.69795)
			(xy 297.356178 -291.744631) (xy 297.333307 -291.788208) (xy 297.303742 -291.827552) (xy 297.268249 -291.861644)
			(xy 297.227746 -291.8896) (xy 297.183284 -291.910698) (xy 297.136013 -291.92439) (xy 297.087158 -291.930322)
			(xy 297.037983 -291.928341) (xy 296.989764 -291.918497) (xy 296.943748 -291.901045) (xy 296.901127 -291.876438)
			(xy 296.863006 -291.845313) (xy 296.830371 -291.808476) (xy 296.804068 -291.76688) (xy 296.784777 -291.721604)
			(xy 296.773 -291.67382) (xy 296.76904 -291.624766) (xy 296.430192 -291.624766) (xy 296.429697 -291.649373)
			(xy 296.421802 -291.69795) (xy 296.406218 -291.744631) (xy 296.383347 -291.788208) (xy 296.353782 -291.827552)
			(xy 296.318289 -291.861644) (xy 296.277786 -291.8896) (xy 296.233324 -291.910698) (xy 296.186053 -291.92439)
			(xy 296.137198 -291.930322) (xy 296.088023 -291.928341) (xy 296.039804 -291.918497) (xy 295.993788 -291.901045)
			(xy 295.951167 -291.876438) (xy 295.913046 -291.845313) (xy 295.880411 -291.808476) (xy 295.854108 -291.76688)
			(xy 295.834817 -291.721604) (xy 295.82304 -291.67382) (xy 295.81908 -291.624766) (xy 295.480232 -291.624766)
			(xy 295.479737 -291.649373) (xy 295.471842 -291.69795) (xy 295.456258 -291.744631) (xy 295.433387 -291.788208)
			(xy 295.403822 -291.827552) (xy 295.368329 -291.861644) (xy 295.327826 -291.8896) (xy 295.283364 -291.910698)
			(xy 295.236093 -291.92439) (xy 295.187238 -291.930322) (xy 295.138063 -291.928341) (xy 295.089844 -291.918497)
			(xy 295.043828 -291.901045) (xy 295.001207 -291.876438) (xy 294.963086 -291.845313) (xy 294.930451 -291.808476)
			(xy 294.904148 -291.76688) (xy 294.884857 -291.721604) (xy 294.87308 -291.67382) (xy 294.86912 -291.624766)
			(xy 294.530018 -291.624766) (xy 294.529523 -291.649373) (xy 294.521628 -291.69795) (xy 294.506044 -291.744631)
			(xy 294.483173 -291.788208) (xy 294.453608 -291.827552) (xy 294.418115 -291.861644) (xy 294.377612 -291.8896)
			(xy 294.33315 -291.910698) (xy 294.285879 -291.92439) (xy 294.237024 -291.930322) (xy 294.187849 -291.928341)
			(xy 294.13963 -291.918497) (xy 294.093614 -291.901045) (xy 294.050993 -291.876438) (xy 294.012872 -291.845313)
			(xy 293.980237 -291.808476) (xy 293.953934 -291.76688) (xy 293.934643 -291.721604) (xy 293.922866 -291.67382)
			(xy 293.918906 -291.624766) (xy 293.580058 -291.624766) (xy 293.579563 -291.649373) (xy 293.571668 -291.69795)
			(xy 293.556084 -291.744631) (xy 293.533213 -291.788208) (xy 293.503648 -291.827552) (xy 293.468155 -291.861644)
			(xy 293.427652 -291.8896) (xy 293.38319 -291.910698) (xy 293.335919 -291.92439) (xy 293.287064 -291.930322)
			(xy 293.237889 -291.928341) (xy 293.18967 -291.918497) (xy 293.143654 -291.901045) (xy 293.101033 -291.876438)
			(xy 293.062912 -291.845313) (xy 293.030277 -291.808476) (xy 293.003974 -291.76688) (xy 292.984683 -291.721604)
			(xy 292.972906 -291.67382) (xy 292.968946 -291.624766) (xy 292.630098 -291.624766) (xy 292.629603 -291.649373)
			(xy 292.621708 -291.69795) (xy 292.606124 -291.744631) (xy 292.583253 -291.788208) (xy 292.553688 -291.827552)
			(xy 292.518195 -291.861644) (xy 292.477692 -291.8896) (xy 292.43323 -291.910698) (xy 292.385959 -291.92439)
			(xy 292.337104 -291.930322) (xy 292.287929 -291.928341) (xy 292.23971 -291.918497) (xy 292.193694 -291.901045)
			(xy 292.151073 -291.876438) (xy 292.112952 -291.845313) (xy 292.080317 -291.808476) (xy 292.054014 -291.76688)
			(xy 292.034723 -291.721604) (xy 292.022946 -291.67382) (xy 292.018986 -291.624766) (xy 290.730178 -291.624766)
			(xy 290.729683 -291.649373) (xy 290.721788 -291.69795) (xy 290.706204 -291.744631) (xy 290.683333 -291.788208)
			(xy 290.653768 -291.827552) (xy 290.618275 -291.861644) (xy 290.577772 -291.8896) (xy 290.53331 -291.910698)
			(xy 290.486039 -291.92439) (xy 290.437184 -291.930322) (xy 290.388009 -291.928341) (xy 290.33979 -291.918497)
			(xy 290.293774 -291.901045) (xy 290.251153 -291.876438) (xy 290.213032 -291.845313) (xy 290.180397 -291.808476)
			(xy 290.154094 -291.76688) (xy 290.134803 -291.721604) (xy 290.123026 -291.67382) (xy 290.119066 -291.624766)
			(xy 289.780218 -291.624766) (xy 289.779723 -291.649373) (xy 289.771828 -291.69795) (xy 289.756244 -291.744631)
			(xy 289.733373 -291.788208) (xy 289.703808 -291.827552) (xy 289.668315 -291.861644) (xy 289.627812 -291.8896)
			(xy 289.58335 -291.910698) (xy 289.536079 -291.92439) (xy 289.487224 -291.930322) (xy 289.438049 -291.928341)
			(xy 289.38983 -291.918497) (xy 289.343814 -291.901045) (xy 289.301193 -291.876438) (xy 289.263072 -291.845313)
			(xy 289.230437 -291.808476) (xy 289.204134 -291.76688) (xy 289.184843 -291.721604) (xy 289.173066 -291.67382)
			(xy 289.169106 -291.624766) (xy 288.830004 -291.624766) (xy 288.829509 -291.649373) (xy 288.821614 -291.69795)
			(xy 288.80603 -291.744631) (xy 288.783159 -291.788208) (xy 288.753594 -291.827552) (xy 288.718101 -291.861644)
			(xy 288.677598 -291.8896) (xy 288.633136 -291.910698) (xy 288.585865 -291.92439) (xy 288.53701 -291.930322)
			(xy 288.487835 -291.928341) (xy 288.439616 -291.918497) (xy 288.3936 -291.901045) (xy 288.350979 -291.876438)
			(xy 288.312858 -291.845313) (xy 288.280223 -291.808476) (xy 288.25392 -291.76688) (xy 288.234629 -291.721604)
			(xy 288.222852 -291.67382) (xy 288.218892 -291.624766) (xy 287.880044 -291.624766) (xy 287.879549 -291.649373)
			(xy 287.871654 -291.69795) (xy 287.85607 -291.744631) (xy 287.833199 -291.788208) (xy 287.803634 -291.827552)
			(xy 287.768141 -291.861644) (xy 287.727638 -291.8896) (xy 287.683176 -291.910698) (xy 287.635905 -291.92439)
			(xy 287.58705 -291.930322) (xy 287.537875 -291.928341) (xy 287.489656 -291.918497) (xy 287.44364 -291.901045)
			(xy 287.401019 -291.876438) (xy 287.362898 -291.845313) (xy 287.330263 -291.808476) (xy 287.30396 -291.76688)
			(xy 287.284669 -291.721604) (xy 287.272892 -291.67382) (xy 287.268932 -291.624766) (xy 286.930084 -291.624766)
			(xy 286.929589 -291.649373) (xy 286.921694 -291.69795) (xy 286.90611 -291.744631) (xy 286.883239 -291.788208)
			(xy 286.853674 -291.827552) (xy 286.818181 -291.861644) (xy 286.777678 -291.8896) (xy 286.733216 -291.910698)
			(xy 286.685945 -291.92439) (xy 286.63709 -291.930322) (xy 286.587915 -291.928341) (xy 286.539696 -291.918497)
			(xy 286.49368 -291.901045) (xy 286.451059 -291.876438) (xy 286.412938 -291.845313) (xy 286.380303 -291.808476)
			(xy 286.354 -291.76688) (xy 286.334709 -291.721604) (xy 286.322932 -291.67382) (xy 286.318972 -291.624766)
			(xy 285.980124 -291.624766) (xy 285.979629 -291.649373) (xy 285.971734 -291.69795) (xy 285.95615 -291.744631)
			(xy 285.933279 -291.788208) (xy 285.903714 -291.827552) (xy 285.868221 -291.861644) (xy 285.827718 -291.8896)
			(xy 285.783256 -291.910698) (xy 285.735985 -291.92439) (xy 285.68713 -291.930322) (xy 285.637955 -291.928341)
			(xy 285.589736 -291.918497) (xy 285.54372 -291.901045) (xy 285.501099 -291.876438) (xy 285.462978 -291.845313)
			(xy 285.430343 -291.808476) (xy 285.40404 -291.76688) (xy 285.384749 -291.721604) (xy 285.372972 -291.67382)
			(xy 285.369012 -291.624766) (xy 285.030164 -291.624766) (xy 285.029669 -291.649373) (xy 285.021774 -291.69795)
			(xy 285.00619 -291.744631) (xy 284.983319 -291.788208) (xy 284.953754 -291.827552) (xy 284.918261 -291.861644)
			(xy 284.877758 -291.8896) (xy 284.833296 -291.910698) (xy 284.786025 -291.92439) (xy 284.73717 -291.930322)
			(xy 284.687995 -291.928341) (xy 284.639776 -291.918497) (xy 284.59376 -291.901045) (xy 284.551139 -291.876438)
			(xy 284.513018 -291.845313) (xy 284.480383 -291.808476) (xy 284.45408 -291.76688) (xy 284.434789 -291.721604)
			(xy 284.423012 -291.67382) (xy 284.419052 -291.624766) (xy 284.080204 -291.624766) (xy 284.079709 -291.649373)
			(xy 284.071814 -291.69795) (xy 284.05623 -291.744631) (xy 284.033359 -291.788208) (xy 284.003794 -291.827552)
			(xy 283.968301 -291.861644) (xy 283.927798 -291.8896) (xy 283.883336 -291.910698) (xy 283.836065 -291.92439)
			(xy 283.78721 -291.930322) (xy 283.738035 -291.928341) (xy 283.689816 -291.918497) (xy 283.6438 -291.901045)
			(xy 283.601179 -291.876438) (xy 283.563058 -291.845313) (xy 283.530423 -291.808476) (xy 283.50412 -291.76688)
			(xy 283.484829 -291.721604) (xy 283.473052 -291.67382) (xy 283.469092 -291.624766) (xy 283.130244 -291.624766)
			(xy 283.129749 -291.649373) (xy 283.121854 -291.69795) (xy 283.10627 -291.744631) (xy 283.083399 -291.788208)
			(xy 283.053834 -291.827552) (xy 283.018341 -291.861644) (xy 282.977838 -291.8896) (xy 282.933376 -291.910698)
			(xy 282.886105 -291.92439) (xy 282.83725 -291.930322) (xy 282.788075 -291.928341) (xy 282.739856 -291.918497)
			(xy 282.69384 -291.901045) (xy 282.651219 -291.876438) (xy 282.613098 -291.845313) (xy 282.580463 -291.808476)
			(xy 282.55416 -291.76688) (xy 282.534869 -291.721604) (xy 282.523092 -291.67382) (xy 282.519132 -291.624766)
			(xy 281.23007 -291.624766) (xy 281.229575 -291.649373) (xy 281.22168 -291.69795) (xy 281.206096 -291.744631)
			(xy 281.183225 -291.788208) (xy 281.15366 -291.827552) (xy 281.118167 -291.861644) (xy 281.077664 -291.8896)
			(xy 281.033202 -291.910698) (xy 280.985931 -291.92439) (xy 280.937076 -291.930322) (xy 280.887901 -291.928341)
			(xy 280.839682 -291.918497) (xy 280.793666 -291.901045) (xy 280.751045 -291.876438) (xy 280.712924 -291.845313)
			(xy 280.680289 -291.808476) (xy 280.653986 -291.76688) (xy 280.634695 -291.721604) (xy 280.622918 -291.67382)
			(xy 280.618958 -291.624766) (xy 280.28011 -291.624766) (xy 280.28011 -291.634926) (xy 280.28011 -291.636704)
			(xy 280.279856 -291.63772) (xy 280.279602 -291.644578) (xy 280.279348 -291.644832) (xy 280.279348 -291.645848)
			(xy 280.27884 -291.657786) (xy 280.277824 -291.665152) (xy 280.277824 -291.665406) (xy 280.276046 -291.674296)
			(xy 280.276046 -291.67455) (xy 280.276046 -291.675058) (xy 280.275284 -291.678868) (xy 280.274776 -291.68217)
			(xy 280.272744 -291.69106) (xy 280.269442 -291.706046) (xy 280.280364 -291.734494) (xy 280.304748 -291.75202)
			(xy 280.312622 -291.757608) (xy 280.319226 -291.76218) (xy 280.325322 -291.766244) (xy 280.333704 -291.77234)
			(xy 280.343864 -291.779452) (xy 280.349452 -291.783262) (xy 280.370788 -291.800026) (xy 280.371296 -291.800534)
			(xy 280.37155 -291.800788) (xy 280.38044 -291.808916) (xy 280.382472 -291.810948) (xy 280.386282 -291.813742)
			(xy 280.391362 -291.819076) (xy 280.392378 -291.820346) (xy 280.394664 -291.822886) (xy 280.395426 -291.823648)
			(xy 280.395934 -291.82441) (xy 280.404316 -291.833808) (xy 280.40457 -291.834062) (xy 280.405078 -291.83457)
			(xy 280.407872 -291.838126) (xy 280.408634 -291.839396) (xy 280.415746 -291.848032) (xy 280.416 -291.848286)
			(xy 280.417016 -291.849556) (xy 280.41727 -291.850064) (xy 280.419556 -291.853112) (xy 280.433053 -291.872693)
			(xy 280.454469 -291.915154) (xy 280.469062 -291.960415) (xy 280.476482 -292.007389) (xy 280.47696 -292.031166)
			(xy 280.47696 -292.122098) (xy 325.457312 -292.122098) (xy 325.457754 -292.095494) (xy 325.465136 -292.0428)
			(xy 325.479771 -291.991644) (xy 325.501375 -291.943019) (xy 325.529528 -291.897869) (xy 325.563683 -291.85707)
			(xy 325.603177 -291.821415) (xy 325.624952 -291.806122) (xy 325.63639 -291.797731) (xy 325.6546 -291.776003)
			(xy 325.666125 -291.750101) (xy 325.670074 -291.722027) (xy 325.66614 -291.693951) (xy 325.654629 -291.668043)
			(xy 325.63643 -291.646306) (xy 325.624952 -291.637974) (xy 325.603163 -291.622704) (xy 325.563684 -291.587034)
			(xy 325.529542 -291.546226) (xy 325.501398 -291.501072) (xy 325.479799 -291.452447) (xy 325.465163 -291.401293)
			(xy 325.457773 -291.348601) (xy 325.457312 -291.321998) (xy 325.457798 -291.294747) (xy 325.465554 -291.240799)
			(xy 325.480909 -291.188504) (xy 325.503551 -291.138927) (xy 325.533017 -291.093077) (xy 325.568708 -291.051886)
			(xy 325.609899 -291.016195) (xy 325.655749 -290.986729) (xy 325.705326 -290.964087) (xy 325.757621 -290.948732)
			(xy 325.811569 -290.940976) (xy 325.866071 -290.940976) (xy 325.920019 -290.948732) (xy 325.972314 -290.964087)
			(xy 326.021891 -290.986729) (xy 326.067741 -291.016195) (xy 326.108932 -291.051886) (xy 326.144623 -291.093077)
			(xy 326.174089 -291.138927) (xy 326.196731 -291.188504) (xy 326.212086 -291.240799) (xy 326.219842 -291.294747)
			(xy 326.220328 -291.321998) (xy 326.219909 -291.348603) (xy 326.212526 -291.401299) (xy 326.197889 -291.452457)
			(xy 326.176282 -291.501083) (xy 326.148125 -291.546233) (xy 326.113965 -291.587031) (xy 326.074465 -291.622683)
			(xy 326.052688 -291.637974) (xy 326.041162 -291.64625) (xy 326.02296 -291.668007) (xy 326.011447 -291.693934)
			(xy 326.007513 -291.722027) (xy 326.011462 -291.750118) (xy 326.022988 -291.776039) (xy 326.041202 -291.797786)
			(xy 326.052688 -291.806122) (xy 326.074484 -291.821382) (xy 326.113961 -291.857055) (xy 326.148101 -291.897865)
			(xy 326.176243 -291.943021) (xy 326.197842 -291.991648) (xy 326.212477 -292.042803) (xy 326.219867 -292.095494)
			(xy 326.220328 -292.122098) (xy 326.219842 -292.149349) (xy 326.212086 -292.203297) (xy 326.196731 -292.255592)
			(xy 326.174089 -292.305169) (xy 326.144623 -292.351019) (xy 326.108932 -292.39221) (xy 326.067741 -292.427901)
			(xy 326.021891 -292.457367) (xy 325.972314 -292.480009) (xy 325.920019 -292.495364) (xy 325.866071 -292.50312)
			(xy 325.811569 -292.50312) (xy 325.757621 -292.495364) (xy 325.705326 -292.480009) (xy 325.655749 -292.457367)
			(xy 325.609899 -292.427901) (xy 325.568708 -292.39221) (xy 325.533017 -292.351019) (xy 325.503551 -292.305169)
			(xy 325.480909 -292.255592) (xy 325.465554 -292.203297) (xy 325.457798 -292.149349) (xy 325.457312 -292.122098)
			(xy 280.47696 -292.122098) (xy 280.47696 -292.177216) (xy 280.475579 -292.204621) (xy 280.464203 -292.258296)
			(xy 280.443419 -292.309075) (xy 280.413897 -292.355323) (xy 280.39568 -292.375844) (xy 280.393902 -292.377622)
			(xy 280.393394 -292.37813) (xy 280.38806 -292.383718) (xy 280.38425 -292.387528) (xy 280.378916 -292.392608)
			(xy 280.368502 -292.402514) (xy 280.362152 -292.407594) (xy 280.361898 -292.407848) (xy 280.355802 -292.412166)
			(xy 280.35504 -292.412928) (xy 280.354278 -292.413436) (xy 280.31948 -292.437566) (xy 280.318972 -292.437566)
			(xy 280.303224 -292.448742) (xy 280.30043 -292.450774) (xy 280.280364 -292.464998) (xy 280.269442 -292.493192)
			(xy 280.272744 -292.507924) (xy 280.272744 -292.508178) (xy 280.27376 -292.513258) (xy 280.276601 -292.527828)
			(xy 280.279783 -292.557345) (xy 280.28011 -292.572186) (xy 280.28011 -292.574726) (xy 281.568918 -292.574726)
			(xy 281.572878 -292.525672) (xy 281.584655 -292.477888) (xy 281.603946 -292.432612) (xy 281.630249 -292.391016)
			(xy 281.662884 -292.354179) (xy 281.701005 -292.323054) (xy 281.743626 -292.298447) (xy 281.789642 -292.280995)
			(xy 281.837861 -292.271151) (xy 281.887036 -292.26917) (xy 281.935891 -292.275102) (xy 281.983162 -292.288794)
			(xy 282.027624 -292.309892) (xy 282.068127 -292.337848) (xy 282.10362 -292.37194) (xy 282.133185 -292.411284)
			(xy 282.156056 -292.454861) (xy 282.17164 -292.501542) (xy 282.179535 -292.550119) (xy 282.18003 -292.574726)
			(xy 282.180025 -292.57498) (xy 282.519132 -292.57498) (xy 282.523092 -292.525926) (xy 282.534869 -292.478142)
			(xy 282.55416 -292.432866) (xy 282.580463 -292.39127) (xy 282.613098 -292.354433) (xy 282.651219 -292.323308)
			(xy 282.69384 -292.298701) (xy 282.739856 -292.281249) (xy 282.788075 -292.271405) (xy 282.83725 -292.269424)
			(xy 282.886105 -292.275356) (xy 282.933376 -292.289048) (xy 282.977838 -292.310146) (xy 283.018341 -292.338102)
			(xy 283.053834 -292.372194) (xy 283.083399 -292.411538) (xy 283.10627 -292.455115) (xy 283.121854 -292.501796)
			(xy 283.129749 -292.550373) (xy 283.130244 -292.57498) (xy 283.469092 -292.57498) (xy 283.473052 -292.525926)
			(xy 283.484829 -292.478142) (xy 283.50412 -292.432866) (xy 283.530423 -292.39127) (xy 283.563058 -292.354433)
			(xy 283.601179 -292.323308) (xy 283.6438 -292.298701) (xy 283.689816 -292.281249) (xy 283.738035 -292.271405)
			(xy 283.78721 -292.269424) (xy 283.836065 -292.275356) (xy 283.883336 -292.289048) (xy 283.927798 -292.310146)
			(xy 283.968301 -292.338102) (xy 284.003794 -292.372194) (xy 284.033359 -292.411538) (xy 284.05623 -292.455115)
			(xy 284.071814 -292.501796) (xy 284.079709 -292.550373) (xy 284.080204 -292.57498) (xy 284.419052 -292.57498)
			(xy 284.423012 -292.525926) (xy 284.434789 -292.478142) (xy 284.45408 -292.432866) (xy 284.480383 -292.39127)
			(xy 284.513018 -292.354433) (xy 284.551139 -292.323308) (xy 284.59376 -292.298701) (xy 284.639776 -292.281249)
			(xy 284.687995 -292.271405) (xy 284.73717 -292.269424) (xy 284.786025 -292.275356) (xy 284.833296 -292.289048)
			(xy 284.877758 -292.310146) (xy 284.918261 -292.338102) (xy 284.953754 -292.372194) (xy 284.983319 -292.411538)
			(xy 285.00619 -292.455115) (xy 285.021774 -292.501796) (xy 285.029669 -292.550373) (xy 285.030164 -292.57498)
			(xy 285.369012 -292.57498) (xy 285.372972 -292.525926) (xy 285.384749 -292.478142) (xy 285.40404 -292.432866)
			(xy 285.430343 -292.39127) (xy 285.462978 -292.354433) (xy 285.501099 -292.323308) (xy 285.54372 -292.298701)
			(xy 285.589736 -292.281249) (xy 285.637955 -292.271405) (xy 285.68713 -292.269424) (xy 285.735985 -292.275356)
			(xy 285.783256 -292.289048) (xy 285.827718 -292.310146) (xy 285.868221 -292.338102) (xy 285.903714 -292.372194)
			(xy 285.933279 -292.411538) (xy 285.95615 -292.455115) (xy 285.971734 -292.501796) (xy 285.979629 -292.550373)
			(xy 285.980124 -292.57498) (xy 286.318972 -292.57498) (xy 286.322932 -292.525926) (xy 286.334709 -292.478142)
			(xy 286.354 -292.432866) (xy 286.380303 -292.39127) (xy 286.412938 -292.354433) (xy 286.451059 -292.323308)
			(xy 286.49368 -292.298701) (xy 286.539696 -292.281249) (xy 286.587915 -292.271405) (xy 286.63709 -292.269424)
			(xy 286.685945 -292.275356) (xy 286.733216 -292.289048) (xy 286.777678 -292.310146) (xy 286.818181 -292.338102)
			(xy 286.853674 -292.372194) (xy 286.883239 -292.411538) (xy 286.90611 -292.455115) (xy 286.921694 -292.501796)
			(xy 286.929589 -292.550373) (xy 286.930084 -292.57498) (xy 287.268932 -292.57498) (xy 287.272892 -292.525926)
			(xy 287.284669 -292.478142) (xy 287.30396 -292.432866) (xy 287.330263 -292.39127) (xy 287.362898 -292.354433)
			(xy 287.401019 -292.323308) (xy 287.44364 -292.298701) (xy 287.489656 -292.281249) (xy 287.537875 -292.271405)
			(xy 287.58705 -292.269424) (xy 287.635905 -292.275356) (xy 287.683176 -292.289048) (xy 287.727638 -292.310146)
			(xy 287.768141 -292.338102) (xy 287.803634 -292.372194) (xy 287.833199 -292.411538) (xy 287.85607 -292.455115)
			(xy 287.871654 -292.501796) (xy 287.879549 -292.550373) (xy 287.880044 -292.57498) (xy 288.219146 -292.57498)
			(xy 288.223106 -292.525926) (xy 288.234883 -292.478142) (xy 288.254174 -292.432866) (xy 288.280477 -292.39127)
			(xy 288.313112 -292.354433) (xy 288.351233 -292.323308) (xy 288.393854 -292.298701) (xy 288.43987 -292.281249)
			(xy 288.488089 -292.271405) (xy 288.537264 -292.269424) (xy 288.586119 -292.275356) (xy 288.63339 -292.289048)
			(xy 288.677852 -292.310146) (xy 288.718355 -292.338102) (xy 288.753848 -292.372194) (xy 288.783413 -292.411538)
			(xy 288.806284 -292.455115) (xy 288.821868 -292.501796) (xy 288.829763 -292.550373) (xy 288.830258 -292.57498)
			(xy 289.169106 -292.57498) (xy 289.173066 -292.525926) (xy 289.184843 -292.478142) (xy 289.204134 -292.432866)
			(xy 289.230437 -292.39127) (xy 289.263072 -292.354433) (xy 289.301193 -292.323308) (xy 289.343814 -292.298701)
			(xy 289.38983 -292.281249) (xy 289.438049 -292.271405) (xy 289.487224 -292.269424) (xy 289.536079 -292.275356)
			(xy 289.58335 -292.289048) (xy 289.627812 -292.310146) (xy 289.668315 -292.338102) (xy 289.703808 -292.372194)
			(xy 289.733373 -292.411538) (xy 289.756244 -292.455115) (xy 289.771828 -292.501796) (xy 289.779723 -292.550373)
			(xy 289.780218 -292.57498) (xy 290.119066 -292.57498) (xy 290.123026 -292.525926) (xy 290.134803 -292.478142)
			(xy 290.154094 -292.432866) (xy 290.180397 -292.39127) (xy 290.213032 -292.354433) (xy 290.251153 -292.323308)
			(xy 290.293774 -292.298701) (xy 290.33979 -292.281249) (xy 290.388009 -292.271405) (xy 290.437184 -292.269424)
			(xy 290.486039 -292.275356) (xy 290.53331 -292.289048) (xy 290.577772 -292.310146) (xy 290.618275 -292.338102)
			(xy 290.653768 -292.372194) (xy 290.683333 -292.411538) (xy 290.706204 -292.455115) (xy 290.721788 -292.501796)
			(xy 290.729683 -292.550373) (xy 290.730173 -292.574726) (xy 292.018986 -292.574726) (xy 292.022946 -292.525672)
			(xy 292.034723 -292.477888) (xy 292.054014 -292.432612) (xy 292.080317 -292.391016) (xy 292.112952 -292.354179)
			(xy 292.151073 -292.323054) (xy 292.193694 -292.298447) (xy 292.23971 -292.280995) (xy 292.287929 -292.271151)
			(xy 292.337104 -292.26917) (xy 292.385959 -292.275102) (xy 292.43323 -292.288794) (xy 292.477692 -292.309892)
			(xy 292.518195 -292.337848) (xy 292.553688 -292.37194) (xy 292.583253 -292.411284) (xy 292.606124 -292.454861)
			(xy 292.621708 -292.501542) (xy 292.629603 -292.550119) (xy 292.630098 -292.574726) (xy 292.968946 -292.574726)
			(xy 292.972906 -292.525672) (xy 292.984683 -292.477888) (xy 293.003974 -292.432612) (xy 293.030277 -292.391016)
			(xy 293.062912 -292.354179) (xy 293.101033 -292.323054) (xy 293.143654 -292.298447) (xy 293.18967 -292.280995)
			(xy 293.237889 -292.271151) (xy 293.287064 -292.26917) (xy 293.335919 -292.275102) (xy 293.38319 -292.288794)
			(xy 293.427652 -292.309892) (xy 293.468155 -292.337848) (xy 293.503648 -292.37194) (xy 293.533213 -292.411284)
			(xy 293.556084 -292.454861) (xy 293.571668 -292.501542) (xy 293.579563 -292.550119) (xy 293.580058 -292.574726)
			(xy 293.918906 -292.574726) (xy 293.922866 -292.525672) (xy 293.934643 -292.477888) (xy 293.953934 -292.432612)
			(xy 293.980237 -292.391016) (xy 294.012872 -292.354179) (xy 294.050993 -292.323054) (xy 294.093614 -292.298447)
			(xy 294.13963 -292.280995) (xy 294.187849 -292.271151) (xy 294.237024 -292.26917) (xy 294.285879 -292.275102)
			(xy 294.33315 -292.288794) (xy 294.377612 -292.309892) (xy 294.418115 -292.337848) (xy 294.453608 -292.37194)
			(xy 294.483173 -292.411284) (xy 294.506044 -292.454861) (xy 294.521628 -292.501542) (xy 294.529523 -292.550119)
			(xy 294.530018 -292.574726) (xy 294.86912 -292.574726) (xy 294.87308 -292.525672) (xy 294.884857 -292.477888)
			(xy 294.904148 -292.432612) (xy 294.930451 -292.391016) (xy 294.963086 -292.354179) (xy 295.001207 -292.323054)
			(xy 295.043828 -292.298447) (xy 295.089844 -292.280995) (xy 295.138063 -292.271151) (xy 295.187238 -292.26917)
			(xy 295.236093 -292.275102) (xy 295.283364 -292.288794) (xy 295.327826 -292.309892) (xy 295.368329 -292.337848)
			(xy 295.403822 -292.37194) (xy 295.433387 -292.411284) (xy 295.456258 -292.454861) (xy 295.471842 -292.501542)
			(xy 295.479737 -292.550119) (xy 295.480232 -292.574726) (xy 295.81908 -292.574726) (xy 295.82304 -292.525672)
			(xy 295.834817 -292.477888) (xy 295.854108 -292.432612) (xy 295.880411 -292.391016) (xy 295.913046 -292.354179)
			(xy 295.951167 -292.323054) (xy 295.993788 -292.298447) (xy 296.039804 -292.280995) (xy 296.088023 -292.271151)
			(xy 296.137198 -292.26917) (xy 296.186053 -292.275102) (xy 296.233324 -292.288794) (xy 296.277786 -292.309892)
			(xy 296.318289 -292.337848) (xy 296.353782 -292.37194) (xy 296.383347 -292.411284) (xy 296.406218 -292.454861)
			(xy 296.421802 -292.501542) (xy 296.429697 -292.550119) (xy 296.430192 -292.574726) (xy 296.76904 -292.574726)
			(xy 296.773 -292.525672) (xy 296.784777 -292.477888) (xy 296.804068 -292.432612) (xy 296.830371 -292.391016)
			(xy 296.863006 -292.354179) (xy 296.901127 -292.323054) (xy 296.943748 -292.298447) (xy 296.989764 -292.280995)
			(xy 297.037983 -292.271151) (xy 297.087158 -292.26917) (xy 297.136013 -292.275102) (xy 297.183284 -292.288794)
			(xy 297.227746 -292.309892) (xy 297.268249 -292.337848) (xy 297.303742 -292.37194) (xy 297.333307 -292.411284)
			(xy 297.356178 -292.454861) (xy 297.371762 -292.501542) (xy 297.379657 -292.550119) (xy 297.380152 -292.574726)
			(xy 297.719 -292.574726) (xy 297.72296 -292.525672) (xy 297.734737 -292.477888) (xy 297.754028 -292.432612)
			(xy 297.780331 -292.391016) (xy 297.812966 -292.354179) (xy 297.851087 -292.323054) (xy 297.893708 -292.298447)
			(xy 297.939724 -292.280995) (xy 297.987943 -292.271151) (xy 298.037118 -292.26917) (xy 298.085973 -292.275102)
			(xy 298.133244 -292.288794) (xy 298.177706 -292.309892) (xy 298.218209 -292.337848) (xy 298.253702 -292.37194)
			(xy 298.283267 -292.411284) (xy 298.306138 -292.454861) (xy 298.321722 -292.501542) (xy 298.329617 -292.550119)
			(xy 298.330112 -292.574726) (xy 298.66896 -292.574726) (xy 298.67292 -292.525672) (xy 298.684697 -292.477888)
			(xy 298.703988 -292.432612) (xy 298.730291 -292.391016) (xy 298.762926 -292.354179) (xy 298.801047 -292.323054)
			(xy 298.843668 -292.298447) (xy 298.889684 -292.280995) (xy 298.937903 -292.271151) (xy 298.987078 -292.26917)
			(xy 299.035933 -292.275102) (xy 299.083204 -292.288794) (xy 299.127666 -292.309892) (xy 299.168169 -292.337848)
			(xy 299.203662 -292.37194) (xy 299.233227 -292.411284) (xy 299.256098 -292.454861) (xy 299.271682 -292.501542)
			(xy 299.279577 -292.550119) (xy 299.280072 -292.574726) (xy 299.61892 -292.574726) (xy 299.62288 -292.525672)
			(xy 299.634657 -292.477888) (xy 299.653948 -292.432612) (xy 299.680251 -292.391016) (xy 299.712886 -292.354179)
			(xy 299.751007 -292.323054) (xy 299.793628 -292.298447) (xy 299.839644 -292.280995) (xy 299.887863 -292.271151)
			(xy 299.937038 -292.26917) (xy 299.985893 -292.275102) (xy 300.033164 -292.288794) (xy 300.077626 -292.309892)
			(xy 300.118129 -292.337848) (xy 300.153622 -292.37194) (xy 300.183187 -292.411284) (xy 300.206058 -292.454861)
			(xy 300.221642 -292.501542) (xy 300.229537 -292.550119) (xy 300.230032 -292.574726) (xy 300.56888 -292.574726)
			(xy 300.57284 -292.525672) (xy 300.584617 -292.477888) (xy 300.603908 -292.432612) (xy 300.630211 -292.391016)
			(xy 300.662846 -292.354179) (xy 300.700967 -292.323054) (xy 300.743588 -292.298447) (xy 300.789604 -292.280995)
			(xy 300.837823 -292.271151) (xy 300.886998 -292.26917) (xy 300.935853 -292.275102) (xy 300.983124 -292.288794)
			(xy 301.027586 -292.309892) (xy 301.068089 -292.337848) (xy 301.103582 -292.37194) (xy 301.133147 -292.411284)
			(xy 301.156018 -292.454861) (xy 301.171602 -292.501542) (xy 301.179497 -292.550119) (xy 301.179992 -292.574726)
			(xy 301.519094 -292.574726) (xy 301.523054 -292.525672) (xy 301.534831 -292.477888) (xy 301.554122 -292.432612)
			(xy 301.580425 -292.391016) (xy 301.61306 -292.354179) (xy 301.651181 -292.323054) (xy 301.693802 -292.298447)
			(xy 301.739818 -292.280995) (xy 301.788037 -292.271151) (xy 301.837212 -292.26917) (xy 301.886067 -292.275102)
			(xy 301.933338 -292.288794) (xy 301.9778 -292.309892) (xy 302.018303 -292.337848) (xy 302.053796 -292.37194)
			(xy 302.083361 -292.411284) (xy 302.106232 -292.454861) (xy 302.121816 -292.501542) (xy 302.129711 -292.550119)
			(xy 302.130206 -292.574726) (xy 302.130201 -292.57498) (xy 302.469054 -292.57498) (xy 302.473014 -292.525926)
			(xy 302.484791 -292.478142) (xy 302.504082 -292.432866) (xy 302.530385 -292.39127) (xy 302.56302 -292.354433)
			(xy 302.601141 -292.323308) (xy 302.643762 -292.298701) (xy 302.689778 -292.281249) (xy 302.737997 -292.271405)
			(xy 302.787172 -292.269424) (xy 302.836027 -292.275356) (xy 302.883298 -292.289048) (xy 302.92776 -292.310146)
			(xy 302.968263 -292.338102) (xy 303.003756 -292.372194) (xy 303.033321 -292.411538) (xy 303.056192 -292.455115)
			(xy 303.071776 -292.501796) (xy 303.079671 -292.550373) (xy 303.080161 -292.574726) (xy 303.419014 -292.574726)
			(xy 303.422974 -292.525672) (xy 303.434751 -292.477888) (xy 303.454042 -292.432612) (xy 303.480345 -292.391016)
			(xy 303.51298 -292.354179) (xy 303.551101 -292.323054) (xy 303.593722 -292.298447) (xy 303.639738 -292.280995)
			(xy 303.687957 -292.271151) (xy 303.737132 -292.26917) (xy 303.785987 -292.275102) (xy 303.833258 -292.288794)
			(xy 303.87772 -292.309892) (xy 303.918223 -292.337848) (xy 303.953716 -292.37194) (xy 303.983281 -292.411284)
			(xy 304.006152 -292.454861) (xy 304.021736 -292.501542) (xy 304.029631 -292.550119) (xy 304.030126 -292.574726)
			(xy 304.368974 -292.574726) (xy 304.372934 -292.525672) (xy 304.384711 -292.477888) (xy 304.404002 -292.432612)
			(xy 304.430305 -292.391016) (xy 304.46294 -292.354179) (xy 304.501061 -292.323054) (xy 304.543682 -292.298447)
			(xy 304.589698 -292.280995) (xy 304.637917 -292.271151) (xy 304.687092 -292.26917) (xy 304.735947 -292.275102)
			(xy 304.783218 -292.288794) (xy 304.82768 -292.309892) (xy 304.868183 -292.337848) (xy 304.903676 -292.37194)
			(xy 304.933241 -292.411284) (xy 304.956112 -292.454861) (xy 304.971696 -292.501542) (xy 304.979591 -292.550119)
			(xy 304.980086 -292.574726) (xy 305.318934 -292.574726) (xy 305.322894 -292.525672) (xy 305.334671 -292.477888)
			(xy 305.353962 -292.432612) (xy 305.380265 -292.391016) (xy 305.4129 -292.354179) (xy 305.451021 -292.323054)
			(xy 305.493642 -292.298447) (xy 305.539658 -292.280995) (xy 305.587877 -292.271151) (xy 305.637052 -292.26917)
			(xy 305.685907 -292.275102) (xy 305.733178 -292.288794) (xy 305.77764 -292.309892) (xy 305.818143 -292.337848)
			(xy 305.853636 -292.37194) (xy 305.883201 -292.411284) (xy 305.906072 -292.454861) (xy 305.921656 -292.501542)
			(xy 305.929551 -292.550119) (xy 305.930046 -292.574726) (xy 306.268894 -292.574726) (xy 306.272854 -292.525672)
			(xy 306.284631 -292.477888) (xy 306.303922 -292.432612) (xy 306.330225 -292.391016) (xy 306.36286 -292.354179)
			(xy 306.400981 -292.323054) (xy 306.443602 -292.298447) (xy 306.489618 -292.280995) (xy 306.537837 -292.271151)
			(xy 306.587012 -292.26917) (xy 306.635867 -292.275102) (xy 306.683138 -292.288794) (xy 306.7276 -292.309892)
			(xy 306.768103 -292.337848) (xy 306.803596 -292.37194) (xy 306.833161 -292.411284) (xy 306.856032 -292.454861)
			(xy 306.871616 -292.501542) (xy 306.879511 -292.550119) (xy 306.880006 -292.574726) (xy 307.219108 -292.574726)
			(xy 307.223068 -292.525672) (xy 307.234845 -292.477888) (xy 307.254136 -292.432612) (xy 307.280439 -292.391016)
			(xy 307.313074 -292.354179) (xy 307.351195 -292.323054) (xy 307.393816 -292.298447) (xy 307.439832 -292.280995)
			(xy 307.488051 -292.271151) (xy 307.537226 -292.26917) (xy 307.586081 -292.275102) (xy 307.633352 -292.288794)
			(xy 307.677814 -292.309892) (xy 307.718317 -292.337848) (xy 307.75381 -292.37194) (xy 307.783375 -292.411284)
			(xy 307.806246 -292.454861) (xy 307.82183 -292.501542) (xy 307.829725 -292.550119) (xy 307.83022 -292.574726)
			(xy 308.169068 -292.574726) (xy 308.173028 -292.525672) (xy 308.184805 -292.477888) (xy 308.204096 -292.432612)
			(xy 308.230399 -292.391016) (xy 308.263034 -292.354179) (xy 308.301155 -292.323054) (xy 308.343776 -292.298447)
			(xy 308.389792 -292.280995) (xy 308.438011 -292.271151) (xy 308.487186 -292.26917) (xy 308.536041 -292.275102)
			(xy 308.583312 -292.288794) (xy 308.627774 -292.309892) (xy 308.668277 -292.337848) (xy 308.70377 -292.37194)
			(xy 308.733335 -292.411284) (xy 308.756206 -292.454861) (xy 308.77179 -292.501542) (xy 308.779685 -292.550119)
			(xy 308.78018 -292.574726) (xy 309.119028 -292.574726) (xy 309.122988 -292.525672) (xy 309.134765 -292.477888)
			(xy 309.154056 -292.432612) (xy 309.180359 -292.391016) (xy 309.212994 -292.354179) (xy 309.251115 -292.323054)
			(xy 309.293736 -292.298447) (xy 309.339752 -292.280995) (xy 309.387971 -292.271151) (xy 309.437146 -292.26917)
			(xy 309.486001 -292.275102) (xy 309.533272 -292.288794) (xy 309.577734 -292.309892) (xy 309.618237 -292.337848)
			(xy 309.65373 -292.37194) (xy 309.683295 -292.411284) (xy 309.706166 -292.454861) (xy 309.72175 -292.501542)
			(xy 309.729645 -292.550119) (xy 309.73014 -292.574726) (xy 310.068988 -292.574726) (xy 310.072948 -292.525672)
			(xy 310.084725 -292.477888) (xy 310.104016 -292.432612) (xy 310.130319 -292.391016) (xy 310.162954 -292.354179)
			(xy 310.201075 -292.323054) (xy 310.243696 -292.298447) (xy 310.289712 -292.280995) (xy 310.337931 -292.271151)
			(xy 310.387106 -292.26917) (xy 310.435961 -292.275102) (xy 310.483232 -292.288794) (xy 310.527694 -292.309892)
			(xy 310.568197 -292.337848) (xy 310.60369 -292.37194) (xy 310.633255 -292.411284) (xy 310.656126 -292.454861)
			(xy 310.67171 -292.501542) (xy 310.679605 -292.550119) (xy 310.6801 -292.574726) (xy 311.018948 -292.574726)
			(xy 311.022908 -292.525672) (xy 311.034685 -292.477888) (xy 311.053976 -292.432612) (xy 311.080279 -292.391016)
			(xy 311.112914 -292.354179) (xy 311.151035 -292.323054) (xy 311.193656 -292.298447) (xy 311.239672 -292.280995)
			(xy 311.287891 -292.271151) (xy 311.337066 -292.26917) (xy 311.385921 -292.275102) (xy 311.433192 -292.288794)
			(xy 311.477654 -292.309892) (xy 311.518157 -292.337848) (xy 311.55365 -292.37194) (xy 311.583215 -292.411284)
			(xy 311.606086 -292.454861) (xy 311.62167 -292.501542) (xy 311.629565 -292.550119) (xy 311.63006 -292.574726)
			(xy 311.968908 -292.574726) (xy 311.972868 -292.525672) (xy 311.984645 -292.477888) (xy 312.003936 -292.432612)
			(xy 312.030239 -292.391016) (xy 312.062874 -292.354179) (xy 312.100995 -292.323054) (xy 312.143616 -292.298447)
			(xy 312.189632 -292.280995) (xy 312.237851 -292.271151) (xy 312.287026 -292.26917) (xy 312.335881 -292.275102)
			(xy 312.383152 -292.288794) (xy 312.427614 -292.309892) (xy 312.468117 -292.337848) (xy 312.50361 -292.37194)
			(xy 312.533175 -292.411284) (xy 312.556046 -292.454861) (xy 312.57163 -292.501542) (xy 312.579525 -292.550119)
			(xy 312.58002 -292.574726) (xy 312.919122 -292.574726) (xy 312.923082 -292.525672) (xy 312.934859 -292.477888)
			(xy 312.95415 -292.432612) (xy 312.980453 -292.391016) (xy 313.013088 -292.354179) (xy 313.051209 -292.323054)
			(xy 313.09383 -292.298447) (xy 313.139846 -292.280995) (xy 313.188065 -292.271151) (xy 313.23724 -292.26917)
			(xy 313.286095 -292.275102) (xy 313.333366 -292.288794) (xy 313.377828 -292.309892) (xy 313.418331 -292.337848)
			(xy 313.453824 -292.37194) (xy 313.483389 -292.411284) (xy 313.50626 -292.454861) (xy 313.521844 -292.501542)
			(xy 313.529739 -292.550119) (xy 313.530234 -292.574726) (xy 313.530229 -292.57498) (xy 313.869082 -292.57498)
			(xy 313.873042 -292.525926) (xy 313.884819 -292.478142) (xy 313.90411 -292.432866) (xy 313.930413 -292.39127)
			(xy 313.963048 -292.354433) (xy 314.001169 -292.323308) (xy 314.04379 -292.298701) (xy 314.089806 -292.281249)
			(xy 314.138025 -292.271405) (xy 314.1872 -292.269424) (xy 314.236055 -292.275356) (xy 314.283326 -292.289048)
			(xy 314.327788 -292.310146) (xy 314.368291 -292.338102) (xy 314.403784 -292.372194) (xy 314.433349 -292.411538)
			(xy 314.45622 -292.455115) (xy 314.471804 -292.501796) (xy 314.479699 -292.550373) (xy 314.480194 -292.57498)
			(xy 314.819042 -292.57498) (xy 314.823002 -292.525926) (xy 314.834779 -292.478142) (xy 314.85407 -292.432866)
			(xy 314.880373 -292.39127) (xy 314.913008 -292.354433) (xy 314.951129 -292.323308) (xy 314.99375 -292.298701)
			(xy 315.039766 -292.281249) (xy 315.087985 -292.271405) (xy 315.13716 -292.269424) (xy 315.186015 -292.275356)
			(xy 315.233286 -292.289048) (xy 315.277748 -292.310146) (xy 315.318251 -292.338102) (xy 315.353744 -292.372194)
			(xy 315.383309 -292.411538) (xy 315.40618 -292.455115) (xy 315.421764 -292.501796) (xy 315.429659 -292.550373)
			(xy 315.430154 -292.57498) (xy 315.429659 -292.599587) (xy 315.421764 -292.648164) (xy 315.40618 -292.694845)
			(xy 315.383309 -292.738422) (xy 315.353744 -292.777766) (xy 315.318251 -292.811858) (xy 315.277748 -292.839814)
			(xy 315.233286 -292.860912) (xy 315.186015 -292.874604) (xy 315.13716 -292.880536) (xy 315.087985 -292.878555)
			(xy 315.039766 -292.868711) (xy 314.99375 -292.851259) (xy 314.951129 -292.826652) (xy 314.913008 -292.795527)
			(xy 314.880373 -292.75869) (xy 314.85407 -292.717094) (xy 314.834779 -292.671818) (xy 314.823002 -292.624034)
			(xy 314.819042 -292.57498) (xy 314.480194 -292.57498) (xy 314.479699 -292.599587) (xy 314.471804 -292.648164)
			(xy 314.45622 -292.694845) (xy 314.433349 -292.738422) (xy 314.403784 -292.777766) (xy 314.368291 -292.811858)
			(xy 314.327788 -292.839814) (xy 314.283326 -292.860912) (xy 314.236055 -292.874604) (xy 314.1872 -292.880536)
			(xy 314.138025 -292.878555) (xy 314.089806 -292.868711) (xy 314.04379 -292.851259) (xy 314.001169 -292.826652)
			(xy 313.963048 -292.795527) (xy 313.930413 -292.75869) (xy 313.90411 -292.717094) (xy 313.884819 -292.671818)
			(xy 313.873042 -292.624034) (xy 313.869082 -292.57498) (xy 313.530229 -292.57498) (xy 313.529739 -292.599333)
			(xy 313.521844 -292.64791) (xy 313.50626 -292.694591) (xy 313.483389 -292.738168) (xy 313.453824 -292.777512)
			(xy 313.418331 -292.811604) (xy 313.377828 -292.83956) (xy 313.333366 -292.860658) (xy 313.286095 -292.87435)
			(xy 313.23724 -292.880282) (xy 313.188065 -292.878301) (xy 313.139846 -292.868457) (xy 313.09383 -292.851005)
			(xy 313.051209 -292.826398) (xy 313.013088 -292.795273) (xy 312.980453 -292.758436) (xy 312.95415 -292.71684)
			(xy 312.934859 -292.671564) (xy 312.923082 -292.62378) (xy 312.919122 -292.574726) (xy 312.58002 -292.574726)
			(xy 312.579525 -292.599333) (xy 312.57163 -292.64791) (xy 312.556046 -292.694591) (xy 312.533175 -292.738168)
			(xy 312.50361 -292.777512) (xy 312.468117 -292.811604) (xy 312.427614 -292.83956) (xy 312.383152 -292.860658)
			(xy 312.335881 -292.87435) (xy 312.287026 -292.880282) (xy 312.237851 -292.878301) (xy 312.189632 -292.868457)
			(xy 312.143616 -292.851005) (xy 312.100995 -292.826398) (xy 312.062874 -292.795273) (xy 312.030239 -292.758436)
			(xy 312.003936 -292.71684) (xy 311.984645 -292.671564) (xy 311.972868 -292.62378) (xy 311.968908 -292.574726)
			(xy 311.63006 -292.574726) (xy 311.629565 -292.599333) (xy 311.62167 -292.64791) (xy 311.606086 -292.694591)
			(xy 311.583215 -292.738168) (xy 311.55365 -292.777512) (xy 311.518157 -292.811604) (xy 311.477654 -292.83956)
			(xy 311.433192 -292.860658) (xy 311.385921 -292.87435) (xy 311.337066 -292.880282) (xy 311.287891 -292.878301)
			(xy 311.239672 -292.868457) (xy 311.193656 -292.851005) (xy 311.151035 -292.826398) (xy 311.112914 -292.795273)
			(xy 311.080279 -292.758436) (xy 311.053976 -292.71684) (xy 311.034685 -292.671564) (xy 311.022908 -292.62378)
			(xy 311.018948 -292.574726) (xy 310.6801 -292.574726) (xy 310.679605 -292.599333) (xy 310.67171 -292.64791)
			(xy 310.656126 -292.694591) (xy 310.633255 -292.738168) (xy 310.60369 -292.777512) (xy 310.568197 -292.811604)
			(xy 310.527694 -292.83956) (xy 310.483232 -292.860658) (xy 310.435961 -292.87435) (xy 310.387106 -292.880282)
			(xy 310.337931 -292.878301) (xy 310.289712 -292.868457) (xy 310.243696 -292.851005) (xy 310.201075 -292.826398)
			(xy 310.162954 -292.795273) (xy 310.130319 -292.758436) (xy 310.104016 -292.71684) (xy 310.084725 -292.671564)
			(xy 310.072948 -292.62378) (xy 310.068988 -292.574726) (xy 309.73014 -292.574726) (xy 309.729645 -292.599333)
			(xy 309.72175 -292.64791) (xy 309.706166 -292.694591) (xy 309.683295 -292.738168) (xy 309.65373 -292.777512)
			(xy 309.618237 -292.811604) (xy 309.577734 -292.83956) (xy 309.533272 -292.860658) (xy 309.486001 -292.87435)
			(xy 309.437146 -292.880282) (xy 309.387971 -292.878301) (xy 309.339752 -292.868457) (xy 309.293736 -292.851005)
			(xy 309.251115 -292.826398) (xy 309.212994 -292.795273) (xy 309.180359 -292.758436) (xy 309.154056 -292.71684)
			(xy 309.134765 -292.671564) (xy 309.122988 -292.62378) (xy 309.119028 -292.574726) (xy 308.78018 -292.574726)
			(xy 308.779685 -292.599333) (xy 308.77179 -292.64791) (xy 308.756206 -292.694591) (xy 308.733335 -292.738168)
			(xy 308.70377 -292.777512) (xy 308.668277 -292.811604) (xy 308.627774 -292.83956) (xy 308.583312 -292.860658)
			(xy 308.536041 -292.87435) (xy 308.487186 -292.880282) (xy 308.438011 -292.878301) (xy 308.389792 -292.868457)
			(xy 308.343776 -292.851005) (xy 308.301155 -292.826398) (xy 308.263034 -292.795273) (xy 308.230399 -292.758436)
			(xy 308.204096 -292.71684) (xy 308.184805 -292.671564) (xy 308.173028 -292.62378) (xy 308.169068 -292.574726)
			(xy 307.83022 -292.574726) (xy 307.829725 -292.599333) (xy 307.82183 -292.64791) (xy 307.806246 -292.694591)
			(xy 307.783375 -292.738168) (xy 307.75381 -292.777512) (xy 307.718317 -292.811604) (xy 307.677814 -292.83956)
			(xy 307.633352 -292.860658) (xy 307.586081 -292.87435) (xy 307.537226 -292.880282) (xy 307.488051 -292.878301)
			(xy 307.439832 -292.868457) (xy 307.393816 -292.851005) (xy 307.351195 -292.826398) (xy 307.313074 -292.795273)
			(xy 307.280439 -292.758436) (xy 307.254136 -292.71684) (xy 307.234845 -292.671564) (xy 307.223068 -292.62378)
			(xy 307.219108 -292.574726) (xy 306.880006 -292.574726) (xy 306.879511 -292.599333) (xy 306.871616 -292.64791)
			(xy 306.856032 -292.694591) (xy 306.833161 -292.738168) (xy 306.803596 -292.777512) (xy 306.768103 -292.811604)
			(xy 306.7276 -292.83956) (xy 306.683138 -292.860658) (xy 306.635867 -292.87435) (xy 306.587012 -292.880282)
			(xy 306.537837 -292.878301) (xy 306.489618 -292.868457) (xy 306.443602 -292.851005) (xy 306.400981 -292.826398)
			(xy 306.36286 -292.795273) (xy 306.330225 -292.758436) (xy 306.303922 -292.71684) (xy 306.284631 -292.671564)
			(xy 306.272854 -292.62378) (xy 306.268894 -292.574726) (xy 305.930046 -292.574726) (xy 305.929551 -292.599333)
			(xy 305.921656 -292.64791) (xy 305.906072 -292.694591) (xy 305.883201 -292.738168) (xy 305.853636 -292.777512)
			(xy 305.818143 -292.811604) (xy 305.77764 -292.83956) (xy 305.733178 -292.860658) (xy 305.685907 -292.87435)
			(xy 305.637052 -292.880282) (xy 305.587877 -292.878301) (xy 305.539658 -292.868457) (xy 305.493642 -292.851005)
			(xy 305.451021 -292.826398) (xy 305.4129 -292.795273) (xy 305.380265 -292.758436) (xy 305.353962 -292.71684)
			(xy 305.334671 -292.671564) (xy 305.322894 -292.62378) (xy 305.318934 -292.574726) (xy 304.980086 -292.574726)
			(xy 304.979591 -292.599333) (xy 304.971696 -292.64791) (xy 304.956112 -292.694591) (xy 304.933241 -292.738168)
			(xy 304.903676 -292.777512) (xy 304.868183 -292.811604) (xy 304.82768 -292.83956) (xy 304.783218 -292.860658)
			(xy 304.735947 -292.87435) (xy 304.687092 -292.880282) (xy 304.637917 -292.878301) (xy 304.589698 -292.868457)
			(xy 304.543682 -292.851005) (xy 304.501061 -292.826398) (xy 304.46294 -292.795273) (xy 304.430305 -292.758436)
			(xy 304.404002 -292.71684) (xy 304.384711 -292.671564) (xy 304.372934 -292.62378) (xy 304.368974 -292.574726)
			(xy 304.030126 -292.574726) (xy 304.029631 -292.599333) (xy 304.021736 -292.64791) (xy 304.006152 -292.694591)
			(xy 303.983281 -292.738168) (xy 303.953716 -292.777512) (xy 303.918223 -292.811604) (xy 303.87772 -292.83956)
			(xy 303.833258 -292.860658) (xy 303.785987 -292.87435) (xy 303.737132 -292.880282) (xy 303.687957 -292.878301)
			(xy 303.639738 -292.868457) (xy 303.593722 -292.851005) (xy 303.551101 -292.826398) (xy 303.51298 -292.795273)
			(xy 303.480345 -292.758436) (xy 303.454042 -292.71684) (xy 303.434751 -292.671564) (xy 303.422974 -292.62378)
			(xy 303.419014 -292.574726) (xy 303.080161 -292.574726) (xy 303.080166 -292.57498) (xy 303.079671 -292.599587)
			(xy 303.071776 -292.648164) (xy 303.056192 -292.694845) (xy 303.033321 -292.738422) (xy 303.003756 -292.777766)
			(xy 302.968263 -292.811858) (xy 302.92776 -292.839814) (xy 302.883298 -292.860912) (xy 302.836027 -292.874604)
			(xy 302.787172 -292.880536) (xy 302.737997 -292.878555) (xy 302.689778 -292.868711) (xy 302.643762 -292.851259)
			(xy 302.601141 -292.826652) (xy 302.56302 -292.795527) (xy 302.530385 -292.75869) (xy 302.504082 -292.717094)
			(xy 302.484791 -292.671818) (xy 302.473014 -292.624034) (xy 302.469054 -292.57498) (xy 302.130201 -292.57498)
			(xy 302.129711 -292.599333) (xy 302.121816 -292.64791) (xy 302.106232 -292.694591) (xy 302.083361 -292.738168)
			(xy 302.053796 -292.777512) (xy 302.018303 -292.811604) (xy 301.9778 -292.83956) (xy 301.933338 -292.860658)
			(xy 301.886067 -292.87435) (xy 301.837212 -292.880282) (xy 301.788037 -292.878301) (xy 301.739818 -292.868457)
			(xy 301.693802 -292.851005) (xy 301.651181 -292.826398) (xy 301.61306 -292.795273) (xy 301.580425 -292.758436)
			(xy 301.554122 -292.71684) (xy 301.534831 -292.671564) (xy 301.523054 -292.62378) (xy 301.519094 -292.574726)
			(xy 301.179992 -292.574726) (xy 301.179497 -292.599333) (xy 301.171602 -292.64791) (xy 301.156018 -292.694591)
			(xy 301.133147 -292.738168) (xy 301.103582 -292.777512) (xy 301.068089 -292.811604) (xy 301.027586 -292.83956)
			(xy 300.983124 -292.860658) (xy 300.935853 -292.87435) (xy 300.886998 -292.880282) (xy 300.837823 -292.878301)
			(xy 300.789604 -292.868457) (xy 300.743588 -292.851005) (xy 300.700967 -292.826398) (xy 300.662846 -292.795273)
			(xy 300.630211 -292.758436) (xy 300.603908 -292.71684) (xy 300.584617 -292.671564) (xy 300.57284 -292.62378)
			(xy 300.56888 -292.574726) (xy 300.230032 -292.574726) (xy 300.229537 -292.599333) (xy 300.221642 -292.64791)
			(xy 300.206058 -292.694591) (xy 300.183187 -292.738168) (xy 300.153622 -292.777512) (xy 300.118129 -292.811604)
			(xy 300.077626 -292.83956) (xy 300.033164 -292.860658) (xy 299.985893 -292.87435) (xy 299.937038 -292.880282)
			(xy 299.887863 -292.878301) (xy 299.839644 -292.868457) (xy 299.793628 -292.851005) (xy 299.751007 -292.826398)
			(xy 299.712886 -292.795273) (xy 299.680251 -292.758436) (xy 299.653948 -292.71684) (xy 299.634657 -292.671564)
			(xy 299.62288 -292.62378) (xy 299.61892 -292.574726) (xy 299.280072 -292.574726) (xy 299.279577 -292.599333)
			(xy 299.271682 -292.64791) (xy 299.256098 -292.694591) (xy 299.233227 -292.738168) (xy 299.203662 -292.777512)
			(xy 299.168169 -292.811604) (xy 299.127666 -292.83956) (xy 299.083204 -292.860658) (xy 299.035933 -292.87435)
			(xy 298.987078 -292.880282) (xy 298.937903 -292.878301) (xy 298.889684 -292.868457) (xy 298.843668 -292.851005)
			(xy 298.801047 -292.826398) (xy 298.762926 -292.795273) (xy 298.730291 -292.758436) (xy 298.703988 -292.71684)
			(xy 298.684697 -292.671564) (xy 298.67292 -292.62378) (xy 298.66896 -292.574726) (xy 298.330112 -292.574726)
			(xy 298.329617 -292.599333) (xy 298.321722 -292.64791) (xy 298.306138 -292.694591) (xy 298.283267 -292.738168)
			(xy 298.253702 -292.777512) (xy 298.218209 -292.811604) (xy 298.177706 -292.83956) (xy 298.133244 -292.860658)
			(xy 298.085973 -292.87435) (xy 298.037118 -292.880282) (xy 297.987943 -292.878301) (xy 297.939724 -292.868457)
			(xy 297.893708 -292.851005) (xy 297.851087 -292.826398) (xy 297.812966 -292.795273) (xy 297.780331 -292.758436)
			(xy 297.754028 -292.71684) (xy 297.734737 -292.671564) (xy 297.72296 -292.62378) (xy 297.719 -292.574726)
			(xy 297.380152 -292.574726) (xy 297.379657 -292.599333) (xy 297.371762 -292.64791) (xy 297.356178 -292.694591)
			(xy 297.333307 -292.738168) (xy 297.303742 -292.777512) (xy 297.268249 -292.811604) (xy 297.227746 -292.83956)
			(xy 297.183284 -292.860658) (xy 297.136013 -292.87435) (xy 297.087158 -292.880282) (xy 297.037983 -292.878301)
			(xy 296.989764 -292.868457) (xy 296.943748 -292.851005) (xy 296.901127 -292.826398) (xy 296.863006 -292.795273)
			(xy 296.830371 -292.758436) (xy 296.804068 -292.71684) (xy 296.784777 -292.671564) (xy 296.773 -292.62378)
			(xy 296.76904 -292.574726) (xy 296.430192 -292.574726) (xy 296.429697 -292.599333) (xy 296.421802 -292.64791)
			(xy 296.406218 -292.694591) (xy 296.383347 -292.738168) (xy 296.353782 -292.777512) (xy 296.318289 -292.811604)
			(xy 296.277786 -292.83956) (xy 296.233324 -292.860658) (xy 296.186053 -292.87435) (xy 296.137198 -292.880282)
			(xy 296.088023 -292.878301) (xy 296.039804 -292.868457) (xy 295.993788 -292.851005) (xy 295.951167 -292.826398)
			(xy 295.913046 -292.795273) (xy 295.880411 -292.758436) (xy 295.854108 -292.71684) (xy 295.834817 -292.671564)
			(xy 295.82304 -292.62378) (xy 295.81908 -292.574726) (xy 295.480232 -292.574726) (xy 295.479737 -292.599333)
			(xy 295.471842 -292.64791) (xy 295.456258 -292.694591) (xy 295.433387 -292.738168) (xy 295.403822 -292.777512)
			(xy 295.368329 -292.811604) (xy 295.327826 -292.83956) (xy 295.283364 -292.860658) (xy 295.236093 -292.87435)
			(xy 295.187238 -292.880282) (xy 295.138063 -292.878301) (xy 295.089844 -292.868457) (xy 295.043828 -292.851005)
			(xy 295.001207 -292.826398) (xy 294.963086 -292.795273) (xy 294.930451 -292.758436) (xy 294.904148 -292.71684)
			(xy 294.884857 -292.671564) (xy 294.87308 -292.62378) (xy 294.86912 -292.574726) (xy 294.530018 -292.574726)
			(xy 294.529523 -292.599333) (xy 294.521628 -292.64791) (xy 294.506044 -292.694591) (xy 294.483173 -292.738168)
			(xy 294.453608 -292.777512) (xy 294.418115 -292.811604) (xy 294.377612 -292.83956) (xy 294.33315 -292.860658)
			(xy 294.285879 -292.87435) (xy 294.237024 -292.880282) (xy 294.187849 -292.878301) (xy 294.13963 -292.868457)
			(xy 294.093614 -292.851005) (xy 294.050993 -292.826398) (xy 294.012872 -292.795273) (xy 293.980237 -292.758436)
			(xy 293.953934 -292.71684) (xy 293.934643 -292.671564) (xy 293.922866 -292.62378) (xy 293.918906 -292.574726)
			(xy 293.580058 -292.574726) (xy 293.579563 -292.599333) (xy 293.571668 -292.64791) (xy 293.556084 -292.694591)
			(xy 293.533213 -292.738168) (xy 293.503648 -292.777512) (xy 293.468155 -292.811604) (xy 293.427652 -292.83956)
			(xy 293.38319 -292.860658) (xy 293.335919 -292.87435) (xy 293.287064 -292.880282) (xy 293.237889 -292.878301)
			(xy 293.18967 -292.868457) (xy 293.143654 -292.851005) (xy 293.101033 -292.826398) (xy 293.062912 -292.795273)
			(xy 293.030277 -292.758436) (xy 293.003974 -292.71684) (xy 292.984683 -292.671564) (xy 292.972906 -292.62378)
			(xy 292.968946 -292.574726) (xy 292.630098 -292.574726) (xy 292.629603 -292.599333) (xy 292.621708 -292.64791)
			(xy 292.606124 -292.694591) (xy 292.583253 -292.738168) (xy 292.553688 -292.777512) (xy 292.518195 -292.811604)
			(xy 292.477692 -292.83956) (xy 292.43323 -292.860658) (xy 292.385959 -292.87435) (xy 292.337104 -292.880282)
			(xy 292.287929 -292.878301) (xy 292.23971 -292.868457) (xy 292.193694 -292.851005) (xy 292.151073 -292.826398)
			(xy 292.112952 -292.795273) (xy 292.080317 -292.758436) (xy 292.054014 -292.71684) (xy 292.034723 -292.671564)
			(xy 292.022946 -292.62378) (xy 292.018986 -292.574726) (xy 290.730173 -292.574726) (xy 290.730178 -292.57498)
			(xy 290.729683 -292.599587) (xy 290.721788 -292.648164) (xy 290.706204 -292.694845) (xy 290.683333 -292.738422)
			(xy 290.653768 -292.777766) (xy 290.618275 -292.811858) (xy 290.577772 -292.839814) (xy 290.53331 -292.860912)
			(xy 290.486039 -292.874604) (xy 290.437184 -292.880536) (xy 290.388009 -292.878555) (xy 290.33979 -292.868711)
			(xy 290.293774 -292.851259) (xy 290.251153 -292.826652) (xy 290.213032 -292.795527) (xy 290.180397 -292.75869)
			(xy 290.154094 -292.717094) (xy 290.134803 -292.671818) (xy 290.123026 -292.624034) (xy 290.119066 -292.57498)
			(xy 289.780218 -292.57498) (xy 289.779723 -292.599587) (xy 289.771828 -292.648164) (xy 289.756244 -292.694845)
			(xy 289.733373 -292.738422) (xy 289.703808 -292.777766) (xy 289.668315 -292.811858) (xy 289.627812 -292.839814)
			(xy 289.58335 -292.860912) (xy 289.536079 -292.874604) (xy 289.487224 -292.880536) (xy 289.438049 -292.878555)
			(xy 289.38983 -292.868711) (xy 289.343814 -292.851259) (xy 289.301193 -292.826652) (xy 289.263072 -292.795527)
			(xy 289.230437 -292.75869) (xy 289.204134 -292.717094) (xy 289.184843 -292.671818) (xy 289.173066 -292.624034)
			(xy 289.169106 -292.57498) (xy 288.830258 -292.57498) (xy 288.829763 -292.599587) (xy 288.821868 -292.648164)
			(xy 288.806284 -292.694845) (xy 288.783413 -292.738422) (xy 288.753848 -292.777766) (xy 288.718355 -292.811858)
			(xy 288.677852 -292.839814) (xy 288.63339 -292.860912) (xy 288.586119 -292.874604) (xy 288.537264 -292.880536)
			(xy 288.488089 -292.878555) (xy 288.43987 -292.868711) (xy 288.393854 -292.851259) (xy 288.351233 -292.826652)
			(xy 288.313112 -292.795527) (xy 288.280477 -292.75869) (xy 288.254174 -292.717094) (xy 288.234883 -292.671818)
			(xy 288.223106 -292.624034) (xy 288.219146 -292.57498) (xy 287.880044 -292.57498) (xy 287.879549 -292.599587)
			(xy 287.871654 -292.648164) (xy 287.85607 -292.694845) (xy 287.833199 -292.738422) (xy 287.803634 -292.777766)
			(xy 287.768141 -292.811858) (xy 287.727638 -292.839814) (xy 287.683176 -292.860912) (xy 287.635905 -292.874604)
			(xy 287.58705 -292.880536) (xy 287.537875 -292.878555) (xy 287.489656 -292.868711) (xy 287.44364 -292.851259)
			(xy 287.401019 -292.826652) (xy 287.362898 -292.795527) (xy 287.330263 -292.75869) (xy 287.30396 -292.717094)
			(xy 287.284669 -292.671818) (xy 287.272892 -292.624034) (xy 287.268932 -292.57498) (xy 286.930084 -292.57498)
			(xy 286.929589 -292.599587) (xy 286.921694 -292.648164) (xy 286.90611 -292.694845) (xy 286.883239 -292.738422)
			(xy 286.853674 -292.777766) (xy 286.818181 -292.811858) (xy 286.777678 -292.839814) (xy 286.733216 -292.860912)
			(xy 286.685945 -292.874604) (xy 286.63709 -292.880536) (xy 286.587915 -292.878555) (xy 286.539696 -292.868711)
			(xy 286.49368 -292.851259) (xy 286.451059 -292.826652) (xy 286.412938 -292.795527) (xy 286.380303 -292.75869)
			(xy 286.354 -292.717094) (xy 286.334709 -292.671818) (xy 286.322932 -292.624034) (xy 286.318972 -292.57498)
			(xy 285.980124 -292.57498) (xy 285.979629 -292.599587) (xy 285.971734 -292.648164) (xy 285.95615 -292.694845)
			(xy 285.933279 -292.738422) (xy 285.903714 -292.777766) (xy 285.868221 -292.811858) (xy 285.827718 -292.839814)
			(xy 285.783256 -292.860912) (xy 285.735985 -292.874604) (xy 285.68713 -292.880536) (xy 285.637955 -292.878555)
			(xy 285.589736 -292.868711) (xy 285.54372 -292.851259) (xy 285.501099 -292.826652) (xy 285.462978 -292.795527)
			(xy 285.430343 -292.75869) (xy 285.40404 -292.717094) (xy 285.384749 -292.671818) (xy 285.372972 -292.624034)
			(xy 285.369012 -292.57498) (xy 285.030164 -292.57498) (xy 285.029669 -292.599587) (xy 285.021774 -292.648164)
			(xy 285.00619 -292.694845) (xy 284.983319 -292.738422) (xy 284.953754 -292.777766) (xy 284.918261 -292.811858)
			(xy 284.877758 -292.839814) (xy 284.833296 -292.860912) (xy 284.786025 -292.874604) (xy 284.73717 -292.880536)
			(xy 284.687995 -292.878555) (xy 284.639776 -292.868711) (xy 284.59376 -292.851259) (xy 284.551139 -292.826652)
			(xy 284.513018 -292.795527) (xy 284.480383 -292.75869) (xy 284.45408 -292.717094) (xy 284.434789 -292.671818)
			(xy 284.423012 -292.624034) (xy 284.419052 -292.57498) (xy 284.080204 -292.57498) (xy 284.079709 -292.599587)
			(xy 284.071814 -292.648164) (xy 284.05623 -292.694845) (xy 284.033359 -292.738422) (xy 284.003794 -292.777766)
			(xy 283.968301 -292.811858) (xy 283.927798 -292.839814) (xy 283.883336 -292.860912) (xy 283.836065 -292.874604)
			(xy 283.78721 -292.880536) (xy 283.738035 -292.878555) (xy 283.689816 -292.868711) (xy 283.6438 -292.851259)
			(xy 283.601179 -292.826652) (xy 283.563058 -292.795527) (xy 283.530423 -292.75869) (xy 283.50412 -292.717094)
			(xy 283.484829 -292.671818) (xy 283.473052 -292.624034) (xy 283.469092 -292.57498) (xy 283.130244 -292.57498)
			(xy 283.129749 -292.599587) (xy 283.121854 -292.648164) (xy 283.10627 -292.694845) (xy 283.083399 -292.738422)
			(xy 283.053834 -292.777766) (xy 283.018341 -292.811858) (xy 282.977838 -292.839814) (xy 282.933376 -292.860912)
			(xy 282.886105 -292.874604) (xy 282.83725 -292.880536) (xy 282.788075 -292.878555) (xy 282.739856 -292.868711)
			(xy 282.69384 -292.851259) (xy 282.651219 -292.826652) (xy 282.613098 -292.795527) (xy 282.580463 -292.75869)
			(xy 282.55416 -292.717094) (xy 282.534869 -292.671818) (xy 282.523092 -292.624034) (xy 282.519132 -292.57498)
			(xy 282.180025 -292.57498) (xy 282.179535 -292.599333) (xy 282.17164 -292.64791) (xy 282.156056 -292.694591)
			(xy 282.133185 -292.738168) (xy 282.10362 -292.777512) (xy 282.068127 -292.811604) (xy 282.027624 -292.83956)
			(xy 281.983162 -292.860658) (xy 281.935891 -292.87435) (xy 281.887036 -292.880282) (xy 281.837861 -292.878301)
			(xy 281.789642 -292.868457) (xy 281.743626 -292.851005) (xy 281.701005 -292.826398) (xy 281.662884 -292.795273)
			(xy 281.630249 -292.758436) (xy 281.603946 -292.71684) (xy 281.584655 -292.671564) (xy 281.572878 -292.62378)
			(xy 281.568918 -292.574726) (xy 280.28011 -292.574726) (xy 280.28011 -292.57498) (xy 280.28011 -292.58514)
			(xy 280.28011 -292.586918) (xy 280.279856 -292.587934) (xy 280.279602 -292.594792) (xy 280.279348 -292.595046)
			(xy 280.279348 -292.596062) (xy 280.27884 -292.608) (xy 280.277824 -292.615366) (xy 280.277824 -292.61562)
			(xy 280.276046 -292.62451) (xy 280.276046 -292.624764) (xy 280.276046 -292.625272) (xy 280.275284 -292.629082)
			(xy 280.274776 -292.632384) (xy 280.272744 -292.641274) (xy 280.269442 -292.65626) (xy 280.280364 -292.684708)
			(xy 280.304748 -292.702234) (xy 280.312622 -292.707822) (xy 280.319226 -292.712394) (xy 280.325322 -292.716458)
			(xy 280.333704 -292.722554) (xy 280.343864 -292.729666) (xy 280.349452 -292.733476) (xy 280.370788 -292.75024)
			(xy 280.373074 -292.752526) (xy 280.374344 -292.753542) (xy 280.388568 -292.767766) (xy 280.389838 -292.767766)
			(xy 280.390854 -292.769036) (xy 280.392378 -292.77056) (xy 280.39568 -292.774116) (xy 280.39695 -292.77564)
			(xy 280.404316 -292.784022) (xy 280.40457 -292.784276) (xy 280.405078 -292.784784) (xy 280.407872 -292.78834)
			(xy 280.408634 -292.78961) (xy 280.415746 -292.798246) (xy 280.416 -292.7985) (xy 280.417016 -292.79977)
			(xy 280.41727 -292.800278) (xy 280.419556 -292.803326) (xy 280.433052 -292.822908) (xy 280.454466 -292.865369)
			(xy 280.469057 -292.91063) (xy 280.476475 -292.957603) (xy 280.47696 -292.98138) (xy 280.47696 -293.52494)
			(xy 280.618958 -293.52494) (xy 280.622918 -293.475886) (xy 280.634695 -293.428102) (xy 280.653986 -293.382826)
			(xy 280.680289 -293.34123) (xy 280.712924 -293.304393) (xy 280.751045 -293.273268) (xy 280.793666 -293.248661)
			(xy 280.839682 -293.231209) (xy 280.887901 -293.221365) (xy 280.937076 -293.219384) (xy 280.985931 -293.225316)
			(xy 281.033202 -293.239008) (xy 281.077664 -293.260106) (xy 281.118167 -293.288062) (xy 281.15366 -293.322154)
			(xy 281.183225 -293.361498) (xy 281.206096 -293.405075) (xy 281.22168 -293.451756) (xy 281.229575 -293.500333)
			(xy 281.23007 -293.52494) (xy 282.519132 -293.52494) (xy 282.523092 -293.475886) (xy 282.534869 -293.428102)
			(xy 282.55416 -293.382826) (xy 282.580463 -293.34123) (xy 282.613098 -293.304393) (xy 282.651219 -293.273268)
			(xy 282.69384 -293.248661) (xy 282.739856 -293.231209) (xy 282.788075 -293.221365) (xy 282.83725 -293.219384)
			(xy 282.886105 -293.225316) (xy 282.933376 -293.239008) (xy 282.977838 -293.260106) (xy 283.018341 -293.288062)
			(xy 283.053834 -293.322154) (xy 283.083399 -293.361498) (xy 283.10627 -293.405075) (xy 283.121854 -293.451756)
			(xy 283.129749 -293.500333) (xy 283.130244 -293.52494) (xy 284.419052 -293.52494) (xy 284.423012 -293.475886)
			(xy 284.434789 -293.428102) (xy 284.45408 -293.382826) (xy 284.480383 -293.34123) (xy 284.513018 -293.304393)
			(xy 284.551139 -293.273268) (xy 284.59376 -293.248661) (xy 284.639776 -293.231209) (xy 284.687995 -293.221365)
			(xy 284.73717 -293.219384) (xy 284.786025 -293.225316) (xy 284.833296 -293.239008) (xy 284.877758 -293.260106)
			(xy 284.918261 -293.288062) (xy 284.953754 -293.322154) (xy 284.983319 -293.361498) (xy 285.00619 -293.405075)
			(xy 285.021774 -293.451756) (xy 285.029669 -293.500333) (xy 285.030164 -293.52494) (xy 286.318972 -293.52494)
			(xy 286.322932 -293.475886) (xy 286.334709 -293.428102) (xy 286.354 -293.382826) (xy 286.380303 -293.34123)
			(xy 286.412938 -293.304393) (xy 286.451059 -293.273268) (xy 286.49368 -293.248661) (xy 286.539696 -293.231209)
			(xy 286.587915 -293.221365) (xy 286.63709 -293.219384) (xy 286.685945 -293.225316) (xy 286.733216 -293.239008)
			(xy 286.777678 -293.260106) (xy 286.818181 -293.288062) (xy 286.853674 -293.322154) (xy 286.883239 -293.361498)
			(xy 286.90611 -293.405075) (xy 286.921694 -293.451756) (xy 286.929589 -293.500333) (xy 286.930084 -293.52494)
			(xy 288.218892 -293.52494) (xy 288.222852 -293.475886) (xy 288.234629 -293.428102) (xy 288.25392 -293.382826)
			(xy 288.280223 -293.34123) (xy 288.312858 -293.304393) (xy 288.350979 -293.273268) (xy 288.3936 -293.248661)
			(xy 288.439616 -293.231209) (xy 288.487835 -293.221365) (xy 288.53701 -293.219384) (xy 288.585865 -293.225316)
			(xy 288.633136 -293.239008) (xy 288.677598 -293.260106) (xy 288.718101 -293.288062) (xy 288.753594 -293.322154)
			(xy 288.783159 -293.361498) (xy 288.80603 -293.405075) (xy 288.821614 -293.451756) (xy 288.829509 -293.500333)
			(xy 288.830004 -293.52494) (xy 290.119066 -293.52494) (xy 290.123026 -293.475886) (xy 290.134803 -293.428102)
			(xy 290.154094 -293.382826) (xy 290.180397 -293.34123) (xy 290.213032 -293.304393) (xy 290.251153 -293.273268)
			(xy 290.293774 -293.248661) (xy 290.33979 -293.231209) (xy 290.388009 -293.221365) (xy 290.437184 -293.219384)
			(xy 290.486039 -293.225316) (xy 290.53331 -293.239008) (xy 290.577772 -293.260106) (xy 290.618275 -293.288062)
			(xy 290.653768 -293.322154) (xy 290.683333 -293.361498) (xy 290.706204 -293.405075) (xy 290.721788 -293.451756)
			(xy 290.729683 -293.500333) (xy 290.730178 -293.52494) (xy 292.968946 -293.52494) (xy 292.972906 -293.475886)
			(xy 292.984683 -293.428102) (xy 293.003974 -293.382826) (xy 293.030277 -293.34123) (xy 293.062912 -293.304393)
			(xy 293.101033 -293.273268) (xy 293.143654 -293.248661) (xy 293.18967 -293.231209) (xy 293.237889 -293.221365)
			(xy 293.287064 -293.219384) (xy 293.335919 -293.225316) (xy 293.38319 -293.239008) (xy 293.427652 -293.260106)
			(xy 293.468155 -293.288062) (xy 293.503648 -293.322154) (xy 293.533213 -293.361498) (xy 293.556084 -293.405075)
			(xy 293.571668 -293.451756) (xy 293.579563 -293.500333) (xy 293.580058 -293.52494) (xy 294.86912 -293.52494)
			(xy 294.87308 -293.475886) (xy 294.884857 -293.428102) (xy 294.904148 -293.382826) (xy 294.930451 -293.34123)
			(xy 294.963086 -293.304393) (xy 295.001207 -293.273268) (xy 295.043828 -293.248661) (xy 295.089844 -293.231209)
			(xy 295.138063 -293.221365) (xy 295.187238 -293.219384) (xy 295.236093 -293.225316) (xy 295.283364 -293.239008)
			(xy 295.327826 -293.260106) (xy 295.368329 -293.288062) (xy 295.403822 -293.322154) (xy 295.433387 -293.361498)
			(xy 295.456258 -293.405075) (xy 295.471842 -293.451756) (xy 295.479737 -293.500333) (xy 295.480232 -293.52494)
			(xy 296.76904 -293.52494) (xy 296.773 -293.475886) (xy 296.784777 -293.428102) (xy 296.804068 -293.382826)
			(xy 296.830371 -293.34123) (xy 296.863006 -293.304393) (xy 296.901127 -293.273268) (xy 296.943748 -293.248661)
			(xy 296.989764 -293.231209) (xy 297.037983 -293.221365) (xy 297.087158 -293.219384) (xy 297.136013 -293.225316)
			(xy 297.183284 -293.239008) (xy 297.227746 -293.260106) (xy 297.268249 -293.288062) (xy 297.303742 -293.322154)
			(xy 297.333307 -293.361498) (xy 297.356178 -293.405075) (xy 297.371762 -293.451756) (xy 297.379657 -293.500333)
			(xy 297.380152 -293.52494) (xy 298.66896 -293.52494) (xy 298.67292 -293.475886) (xy 298.684697 -293.428102)
			(xy 298.703988 -293.382826) (xy 298.730291 -293.34123) (xy 298.762926 -293.304393) (xy 298.801047 -293.273268)
			(xy 298.843668 -293.248661) (xy 298.889684 -293.231209) (xy 298.937903 -293.221365) (xy 298.987078 -293.219384)
			(xy 299.035933 -293.225316) (xy 299.083204 -293.239008) (xy 299.127666 -293.260106) (xy 299.168169 -293.288062)
			(xy 299.203662 -293.322154) (xy 299.233227 -293.361498) (xy 299.256098 -293.405075) (xy 299.271682 -293.451756)
			(xy 299.279577 -293.500333) (xy 299.280072 -293.52494) (xy 300.56888 -293.52494) (xy 300.57284 -293.475886)
			(xy 300.584617 -293.428102) (xy 300.603908 -293.382826) (xy 300.630211 -293.34123) (xy 300.662846 -293.304393)
			(xy 300.700967 -293.273268) (xy 300.743588 -293.248661) (xy 300.789604 -293.231209) (xy 300.837823 -293.221365)
			(xy 300.886998 -293.219384) (xy 300.935853 -293.225316) (xy 300.983124 -293.239008) (xy 301.027586 -293.260106)
			(xy 301.068089 -293.288062) (xy 301.103582 -293.322154) (xy 301.133147 -293.361498) (xy 301.156018 -293.405075)
			(xy 301.171602 -293.451756) (xy 301.179497 -293.500333) (xy 301.179992 -293.52494) (xy 301.519094 -293.52494)
			(xy 301.523054 -293.475886) (xy 301.534831 -293.428102) (xy 301.554122 -293.382826) (xy 301.580425 -293.34123)
			(xy 301.61306 -293.304393) (xy 301.651181 -293.273268) (xy 301.693802 -293.248661) (xy 301.739818 -293.231209)
			(xy 301.788037 -293.221365) (xy 301.837212 -293.219384) (xy 301.886067 -293.225316) (xy 301.933338 -293.239008)
			(xy 301.9778 -293.260106) (xy 302.018303 -293.288062) (xy 302.053796 -293.322154) (xy 302.083361 -293.361498)
			(xy 302.106232 -293.405075) (xy 302.121816 -293.451756) (xy 302.129711 -293.500333) (xy 302.130206 -293.52494)
			(xy 302.469054 -293.52494) (xy 302.473014 -293.475886) (xy 302.484791 -293.428102) (xy 302.504082 -293.382826)
			(xy 302.530385 -293.34123) (xy 302.56302 -293.304393) (xy 302.601141 -293.273268) (xy 302.643762 -293.248661)
			(xy 302.689778 -293.231209) (xy 302.737997 -293.221365) (xy 302.787172 -293.219384) (xy 302.836027 -293.225316)
			(xy 302.883298 -293.239008) (xy 302.92776 -293.260106) (xy 302.968263 -293.288062) (xy 303.003756 -293.322154)
			(xy 303.033321 -293.361498) (xy 303.056192 -293.405075) (xy 303.071776 -293.451756) (xy 303.079671 -293.500333)
			(xy 303.080166 -293.52494) (xy 303.419014 -293.52494) (xy 303.422974 -293.475886) (xy 303.434751 -293.428102)
			(xy 303.454042 -293.382826) (xy 303.480345 -293.34123) (xy 303.51298 -293.304393) (xy 303.551101 -293.273268)
			(xy 303.593722 -293.248661) (xy 303.639738 -293.231209) (xy 303.687957 -293.221365) (xy 303.737132 -293.219384)
			(xy 303.785987 -293.225316) (xy 303.833258 -293.239008) (xy 303.87772 -293.260106) (xy 303.918223 -293.288062)
			(xy 303.953716 -293.322154) (xy 303.983281 -293.361498) (xy 304.006152 -293.405075) (xy 304.021736 -293.451756)
			(xy 304.029631 -293.500333) (xy 304.030126 -293.52494) (xy 304.368974 -293.52494) (xy 304.372934 -293.475886)
			(xy 304.384711 -293.428102) (xy 304.404002 -293.382826) (xy 304.430305 -293.34123) (xy 304.46294 -293.304393)
			(xy 304.501061 -293.273268) (xy 304.543682 -293.248661) (xy 304.589698 -293.231209) (xy 304.637917 -293.221365)
			(xy 304.687092 -293.219384) (xy 304.735947 -293.225316) (xy 304.783218 -293.239008) (xy 304.82768 -293.260106)
			(xy 304.868183 -293.288062) (xy 304.903676 -293.322154) (xy 304.933241 -293.361498) (xy 304.956112 -293.405075)
			(xy 304.971696 -293.451756) (xy 304.979591 -293.500333) (xy 304.980086 -293.52494) (xy 305.318934 -293.52494)
			(xy 305.322894 -293.475886) (xy 305.334671 -293.428102) (xy 305.353962 -293.382826) (xy 305.380265 -293.34123)
			(xy 305.4129 -293.304393) (xy 305.451021 -293.273268) (xy 305.493642 -293.248661) (xy 305.539658 -293.231209)
			(xy 305.587877 -293.221365) (xy 305.637052 -293.219384) (xy 305.685907 -293.225316) (xy 305.733178 -293.239008)
			(xy 305.77764 -293.260106) (xy 305.818143 -293.288062) (xy 305.853636 -293.322154) (xy 305.883201 -293.361498)
			(xy 305.906072 -293.405075) (xy 305.921656 -293.451756) (xy 305.929551 -293.500333) (xy 305.930046 -293.52494)
			(xy 306.269148 -293.52494) (xy 306.273108 -293.475886) (xy 306.284885 -293.428102) (xy 306.304176 -293.382826)
			(xy 306.330479 -293.34123) (xy 306.363114 -293.304393) (xy 306.401235 -293.273268) (xy 306.443856 -293.248661)
			(xy 306.489872 -293.231209) (xy 306.538091 -293.221365) (xy 306.587266 -293.219384) (xy 306.636121 -293.225316)
			(xy 306.683392 -293.239008) (xy 306.727854 -293.260106) (xy 306.768357 -293.288062) (xy 306.80385 -293.322154)
			(xy 306.833415 -293.361498) (xy 306.856286 -293.405075) (xy 306.87187 -293.451756) (xy 306.879765 -293.500333)
			(xy 306.88026 -293.52494) (xy 307.219108 -293.52494) (xy 307.223068 -293.475886) (xy 307.234845 -293.428102)
			(xy 307.254136 -293.382826) (xy 307.280439 -293.34123) (xy 307.313074 -293.304393) (xy 307.351195 -293.273268)
			(xy 307.393816 -293.248661) (xy 307.439832 -293.231209) (xy 307.488051 -293.221365) (xy 307.537226 -293.219384)
			(xy 307.586081 -293.225316) (xy 307.633352 -293.239008) (xy 307.677814 -293.260106) (xy 307.718317 -293.288062)
			(xy 307.75381 -293.322154) (xy 307.783375 -293.361498) (xy 307.806246 -293.405075) (xy 307.82183 -293.451756)
			(xy 307.829725 -293.500333) (xy 307.83022 -293.52494) (xy 308.169068 -293.52494) (xy 308.173028 -293.475886)
			(xy 308.184805 -293.428102) (xy 308.204096 -293.382826) (xy 308.230399 -293.34123) (xy 308.263034 -293.304393)
			(xy 308.301155 -293.273268) (xy 308.343776 -293.248661) (xy 308.389792 -293.231209) (xy 308.438011 -293.221365)
			(xy 308.487186 -293.219384) (xy 308.536041 -293.225316) (xy 308.583312 -293.239008) (xy 308.627774 -293.260106)
			(xy 308.668277 -293.288062) (xy 308.70377 -293.322154) (xy 308.733335 -293.361498) (xy 308.756206 -293.405075)
			(xy 308.77179 -293.451756) (xy 308.779685 -293.500333) (xy 308.78018 -293.52494) (xy 309.119028 -293.52494)
			(xy 309.122988 -293.475886) (xy 309.134765 -293.428102) (xy 309.154056 -293.382826) (xy 309.180359 -293.34123)
			(xy 309.212994 -293.304393) (xy 309.251115 -293.273268) (xy 309.293736 -293.248661) (xy 309.339752 -293.231209)
			(xy 309.387971 -293.221365) (xy 309.437146 -293.219384) (xy 309.486001 -293.225316) (xy 309.533272 -293.239008)
			(xy 309.577734 -293.260106) (xy 309.618237 -293.288062) (xy 309.65373 -293.322154) (xy 309.683295 -293.361498)
			(xy 309.706166 -293.405075) (xy 309.72175 -293.451756) (xy 309.729645 -293.500333) (xy 309.73014 -293.52494)
			(xy 310.068988 -293.52494) (xy 310.072948 -293.475886) (xy 310.084725 -293.428102) (xy 310.104016 -293.382826)
			(xy 310.130319 -293.34123) (xy 310.162954 -293.304393) (xy 310.201075 -293.273268) (xy 310.243696 -293.248661)
			(xy 310.289712 -293.231209) (xy 310.337931 -293.221365) (xy 310.387106 -293.219384) (xy 310.435961 -293.225316)
			(xy 310.483232 -293.239008) (xy 310.527694 -293.260106) (xy 310.568197 -293.288062) (xy 310.60369 -293.322154)
			(xy 310.633255 -293.361498) (xy 310.656126 -293.405075) (xy 310.67171 -293.451756) (xy 310.679605 -293.500333)
			(xy 310.6801 -293.52494) (xy 311.018948 -293.52494) (xy 311.022908 -293.475886) (xy 311.034685 -293.428102)
			(xy 311.053976 -293.382826) (xy 311.080279 -293.34123) (xy 311.112914 -293.304393) (xy 311.151035 -293.273268)
			(xy 311.193656 -293.248661) (xy 311.239672 -293.231209) (xy 311.287891 -293.221365) (xy 311.337066 -293.219384)
			(xy 311.385921 -293.225316) (xy 311.433192 -293.239008) (xy 311.477654 -293.260106) (xy 311.518157 -293.288062)
			(xy 311.55365 -293.322154) (xy 311.583215 -293.361498) (xy 311.606086 -293.405075) (xy 311.62167 -293.451756)
			(xy 311.629565 -293.500333) (xy 311.63006 -293.52494) (xy 311.968908 -293.52494) (xy 311.972868 -293.475886)
			(xy 311.984645 -293.428102) (xy 312.003936 -293.382826) (xy 312.030239 -293.34123) (xy 312.062874 -293.304393)
			(xy 312.100995 -293.273268) (xy 312.143616 -293.248661) (xy 312.189632 -293.231209) (xy 312.237851 -293.221365)
			(xy 312.287026 -293.219384) (xy 312.335881 -293.225316) (xy 312.383152 -293.239008) (xy 312.427614 -293.260106)
			(xy 312.468117 -293.288062) (xy 312.50361 -293.322154) (xy 312.533175 -293.361498) (xy 312.556046 -293.405075)
			(xy 312.57163 -293.451756) (xy 312.579525 -293.500333) (xy 312.58002 -293.52494) (xy 312.919122 -293.52494)
			(xy 312.923082 -293.475886) (xy 312.934859 -293.428102) (xy 312.95415 -293.382826) (xy 312.980453 -293.34123)
			(xy 313.013088 -293.304393) (xy 313.051209 -293.273268) (xy 313.09383 -293.248661) (xy 313.139846 -293.231209)
			(xy 313.188065 -293.221365) (xy 313.23724 -293.219384) (xy 313.286095 -293.225316) (xy 313.333366 -293.239008)
			(xy 313.377828 -293.260106) (xy 313.418331 -293.288062) (xy 313.453824 -293.322154) (xy 313.483389 -293.361498)
			(xy 313.50626 -293.405075) (xy 313.521844 -293.451756) (xy 313.529739 -293.500333) (xy 313.530234 -293.52494)
			(xy 313.869082 -293.52494) (xy 313.873042 -293.475886) (xy 313.884819 -293.428102) (xy 313.90411 -293.382826)
			(xy 313.930413 -293.34123) (xy 313.963048 -293.304393) (xy 314.001169 -293.273268) (xy 314.04379 -293.248661)
			(xy 314.089806 -293.231209) (xy 314.138025 -293.221365) (xy 314.1872 -293.219384) (xy 314.236055 -293.225316)
			(xy 314.283326 -293.239008) (xy 314.327788 -293.260106) (xy 314.368291 -293.288062) (xy 314.403784 -293.322154)
			(xy 314.433349 -293.361498) (xy 314.45622 -293.405075) (xy 314.471804 -293.451756) (xy 314.479699 -293.500333)
			(xy 314.480194 -293.52494) (xy 314.819042 -293.52494) (xy 314.823002 -293.475886) (xy 314.834779 -293.428102)
			(xy 314.85407 -293.382826) (xy 314.880373 -293.34123) (xy 314.913008 -293.304393) (xy 314.951129 -293.273268)
			(xy 314.99375 -293.248661) (xy 315.039766 -293.231209) (xy 315.087985 -293.221365) (xy 315.13716 -293.219384)
			(xy 315.186015 -293.225316) (xy 315.233286 -293.239008) (xy 315.277748 -293.260106) (xy 315.318251 -293.288062)
			(xy 315.353744 -293.322154) (xy 315.383309 -293.361498) (xy 315.40618 -293.405075) (xy 315.421764 -293.451756)
			(xy 315.429659 -293.500333) (xy 315.430154 -293.52494) (xy 315.429659 -293.549547) (xy 315.421764 -293.598124)
			(xy 315.40618 -293.644805) (xy 315.383309 -293.688382) (xy 315.353744 -293.727726) (xy 315.318251 -293.761818)
			(xy 315.277748 -293.789774) (xy 315.233286 -293.810872) (xy 315.186015 -293.824564) (xy 315.13716 -293.830496)
			(xy 315.087985 -293.828515) (xy 315.039766 -293.818671) (xy 314.99375 -293.801219) (xy 314.951129 -293.776612)
			(xy 314.913008 -293.745487) (xy 314.880373 -293.70865) (xy 314.85407 -293.667054) (xy 314.834779 -293.621778)
			(xy 314.823002 -293.573994) (xy 314.819042 -293.52494) (xy 314.480194 -293.52494) (xy 314.479699 -293.549547)
			(xy 314.471804 -293.598124) (xy 314.45622 -293.644805) (xy 314.433349 -293.688382) (xy 314.403784 -293.727726)
			(xy 314.368291 -293.761818) (xy 314.327788 -293.789774) (xy 314.283326 -293.810872) (xy 314.236055 -293.824564)
			(xy 314.1872 -293.830496) (xy 314.138025 -293.828515) (xy 314.089806 -293.818671) (xy 314.04379 -293.801219)
			(xy 314.001169 -293.776612) (xy 313.963048 -293.745487) (xy 313.930413 -293.70865) (xy 313.90411 -293.667054)
			(xy 313.884819 -293.621778) (xy 313.873042 -293.573994) (xy 313.869082 -293.52494) (xy 313.530234 -293.52494)
			(xy 313.529739 -293.549547) (xy 313.521844 -293.598124) (xy 313.50626 -293.644805) (xy 313.483389 -293.688382)
			(xy 313.453824 -293.727726) (xy 313.418331 -293.761818) (xy 313.377828 -293.789774) (xy 313.333366 -293.810872)
			(xy 313.286095 -293.824564) (xy 313.23724 -293.830496) (xy 313.188065 -293.828515) (xy 313.139846 -293.818671)
			(xy 313.09383 -293.801219) (xy 313.051209 -293.776612) (xy 313.013088 -293.745487) (xy 312.980453 -293.70865)
			(xy 312.95415 -293.667054) (xy 312.934859 -293.621778) (xy 312.923082 -293.573994) (xy 312.919122 -293.52494)
			(xy 312.58002 -293.52494) (xy 312.579525 -293.549547) (xy 312.57163 -293.598124) (xy 312.556046 -293.644805)
			(xy 312.533175 -293.688382) (xy 312.50361 -293.727726) (xy 312.468117 -293.761818) (xy 312.427614 -293.789774)
			(xy 312.383152 -293.810872) (xy 312.335881 -293.824564) (xy 312.287026 -293.830496) (xy 312.237851 -293.828515)
			(xy 312.189632 -293.818671) (xy 312.143616 -293.801219) (xy 312.100995 -293.776612) (xy 312.062874 -293.745487)
			(xy 312.030239 -293.70865) (xy 312.003936 -293.667054) (xy 311.984645 -293.621778) (xy 311.972868 -293.573994)
			(xy 311.968908 -293.52494) (xy 311.63006 -293.52494) (xy 311.629565 -293.549547) (xy 311.62167 -293.598124)
			(xy 311.606086 -293.644805) (xy 311.583215 -293.688382) (xy 311.55365 -293.727726) (xy 311.518157 -293.761818)
			(xy 311.477654 -293.789774) (xy 311.433192 -293.810872) (xy 311.385921 -293.824564) (xy 311.337066 -293.830496)
			(xy 311.287891 -293.828515) (xy 311.239672 -293.818671) (xy 311.193656 -293.801219) (xy 311.151035 -293.776612)
			(xy 311.112914 -293.745487) (xy 311.080279 -293.70865) (xy 311.053976 -293.667054) (xy 311.034685 -293.621778)
			(xy 311.022908 -293.573994) (xy 311.018948 -293.52494) (xy 310.6801 -293.52494) (xy 310.679605 -293.549547)
			(xy 310.67171 -293.598124) (xy 310.656126 -293.644805) (xy 310.633255 -293.688382) (xy 310.60369 -293.727726)
			(xy 310.568197 -293.761818) (xy 310.527694 -293.789774) (xy 310.483232 -293.810872) (xy 310.435961 -293.824564)
			(xy 310.387106 -293.830496) (xy 310.337931 -293.828515) (xy 310.289712 -293.818671) (xy 310.243696 -293.801219)
			(xy 310.201075 -293.776612) (xy 310.162954 -293.745487) (xy 310.130319 -293.70865) (xy 310.104016 -293.667054)
			(xy 310.084725 -293.621778) (xy 310.072948 -293.573994) (xy 310.068988 -293.52494) (xy 309.73014 -293.52494)
			(xy 309.729645 -293.549547) (xy 309.72175 -293.598124) (xy 309.706166 -293.644805) (xy 309.683295 -293.688382)
			(xy 309.65373 -293.727726) (xy 309.618237 -293.761818) (xy 309.577734 -293.789774) (xy 309.533272 -293.810872)
			(xy 309.486001 -293.824564) (xy 309.437146 -293.830496) (xy 309.387971 -293.828515) (xy 309.339752 -293.818671)
			(xy 309.293736 -293.801219) (xy 309.251115 -293.776612) (xy 309.212994 -293.745487) (xy 309.180359 -293.70865)
			(xy 309.154056 -293.667054) (xy 309.134765 -293.621778) (xy 309.122988 -293.573994) (xy 309.119028 -293.52494)
			(xy 308.78018 -293.52494) (xy 308.779685 -293.549547) (xy 308.77179 -293.598124) (xy 308.756206 -293.644805)
			(xy 308.733335 -293.688382) (xy 308.70377 -293.727726) (xy 308.668277 -293.761818) (xy 308.627774 -293.789774)
			(xy 308.583312 -293.810872) (xy 308.536041 -293.824564) (xy 308.487186 -293.830496) (xy 308.438011 -293.828515)
			(xy 308.389792 -293.818671) (xy 308.343776 -293.801219) (xy 308.301155 -293.776612) (xy 308.263034 -293.745487)
			(xy 308.230399 -293.70865) (xy 308.204096 -293.667054) (xy 308.184805 -293.621778) (xy 308.173028 -293.573994)
			(xy 308.169068 -293.52494) (xy 307.83022 -293.52494) (xy 307.829725 -293.549547) (xy 307.82183 -293.598124)
			(xy 307.806246 -293.644805) (xy 307.783375 -293.688382) (xy 307.75381 -293.727726) (xy 307.718317 -293.761818)
			(xy 307.677814 -293.789774) (xy 307.633352 -293.810872) (xy 307.586081 -293.824564) (xy 307.537226 -293.830496)
			(xy 307.488051 -293.828515) (xy 307.439832 -293.818671) (xy 307.393816 -293.801219) (xy 307.351195 -293.776612)
			(xy 307.313074 -293.745487) (xy 307.280439 -293.70865) (xy 307.254136 -293.667054) (xy 307.234845 -293.621778)
			(xy 307.223068 -293.573994) (xy 307.219108 -293.52494) (xy 306.88026 -293.52494) (xy 306.879765 -293.549547)
			(xy 306.87187 -293.598124) (xy 306.856286 -293.644805) (xy 306.833415 -293.688382) (xy 306.80385 -293.727726)
			(xy 306.768357 -293.761818) (xy 306.727854 -293.789774) (xy 306.683392 -293.810872) (xy 306.636121 -293.824564)
			(xy 306.587266 -293.830496) (xy 306.538091 -293.828515) (xy 306.489872 -293.818671) (xy 306.443856 -293.801219)
			(xy 306.401235 -293.776612) (xy 306.363114 -293.745487) (xy 306.330479 -293.70865) (xy 306.304176 -293.667054)
			(xy 306.284885 -293.621778) (xy 306.273108 -293.573994) (xy 306.269148 -293.52494) (xy 305.930046 -293.52494)
			(xy 305.929551 -293.549547) (xy 305.921656 -293.598124) (xy 305.906072 -293.644805) (xy 305.883201 -293.688382)
			(xy 305.853636 -293.727726) (xy 305.818143 -293.761818) (xy 305.77764 -293.789774) (xy 305.733178 -293.810872)
			(xy 305.685907 -293.824564) (xy 305.637052 -293.830496) (xy 305.587877 -293.828515) (xy 305.539658 -293.818671)
			(xy 305.493642 -293.801219) (xy 305.451021 -293.776612) (xy 305.4129 -293.745487) (xy 305.380265 -293.70865)
			(xy 305.353962 -293.667054) (xy 305.334671 -293.621778) (xy 305.322894 -293.573994) (xy 305.318934 -293.52494)
			(xy 304.980086 -293.52494) (xy 304.979591 -293.549547) (xy 304.971696 -293.598124) (xy 304.956112 -293.644805)
			(xy 304.933241 -293.688382) (xy 304.903676 -293.727726) (xy 304.868183 -293.761818) (xy 304.82768 -293.789774)
			(xy 304.783218 -293.810872) (xy 304.735947 -293.824564) (xy 304.687092 -293.830496) (xy 304.637917 -293.828515)
			(xy 304.589698 -293.818671) (xy 304.543682 -293.801219) (xy 304.501061 -293.776612) (xy 304.46294 -293.745487)
			(xy 304.430305 -293.70865) (xy 304.404002 -293.667054) (xy 304.384711 -293.621778) (xy 304.372934 -293.573994)
			(xy 304.368974 -293.52494) (xy 304.030126 -293.52494) (xy 304.029631 -293.549547) (xy 304.021736 -293.598124)
			(xy 304.006152 -293.644805) (xy 303.983281 -293.688382) (xy 303.953716 -293.727726) (xy 303.918223 -293.761818)
			(xy 303.87772 -293.789774) (xy 303.833258 -293.810872) (xy 303.785987 -293.824564) (xy 303.737132 -293.830496)
			(xy 303.687957 -293.828515) (xy 303.639738 -293.818671) (xy 303.593722 -293.801219) (xy 303.551101 -293.776612)
			(xy 303.51298 -293.745487) (xy 303.480345 -293.70865) (xy 303.454042 -293.667054) (xy 303.434751 -293.621778)
			(xy 303.422974 -293.573994) (xy 303.419014 -293.52494) (xy 303.080166 -293.52494) (xy 303.079671 -293.549547)
			(xy 303.071776 -293.598124) (xy 303.056192 -293.644805) (xy 303.033321 -293.688382) (xy 303.003756 -293.727726)
			(xy 302.968263 -293.761818) (xy 302.92776 -293.789774) (xy 302.883298 -293.810872) (xy 302.836027 -293.824564)
			(xy 302.787172 -293.830496) (xy 302.737997 -293.828515) (xy 302.689778 -293.818671) (xy 302.643762 -293.801219)
			(xy 302.601141 -293.776612) (xy 302.56302 -293.745487) (xy 302.530385 -293.70865) (xy 302.504082 -293.667054)
			(xy 302.484791 -293.621778) (xy 302.473014 -293.573994) (xy 302.469054 -293.52494) (xy 302.130206 -293.52494)
			(xy 302.129711 -293.549547) (xy 302.121816 -293.598124) (xy 302.106232 -293.644805) (xy 302.083361 -293.688382)
			(xy 302.053796 -293.727726) (xy 302.018303 -293.761818) (xy 301.9778 -293.789774) (xy 301.933338 -293.810872)
			(xy 301.886067 -293.824564) (xy 301.837212 -293.830496) (xy 301.788037 -293.828515) (xy 301.739818 -293.818671)
			(xy 301.693802 -293.801219) (xy 301.651181 -293.776612) (xy 301.61306 -293.745487) (xy 301.580425 -293.70865)
			(xy 301.554122 -293.667054) (xy 301.534831 -293.621778) (xy 301.523054 -293.573994) (xy 301.519094 -293.52494)
			(xy 301.179992 -293.52494) (xy 301.179497 -293.549547) (xy 301.171602 -293.598124) (xy 301.156018 -293.644805)
			(xy 301.133147 -293.688382) (xy 301.103582 -293.727726) (xy 301.068089 -293.761818) (xy 301.027586 -293.789774)
			(xy 300.983124 -293.810872) (xy 300.935853 -293.824564) (xy 300.886998 -293.830496) (xy 300.837823 -293.828515)
			(xy 300.789604 -293.818671) (xy 300.743588 -293.801219) (xy 300.700967 -293.776612) (xy 300.662846 -293.745487)
			(xy 300.630211 -293.70865) (xy 300.603908 -293.667054) (xy 300.584617 -293.621778) (xy 300.57284 -293.573994)
			(xy 300.56888 -293.52494) (xy 299.280072 -293.52494) (xy 299.279577 -293.549547) (xy 299.271682 -293.598124)
			(xy 299.256098 -293.644805) (xy 299.233227 -293.688382) (xy 299.203662 -293.727726) (xy 299.168169 -293.761818)
			(xy 299.127666 -293.789774) (xy 299.083204 -293.810872) (xy 299.035933 -293.824564) (xy 298.987078 -293.830496)
			(xy 298.937903 -293.828515) (xy 298.889684 -293.818671) (xy 298.843668 -293.801219) (xy 298.801047 -293.776612)
			(xy 298.762926 -293.745487) (xy 298.730291 -293.70865) (xy 298.703988 -293.667054) (xy 298.684697 -293.621778)
			(xy 298.67292 -293.573994) (xy 298.66896 -293.52494) (xy 297.380152 -293.52494) (xy 297.379657 -293.549547)
			(xy 297.371762 -293.598124) (xy 297.356178 -293.644805) (xy 297.333307 -293.688382) (xy 297.303742 -293.727726)
			(xy 297.268249 -293.761818) (xy 297.227746 -293.789774) (xy 297.183284 -293.810872) (xy 297.136013 -293.824564)
			(xy 297.087158 -293.830496) (xy 297.037983 -293.828515) (xy 296.989764 -293.818671) (xy 296.943748 -293.801219)
			(xy 296.901127 -293.776612) (xy 296.863006 -293.745487) (xy 296.830371 -293.70865) (xy 296.804068 -293.667054)
			(xy 296.784777 -293.621778) (xy 296.773 -293.573994) (xy 296.76904 -293.52494) (xy 295.480232 -293.52494)
			(xy 295.479737 -293.549547) (xy 295.471842 -293.598124) (xy 295.456258 -293.644805) (xy 295.433387 -293.688382)
			(xy 295.403822 -293.727726) (xy 295.368329 -293.761818) (xy 295.327826 -293.789774) (xy 295.283364 -293.810872)
			(xy 295.236093 -293.824564) (xy 295.187238 -293.830496) (xy 295.138063 -293.828515) (xy 295.089844 -293.818671)
			(xy 295.043828 -293.801219) (xy 295.001207 -293.776612) (xy 294.963086 -293.745487) (xy 294.930451 -293.70865)
			(xy 294.904148 -293.667054) (xy 294.884857 -293.621778) (xy 294.87308 -293.573994) (xy 294.86912 -293.52494)
			(xy 293.580058 -293.52494) (xy 293.579563 -293.549547) (xy 293.571668 -293.598124) (xy 293.556084 -293.644805)
			(xy 293.533213 -293.688382) (xy 293.503648 -293.727726) (xy 293.468155 -293.761818) (xy 293.427652 -293.789774)
			(xy 293.38319 -293.810872) (xy 293.335919 -293.824564) (xy 293.287064 -293.830496) (xy 293.237889 -293.828515)
			(xy 293.18967 -293.818671) (xy 293.143654 -293.801219) (xy 293.101033 -293.776612) (xy 293.062912 -293.745487)
			(xy 293.030277 -293.70865) (xy 293.003974 -293.667054) (xy 292.984683 -293.621778) (xy 292.972906 -293.573994)
			(xy 292.968946 -293.52494) (xy 290.730178 -293.52494) (xy 290.729683 -293.549547) (xy 290.721788 -293.598124)
			(xy 290.706204 -293.644805) (xy 290.683333 -293.688382) (xy 290.653768 -293.727726) (xy 290.618275 -293.761818)
			(xy 290.577772 -293.789774) (xy 290.53331 -293.810872) (xy 290.486039 -293.824564) (xy 290.437184 -293.830496)
			(xy 290.388009 -293.828515) (xy 290.33979 -293.818671) (xy 290.293774 -293.801219) (xy 290.251153 -293.776612)
			(xy 290.213032 -293.745487) (xy 290.180397 -293.70865) (xy 290.154094 -293.667054) (xy 290.134803 -293.621778)
			(xy 290.123026 -293.573994) (xy 290.119066 -293.52494) (xy 288.830004 -293.52494) (xy 288.829509 -293.549547)
			(xy 288.821614 -293.598124) (xy 288.80603 -293.644805) (xy 288.783159 -293.688382) (xy 288.753594 -293.727726)
			(xy 288.718101 -293.761818) (xy 288.677598 -293.789774) (xy 288.633136 -293.810872) (xy 288.585865 -293.824564)
			(xy 288.53701 -293.830496) (xy 288.487835 -293.828515) (xy 288.439616 -293.818671) (xy 288.3936 -293.801219)
			(xy 288.350979 -293.776612) (xy 288.312858 -293.745487) (xy 288.280223 -293.70865) (xy 288.25392 -293.667054)
			(xy 288.234629 -293.621778) (xy 288.222852 -293.573994) (xy 288.218892 -293.52494) (xy 286.930084 -293.52494)
			(xy 286.929589 -293.549547) (xy 286.921694 -293.598124) (xy 286.90611 -293.644805) (xy 286.883239 -293.688382)
			(xy 286.853674 -293.727726) (xy 286.818181 -293.761818) (xy 286.777678 -293.789774) (xy 286.733216 -293.810872)
			(xy 286.685945 -293.824564) (xy 286.63709 -293.830496) (xy 286.587915 -293.828515) (xy 286.539696 -293.818671)
			(xy 286.49368 -293.801219) (xy 286.451059 -293.776612) (xy 286.412938 -293.745487) (xy 286.380303 -293.70865)
			(xy 286.354 -293.667054) (xy 286.334709 -293.621778) (xy 286.322932 -293.573994) (xy 286.318972 -293.52494)
			(xy 285.030164 -293.52494) (xy 285.029669 -293.549547) (xy 285.021774 -293.598124) (xy 285.00619 -293.644805)
			(xy 284.983319 -293.688382) (xy 284.953754 -293.727726) (xy 284.918261 -293.761818) (xy 284.877758 -293.789774)
			(xy 284.833296 -293.810872) (xy 284.786025 -293.824564) (xy 284.73717 -293.830496) (xy 284.687995 -293.828515)
			(xy 284.639776 -293.818671) (xy 284.59376 -293.801219) (xy 284.551139 -293.776612) (xy 284.513018 -293.745487)
			(xy 284.480383 -293.70865) (xy 284.45408 -293.667054) (xy 284.434789 -293.621778) (xy 284.423012 -293.573994)
			(xy 284.419052 -293.52494) (xy 283.130244 -293.52494) (xy 283.129749 -293.549547) (xy 283.121854 -293.598124)
			(xy 283.10627 -293.644805) (xy 283.083399 -293.688382) (xy 283.053834 -293.727726) (xy 283.018341 -293.761818)
			(xy 282.977838 -293.789774) (xy 282.933376 -293.810872) (xy 282.886105 -293.824564) (xy 282.83725 -293.830496)
			(xy 282.788075 -293.828515) (xy 282.739856 -293.818671) (xy 282.69384 -293.801219) (xy 282.651219 -293.776612)
			(xy 282.613098 -293.745487) (xy 282.580463 -293.70865) (xy 282.55416 -293.667054) (xy 282.534869 -293.621778)
			(xy 282.523092 -293.573994) (xy 282.519132 -293.52494) (xy 281.23007 -293.52494) (xy 281.229575 -293.549547)
			(xy 281.22168 -293.598124) (xy 281.206096 -293.644805) (xy 281.183225 -293.688382) (xy 281.15366 -293.727726)
			(xy 281.118167 -293.761818) (xy 281.077664 -293.789774) (xy 281.033202 -293.810872) (xy 280.985931 -293.824564)
			(xy 280.937076 -293.830496) (xy 280.887901 -293.828515) (xy 280.839682 -293.818671) (xy 280.793666 -293.801219)
			(xy 280.751045 -293.776612) (xy 280.712924 -293.745487) (xy 280.680289 -293.70865) (xy 280.653986 -293.667054)
			(xy 280.634695 -293.621778) (xy 280.622918 -293.573994) (xy 280.618958 -293.52494) (xy 280.47696 -293.52494)
			(xy 280.47696 -293.653464) (xy 280.476373 -293.681076) (xy 280.466447 -293.735399) (xy 280.446895 -293.787044)
			(xy 280.418357 -293.834321) (xy 280.400506 -293.855394) (xy 280.399744 -293.856156) (xy 280.399236 -293.856664)
			(xy 280.398982 -293.856918) (xy 280.396442 -293.859712) (xy 280.394156 -293.862252) (xy 280.393902 -293.862506)
			(xy 280.39187 -293.864538) (xy 280.391362 -293.865046) (xy 280.388822 -293.86784) (xy 280.38806 -293.868602)
			(xy 280.387806 -293.868602) (xy 280.3525 -293.903908) (xy 280.283158 -293.973504) (xy 280.276479 -293.980916)
			(xy 280.268905 -293.999351) (xy 280.268426 -294.009318) (xy 280.268426 -294.380158) (xy 280.268934 -294.386254)
			(xy 280.270204 -294.39743) (xy 280.270966 -294.400732) (xy 280.270966 -294.40124) (xy 280.275217 -294.419358)
			(xy 280.279802 -294.456292) (xy 280.28011 -294.4749) (xy 281.568918 -294.4749) (xy 281.572878 -294.425846)
			(xy 281.584655 -294.378062) (xy 281.603946 -294.332786) (xy 281.630249 -294.29119) (xy 281.662884 -294.254353)
			(xy 281.701005 -294.223228) (xy 281.743626 -294.198621) (xy 281.789642 -294.181169) (xy 281.837861 -294.171325)
			(xy 281.887036 -294.169344) (xy 281.935891 -294.175276) (xy 281.983162 -294.188968) (xy 282.027624 -294.210066)
			(xy 282.068127 -294.238022) (xy 282.10362 -294.272114) (xy 282.133185 -294.311458) (xy 282.156056 -294.355035)
			(xy 282.17164 -294.401716) (xy 282.179535 -294.450293) (xy 282.18003 -294.4749) (xy 283.469092 -294.4749)
			(xy 283.473052 -294.425846) (xy 283.484829 -294.378062) (xy 283.50412 -294.332786) (xy 283.530423 -294.29119)
			(xy 283.563058 -294.254353) (xy 283.601179 -294.223228) (xy 283.6438 -294.198621) (xy 283.689816 -294.181169)
			(xy 283.738035 -294.171325) (xy 283.78721 -294.169344) (xy 283.836065 -294.175276) (xy 283.883336 -294.188968)
			(xy 283.927798 -294.210066) (xy 283.968301 -294.238022) (xy 284.003794 -294.272114) (xy 284.033359 -294.311458)
			(xy 284.05623 -294.355035) (xy 284.071814 -294.401716) (xy 284.079709 -294.450293) (xy 284.080204 -294.4749)
			(xy 285.369012 -294.4749) (xy 285.372972 -294.425846) (xy 285.384749 -294.378062) (xy 285.40404 -294.332786)
			(xy 285.430343 -294.29119) (xy 285.462978 -294.254353) (xy 285.501099 -294.223228) (xy 285.54372 -294.198621)
			(xy 285.589736 -294.181169) (xy 285.637955 -294.171325) (xy 285.68713 -294.169344) (xy 285.735985 -294.175276)
			(xy 285.783256 -294.188968) (xy 285.827718 -294.210066) (xy 285.868221 -294.238022) (xy 285.903714 -294.272114)
			(xy 285.933279 -294.311458) (xy 285.95615 -294.355035) (xy 285.971734 -294.401716) (xy 285.979629 -294.450293)
			(xy 285.980124 -294.4749) (xy 287.268932 -294.4749) (xy 287.272892 -294.425846) (xy 287.284669 -294.378062)
			(xy 287.30396 -294.332786) (xy 287.330263 -294.29119) (xy 287.362898 -294.254353) (xy 287.401019 -294.223228)
			(xy 287.44364 -294.198621) (xy 287.489656 -294.181169) (xy 287.537875 -294.171325) (xy 287.58705 -294.169344)
			(xy 287.635905 -294.175276) (xy 287.683176 -294.188968) (xy 287.727638 -294.210066) (xy 287.768141 -294.238022)
			(xy 287.803634 -294.272114) (xy 287.833199 -294.311458) (xy 287.85607 -294.355035) (xy 287.871654 -294.401716)
			(xy 287.879549 -294.450293) (xy 287.880044 -294.4749) (xy 289.169106 -294.4749) (xy 289.173066 -294.425846)
			(xy 289.184843 -294.378062) (xy 289.204134 -294.332786) (xy 289.230437 -294.29119) (xy 289.263072 -294.254353)
			(xy 289.301193 -294.223228) (xy 289.343814 -294.198621) (xy 289.38983 -294.181169) (xy 289.438049 -294.171325)
			(xy 289.487224 -294.169344) (xy 289.536079 -294.175276) (xy 289.58335 -294.188968) (xy 289.627812 -294.210066)
			(xy 289.668315 -294.238022) (xy 289.703808 -294.272114) (xy 289.733373 -294.311458) (xy 289.756244 -294.355035)
			(xy 289.771828 -294.401716) (xy 289.779723 -294.450293) (xy 289.780218 -294.4749) (xy 292.018986 -294.4749)
			(xy 292.022946 -294.425846) (xy 292.034723 -294.378062) (xy 292.054014 -294.332786) (xy 292.080317 -294.29119)
			(xy 292.112952 -294.254353) (xy 292.151073 -294.223228) (xy 292.193694 -294.198621) (xy 292.23971 -294.181169)
			(xy 292.287929 -294.171325) (xy 292.337104 -294.169344) (xy 292.385959 -294.175276) (xy 292.43323 -294.188968)
			(xy 292.477692 -294.210066) (xy 292.518195 -294.238022) (xy 292.553688 -294.272114) (xy 292.583253 -294.311458)
			(xy 292.606124 -294.355035) (xy 292.621708 -294.401716) (xy 292.629603 -294.450293) (xy 292.630098 -294.4749)
			(xy 293.918906 -294.4749) (xy 293.922866 -294.425846) (xy 293.934643 -294.378062) (xy 293.953934 -294.332786)
			(xy 293.980237 -294.29119) (xy 294.012872 -294.254353) (xy 294.050993 -294.223228) (xy 294.093614 -294.198621)
			(xy 294.13963 -294.181169) (xy 294.187849 -294.171325) (xy 294.237024 -294.169344) (xy 294.285879 -294.175276)
			(xy 294.33315 -294.188968) (xy 294.377612 -294.210066) (xy 294.418115 -294.238022) (xy 294.453608 -294.272114)
			(xy 294.483173 -294.311458) (xy 294.506044 -294.355035) (xy 294.521628 -294.401716) (xy 294.529523 -294.450293)
			(xy 294.530018 -294.4749) (xy 295.81908 -294.4749) (xy 295.82304 -294.425846) (xy 295.834817 -294.378062)
			(xy 295.854108 -294.332786) (xy 295.880411 -294.29119) (xy 295.913046 -294.254353) (xy 295.951167 -294.223228)
			(xy 295.993788 -294.198621) (xy 296.039804 -294.181169) (xy 296.088023 -294.171325) (xy 296.137198 -294.169344)
			(xy 296.186053 -294.175276) (xy 296.233324 -294.188968) (xy 296.277786 -294.210066) (xy 296.318289 -294.238022)
			(xy 296.353782 -294.272114) (xy 296.383347 -294.311458) (xy 296.406218 -294.355035) (xy 296.421802 -294.401716)
			(xy 296.429697 -294.450293) (xy 296.430192 -294.4749) (xy 297.719 -294.4749) (xy 297.72296 -294.425846)
			(xy 297.734737 -294.378062) (xy 297.754028 -294.332786) (xy 297.780331 -294.29119) (xy 297.812966 -294.254353)
			(xy 297.851087 -294.223228) (xy 297.893708 -294.198621) (xy 297.939724 -294.181169) (xy 297.987943 -294.171325)
			(xy 298.037118 -294.169344) (xy 298.085973 -294.175276) (xy 298.133244 -294.188968) (xy 298.177706 -294.210066)
			(xy 298.218209 -294.238022) (xy 298.253702 -294.272114) (xy 298.283267 -294.311458) (xy 298.306138 -294.355035)
			(xy 298.321722 -294.401716) (xy 298.329617 -294.450293) (xy 298.330112 -294.4749) (xy 298.66896 -294.4749)
			(xy 298.67292 -294.425846) (xy 298.684697 -294.378062) (xy 298.703988 -294.332786) (xy 298.730291 -294.29119)
			(xy 298.762926 -294.254353) (xy 298.801047 -294.223228) (xy 298.843668 -294.198621) (xy 298.889684 -294.181169)
			(xy 298.937903 -294.171325) (xy 298.987078 -294.169344) (xy 299.035933 -294.175276) (xy 299.083204 -294.188968)
			(xy 299.127666 -294.210066) (xy 299.168169 -294.238022) (xy 299.203662 -294.272114) (xy 299.233227 -294.311458)
			(xy 299.256098 -294.355035) (xy 299.271682 -294.401716) (xy 299.279577 -294.450293) (xy 299.280072 -294.4749)
			(xy 299.61892 -294.4749) (xy 299.62288 -294.425846) (xy 299.634657 -294.378062) (xy 299.653948 -294.332786)
			(xy 299.680251 -294.29119) (xy 299.712886 -294.254353) (xy 299.751007 -294.223228) (xy 299.793628 -294.198621)
			(xy 299.839644 -294.181169) (xy 299.887863 -294.171325) (xy 299.937038 -294.169344) (xy 299.985893 -294.175276)
			(xy 300.033164 -294.188968) (xy 300.077626 -294.210066) (xy 300.118129 -294.238022) (xy 300.153622 -294.272114)
			(xy 300.183187 -294.311458) (xy 300.206058 -294.355035) (xy 300.221642 -294.401716) (xy 300.229537 -294.450293)
			(xy 300.230032 -294.4749) (xy 300.56888 -294.4749) (xy 300.57284 -294.425846) (xy 300.584617 -294.378062)
			(xy 300.603908 -294.332786) (xy 300.630211 -294.29119) (xy 300.662846 -294.254353) (xy 300.700967 -294.223228)
			(xy 300.743588 -294.198621) (xy 300.789604 -294.181169) (xy 300.837823 -294.171325) (xy 300.886998 -294.169344)
			(xy 300.935853 -294.175276) (xy 300.983124 -294.188968) (xy 301.027586 -294.210066) (xy 301.068089 -294.238022)
			(xy 301.103582 -294.272114) (xy 301.133147 -294.311458) (xy 301.156018 -294.355035) (xy 301.171602 -294.401716)
			(xy 301.179497 -294.450293) (xy 301.179992 -294.4749) (xy 301.519094 -294.4749) (xy 301.523054 -294.425846)
			(xy 301.534831 -294.378062) (xy 301.554122 -294.332786) (xy 301.580425 -294.29119) (xy 301.61306 -294.254353)
			(xy 301.651181 -294.223228) (xy 301.693802 -294.198621) (xy 301.739818 -294.181169) (xy 301.788037 -294.171325)
			(xy 301.837212 -294.169344) (xy 301.886067 -294.175276) (xy 301.933338 -294.188968) (xy 301.9778 -294.210066)
			(xy 302.018303 -294.238022) (xy 302.053796 -294.272114) (xy 302.083361 -294.311458) (xy 302.106232 -294.355035)
			(xy 302.121816 -294.401716) (xy 302.129711 -294.450293) (xy 302.130206 -294.4749) (xy 302.469054 -294.4749)
			(xy 302.473014 -294.425846) (xy 302.484791 -294.378062) (xy 302.504082 -294.332786) (xy 302.530385 -294.29119)
			(xy 302.56302 -294.254353) (xy 302.601141 -294.223228) (xy 302.643762 -294.198621) (xy 302.689778 -294.181169)
			(xy 302.737997 -294.171325) (xy 302.787172 -294.169344) (xy 302.836027 -294.175276) (xy 302.883298 -294.188968)
			(xy 302.92776 -294.210066) (xy 302.968263 -294.238022) (xy 303.003756 -294.272114) (xy 303.033321 -294.311458)
			(xy 303.056192 -294.355035) (xy 303.071776 -294.401716) (xy 303.079671 -294.450293) (xy 303.080166 -294.4749)
			(xy 303.419014 -294.4749) (xy 303.422974 -294.425846) (xy 303.434751 -294.378062) (xy 303.454042 -294.332786)
			(xy 303.480345 -294.29119) (xy 303.51298 -294.254353) (xy 303.551101 -294.223228) (xy 303.593722 -294.198621)
			(xy 303.639738 -294.181169) (xy 303.687957 -294.171325) (xy 303.737132 -294.169344) (xy 303.785987 -294.175276)
			(xy 303.833258 -294.188968) (xy 303.87772 -294.210066) (xy 303.918223 -294.238022) (xy 303.953716 -294.272114)
			(xy 303.983281 -294.311458) (xy 304.006152 -294.355035) (xy 304.021736 -294.401716) (xy 304.029631 -294.450293)
			(xy 304.030126 -294.4749) (xy 304.368974 -294.4749) (xy 304.372934 -294.425846) (xy 304.384711 -294.378062)
			(xy 304.404002 -294.332786) (xy 304.430305 -294.29119) (xy 304.46294 -294.254353) (xy 304.501061 -294.223228)
			(xy 304.543682 -294.198621) (xy 304.589698 -294.181169) (xy 304.637917 -294.171325) (xy 304.687092 -294.169344)
			(xy 304.735947 -294.175276) (xy 304.783218 -294.188968) (xy 304.82768 -294.210066) (xy 304.868183 -294.238022)
			(xy 304.903676 -294.272114) (xy 304.933241 -294.311458) (xy 304.956112 -294.355035) (xy 304.971696 -294.401716)
			(xy 304.979591 -294.450293) (xy 304.980086 -294.4749) (xy 305.318934 -294.4749) (xy 305.322894 -294.425846)
			(xy 305.334671 -294.378062) (xy 305.353962 -294.332786) (xy 305.380265 -294.29119) (xy 305.4129 -294.254353)
			(xy 305.451021 -294.223228) (xy 305.493642 -294.198621) (xy 305.539658 -294.181169) (xy 305.587877 -294.171325)
			(xy 305.637052 -294.169344) (xy 305.685907 -294.175276) (xy 305.733178 -294.188968) (xy 305.77764 -294.210066)
			(xy 305.818143 -294.238022) (xy 305.853636 -294.272114) (xy 305.883201 -294.311458) (xy 305.906072 -294.355035)
			(xy 305.921656 -294.401716) (xy 305.929551 -294.450293) (xy 305.930046 -294.4749) (xy 306.268894 -294.4749)
			(xy 306.272854 -294.425846) (xy 306.284631 -294.378062) (xy 306.303922 -294.332786) (xy 306.330225 -294.29119)
			(xy 306.36286 -294.254353) (xy 306.400981 -294.223228) (xy 306.443602 -294.198621) (xy 306.489618 -294.181169)
			(xy 306.537837 -294.171325) (xy 306.587012 -294.169344) (xy 306.635867 -294.175276) (xy 306.683138 -294.188968)
			(xy 306.7276 -294.210066) (xy 306.768103 -294.238022) (xy 306.803596 -294.272114) (xy 306.833161 -294.311458)
			(xy 306.856032 -294.355035) (xy 306.871616 -294.401716) (xy 306.879511 -294.450293) (xy 306.880006 -294.4749)
			(xy 307.219108 -294.4749) (xy 307.223068 -294.425846) (xy 307.234845 -294.378062) (xy 307.254136 -294.332786)
			(xy 307.280439 -294.29119) (xy 307.313074 -294.254353) (xy 307.351195 -294.223228) (xy 307.393816 -294.198621)
			(xy 307.439832 -294.181169) (xy 307.488051 -294.171325) (xy 307.537226 -294.169344) (xy 307.586081 -294.175276)
			(xy 307.633352 -294.188968) (xy 307.677814 -294.210066) (xy 307.718317 -294.238022) (xy 307.75381 -294.272114)
			(xy 307.783375 -294.311458) (xy 307.806246 -294.355035) (xy 307.82183 -294.401716) (xy 307.829725 -294.450293)
			(xy 307.83022 -294.4749) (xy 308.169068 -294.4749) (xy 308.173028 -294.425846) (xy 308.184805 -294.378062)
			(xy 308.204096 -294.332786) (xy 308.230399 -294.29119) (xy 308.263034 -294.254353) (xy 308.301155 -294.223228)
			(xy 308.343776 -294.198621) (xy 308.389792 -294.181169) (xy 308.438011 -294.171325) (xy 308.487186 -294.169344)
			(xy 308.536041 -294.175276) (xy 308.583312 -294.188968) (xy 308.627774 -294.210066) (xy 308.668277 -294.238022)
			(xy 308.70377 -294.272114) (xy 308.733335 -294.311458) (xy 308.756206 -294.355035) (xy 308.77179 -294.401716)
			(xy 308.779685 -294.450293) (xy 308.78018 -294.4749) (xy 309.119028 -294.4749) (xy 309.122988 -294.425846)
			(xy 309.134765 -294.378062) (xy 309.154056 -294.332786) (xy 309.180359 -294.29119) (xy 309.212994 -294.254353)
			(xy 309.251115 -294.223228) (xy 309.293736 -294.198621) (xy 309.339752 -294.181169) (xy 309.387971 -294.171325)
			(xy 309.437146 -294.169344) (xy 309.486001 -294.175276) (xy 309.533272 -294.188968) (xy 309.577734 -294.210066)
			(xy 309.618237 -294.238022) (xy 309.65373 -294.272114) (xy 309.683295 -294.311458) (xy 309.706166 -294.355035)
			(xy 309.72175 -294.401716) (xy 309.729645 -294.450293) (xy 309.73014 -294.4749) (xy 310.068988 -294.4749)
			(xy 310.072948 -294.425846) (xy 310.084725 -294.378062) (xy 310.104016 -294.332786) (xy 310.130319 -294.29119)
			(xy 310.162954 -294.254353) (xy 310.201075 -294.223228) (xy 310.243696 -294.198621) (xy 310.289712 -294.181169)
			(xy 310.337931 -294.171325) (xy 310.387106 -294.169344) (xy 310.435961 -294.175276) (xy 310.483232 -294.188968)
			(xy 310.527694 -294.210066) (xy 310.568197 -294.238022) (xy 310.60369 -294.272114) (xy 310.633255 -294.311458)
			(xy 310.656126 -294.355035) (xy 310.67171 -294.401716) (xy 310.679605 -294.450293) (xy 310.6801 -294.4749)
			(xy 311.018948 -294.4749) (xy 311.022908 -294.425846) (xy 311.034685 -294.378062) (xy 311.053976 -294.332786)
			(xy 311.080279 -294.29119) (xy 311.112914 -294.254353) (xy 311.151035 -294.223228) (xy 311.193656 -294.198621)
			(xy 311.239672 -294.181169) (xy 311.287891 -294.171325) (xy 311.337066 -294.169344) (xy 311.385921 -294.175276)
			(xy 311.433192 -294.188968) (xy 311.477654 -294.210066) (xy 311.518157 -294.238022) (xy 311.55365 -294.272114)
			(xy 311.583215 -294.311458) (xy 311.606086 -294.355035) (xy 311.62167 -294.401716) (xy 311.629565 -294.450293)
			(xy 311.63006 -294.4749) (xy 311.968908 -294.4749) (xy 311.972868 -294.425846) (xy 311.984645 -294.378062)
			(xy 312.003936 -294.332786) (xy 312.030239 -294.29119) (xy 312.062874 -294.254353) (xy 312.100995 -294.223228)
			(xy 312.143616 -294.198621) (xy 312.189632 -294.181169) (xy 312.237851 -294.171325) (xy 312.287026 -294.169344)
			(xy 312.335881 -294.175276) (xy 312.383152 -294.188968) (xy 312.427614 -294.210066) (xy 312.468117 -294.238022)
			(xy 312.50361 -294.272114) (xy 312.533175 -294.311458) (xy 312.556046 -294.355035) (xy 312.57163 -294.401716)
			(xy 312.579525 -294.450293) (xy 312.58002 -294.4749) (xy 312.919122 -294.4749) (xy 312.923082 -294.425846)
			(xy 312.934859 -294.378062) (xy 312.95415 -294.332786) (xy 312.980453 -294.29119) (xy 313.013088 -294.254353)
			(xy 313.051209 -294.223228) (xy 313.09383 -294.198621) (xy 313.139846 -294.181169) (xy 313.188065 -294.171325)
			(xy 313.23724 -294.169344) (xy 313.286095 -294.175276) (xy 313.333366 -294.188968) (xy 313.377828 -294.210066)
			(xy 313.418331 -294.238022) (xy 313.453824 -294.272114) (xy 313.483389 -294.311458) (xy 313.50626 -294.355035)
			(xy 313.521844 -294.401716) (xy 313.529739 -294.450293) (xy 313.530234 -294.4749) (xy 313.869082 -294.4749)
			(xy 313.873042 -294.425846) (xy 313.884819 -294.378062) (xy 313.90411 -294.332786) (xy 313.930413 -294.29119)
			(xy 313.963048 -294.254353) (xy 314.001169 -294.223228) (xy 314.04379 -294.198621) (xy 314.089806 -294.181169)
			(xy 314.138025 -294.171325) (xy 314.1872 -294.169344) (xy 314.236055 -294.175276) (xy 314.283326 -294.188968)
			(xy 314.327788 -294.210066) (xy 314.368291 -294.238022) (xy 314.403784 -294.272114) (xy 314.433349 -294.311458)
			(xy 314.45622 -294.355035) (xy 314.471804 -294.401716) (xy 314.479699 -294.450293) (xy 314.480194 -294.4749)
			(xy 314.819042 -294.4749) (xy 314.823002 -294.425846) (xy 314.834779 -294.378062) (xy 314.85407 -294.332786)
			(xy 314.880373 -294.29119) (xy 314.913008 -294.254353) (xy 314.951129 -294.223228) (xy 314.99375 -294.198621)
			(xy 315.039766 -294.181169) (xy 315.087985 -294.171325) (xy 315.13716 -294.169344) (xy 315.186015 -294.175276)
			(xy 315.233286 -294.188968) (xy 315.277748 -294.210066) (xy 315.318251 -294.238022) (xy 315.353744 -294.272114)
			(xy 315.383309 -294.311458) (xy 315.40618 -294.355035) (xy 315.421764 -294.401716) (xy 315.429659 -294.450293)
			(xy 315.430154 -294.4749) (xy 315.429659 -294.499507) (xy 315.421764 -294.548084) (xy 315.40618 -294.594765)
			(xy 315.383309 -294.638342) (xy 315.370443 -294.655464) (xy 321.363026 -294.655464) (xy 321.370781 -294.601508)
			(xy 321.386135 -294.549205) (xy 321.408778 -294.49962) (xy 321.438246 -294.453761) (xy 321.473941 -294.412564)
			(xy 321.515135 -294.376866) (xy 321.560991 -294.347393) (xy 321.610574 -294.324747) (xy 321.662876 -294.309388)
			(xy 321.716831 -294.301628) (xy 321.744086 -294.301164) (xy 321.769486 -294.301926) (xy 321.784217 -294.302451)
			(xy 321.812948 -294.295898) (xy 321.838614 -294.281417) (xy 321.859079 -294.260214) (xy 321.872642 -294.234052)
			(xy 321.878174 -294.205107) (xy 321.875215 -294.175788) (xy 321.87007 -294.161972) (xy 321.860908 -294.13877)
			(xy 321.848018 -294.090579) (xy 321.841518 -294.041119) (xy 321.841114 -294.016176) (xy 321.841604 -293.988927)
			(xy 321.849363 -293.934985) (xy 321.86472 -293.882696) (xy 321.887361 -293.833124) (xy 321.916827 -293.787279)
			(xy 321.952517 -293.746094) (xy 321.993705 -293.710407) (xy 322.039553 -293.680946) (xy 322.089126 -293.658308)
			(xy 322.141417 -293.642956) (xy 322.19536 -293.635202) (xy 322.249857 -293.635203) (xy 322.3038 -293.64296)
			(xy 322.35609 -293.658314) (xy 322.405663 -293.680954) (xy 322.451509 -293.710418) (xy 322.492695 -293.746106)
			(xy 322.528383 -293.787293) (xy 322.557847 -293.833139) (xy 322.580487 -293.882712) (xy 322.595841 -293.935002)
			(xy 322.602399 -293.980616) (xy 323.480682 -293.980616) (xy 323.484753 -293.924994) (xy 323.496879 -293.870557)
			(xy 323.516802 -293.818466) (xy 323.544098 -293.769831) (xy 323.578184 -293.725688) (xy 323.618333 -293.686979)
			(xy 323.663691 -293.654528) (xy 323.713291 -293.629027) (xy 323.766075 -293.61102) (xy 323.820918 -293.60089)
			(xy 323.876652 -293.598853) (xy 323.932089 -293.604953) (xy 323.986046 -293.619059) (xy 324.037375 -293.640871)
			(xy 324.084981 -293.669925) (xy 324.127849 -293.7056) (xy 324.165066 -293.747137) (xy 324.195839 -293.79365)
			(xy 324.219511 -293.844147) (xy 324.235579 -293.897554) (xy 324.243699 -293.95273) (xy 324.244208 -293.980616)
			(xy 324.243699 -294.008502) (xy 324.235579 -294.063678) (xy 324.219511 -294.117085) (xy 324.195839 -294.167582)
			(xy 324.165066 -294.214095) (xy 324.127849 -294.255632) (xy 324.084981 -294.291307) (xy 324.037375 -294.320361)
			(xy 323.986046 -294.342173) (xy 323.932089 -294.356279) (xy 323.876652 -294.362379) (xy 323.820918 -294.360342)
			(xy 323.766075 -294.350212) (xy 323.713291 -294.332205) (xy 323.663691 -294.306704) (xy 323.618333 -294.274253)
			(xy 323.578184 -294.235544) (xy 323.544098 -294.191401) (xy 323.516802 -294.142766) (xy 323.496879 -294.090675)
			(xy 323.484753 -294.036238) (xy 323.480682 -293.980616) (xy 322.602399 -293.980616) (xy 322.603597 -293.988945)
			(xy 322.603598 -294.043442) (xy 322.595844 -294.097385) (xy 322.580491 -294.149676) (xy 322.557853 -294.199249)
			(xy 322.528391 -294.245096) (xy 322.492704 -294.286284) (xy 322.451519 -294.321974) (xy 322.405674 -294.35144)
			(xy 322.356103 -294.374081) (xy 322.303813 -294.389438) (xy 322.249871 -294.397196) (xy 322.222622 -294.397684)
			(xy 322.197222 -294.396922) (xy 322.182492 -294.396476) (xy 322.153774 -294.403023) (xy 322.128118 -294.417493)
			(xy 322.107658 -294.438682) (xy 322.094094 -294.464828) (xy 322.088555 -294.493757) (xy 322.08934 -294.50157)
			(xy 322.736462 -294.50157) (xy 322.740533 -294.445948) (xy 322.752659 -294.391511) (xy 322.772582 -294.33942)
			(xy 322.799878 -294.290785) (xy 322.833964 -294.246642) (xy 322.874113 -294.207933) (xy 322.919471 -294.175482)
			(xy 322.969071 -294.149981) (xy 323.021855 -294.131974) (xy 323.076698 -294.121844) (xy 323.132432 -294.119807)
			(xy 323.187869 -294.125907) (xy 323.241826 -294.140013) (xy 323.293155 -294.161825) (xy 323.340761 -294.190879)
			(xy 323.383629 -294.226554) (xy 323.420846 -294.268091) (xy 323.451619 -294.314604) (xy 323.475291 -294.365101)
			(xy 323.491359 -294.418508) (xy 323.499479 -294.473684) (xy 323.499988 -294.50157) (xy 323.499479 -294.529456)
			(xy 323.491359 -294.584632) (xy 323.475291 -294.638039) (xy 323.451619 -294.688536) (xy 323.420846 -294.735049)
			(xy 323.383629 -294.776586) (xy 323.340761 -294.812261) (xy 323.293155 -294.841315) (xy 323.241826 -294.863127)
			(xy 323.187869 -294.877233) (xy 323.132432 -294.883333) (xy 323.076698 -294.881296) (xy 323.021855 -294.871166)
			(xy 322.969071 -294.853159) (xy 322.919471 -294.827658) (xy 322.874113 -294.795207) (xy 322.833964 -294.756498)
			(xy 322.799878 -294.712355) (xy 322.772582 -294.66372) (xy 322.752659 -294.611629) (xy 322.740533 -294.557192)
			(xy 322.736462 -294.50157) (xy 322.08934 -294.50157) (xy 322.091501 -294.523064) (xy 322.096638 -294.536876)
			(xy 322.105784 -294.560084) (xy 322.118681 -294.608272) (xy 322.125186 -294.65773) (xy 322.125594 -294.682672)
			(xy 322.125175 -294.709927) (xy 322.117421 -294.763883) (xy 322.102068 -294.816186) (xy 322.079427 -294.865772)
			(xy 322.04996 -294.911631) (xy 322.014266 -294.952829) (xy 321.973072 -294.988529) (xy 321.927217 -295.018002)
			(xy 321.877634 -295.04065) (xy 321.825333 -295.05601) (xy 321.771378 -295.063771) (xy 321.716868 -295.063775)
			(xy 321.662912 -295.05602) (xy 321.610609 -295.040666) (xy 321.561024 -295.018025) (xy 321.515165 -294.988557)
			(xy 321.473967 -294.952863) (xy 321.438268 -294.911668) (xy 321.408795 -294.865813) (xy 321.386149 -294.81623)
			(xy 321.370789 -294.763929) (xy 321.363028 -294.709974) (xy 321.363026 -294.655464) (xy 315.370443 -294.655464)
			(xy 315.353744 -294.677686) (xy 315.318251 -294.711778) (xy 315.277748 -294.739734) (xy 315.233286 -294.760832)
			(xy 315.186015 -294.774524) (xy 315.13716 -294.780456) (xy 315.087985 -294.778475) (xy 315.039766 -294.768631)
			(xy 314.99375 -294.751179) (xy 314.951129 -294.726572) (xy 314.913008 -294.695447) (xy 314.880373 -294.65861)
			(xy 314.85407 -294.617014) (xy 314.834779 -294.571738) (xy 314.823002 -294.523954) (xy 314.819042 -294.4749)
			(xy 314.480194 -294.4749) (xy 314.479699 -294.499507) (xy 314.471804 -294.548084) (xy 314.45622 -294.594765)
			(xy 314.433349 -294.638342) (xy 314.403784 -294.677686) (xy 314.368291 -294.711778) (xy 314.327788 -294.739734)
			(xy 314.283326 -294.760832) (xy 314.236055 -294.774524) (xy 314.1872 -294.780456) (xy 314.138025 -294.778475)
			(xy 314.089806 -294.768631) (xy 314.04379 -294.751179) (xy 314.001169 -294.726572) (xy 313.963048 -294.695447)
			(xy 313.930413 -294.65861) (xy 313.90411 -294.617014) (xy 313.884819 -294.571738) (xy 313.873042 -294.523954)
			(xy 313.869082 -294.4749) (xy 313.530234 -294.4749) (xy 313.529739 -294.499507) (xy 313.521844 -294.548084)
			(xy 313.50626 -294.594765) (xy 313.483389 -294.638342) (xy 313.453824 -294.677686) (xy 313.418331 -294.711778)
			(xy 313.377828 -294.739734) (xy 313.333366 -294.760832) (xy 313.286095 -294.774524) (xy 313.23724 -294.780456)
			(xy 313.188065 -294.778475) (xy 313.139846 -294.768631) (xy 313.09383 -294.751179) (xy 313.051209 -294.726572)
			(xy 313.013088 -294.695447) (xy 312.980453 -294.65861) (xy 312.95415 -294.617014) (xy 312.934859 -294.571738)
			(xy 312.923082 -294.523954) (xy 312.919122 -294.4749) (xy 312.58002 -294.4749) (xy 312.579525 -294.499507)
			(xy 312.57163 -294.548084) (xy 312.556046 -294.594765) (xy 312.533175 -294.638342) (xy 312.50361 -294.677686)
			(xy 312.468117 -294.711778) (xy 312.427614 -294.739734) (xy 312.383152 -294.760832) (xy 312.335881 -294.774524)
			(xy 312.287026 -294.780456) (xy 312.237851 -294.778475) (xy 312.189632 -294.768631) (xy 312.143616 -294.751179)
			(xy 312.100995 -294.726572) (xy 312.062874 -294.695447) (xy 312.030239 -294.65861) (xy 312.003936 -294.617014)
			(xy 311.984645 -294.571738) (xy 311.972868 -294.523954) (xy 311.968908 -294.4749) (xy 311.63006 -294.4749)
			(xy 311.629565 -294.499507) (xy 311.62167 -294.548084) (xy 311.606086 -294.594765) (xy 311.583215 -294.638342)
			(xy 311.55365 -294.677686) (xy 311.518157 -294.711778) (xy 311.477654 -294.739734) (xy 311.433192 -294.760832)
			(xy 311.385921 -294.774524) (xy 311.337066 -294.780456) (xy 311.287891 -294.778475) (xy 311.239672 -294.768631)
			(xy 311.193656 -294.751179) (xy 311.151035 -294.726572) (xy 311.112914 -294.695447) (xy 311.080279 -294.65861)
			(xy 311.053976 -294.617014) (xy 311.034685 -294.571738) (xy 311.022908 -294.523954) (xy 311.018948 -294.4749)
			(xy 310.6801 -294.4749) (xy 310.679605 -294.499507) (xy 310.67171 -294.548084) (xy 310.656126 -294.594765)
			(xy 310.633255 -294.638342) (xy 310.60369 -294.677686) (xy 310.568197 -294.711778) (xy 310.527694 -294.739734)
			(xy 310.483232 -294.760832) (xy 310.435961 -294.774524) (xy 310.387106 -294.780456) (xy 310.337931 -294.778475)
			(xy 310.289712 -294.768631) (xy 310.243696 -294.751179) (xy 310.201075 -294.726572) (xy 310.162954 -294.695447)
			(xy 310.130319 -294.65861) (xy 310.104016 -294.617014) (xy 310.084725 -294.571738) (xy 310.072948 -294.523954)
			(xy 310.068988 -294.4749) (xy 309.73014 -294.4749) (xy 309.729645 -294.499507) (xy 309.72175 -294.548084)
			(xy 309.706166 -294.594765) (xy 309.683295 -294.638342) (xy 309.65373 -294.677686) (xy 309.618237 -294.711778)
			(xy 309.577734 -294.739734) (xy 309.533272 -294.760832) (xy 309.486001 -294.774524) (xy 309.437146 -294.780456)
			(xy 309.387971 -294.778475) (xy 309.339752 -294.768631) (xy 309.293736 -294.751179) (xy 309.251115 -294.726572)
			(xy 309.212994 -294.695447) (xy 309.180359 -294.65861) (xy 309.154056 -294.617014) (xy 309.134765 -294.571738)
			(xy 309.122988 -294.523954) (xy 309.119028 -294.4749) (xy 308.78018 -294.4749) (xy 308.779685 -294.499507)
			(xy 308.77179 -294.548084) (xy 308.756206 -294.594765) (xy 308.733335 -294.638342) (xy 308.70377 -294.677686)
			(xy 308.668277 -294.711778) (xy 308.627774 -294.739734) (xy 308.583312 -294.760832) (xy 308.536041 -294.774524)
			(xy 308.487186 -294.780456) (xy 308.438011 -294.778475) (xy 308.389792 -294.768631) (xy 308.343776 -294.751179)
			(xy 308.301155 -294.726572) (xy 308.263034 -294.695447) (xy 308.230399 -294.65861) (xy 308.204096 -294.617014)
			(xy 308.184805 -294.571738) (xy 308.173028 -294.523954) (xy 308.169068 -294.4749) (xy 307.83022 -294.4749)
			(xy 307.829725 -294.499507) (xy 307.82183 -294.548084) (xy 307.806246 -294.594765) (xy 307.783375 -294.638342)
			(xy 307.75381 -294.677686) (xy 307.718317 -294.711778) (xy 307.677814 -294.739734) (xy 307.633352 -294.760832)
			(xy 307.586081 -294.774524) (xy 307.537226 -294.780456) (xy 307.488051 -294.778475) (xy 307.439832 -294.768631)
			(xy 307.393816 -294.751179) (xy 307.351195 -294.726572) (xy 307.313074 -294.695447) (xy 307.280439 -294.65861)
			(xy 307.254136 -294.617014) (xy 307.234845 -294.571738) (xy 307.223068 -294.523954) (xy 307.219108 -294.4749)
			(xy 306.880006 -294.4749) (xy 306.879511 -294.499507) (xy 306.871616 -294.548084) (xy 306.856032 -294.594765)
			(xy 306.833161 -294.638342) (xy 306.803596 -294.677686) (xy 306.768103 -294.711778) (xy 306.7276 -294.739734)
			(xy 306.683138 -294.760832) (xy 306.635867 -294.774524) (xy 306.587012 -294.780456) (xy 306.537837 -294.778475)
			(xy 306.489618 -294.768631) (xy 306.443602 -294.751179) (xy 306.400981 -294.726572) (xy 306.36286 -294.695447)
			(xy 306.330225 -294.65861) (xy 306.303922 -294.617014) (xy 306.284631 -294.571738) (xy 306.272854 -294.523954)
			(xy 306.268894 -294.4749) (xy 305.930046 -294.4749) (xy 305.929551 -294.499507) (xy 305.921656 -294.548084)
			(xy 305.906072 -294.594765) (xy 305.883201 -294.638342) (xy 305.853636 -294.677686) (xy 305.818143 -294.711778)
			(xy 305.77764 -294.739734) (xy 305.733178 -294.760832) (xy 305.685907 -294.774524) (xy 305.637052 -294.780456)
			(xy 305.587877 -294.778475) (xy 305.539658 -294.768631) (xy 305.493642 -294.751179) (xy 305.451021 -294.726572)
			(xy 305.4129 -294.695447) (xy 305.380265 -294.65861) (xy 305.353962 -294.617014) (xy 305.334671 -294.571738)
			(xy 305.322894 -294.523954) (xy 305.318934 -294.4749) (xy 304.980086 -294.4749) (xy 304.979591 -294.499507)
			(xy 304.971696 -294.548084) (xy 304.956112 -294.594765) (xy 304.933241 -294.638342) (xy 304.903676 -294.677686)
			(xy 304.868183 -294.711778) (xy 304.82768 -294.739734) (xy 304.783218 -294.760832) (xy 304.735947 -294.774524)
			(xy 304.687092 -294.780456) (xy 304.637917 -294.778475) (xy 304.589698 -294.768631) (xy 304.543682 -294.751179)
			(xy 304.501061 -294.726572) (xy 304.46294 -294.695447) (xy 304.430305 -294.65861) (xy 304.404002 -294.617014)
			(xy 304.384711 -294.571738) (xy 304.372934 -294.523954) (xy 304.368974 -294.4749) (xy 304.030126 -294.4749)
			(xy 304.029631 -294.499507) (xy 304.021736 -294.548084) (xy 304.006152 -294.594765) (xy 303.983281 -294.638342)
			(xy 303.953716 -294.677686) (xy 303.918223 -294.711778) (xy 303.87772 -294.739734) (xy 303.833258 -294.760832)
			(xy 303.785987 -294.774524) (xy 303.737132 -294.780456) (xy 303.687957 -294.778475) (xy 303.639738 -294.768631)
			(xy 303.593722 -294.751179) (xy 303.551101 -294.726572) (xy 303.51298 -294.695447) (xy 303.480345 -294.65861)
			(xy 303.454042 -294.617014) (xy 303.434751 -294.571738) (xy 303.422974 -294.523954) (xy 303.419014 -294.4749)
			(xy 303.080166 -294.4749) (xy 303.079671 -294.499507) (xy 303.071776 -294.548084) (xy 303.056192 -294.594765)
			(xy 303.033321 -294.638342) (xy 303.003756 -294.677686) (xy 302.968263 -294.711778) (xy 302.92776 -294.739734)
			(xy 302.883298 -294.760832) (xy 302.836027 -294.774524) (xy 302.787172 -294.780456) (xy 302.737997 -294.778475)
			(xy 302.689778 -294.768631) (xy 302.643762 -294.751179) (xy 302.601141 -294.726572) (xy 302.56302 -294.695447)
			(xy 302.530385 -294.65861) (xy 302.504082 -294.617014) (xy 302.484791 -294.571738) (xy 302.473014 -294.523954)
			(xy 302.469054 -294.4749) (xy 302.130206 -294.4749) (xy 302.129711 -294.499507) (xy 302.121816 -294.548084)
			(xy 302.106232 -294.594765) (xy 302.083361 -294.638342) (xy 302.053796 -294.677686) (xy 302.018303 -294.711778)
			(xy 301.9778 -294.739734) (xy 301.933338 -294.760832) (xy 301.886067 -294.774524) (xy 301.837212 -294.780456)
			(xy 301.788037 -294.778475) (xy 301.739818 -294.768631) (xy 301.693802 -294.751179) (xy 301.651181 -294.726572)
			(xy 301.61306 -294.695447) (xy 301.580425 -294.65861) (xy 301.554122 -294.617014) (xy 301.534831 -294.571738)
			(xy 301.523054 -294.523954) (xy 301.519094 -294.4749) (xy 301.179992 -294.4749) (xy 301.179497 -294.499507)
			(xy 301.171602 -294.548084) (xy 301.156018 -294.594765) (xy 301.133147 -294.638342) (xy 301.103582 -294.677686)
			(xy 301.068089 -294.711778) (xy 301.027586 -294.739734) (xy 300.983124 -294.760832) (xy 300.935853 -294.774524)
			(xy 300.886998 -294.780456) (xy 300.837823 -294.778475) (xy 300.789604 -294.768631) (xy 300.743588 -294.751179)
			(xy 300.700967 -294.726572) (xy 300.662846 -294.695447) (xy 300.630211 -294.65861) (xy 300.603908 -294.617014)
			(xy 300.584617 -294.571738) (xy 300.57284 -294.523954) (xy 300.56888 -294.4749) (xy 300.230032 -294.4749)
			(xy 300.229537 -294.499507) (xy 300.221642 -294.548084) (xy 300.206058 -294.594765) (xy 300.183187 -294.638342)
			(xy 300.153622 -294.677686) (xy 300.118129 -294.711778) (xy 300.077626 -294.739734) (xy 300.033164 -294.760832)
			(xy 299.985893 -294.774524) (xy 299.937038 -294.780456) (xy 299.887863 -294.778475) (xy 299.839644 -294.768631)
			(xy 299.793628 -294.751179) (xy 299.751007 -294.726572) (xy 299.712886 -294.695447) (xy 299.680251 -294.65861)
			(xy 299.653948 -294.617014) (xy 299.634657 -294.571738) (xy 299.62288 -294.523954) (xy 299.61892 -294.4749)
			(xy 299.280072 -294.4749) (xy 299.279577 -294.499507) (xy 299.271682 -294.548084) (xy 299.256098 -294.594765)
			(xy 299.233227 -294.638342) (xy 299.203662 -294.677686) (xy 299.168169 -294.711778) (xy 299.127666 -294.739734)
			(xy 299.083204 -294.760832) (xy 299.035933 -294.774524) (xy 298.987078 -294.780456) (xy 298.937903 -294.778475)
			(xy 298.889684 -294.768631) (xy 298.843668 -294.751179) (xy 298.801047 -294.726572) (xy 298.762926 -294.695447)
			(xy 298.730291 -294.65861) (xy 298.703988 -294.617014) (xy 298.684697 -294.571738) (xy 298.67292 -294.523954)
			(xy 298.66896 -294.4749) (xy 298.330112 -294.4749) (xy 298.329617 -294.499507) (xy 298.321722 -294.548084)
			(xy 298.306138 -294.594765) (xy 298.283267 -294.638342) (xy 298.253702 -294.677686) (xy 298.218209 -294.711778)
			(xy 298.177706 -294.739734) (xy 298.133244 -294.760832) (xy 298.085973 -294.774524) (xy 298.037118 -294.780456)
			(xy 297.987943 -294.778475) (xy 297.939724 -294.768631) (xy 297.893708 -294.751179) (xy 297.851087 -294.726572)
			(xy 297.812966 -294.695447) (xy 297.780331 -294.65861) (xy 297.754028 -294.617014) (xy 297.734737 -294.571738)
			(xy 297.72296 -294.523954) (xy 297.719 -294.4749) (xy 296.430192 -294.4749) (xy 296.429697 -294.499507)
			(xy 296.421802 -294.548084) (xy 296.406218 -294.594765) (xy 296.383347 -294.638342) (xy 296.353782 -294.677686)
			(xy 296.318289 -294.711778) (xy 296.277786 -294.739734) (xy 296.233324 -294.760832) (xy 296.186053 -294.774524)
			(xy 296.137198 -294.780456) (xy 296.088023 -294.778475) (xy 296.039804 -294.768631) (xy 295.993788 -294.751179)
			(xy 295.951167 -294.726572) (xy 295.913046 -294.695447) (xy 295.880411 -294.65861) (xy 295.854108 -294.617014)
			(xy 295.834817 -294.571738) (xy 295.82304 -294.523954) (xy 295.81908 -294.4749) (xy 294.530018 -294.4749)
			(xy 294.529523 -294.499507) (xy 294.521628 -294.548084) (xy 294.506044 -294.594765) (xy 294.483173 -294.638342)
			(xy 294.453608 -294.677686) (xy 294.418115 -294.711778) (xy 294.377612 -294.739734) (xy 294.33315 -294.760832)
			(xy 294.285879 -294.774524) (xy 294.237024 -294.780456) (xy 294.187849 -294.778475) (xy 294.13963 -294.768631)
			(xy 294.093614 -294.751179) (xy 294.050993 -294.726572) (xy 294.012872 -294.695447) (xy 293.980237 -294.65861)
			(xy 293.953934 -294.617014) (xy 293.934643 -294.571738) (xy 293.922866 -294.523954) (xy 293.918906 -294.4749)
			(xy 292.630098 -294.4749) (xy 292.629603 -294.499507) (xy 292.621708 -294.548084) (xy 292.606124 -294.594765)
			(xy 292.583253 -294.638342) (xy 292.553688 -294.677686) (xy 292.518195 -294.711778) (xy 292.477692 -294.739734)
			(xy 292.43323 -294.760832) (xy 292.385959 -294.774524) (xy 292.337104 -294.780456) (xy 292.287929 -294.778475)
			(xy 292.23971 -294.768631) (xy 292.193694 -294.751179) (xy 292.151073 -294.726572) (xy 292.112952 -294.695447)
			(xy 292.080317 -294.65861) (xy 292.054014 -294.617014) (xy 292.034723 -294.571738) (xy 292.022946 -294.523954)
			(xy 292.018986 -294.4749) (xy 289.780218 -294.4749) (xy 289.779723 -294.499507) (xy 289.771828 -294.548084)
			(xy 289.756244 -294.594765) (xy 289.733373 -294.638342) (xy 289.703808 -294.677686) (xy 289.668315 -294.711778)
			(xy 289.627812 -294.739734) (xy 289.58335 -294.760832) (xy 289.536079 -294.774524) (xy 289.487224 -294.780456)
			(xy 289.438049 -294.778475) (xy 289.38983 -294.768631) (xy 289.343814 -294.751179) (xy 289.301193 -294.726572)
			(xy 289.263072 -294.695447) (xy 289.230437 -294.65861) (xy 289.204134 -294.617014) (xy 289.184843 -294.571738)
			(xy 289.173066 -294.523954) (xy 289.169106 -294.4749) (xy 287.880044 -294.4749) (xy 287.879549 -294.499507)
			(xy 287.871654 -294.548084) (xy 287.85607 -294.594765) (xy 287.833199 -294.638342) (xy 287.803634 -294.677686)
			(xy 287.768141 -294.711778) (xy 287.727638 -294.739734) (xy 287.683176 -294.760832) (xy 287.635905 -294.774524)
			(xy 287.58705 -294.780456) (xy 287.537875 -294.778475) (xy 287.489656 -294.768631) (xy 287.44364 -294.751179)
			(xy 287.401019 -294.726572) (xy 287.362898 -294.695447) (xy 287.330263 -294.65861) (xy 287.30396 -294.617014)
			(xy 287.284669 -294.571738) (xy 287.272892 -294.523954) (xy 287.268932 -294.4749) (xy 285.980124 -294.4749)
			(xy 285.979629 -294.499507) (xy 285.971734 -294.548084) (xy 285.95615 -294.594765) (xy 285.933279 -294.638342)
			(xy 285.903714 -294.677686) (xy 285.868221 -294.711778) (xy 285.827718 -294.739734) (xy 285.783256 -294.760832)
			(xy 285.735985 -294.774524) (xy 285.68713 -294.780456) (xy 285.637955 -294.778475) (xy 285.589736 -294.768631)
			(xy 285.54372 -294.751179) (xy 285.501099 -294.726572) (xy 285.462978 -294.695447) (xy 285.430343 -294.65861)
			(xy 285.40404 -294.617014) (xy 285.384749 -294.571738) (xy 285.372972 -294.523954) (xy 285.369012 -294.4749)
			(xy 284.080204 -294.4749) (xy 284.079709 -294.499507) (xy 284.071814 -294.548084) (xy 284.05623 -294.594765)
			(xy 284.033359 -294.638342) (xy 284.003794 -294.677686) (xy 283.968301 -294.711778) (xy 283.927798 -294.739734)
			(xy 283.883336 -294.760832) (xy 283.836065 -294.774524) (xy 283.78721 -294.780456) (xy 283.738035 -294.778475)
			(xy 283.689816 -294.768631) (xy 283.6438 -294.751179) (xy 283.601179 -294.726572) (xy 283.563058 -294.695447)
			(xy 283.530423 -294.65861) (xy 283.50412 -294.617014) (xy 283.484829 -294.571738) (xy 283.473052 -294.523954)
			(xy 283.469092 -294.4749) (xy 282.18003 -294.4749) (xy 282.179535 -294.499507) (xy 282.17164 -294.548084)
			(xy 282.156056 -294.594765) (xy 282.133185 -294.638342) (xy 282.10362 -294.677686) (xy 282.068127 -294.711778)
			(xy 282.027624 -294.739734) (xy 281.983162 -294.760832) (xy 281.935891 -294.774524) (xy 281.887036 -294.780456)
			(xy 281.837861 -294.778475) (xy 281.789642 -294.768631) (xy 281.743626 -294.751179) (xy 281.701005 -294.726572)
			(xy 281.662884 -294.695447) (xy 281.630249 -294.65861) (xy 281.603946 -294.617014) (xy 281.584655 -294.571738)
			(xy 281.572878 -294.523954) (xy 281.568918 -294.4749) (xy 280.28011 -294.4749) (xy 280.28011 -294.494966)
			(xy 280.280364 -294.498776) (xy 280.281371 -294.507818) (xy 280.288917 -294.524357) (xy 280.295096 -294.531034)
			(xy 280.356818 -294.592756) (xy 280.357834 -294.593518) (xy 280.359612 -294.595296) (xy 280.360374 -294.596058)
			(xy 280.363422 -294.599106) (xy 280.45918 -294.694864) (xy 280.465352 -294.701235) (xy 280.477043 -294.714579)
			(xy 280.482548 -294.721534) (xy 280.48331 -294.722296) (xy 280.486358 -294.725852) (xy 280.505408 -294.754554)
			(xy 280.518621 -294.777957) (xy 280.537508 -294.828267) (xy 280.547298 -294.881106) (xy 280.54808 -294.90797)
			(xy 280.54808 -295.697402) (xy 280.548478 -295.706891) (xy 280.555372 -295.724574) (xy 280.568192 -295.73857)
			(xy 280.576528 -295.743122) (xy 280.589482 -295.749472) (xy 280.618184 -295.746424) (xy 281.313382 -295.209468)
			(xy 281.320834 -295.204202) (xy 281.338255 -295.198818) (xy 281.35646 -295.199847) (xy 281.373164 -295.207159)
			(xy 281.37993 -295.213278) (xy 281.380438 -295.213786) (xy 281.386563 -295.220349) (xy 281.394119 -295.236621)
			(xy 281.39517 -295.245536) (xy 281.395932 -295.25468) (xy 281.390852 -295.27246) (xy 281.328536 -295.355518)
			(xy 324.815706 -295.355518) (xy 324.819777 -295.299896) (xy 324.831903 -295.245459) (xy 324.851826 -295.193368)
			(xy 324.879122 -295.144733) (xy 324.913208 -295.10059) (xy 324.953357 -295.061881) (xy 324.998715 -295.02943)
			(xy 325.048315 -295.003929) (xy 325.101099 -294.985922) (xy 325.155942 -294.975792) (xy 325.211676 -294.973755)
			(xy 325.267113 -294.979855) (xy 325.32107 -294.993961) (xy 325.372399 -295.015773) (xy 325.420005 -295.044827)
			(xy 325.462873 -295.080502) (xy 325.50009 -295.122039) (xy 325.530863 -295.168552) (xy 325.554535 -295.219049)
			(xy 325.570603 -295.272456) (xy 325.578723 -295.327632) (xy 325.579232 -295.355518) (xy 325.578723 -295.383404)
			(xy 325.570603 -295.43858) (xy 325.554535 -295.491987) (xy 325.530863 -295.542484) (xy 325.50009 -295.588997)
			(xy 325.462873 -295.630534) (xy 325.420005 -295.666209) (xy 325.372399 -295.695263) (xy 325.32107 -295.717075)
			(xy 325.267113 -295.731181) (xy 325.211676 -295.737281) (xy 325.155942 -295.735244) (xy 325.101099 -295.725114)
			(xy 325.048315 -295.707107) (xy 324.998715 -295.681606) (xy 324.953357 -295.649155) (xy 324.913208 -295.610446)
			(xy 324.879122 -295.566303) (xy 324.851826 -295.517668) (xy 324.831903 -295.465577) (xy 324.819777 -295.41114)
			(xy 324.815706 -295.355518) (xy 281.328536 -295.355518) (xy 280.85288 -295.989502) (xy 280.846559 -295.998967)
			(xy 280.842086 -296.021252) (xy 280.844244 -296.032428) (xy 280.848816 -296.05097) (xy 280.879296 -296.072306)
			(xy 280.898092 -296.070782) (xy 280.924762 -296.069512) (xy 280.933144 -296.069512) (xy 280.956706 -296.070588)
			(xy 281.003095 -296.0791) (xy 281.047623 -296.094646) (xy 281.08923 -296.116858) (xy 281.126924 -296.145206)
			(xy 281.159808 -296.179016) (xy 281.1871 -296.217481) (xy 281.208149 -296.259688) (xy 281.222455 -296.30463)
			(xy 281.229677 -296.351238) (xy 281.23007 -296.37482) (xy 282.519132 -296.37482) (xy 282.523092 -296.325766)
			(xy 282.534869 -296.277982) (xy 282.55416 -296.232706) (xy 282.580463 -296.19111) (xy 282.613098 -296.154273)
			(xy 282.651219 -296.123148) (xy 282.69384 -296.098541) (xy 282.739856 -296.081089) (xy 282.788075 -296.071245)
			(xy 282.83725 -296.069264) (xy 282.886105 -296.075196) (xy 282.933376 -296.088888) (xy 282.977838 -296.109986)
			(xy 283.018341 -296.137942) (xy 283.053834 -296.172034) (xy 283.083399 -296.211378) (xy 283.10627 -296.254955)
			(xy 283.121854 -296.301636) (xy 283.129749 -296.350213) (xy 283.130244 -296.37482) (xy 284.419052 -296.37482)
			(xy 284.423012 -296.325766) (xy 284.434789 -296.277982) (xy 284.45408 -296.232706) (xy 284.480383 -296.19111)
			(xy 284.513018 -296.154273) (xy 284.551139 -296.123148) (xy 284.59376 -296.098541) (xy 284.639776 -296.081089)
			(xy 284.687995 -296.071245) (xy 284.73717 -296.069264) (xy 284.786025 -296.075196) (xy 284.833296 -296.088888)
			(xy 284.877758 -296.109986) (xy 284.918261 -296.137942) (xy 284.953754 -296.172034) (xy 284.983319 -296.211378)
			(xy 285.00619 -296.254955) (xy 285.021774 -296.301636) (xy 285.029669 -296.350213) (xy 285.030164 -296.37482)
			(xy 286.318972 -296.37482) (xy 286.322932 -296.325766) (xy 286.334709 -296.277982) (xy 286.354 -296.232706)
			(xy 286.380303 -296.19111) (xy 286.412938 -296.154273) (xy 286.451059 -296.123148) (xy 286.49368 -296.098541)
			(xy 286.539696 -296.081089) (xy 286.587915 -296.071245) (xy 286.63709 -296.069264) (xy 286.685945 -296.075196)
			(xy 286.733216 -296.088888) (xy 286.777678 -296.109986) (xy 286.818181 -296.137942) (xy 286.853674 -296.172034)
			(xy 286.883239 -296.211378) (xy 286.90611 -296.254955) (xy 286.921694 -296.301636) (xy 286.929589 -296.350213)
			(xy 286.930084 -296.37482) (xy 288.219146 -296.37482) (xy 288.223106 -296.325766) (xy 288.234883 -296.277982)
			(xy 288.254174 -296.232706) (xy 288.280477 -296.19111) (xy 288.313112 -296.154273) (xy 288.351233 -296.123148)
			(xy 288.393854 -296.098541) (xy 288.43987 -296.081089) (xy 288.488089 -296.071245) (xy 288.537264 -296.069264)
			(xy 288.586119 -296.075196) (xy 288.63339 -296.088888) (xy 288.677852 -296.109986) (xy 288.718355 -296.137942)
			(xy 288.753848 -296.172034) (xy 288.783413 -296.211378) (xy 288.806284 -296.254955) (xy 288.821868 -296.301636)
			(xy 288.829763 -296.350213) (xy 288.830258 -296.37482) (xy 290.119066 -296.37482) (xy 290.123026 -296.325766)
			(xy 290.134803 -296.277982) (xy 290.154094 -296.232706) (xy 290.180397 -296.19111) (xy 290.213032 -296.154273)
			(xy 290.251153 -296.123148) (xy 290.293774 -296.098541) (xy 290.33979 -296.081089) (xy 290.388009 -296.071245)
			(xy 290.437184 -296.069264) (xy 290.486039 -296.075196) (xy 290.53331 -296.088888) (xy 290.577772 -296.109986)
			(xy 290.618275 -296.137942) (xy 290.653768 -296.172034) (xy 290.683333 -296.211378) (xy 290.706204 -296.254955)
			(xy 290.721788 -296.301636) (xy 290.729683 -296.350213) (xy 290.730178 -296.37482) (xy 292.968946 -296.37482)
			(xy 292.972906 -296.325766) (xy 292.984683 -296.277982) (xy 293.003974 -296.232706) (xy 293.030277 -296.19111)
			(xy 293.062912 -296.154273) (xy 293.101033 -296.123148) (xy 293.143654 -296.098541) (xy 293.18967 -296.081089)
			(xy 293.237889 -296.071245) (xy 293.287064 -296.069264) (xy 293.335919 -296.075196) (xy 293.38319 -296.088888)
			(xy 293.427652 -296.109986) (xy 293.468155 -296.137942) (xy 293.503648 -296.172034) (xy 293.533213 -296.211378)
			(xy 293.556084 -296.254955) (xy 293.571668 -296.301636) (xy 293.579563 -296.350213) (xy 293.580058 -296.37482)
			(xy 294.86912 -296.37482) (xy 294.87308 -296.325766) (xy 294.884857 -296.277982) (xy 294.904148 -296.232706)
			(xy 294.930451 -296.19111) (xy 294.963086 -296.154273) (xy 295.001207 -296.123148) (xy 295.043828 -296.098541)
			(xy 295.089844 -296.081089) (xy 295.138063 -296.071245) (xy 295.187238 -296.069264) (xy 295.236093 -296.075196)
			(xy 295.283364 -296.088888) (xy 295.327826 -296.109986) (xy 295.368329 -296.137942) (xy 295.403822 -296.172034)
			(xy 295.433387 -296.211378) (xy 295.456258 -296.254955) (xy 295.471842 -296.301636) (xy 295.479737 -296.350213)
			(xy 295.480232 -296.37482) (xy 296.76904 -296.37482) (xy 296.773 -296.325766) (xy 296.784777 -296.277982)
			(xy 296.804068 -296.232706) (xy 296.830371 -296.19111) (xy 296.863006 -296.154273) (xy 296.901127 -296.123148)
			(xy 296.943748 -296.098541) (xy 296.989764 -296.081089) (xy 297.037983 -296.071245) (xy 297.087158 -296.069264)
			(xy 297.136013 -296.075196) (xy 297.183284 -296.088888) (xy 297.227746 -296.109986) (xy 297.268249 -296.137942)
			(xy 297.303742 -296.172034) (xy 297.333307 -296.211378) (xy 297.356178 -296.254955) (xy 297.371762 -296.301636)
			(xy 297.379657 -296.350213) (xy 297.380152 -296.37482) (xy 298.66896 -296.37482) (xy 298.67292 -296.325766)
			(xy 298.684697 -296.277982) (xy 298.703988 -296.232706) (xy 298.730291 -296.19111) (xy 298.762926 -296.154273)
			(xy 298.801047 -296.123148) (xy 298.843668 -296.098541) (xy 298.889684 -296.081089) (xy 298.937903 -296.071245)
			(xy 298.987078 -296.069264) (xy 299.035933 -296.075196) (xy 299.083204 -296.088888) (xy 299.127666 -296.109986)
			(xy 299.168169 -296.137942) (xy 299.203662 -296.172034) (xy 299.233227 -296.211378) (xy 299.256098 -296.254955)
			(xy 299.271682 -296.301636) (xy 299.279577 -296.350213) (xy 299.280072 -296.37482) (xy 299.61892 -296.37482)
			(xy 299.62288 -296.325766) (xy 299.634657 -296.277982) (xy 299.653948 -296.232706) (xy 299.680251 -296.19111)
			(xy 299.712886 -296.154273) (xy 299.751007 -296.123148) (xy 299.793628 -296.098541) (xy 299.839644 -296.081089)
			(xy 299.887863 -296.071245) (xy 299.937038 -296.069264) (xy 299.985893 -296.075196) (xy 300.033164 -296.088888)
			(xy 300.077626 -296.109986) (xy 300.118129 -296.137942) (xy 300.153622 -296.172034) (xy 300.183187 -296.211378)
			(xy 300.206058 -296.254955) (xy 300.221642 -296.301636) (xy 300.229537 -296.350213) (xy 300.230032 -296.37482)
			(xy 300.56888 -296.37482) (xy 300.57284 -296.325766) (xy 300.584617 -296.277982) (xy 300.603908 -296.232706)
			(xy 300.630211 -296.19111) (xy 300.662846 -296.154273) (xy 300.700967 -296.123148) (xy 300.743588 -296.098541)
			(xy 300.789604 -296.081089) (xy 300.837823 -296.071245) (xy 300.886998 -296.069264) (xy 300.935853 -296.075196)
			(xy 300.983124 -296.088888) (xy 301.027586 -296.109986) (xy 301.068089 -296.137942) (xy 301.103582 -296.172034)
			(xy 301.133147 -296.211378) (xy 301.156018 -296.254955) (xy 301.171602 -296.301636) (xy 301.179497 -296.350213)
			(xy 301.179992 -296.37482) (xy 301.519094 -296.37482) (xy 301.523054 -296.325766) (xy 301.534831 -296.277982)
			(xy 301.554122 -296.232706) (xy 301.580425 -296.19111) (xy 301.61306 -296.154273) (xy 301.651181 -296.123148)
			(xy 301.693802 -296.098541) (xy 301.739818 -296.081089) (xy 301.788037 -296.071245) (xy 301.837212 -296.069264)
			(xy 301.886067 -296.075196) (xy 301.933338 -296.088888) (xy 301.9778 -296.109986) (xy 302.018303 -296.137942)
			(xy 302.053796 -296.172034) (xy 302.083361 -296.211378) (xy 302.106232 -296.254955) (xy 302.121816 -296.301636)
			(xy 302.129711 -296.350213) (xy 302.130206 -296.37482) (xy 302.469054 -296.37482) (xy 302.473014 -296.325766)
			(xy 302.484791 -296.277982) (xy 302.504082 -296.232706) (xy 302.530385 -296.19111) (xy 302.56302 -296.154273)
			(xy 302.601141 -296.123148) (xy 302.643762 -296.098541) (xy 302.689778 -296.081089) (xy 302.737997 -296.071245)
			(xy 302.787172 -296.069264) (xy 302.836027 -296.075196) (xy 302.883298 -296.088888) (xy 302.92776 -296.109986)
			(xy 302.968263 -296.137942) (xy 303.003756 -296.172034) (xy 303.033321 -296.211378) (xy 303.056192 -296.254955)
			(xy 303.071776 -296.301636) (xy 303.079671 -296.350213) (xy 303.080166 -296.37482) (xy 303.419014 -296.37482)
			(xy 303.422974 -296.325766) (xy 303.434751 -296.277982) (xy 303.454042 -296.232706) (xy 303.480345 -296.19111)
			(xy 303.51298 -296.154273) (xy 303.551101 -296.123148) (xy 303.593722 -296.098541) (xy 303.639738 -296.081089)
			(xy 303.687957 -296.071245) (xy 303.737132 -296.069264) (xy 303.785987 -296.075196) (xy 303.833258 -296.088888)
			(xy 303.87772 -296.109986) (xy 303.918223 -296.137942) (xy 303.953716 -296.172034) (xy 303.983281 -296.211378)
			(xy 304.006152 -296.254955) (xy 304.021736 -296.301636) (xy 304.029631 -296.350213) (xy 304.030126 -296.37482)
			(xy 304.368974 -296.37482) (xy 304.372934 -296.325766) (xy 304.384711 -296.277982) (xy 304.404002 -296.232706)
			(xy 304.430305 -296.19111) (xy 304.46294 -296.154273) (xy 304.501061 -296.123148) (xy 304.543682 -296.098541)
			(xy 304.589698 -296.081089) (xy 304.637917 -296.071245) (xy 304.687092 -296.069264) (xy 304.735947 -296.075196)
			(xy 304.783218 -296.088888) (xy 304.82768 -296.109986) (xy 304.868183 -296.137942) (xy 304.903676 -296.172034)
			(xy 304.933241 -296.211378) (xy 304.956112 -296.254955) (xy 304.971696 -296.301636) (xy 304.979591 -296.350213)
			(xy 304.980086 -296.37482) (xy 305.318934 -296.37482) (xy 305.322894 -296.325766) (xy 305.334671 -296.277982)
			(xy 305.353962 -296.232706) (xy 305.380265 -296.19111) (xy 305.4129 -296.154273) (xy 305.451021 -296.123148)
			(xy 305.493642 -296.098541) (xy 305.539658 -296.081089) (xy 305.587877 -296.071245) (xy 305.637052 -296.069264)
			(xy 305.685907 -296.075196) (xy 305.733178 -296.088888) (xy 305.77764 -296.109986) (xy 305.818143 -296.137942)
			(xy 305.853636 -296.172034) (xy 305.883201 -296.211378) (xy 305.906072 -296.254955) (xy 305.921656 -296.301636)
			(xy 305.929551 -296.350213) (xy 305.930046 -296.37482) (xy 306.268894 -296.37482) (xy 306.272854 -296.325766)
			(xy 306.284631 -296.277982) (xy 306.303922 -296.232706) (xy 306.330225 -296.19111) (xy 306.36286 -296.154273)
			(xy 306.400981 -296.123148) (xy 306.443602 -296.098541) (xy 306.489618 -296.081089) (xy 306.537837 -296.071245)
			(xy 306.587012 -296.069264) (xy 306.635867 -296.075196) (xy 306.683138 -296.088888) (xy 306.7276 -296.109986)
			(xy 306.768103 -296.137942) (xy 306.803596 -296.172034) (xy 306.833161 -296.211378) (xy 306.856032 -296.254955)
			(xy 306.871616 -296.301636) (xy 306.879511 -296.350213) (xy 306.880006 -296.37482) (xy 307.219108 -296.37482)
			(xy 307.223068 -296.325766) (xy 307.234845 -296.277982) (xy 307.254136 -296.232706) (xy 307.280439 -296.19111)
			(xy 307.313074 -296.154273) (xy 307.351195 -296.123148) (xy 307.393816 -296.098541) (xy 307.439832 -296.081089)
			(xy 307.488051 -296.071245) (xy 307.537226 -296.069264) (xy 307.586081 -296.075196) (xy 307.633352 -296.088888)
			(xy 307.677814 -296.109986) (xy 307.718317 -296.137942) (xy 307.75381 -296.172034) (xy 307.783375 -296.211378)
			(xy 307.806246 -296.254955) (xy 307.82183 -296.301636) (xy 307.829725 -296.350213) (xy 307.83022 -296.37482)
			(xy 308.169068 -296.37482) (xy 308.173028 -296.325766) (xy 308.184805 -296.277982) (xy 308.204096 -296.232706)
			(xy 308.230399 -296.19111) (xy 308.263034 -296.154273) (xy 308.301155 -296.123148) (xy 308.343776 -296.098541)
			(xy 308.389792 -296.081089) (xy 308.438011 -296.071245) (xy 308.487186 -296.069264) (xy 308.536041 -296.075196)
			(xy 308.583312 -296.088888) (xy 308.627774 -296.109986) (xy 308.668277 -296.137942) (xy 308.70377 -296.172034)
			(xy 308.733335 -296.211378) (xy 308.756206 -296.254955) (xy 308.77179 -296.301636) (xy 308.779685 -296.350213)
			(xy 308.78018 -296.37482) (xy 309.119028 -296.37482) (xy 309.122988 -296.325766) (xy 309.134765 -296.277982)
			(xy 309.154056 -296.232706) (xy 309.180359 -296.19111) (xy 309.212994 -296.154273) (xy 309.251115 -296.123148)
			(xy 309.293736 -296.098541) (xy 309.339752 -296.081089) (xy 309.387971 -296.071245) (xy 309.437146 -296.069264)
			(xy 309.486001 -296.075196) (xy 309.533272 -296.088888) (xy 309.577734 -296.109986) (xy 309.618237 -296.137942)
			(xy 309.65373 -296.172034) (xy 309.683295 -296.211378) (xy 309.706166 -296.254955) (xy 309.72175 -296.301636)
			(xy 309.729645 -296.350213) (xy 309.73014 -296.37482) (xy 310.068988 -296.37482) (xy 310.072948 -296.325766)
			(xy 310.084725 -296.277982) (xy 310.104016 -296.232706) (xy 310.130319 -296.19111) (xy 310.162954 -296.154273)
			(xy 310.201075 -296.123148) (xy 310.243696 -296.098541) (xy 310.289712 -296.081089) (xy 310.337931 -296.071245)
			(xy 310.387106 -296.069264) (xy 310.435961 -296.075196) (xy 310.483232 -296.088888) (xy 310.527694 -296.109986)
			(xy 310.568197 -296.137942) (xy 310.60369 -296.172034) (xy 310.633255 -296.211378) (xy 310.656126 -296.254955)
			(xy 310.67171 -296.301636) (xy 310.679605 -296.350213) (xy 310.6801 -296.37482) (xy 311.018948 -296.37482)
			(xy 311.022908 -296.325766) (xy 311.034685 -296.277982) (xy 311.053976 -296.232706) (xy 311.080279 -296.19111)
			(xy 311.112914 -296.154273) (xy 311.151035 -296.123148) (xy 311.193656 -296.098541) (xy 311.239672 -296.081089)
			(xy 311.287891 -296.071245) (xy 311.337066 -296.069264) (xy 311.385921 -296.075196) (xy 311.433192 -296.088888)
			(xy 311.477654 -296.109986) (xy 311.518157 -296.137942) (xy 311.55365 -296.172034) (xy 311.583215 -296.211378)
			(xy 311.606086 -296.254955) (xy 311.62167 -296.301636) (xy 311.629565 -296.350213) (xy 311.63006 -296.37482)
			(xy 311.968908 -296.37482) (xy 311.972868 -296.325766) (xy 311.984645 -296.277982) (xy 312.003936 -296.232706)
			(xy 312.030239 -296.19111) (xy 312.062874 -296.154273) (xy 312.100995 -296.123148) (xy 312.143616 -296.098541)
			(xy 312.189632 -296.081089) (xy 312.237851 -296.071245) (xy 312.287026 -296.069264) (xy 312.335881 -296.075196)
			(xy 312.383152 -296.088888) (xy 312.427614 -296.109986) (xy 312.468117 -296.137942) (xy 312.50361 -296.172034)
			(xy 312.533175 -296.211378) (xy 312.556046 -296.254955) (xy 312.57163 -296.301636) (xy 312.579525 -296.350213)
			(xy 312.58002 -296.37482) (xy 312.919122 -296.37482) (xy 312.923082 -296.325766) (xy 312.934859 -296.277982)
			(xy 312.95415 -296.232706) (xy 312.980453 -296.19111) (xy 313.013088 -296.154273) (xy 313.051209 -296.123148)
			(xy 313.09383 -296.098541) (xy 313.139846 -296.081089) (xy 313.188065 -296.071245) (xy 313.23724 -296.069264)
			(xy 313.286095 -296.075196) (xy 313.333366 -296.088888) (xy 313.377828 -296.109986) (xy 313.418331 -296.137942)
			(xy 313.453824 -296.172034) (xy 313.483389 -296.211378) (xy 313.50626 -296.254955) (xy 313.521844 -296.301636)
			(xy 313.529739 -296.350213) (xy 313.530234 -296.37482) (xy 313.869082 -296.37482) (xy 313.873042 -296.325766)
			(xy 313.884819 -296.277982) (xy 313.90411 -296.232706) (xy 313.930413 -296.19111) (xy 313.963048 -296.154273)
			(xy 314.001169 -296.123148) (xy 314.04379 -296.098541) (xy 314.089806 -296.081089) (xy 314.138025 -296.071245)
			(xy 314.1872 -296.069264) (xy 314.236055 -296.075196) (xy 314.283326 -296.088888) (xy 314.327788 -296.109986)
			(xy 314.368291 -296.137942) (xy 314.403784 -296.172034) (xy 314.433349 -296.211378) (xy 314.45622 -296.254955)
			(xy 314.471804 -296.301636) (xy 314.479699 -296.350213) (xy 314.480194 -296.37482) (xy 314.819042 -296.37482)
			(xy 314.823002 -296.325766) (xy 314.834779 -296.277982) (xy 314.85407 -296.232706) (xy 314.880373 -296.19111)
			(xy 314.913008 -296.154273) (xy 314.951129 -296.123148) (xy 314.99375 -296.098541) (xy 315.039766 -296.081089)
			(xy 315.087985 -296.071245) (xy 315.13716 -296.069264) (xy 315.186015 -296.075196) (xy 315.233286 -296.088888)
			(xy 315.277748 -296.109986) (xy 315.318251 -296.137942) (xy 315.353744 -296.172034) (xy 315.360113 -296.18051)
			(xy 316.956184 -296.18051) (xy 316.960255 -296.124888) (xy 316.972381 -296.070451) (xy 316.992304 -296.01836)
			(xy 317.0196 -295.969725) (xy 317.053686 -295.925582) (xy 317.093835 -295.886873) (xy 317.139193 -295.854422)
			(xy 317.188793 -295.828921) (xy 317.241577 -295.810914) (xy 317.29642 -295.800784) (xy 317.352154 -295.798747)
			(xy 317.407591 -295.804847) (xy 317.461548 -295.818953) (xy 317.512877 -295.840765) (xy 317.560483 -295.869819)
			(xy 317.603351 -295.905494) (xy 317.640568 -295.947031) (xy 317.671341 -295.993544) (xy 317.695013 -296.044041)
			(xy 317.711081 -296.097448) (xy 317.719201 -296.152624) (xy 317.71971 -296.18051) (xy 317.719201 -296.208396)
			(xy 317.711081 -296.263572) (xy 317.695013 -296.316979) (xy 317.671341 -296.367476) (xy 317.640568 -296.413989)
			(xy 317.603351 -296.455526) (xy 317.560483 -296.491201) (xy 317.512877 -296.520255) (xy 317.461548 -296.542067)
			(xy 317.407591 -296.556173) (xy 317.352154 -296.562273) (xy 317.29642 -296.560236) (xy 317.241577 -296.550106)
			(xy 317.188793 -296.532099) (xy 317.139193 -296.506598) (xy 317.093835 -296.474147) (xy 317.053686 -296.435438)
			(xy 317.0196 -296.391295) (xy 316.992304 -296.34266) (xy 316.972381 -296.290569) (xy 316.960255 -296.236132)
			(xy 316.956184 -296.18051) (xy 315.360113 -296.18051) (xy 315.383309 -296.211378) (xy 315.40618 -296.254955)
			(xy 315.421764 -296.301636) (xy 315.429659 -296.350213) (xy 315.430154 -296.37482) (xy 315.429659 -296.399427)
			(xy 315.421764 -296.448004) (xy 315.40618 -296.494685) (xy 315.383309 -296.538262) (xy 315.353744 -296.577606)
			(xy 315.318251 -296.611698) (xy 315.31626 -296.613072) (xy 321.462398 -296.613072) (xy 321.466469 -296.55745)
			(xy 321.478595 -296.503013) (xy 321.498518 -296.450922) (xy 321.525814 -296.402287) (xy 321.5599 -296.358144)
			(xy 321.600049 -296.319435) (xy 321.645407 -296.286984) (xy 321.695007 -296.261483) (xy 321.747791 -296.243476)
			(xy 321.802634 -296.233346) (xy 321.858368 -296.231309) (xy 321.913805 -296.237409) (xy 321.967762 -296.251515)
			(xy 322.019091 -296.273327) (xy 322.066697 -296.302381) (xy 322.109565 -296.338056) (xy 322.146782 -296.379593)
			(xy 322.177555 -296.426106) (xy 322.201227 -296.476603) (xy 322.217295 -296.53001) (xy 322.225415 -296.585186)
			(xy 322.225924 -296.613072) (xy 322.737224 -296.613072) (xy 322.741295 -296.55745) (xy 322.753421 -296.503013)
			(xy 322.773344 -296.450922) (xy 322.80064 -296.402287) (xy 322.834726 -296.358144) (xy 322.874875 -296.319435)
			(xy 322.920233 -296.286984) (xy 322.969833 -296.261483) (xy 323.022617 -296.243476) (xy 323.07746 -296.233346)
			(xy 323.133194 -296.231309) (xy 323.188631 -296.237409) (xy 323.242588 -296.251515) (xy 323.293917 -296.273327)
			(xy 323.341523 -296.302381) (xy 323.384391 -296.338056) (xy 323.421608 -296.379593) (xy 323.452381 -296.426106)
			(xy 323.476053 -296.476603) (xy 323.492121 -296.53001) (xy 323.500241 -296.585186) (xy 323.50075 -296.613072)
			(xy 323.500241 -296.640958) (xy 323.492121 -296.696134) (xy 323.476053 -296.749541) (xy 323.452381 -296.800038)
			(xy 323.421608 -296.846551) (xy 323.384391 -296.888088) (xy 323.341523 -296.923763) (xy 323.293917 -296.952817)
			(xy 323.242588 -296.974629) (xy 323.188631 -296.988735) (xy 323.133194 -296.994835) (xy 323.07746 -296.992798)
			(xy 323.022617 -296.982668) (xy 322.969833 -296.964661) (xy 322.920233 -296.93916) (xy 322.874875 -296.906709)
			(xy 322.834726 -296.868) (xy 322.80064 -296.823857) (xy 322.773344 -296.775222) (xy 322.753421 -296.723131)
			(xy 322.741295 -296.668694) (xy 322.737224 -296.613072) (xy 322.225924 -296.613072) (xy 322.225415 -296.640958)
			(xy 322.217295 -296.696134) (xy 322.201227 -296.749541) (xy 322.177555 -296.800038) (xy 322.146782 -296.846551)
			(xy 322.109565 -296.888088) (xy 322.066697 -296.923763) (xy 322.019091 -296.952817) (xy 321.967762 -296.974629)
			(xy 321.913805 -296.988735) (xy 321.858368 -296.994835) (xy 321.802634 -296.992798) (xy 321.747791 -296.982668)
			(xy 321.695007 -296.964661) (xy 321.645407 -296.93916) (xy 321.600049 -296.906709) (xy 321.5599 -296.868)
			(xy 321.525814 -296.823857) (xy 321.498518 -296.775222) (xy 321.478595 -296.723131) (xy 321.466469 -296.668694)
			(xy 321.462398 -296.613072) (xy 315.31626 -296.613072) (xy 315.277748 -296.639654) (xy 315.233286 -296.660752)
			(xy 315.186015 -296.674444) (xy 315.13716 -296.680376) (xy 315.087985 -296.678395) (xy 315.039766 -296.668551)
			(xy 314.99375 -296.651099) (xy 314.951129 -296.626492) (xy 314.913008 -296.595367) (xy 314.880373 -296.55853)
			(xy 314.85407 -296.516934) (xy 314.834779 -296.471658) (xy 314.823002 -296.423874) (xy 314.819042 -296.37482)
			(xy 314.480194 -296.37482) (xy 314.479699 -296.399427) (xy 314.471804 -296.448004) (xy 314.45622 -296.494685)
			(xy 314.433349 -296.538262) (xy 314.403784 -296.577606) (xy 314.368291 -296.611698) (xy 314.327788 -296.639654)
			(xy 314.283326 -296.660752) (xy 314.236055 -296.674444) (xy 314.1872 -296.680376) (xy 314.138025 -296.678395)
			(xy 314.089806 -296.668551) (xy 314.04379 -296.651099) (xy 314.001169 -296.626492) (xy 313.963048 -296.595367)
			(xy 313.930413 -296.55853) (xy 313.90411 -296.516934) (xy 313.884819 -296.471658) (xy 313.873042 -296.423874)
			(xy 313.869082 -296.37482) (xy 313.530234 -296.37482) (xy 313.529739 -296.399427) (xy 313.521844 -296.448004)
			(xy 313.50626 -296.494685) (xy 313.483389 -296.538262) (xy 313.453824 -296.577606) (xy 313.418331 -296.611698)
			(xy 313.377828 -296.639654) (xy 313.333366 -296.660752) (xy 313.286095 -296.674444) (xy 313.23724 -296.680376)
			(xy 313.188065 -296.678395) (xy 313.139846 -296.668551) (xy 313.09383 -296.651099) (xy 313.051209 -296.626492)
			(xy 313.013088 -296.595367) (xy 312.980453 -296.55853) (xy 312.95415 -296.516934) (xy 312.934859 -296.471658)
			(xy 312.923082 -296.423874) (xy 312.919122 -296.37482) (xy 312.58002 -296.37482) (xy 312.579525 -296.399427)
			(xy 312.57163 -296.448004) (xy 312.556046 -296.494685) (xy 312.533175 -296.538262) (xy 312.50361 -296.577606)
			(xy 312.468117 -296.611698) (xy 312.427614 -296.639654) (xy 312.383152 -296.660752) (xy 312.335881 -296.674444)
			(xy 312.287026 -296.680376) (xy 312.237851 -296.678395) (xy 312.189632 -296.668551) (xy 312.143616 -296.651099)
			(xy 312.100995 -296.626492) (xy 312.062874 -296.595367) (xy 312.030239 -296.55853) (xy 312.003936 -296.516934)
			(xy 311.984645 -296.471658) (xy 311.972868 -296.423874) (xy 311.968908 -296.37482) (xy 311.63006 -296.37482)
			(xy 311.629565 -296.399427) (xy 311.62167 -296.448004) (xy 311.606086 -296.494685) (xy 311.583215 -296.538262)
			(xy 311.55365 -296.577606) (xy 311.518157 -296.611698) (xy 311.477654 -296.639654) (xy 311.433192 -296.660752)
			(xy 311.385921 -296.674444) (xy 311.337066 -296.680376) (xy 311.287891 -296.678395) (xy 311.239672 -296.668551)
			(xy 311.193656 -296.651099) (xy 311.151035 -296.626492) (xy 311.112914 -296.595367) (xy 311.080279 -296.55853)
			(xy 311.053976 -296.516934) (xy 311.034685 -296.471658) (xy 311.022908 -296.423874) (xy 311.018948 -296.37482)
			(xy 310.6801 -296.37482) (xy 310.679605 -296.399427) (xy 310.67171 -296.448004) (xy 310.656126 -296.494685)
			(xy 310.633255 -296.538262) (xy 310.60369 -296.577606) (xy 310.568197 -296.611698) (xy 310.527694 -296.639654)
			(xy 310.483232 -296.660752) (xy 310.435961 -296.674444) (xy 310.387106 -296.680376) (xy 310.337931 -296.678395)
			(xy 310.289712 -296.668551) (xy 310.243696 -296.651099) (xy 310.201075 -296.626492) (xy 310.162954 -296.595367)
			(xy 310.130319 -296.55853) (xy 310.104016 -296.516934) (xy 310.084725 -296.471658) (xy 310.072948 -296.423874)
			(xy 310.068988 -296.37482) (xy 309.73014 -296.37482) (xy 309.729645 -296.399427) (xy 309.72175 -296.448004)
			(xy 309.706166 -296.494685) (xy 309.683295 -296.538262) (xy 309.65373 -296.577606) (xy 309.618237 -296.611698)
			(xy 309.577734 -296.639654) (xy 309.533272 -296.660752) (xy 309.486001 -296.674444) (xy 309.437146 -296.680376)
			(xy 309.387971 -296.678395) (xy 309.339752 -296.668551) (xy 309.293736 -296.651099) (xy 309.251115 -296.626492)
			(xy 309.212994 -296.595367) (xy 309.180359 -296.55853) (xy 309.154056 -296.516934) (xy 309.134765 -296.471658)
			(xy 309.122988 -296.423874) (xy 309.119028 -296.37482) (xy 308.78018 -296.37482) (xy 308.779685 -296.399427)
			(xy 308.77179 -296.448004) (xy 308.756206 -296.494685) (xy 308.733335 -296.538262) (xy 308.70377 -296.577606)
			(xy 308.668277 -296.611698) (xy 308.627774 -296.639654) (xy 308.583312 -296.660752) (xy 308.536041 -296.674444)
			(xy 308.487186 -296.680376) (xy 308.438011 -296.678395) (xy 308.389792 -296.668551) (xy 308.343776 -296.651099)
			(xy 308.301155 -296.626492) (xy 308.263034 -296.595367) (xy 308.230399 -296.55853) (xy 308.204096 -296.516934)
			(xy 308.184805 -296.471658) (xy 308.173028 -296.423874) (xy 308.169068 -296.37482) (xy 307.83022 -296.37482)
			(xy 307.829725 -296.399427) (xy 307.82183 -296.448004) (xy 307.806246 -296.494685) (xy 307.783375 -296.538262)
			(xy 307.75381 -296.577606) (xy 307.718317 -296.611698) (xy 307.677814 -296.639654) (xy 307.633352 -296.660752)
			(xy 307.586081 -296.674444) (xy 307.537226 -296.680376) (xy 307.488051 -296.678395) (xy 307.439832 -296.668551)
			(xy 307.393816 -296.651099) (xy 307.351195 -296.626492) (xy 307.313074 -296.595367) (xy 307.280439 -296.55853)
			(xy 307.254136 -296.516934) (xy 307.234845 -296.471658) (xy 307.223068 -296.423874) (xy 307.219108 -296.37482)
			(xy 306.880006 -296.37482) (xy 306.879511 -296.399427) (xy 306.871616 -296.448004) (xy 306.856032 -296.494685)
			(xy 306.833161 -296.538262) (xy 306.803596 -296.577606) (xy 306.768103 -296.611698) (xy 306.7276 -296.639654)
			(xy 306.683138 -296.660752) (xy 306.635867 -296.674444) (xy 306.587012 -296.680376) (xy 306.537837 -296.678395)
			(xy 306.489618 -296.668551) (xy 306.443602 -296.651099) (xy 306.400981 -296.626492) (xy 306.36286 -296.595367)
			(xy 306.330225 -296.55853) (xy 306.303922 -296.516934) (xy 306.284631 -296.471658) (xy 306.272854 -296.423874)
			(xy 306.268894 -296.37482) (xy 305.930046 -296.37482) (xy 305.929551 -296.399427) (xy 305.921656 -296.448004)
			(xy 305.906072 -296.494685) (xy 305.883201 -296.538262) (xy 305.853636 -296.577606) (xy 305.818143 -296.611698)
			(xy 305.77764 -296.639654) (xy 305.733178 -296.660752) (xy 305.685907 -296.674444) (xy 305.637052 -296.680376)
			(xy 305.587877 -296.678395) (xy 305.539658 -296.668551) (xy 305.493642 -296.651099) (xy 305.451021 -296.626492)
			(xy 305.4129 -296.595367) (xy 305.380265 -296.55853) (xy 305.353962 -296.516934) (xy 305.334671 -296.471658)
			(xy 305.322894 -296.423874) (xy 305.318934 -296.37482) (xy 304.980086 -296.37482) (xy 304.979591 -296.399427)
			(xy 304.971696 -296.448004) (xy 304.956112 -296.494685) (xy 304.933241 -296.538262) (xy 304.903676 -296.577606)
			(xy 304.868183 -296.611698) (xy 304.82768 -296.639654) (xy 304.783218 -296.660752) (xy 304.735947 -296.674444)
			(xy 304.687092 -296.680376) (xy 304.637917 -296.678395) (xy 304.589698 -296.668551) (xy 304.543682 -296.651099)
			(xy 304.501061 -296.626492) (xy 304.46294 -296.595367) (xy 304.430305 -296.55853) (xy 304.404002 -296.516934)
			(xy 304.384711 -296.471658) (xy 304.372934 -296.423874) (xy 304.368974 -296.37482) (xy 304.030126 -296.37482)
			(xy 304.029631 -296.399427) (xy 304.021736 -296.448004) (xy 304.006152 -296.494685) (xy 303.983281 -296.538262)
			(xy 303.953716 -296.577606) (xy 303.918223 -296.611698) (xy 303.87772 -296.639654) (xy 303.833258 -296.660752)
			(xy 303.785987 -296.674444) (xy 303.737132 -296.680376) (xy 303.687957 -296.678395) (xy 303.639738 -296.668551)
			(xy 303.593722 -296.651099) (xy 303.551101 -296.626492) (xy 303.51298 -296.595367) (xy 303.480345 -296.55853)
			(xy 303.454042 -296.516934) (xy 303.434751 -296.471658) (xy 303.422974 -296.423874) (xy 303.419014 -296.37482)
			(xy 303.080166 -296.37482) (xy 303.079671 -296.399427) (xy 303.071776 -296.448004) (xy 303.056192 -296.494685)
			(xy 303.033321 -296.538262) (xy 303.003756 -296.577606) (xy 302.968263 -296.611698) (xy 302.92776 -296.639654)
			(xy 302.883298 -296.660752) (xy 302.836027 -296.674444) (xy 302.787172 -296.680376) (xy 302.737997 -296.678395)
			(xy 302.689778 -296.668551) (xy 302.643762 -296.651099) (xy 302.601141 -296.626492) (xy 302.56302 -296.595367)
			(xy 302.530385 -296.55853) (xy 302.504082 -296.516934) (xy 302.484791 -296.471658) (xy 302.473014 -296.423874)
			(xy 302.469054 -296.37482) (xy 302.130206 -296.37482) (xy 302.129711 -296.399427) (xy 302.121816 -296.448004)
			(xy 302.106232 -296.494685) (xy 302.083361 -296.538262) (xy 302.053796 -296.577606) (xy 302.018303 -296.611698)
			(xy 301.9778 -296.639654) (xy 301.933338 -296.660752) (xy 301.886067 -296.674444) (xy 301.837212 -296.680376)
			(xy 301.788037 -296.678395) (xy 301.739818 -296.668551) (xy 301.693802 -296.651099) (xy 301.651181 -296.626492)
			(xy 301.61306 -296.595367) (xy 301.580425 -296.55853) (xy 301.554122 -296.516934) (xy 301.534831 -296.471658)
			(xy 301.523054 -296.423874) (xy 301.519094 -296.37482) (xy 301.179992 -296.37482) (xy 301.179497 -296.399427)
			(xy 301.171602 -296.448004) (xy 301.156018 -296.494685) (xy 301.133147 -296.538262) (xy 301.103582 -296.577606)
			(xy 301.068089 -296.611698) (xy 301.027586 -296.639654) (xy 300.983124 -296.660752) (xy 300.935853 -296.674444)
			(xy 300.886998 -296.680376) (xy 300.837823 -296.678395) (xy 300.789604 -296.668551) (xy 300.743588 -296.651099)
			(xy 300.700967 -296.626492) (xy 300.662846 -296.595367) (xy 300.630211 -296.55853) (xy 300.603908 -296.516934)
			(xy 300.584617 -296.471658) (xy 300.57284 -296.423874) (xy 300.56888 -296.37482) (xy 300.230032 -296.37482)
			(xy 300.229537 -296.399427) (xy 300.221642 -296.448004) (xy 300.206058 -296.494685) (xy 300.183187 -296.538262)
			(xy 300.153622 -296.577606) (xy 300.118129 -296.611698) (xy 300.077626 -296.639654) (xy 300.033164 -296.660752)
			(xy 299.985893 -296.674444) (xy 299.937038 -296.680376) (xy 299.887863 -296.678395) (xy 299.839644 -296.668551)
			(xy 299.793628 -296.651099) (xy 299.751007 -296.626492) (xy 299.712886 -296.595367) (xy 299.680251 -296.55853)
			(xy 299.653948 -296.516934) (xy 299.634657 -296.471658) (xy 299.62288 -296.423874) (xy 299.61892 -296.37482)
			(xy 299.280072 -296.37482) (xy 299.279577 -296.399427) (xy 299.271682 -296.448004) (xy 299.256098 -296.494685)
			(xy 299.233227 -296.538262) (xy 299.203662 -296.577606) (xy 299.168169 -296.611698) (xy 299.127666 -296.639654)
			(xy 299.083204 -296.660752) (xy 299.035933 -296.674444) (xy 298.987078 -296.680376) (xy 298.937903 -296.678395)
			(xy 298.889684 -296.668551) (xy 298.843668 -296.651099) (xy 298.801047 -296.626492) (xy 298.762926 -296.595367)
			(xy 298.730291 -296.55853) (xy 298.703988 -296.516934) (xy 298.684697 -296.471658) (xy 298.67292 -296.423874)
			(xy 298.66896 -296.37482) (xy 297.380152 -296.37482) (xy 297.379657 -296.399427) (xy 297.371762 -296.448004)
			(xy 297.356178 -296.494685) (xy 297.333307 -296.538262) (xy 297.303742 -296.577606) (xy 297.268249 -296.611698)
			(xy 297.227746 -296.639654) (xy 297.183284 -296.660752) (xy 297.136013 -296.674444) (xy 297.087158 -296.680376)
			(xy 297.037983 -296.678395) (xy 296.989764 -296.668551) (xy 296.943748 -296.651099) (xy 296.901127 -296.626492)
			(xy 296.863006 -296.595367) (xy 296.830371 -296.55853) (xy 296.804068 -296.516934) (xy 296.784777 -296.471658)
			(xy 296.773 -296.423874) (xy 296.76904 -296.37482) (xy 295.480232 -296.37482) (xy 295.479737 -296.399427)
			(xy 295.471842 -296.448004) (xy 295.456258 -296.494685) (xy 295.433387 -296.538262) (xy 295.403822 -296.577606)
			(xy 295.368329 -296.611698) (xy 295.327826 -296.639654) (xy 295.283364 -296.660752) (xy 295.236093 -296.674444)
			(xy 295.187238 -296.680376) (xy 295.138063 -296.678395) (xy 295.089844 -296.668551) (xy 295.043828 -296.651099)
			(xy 295.001207 -296.626492) (xy 294.963086 -296.595367) (xy 294.930451 -296.55853) (xy 294.904148 -296.516934)
			(xy 294.884857 -296.471658) (xy 294.87308 -296.423874) (xy 294.86912 -296.37482) (xy 293.580058 -296.37482)
			(xy 293.579563 -296.399427) (xy 293.571668 -296.448004) (xy 293.556084 -296.494685) (xy 293.533213 -296.538262)
			(xy 293.503648 -296.577606) (xy 293.468155 -296.611698) (xy 293.427652 -296.639654) (xy 293.38319 -296.660752)
			(xy 293.335919 -296.674444) (xy 293.287064 -296.680376) (xy 293.237889 -296.678395) (xy 293.18967 -296.668551)
			(xy 293.143654 -296.651099) (xy 293.101033 -296.626492) (xy 293.062912 -296.595367) (xy 293.030277 -296.55853)
			(xy 293.003974 -296.516934) (xy 292.984683 -296.471658) (xy 292.972906 -296.423874) (xy 292.968946 -296.37482)
			(xy 290.730178 -296.37482) (xy 290.729683 -296.399427) (xy 290.721788 -296.448004) (xy 290.706204 -296.494685)
			(xy 290.683333 -296.538262) (xy 290.653768 -296.577606) (xy 290.618275 -296.611698) (xy 290.577772 -296.639654)
			(xy 290.53331 -296.660752) (xy 290.486039 -296.674444) (xy 290.437184 -296.680376) (xy 290.388009 -296.678395)
			(xy 290.33979 -296.668551) (xy 290.293774 -296.651099) (xy 290.251153 -296.626492) (xy 290.213032 -296.595367)
			(xy 290.180397 -296.55853) (xy 290.154094 -296.516934) (xy 290.134803 -296.471658) (xy 290.123026 -296.423874)
			(xy 290.119066 -296.37482) (xy 288.830258 -296.37482) (xy 288.829763 -296.399427) (xy 288.821868 -296.448004)
			(xy 288.806284 -296.494685) (xy 288.783413 -296.538262) (xy 288.753848 -296.577606) (xy 288.718355 -296.611698)
			(xy 288.677852 -296.639654) (xy 288.63339 -296.660752) (xy 288.586119 -296.674444) (xy 288.537264 -296.680376)
			(xy 288.488089 -296.678395) (xy 288.43987 -296.668551) (xy 288.393854 -296.651099) (xy 288.351233 -296.626492)
			(xy 288.313112 -296.595367) (xy 288.280477 -296.55853) (xy 288.254174 -296.516934) (xy 288.234883 -296.471658)
			(xy 288.223106 -296.423874) (xy 288.219146 -296.37482) (xy 286.930084 -296.37482) (xy 286.929589 -296.399427)
			(xy 286.921694 -296.448004) (xy 286.90611 -296.494685) (xy 286.883239 -296.538262) (xy 286.853674 -296.577606)
			(xy 286.818181 -296.611698) (xy 286.777678 -296.639654) (xy 286.733216 -296.660752) (xy 286.685945 -296.674444)
			(xy 286.63709 -296.680376) (xy 286.587915 -296.678395) (xy 286.539696 -296.668551) (xy 286.49368 -296.651099)
			(xy 286.451059 -296.626492) (xy 286.412938 -296.595367) (xy 286.380303 -296.55853) (xy 286.354 -296.516934)
			(xy 286.334709 -296.471658) (xy 286.322932 -296.423874) (xy 286.318972 -296.37482) (xy 285.030164 -296.37482)
			(xy 285.029669 -296.399427) (xy 285.021774 -296.448004) (xy 285.00619 -296.494685) (xy 284.983319 -296.538262)
			(xy 284.953754 -296.577606) (xy 284.918261 -296.611698) (xy 284.877758 -296.639654) (xy 284.833296 -296.660752)
			(xy 284.786025 -296.674444) (xy 284.73717 -296.680376) (xy 284.687995 -296.678395) (xy 284.639776 -296.668551)
			(xy 284.59376 -296.651099) (xy 284.551139 -296.626492) (xy 284.513018 -296.595367) (xy 284.480383 -296.55853)
			(xy 284.45408 -296.516934) (xy 284.434789 -296.471658) (xy 284.423012 -296.423874) (xy 284.419052 -296.37482)
			(xy 283.130244 -296.37482) (xy 283.129749 -296.399427) (xy 283.121854 -296.448004) (xy 283.10627 -296.494685)
			(xy 283.083399 -296.538262) (xy 283.053834 -296.577606) (xy 283.018341 -296.611698) (xy 282.977838 -296.639654)
			(xy 282.933376 -296.660752) (xy 282.886105 -296.674444) (xy 282.83725 -296.680376) (xy 282.788075 -296.678395)
			(xy 282.739856 -296.668551) (xy 282.69384 -296.651099) (xy 282.651219 -296.626492) (xy 282.613098 -296.595367)
			(xy 282.580463 -296.55853) (xy 282.55416 -296.516934) (xy 282.534869 -296.471658) (xy 282.523092 -296.423874)
			(xy 282.519132 -296.37482) (xy 281.23007 -296.37482) (xy 281.229622 -296.398811) (xy 281.222113 -296.446202)
			(xy 281.207282 -296.491834) (xy 281.185495 -296.534585) (xy 281.157288 -296.573401) (xy 281.123357 -296.607326)
			(xy 281.084535 -296.635525) (xy 281.041781 -296.657304) (xy 280.996145 -296.672126) (xy 280.948753 -296.679627)
			(xy 280.924762 -296.680128) (xy 280.900326 -296.679645) (xy 280.852079 -296.671859) (xy 280.805686 -296.656492)
			(xy 280.762331 -296.633936) (xy 280.723119 -296.604766) (xy 280.689052 -296.569726) (xy 280.660996 -296.529709)
			(xy 280.649934 -296.507916) (xy 280.644092 -296.496232) (xy 280.62301 -296.481246) (xy 280.557224 -296.473372)
			(xy 280.512266 -296.467784) (xy 280.48839 -296.477436) (xy 280.480008 -296.487596) (xy 280.475182 -296.493438)
			(xy 280.473404 -296.49547) (xy 280.471118 -296.498772) (xy 280.466038 -296.503598) (xy 280.464768 -296.504868)
			(xy 280.463498 -296.506392) (xy 280.462482 -296.507408) (xy 280.46172 -296.50817) (xy 280.461212 -296.508678)
			(xy 280.453846 -296.516044) (xy 280.453338 -296.516552) (xy 280.453084 -296.516806) (xy 280.443178 -296.526712)
			(xy 280.402538 -296.567606) (xy 280.280872 -296.689272) (xy 280.275232 -296.696342) (xy 280.268873 -296.713258)
			(xy 280.268426 -296.722292) (xy 280.268426 -297.230038) (xy 280.268934 -297.236134) (xy 280.270204 -297.24731)
			(xy 280.270966 -297.250612) (xy 280.270966 -297.25112) (xy 280.275218 -297.269238) (xy 280.279805 -297.306172)
			(xy 280.28011 -297.32478) (xy 281.568918 -297.32478) (xy 281.572878 -297.275726) (xy 281.584655 -297.227942)
			(xy 281.603946 -297.182666) (xy 281.630249 -297.14107) (xy 281.662884 -297.104233) (xy 281.701005 -297.073108)
			(xy 281.743626 -297.048501) (xy 281.789642 -297.031049) (xy 281.837861 -297.021205) (xy 281.887036 -297.019224)
			(xy 281.935891 -297.025156) (xy 281.983162 -297.038848) (xy 282.027624 -297.059946) (xy 282.068127 -297.087902)
			(xy 282.10362 -297.121994) (xy 282.133185 -297.161338) (xy 282.156056 -297.204915) (xy 282.17164 -297.251596)
			(xy 282.179535 -297.300173) (xy 282.18003 -297.32478) (xy 283.469092 -297.32478) (xy 283.473052 -297.275726)
			(xy 283.484829 -297.227942) (xy 283.50412 -297.182666) (xy 283.530423 -297.14107) (xy 283.563058 -297.104233)
			(xy 283.601179 -297.073108) (xy 283.6438 -297.048501) (xy 283.689816 -297.031049) (xy 283.738035 -297.021205)
			(xy 283.78721 -297.019224) (xy 283.836065 -297.025156) (xy 283.883336 -297.038848) (xy 283.927798 -297.059946)
			(xy 283.968301 -297.087902) (xy 284.003794 -297.121994) (xy 284.033359 -297.161338) (xy 284.05623 -297.204915)
			(xy 284.071814 -297.251596) (xy 284.079709 -297.300173) (xy 284.080204 -297.32478) (xy 285.369012 -297.32478)
			(xy 285.372972 -297.275726) (xy 285.384749 -297.227942) (xy 285.40404 -297.182666) (xy 285.430343 -297.14107)
			(xy 285.462978 -297.104233) (xy 285.501099 -297.073108) (xy 285.54372 -297.048501) (xy 285.589736 -297.031049)
			(xy 285.637955 -297.021205) (xy 285.68713 -297.019224) (xy 285.735985 -297.025156) (xy 285.783256 -297.038848)
			(xy 285.827718 -297.059946) (xy 285.868221 -297.087902) (xy 285.903714 -297.121994) (xy 285.933279 -297.161338)
			(xy 285.95615 -297.204915) (xy 285.971734 -297.251596) (xy 285.979629 -297.300173) (xy 285.980124 -297.32478)
			(xy 287.268932 -297.32478) (xy 287.272892 -297.275726) (xy 287.284669 -297.227942) (xy 287.30396 -297.182666)
			(xy 287.330263 -297.14107) (xy 287.362898 -297.104233) (xy 287.401019 -297.073108) (xy 287.44364 -297.048501)
			(xy 287.489656 -297.031049) (xy 287.537875 -297.021205) (xy 287.58705 -297.019224) (xy 287.635905 -297.025156)
			(xy 287.683176 -297.038848) (xy 287.727638 -297.059946) (xy 287.768141 -297.087902) (xy 287.803634 -297.121994)
			(xy 287.833199 -297.161338) (xy 287.85607 -297.204915) (xy 287.871654 -297.251596) (xy 287.879549 -297.300173)
			(xy 287.880044 -297.32478) (xy 289.169106 -297.32478) (xy 289.173066 -297.275726) (xy 289.184843 -297.227942)
			(xy 289.204134 -297.182666) (xy 289.230437 -297.14107) (xy 289.263072 -297.104233) (xy 289.301193 -297.073108)
			(xy 289.343814 -297.048501) (xy 289.38983 -297.031049) (xy 289.438049 -297.021205) (xy 289.487224 -297.019224)
			(xy 289.536079 -297.025156) (xy 289.58335 -297.038848) (xy 289.627812 -297.059946) (xy 289.668315 -297.087902)
			(xy 289.703808 -297.121994) (xy 289.733373 -297.161338) (xy 289.756244 -297.204915) (xy 289.771828 -297.251596)
			(xy 289.779723 -297.300173) (xy 289.780218 -297.32478) (xy 292.018986 -297.32478) (xy 292.022946 -297.275726)
			(xy 292.034723 -297.227942) (xy 292.054014 -297.182666) (xy 292.080317 -297.14107) (xy 292.112952 -297.104233)
			(xy 292.151073 -297.073108) (xy 292.193694 -297.048501) (xy 292.23971 -297.031049) (xy 292.287929 -297.021205)
			(xy 292.337104 -297.019224) (xy 292.385959 -297.025156) (xy 292.43323 -297.038848) (xy 292.477692 -297.059946)
			(xy 292.518195 -297.087902) (xy 292.553688 -297.121994) (xy 292.583253 -297.161338) (xy 292.606124 -297.204915)
			(xy 292.621708 -297.251596) (xy 292.629603 -297.300173) (xy 292.630098 -297.32478) (xy 293.918906 -297.32478)
			(xy 293.922866 -297.275726) (xy 293.934643 -297.227942) (xy 293.953934 -297.182666) (xy 293.980237 -297.14107)
			(xy 294.012872 -297.104233) (xy 294.050993 -297.073108) (xy 294.093614 -297.048501) (xy 294.13963 -297.031049)
			(xy 294.187849 -297.021205) (xy 294.237024 -297.019224) (xy 294.285879 -297.025156) (xy 294.33315 -297.038848)
			(xy 294.377612 -297.059946) (xy 294.418115 -297.087902) (xy 294.453608 -297.121994) (xy 294.483173 -297.161338)
			(xy 294.506044 -297.204915) (xy 294.521628 -297.251596) (xy 294.529523 -297.300173) (xy 294.530018 -297.32478)
			(xy 295.81908 -297.32478) (xy 295.82304 -297.275726) (xy 295.834817 -297.227942) (xy 295.854108 -297.182666)
			(xy 295.880411 -297.14107) (xy 295.913046 -297.104233) (xy 295.951167 -297.073108) (xy 295.993788 -297.048501)
			(xy 296.039804 -297.031049) (xy 296.088023 -297.021205) (xy 296.137198 -297.019224) (xy 296.186053 -297.025156)
			(xy 296.233324 -297.038848) (xy 296.277786 -297.059946) (xy 296.318289 -297.087902) (xy 296.353782 -297.121994)
			(xy 296.383347 -297.161338) (xy 296.406218 -297.204915) (xy 296.421802 -297.251596) (xy 296.429697 -297.300173)
			(xy 296.430192 -297.32478) (xy 297.719 -297.32478) (xy 297.72296 -297.275726) (xy 297.734737 -297.227942)
			(xy 297.754028 -297.182666) (xy 297.780331 -297.14107) (xy 297.812966 -297.104233) (xy 297.851087 -297.073108)
			(xy 297.893708 -297.048501) (xy 297.939724 -297.031049) (xy 297.987943 -297.021205) (xy 298.037118 -297.019224)
			(xy 298.085973 -297.025156) (xy 298.133244 -297.038848) (xy 298.177706 -297.059946) (xy 298.218209 -297.087902)
			(xy 298.253702 -297.121994) (xy 298.283267 -297.161338) (xy 298.306138 -297.204915) (xy 298.321722 -297.251596)
			(xy 298.329617 -297.300173) (xy 298.330112 -297.32478) (xy 298.66896 -297.32478) (xy 298.67292 -297.275726)
			(xy 298.684697 -297.227942) (xy 298.703988 -297.182666) (xy 298.730291 -297.14107) (xy 298.762926 -297.104233)
			(xy 298.801047 -297.073108) (xy 298.843668 -297.048501) (xy 298.889684 -297.031049) (xy 298.937903 -297.021205)
			(xy 298.987078 -297.019224) (xy 299.035933 -297.025156) (xy 299.083204 -297.038848) (xy 299.127666 -297.059946)
			(xy 299.168169 -297.087902) (xy 299.203662 -297.121994) (xy 299.233227 -297.161338) (xy 299.256098 -297.204915)
			(xy 299.271682 -297.251596) (xy 299.279577 -297.300173) (xy 299.280072 -297.32478) (xy 299.61892 -297.32478)
			(xy 299.62288 -297.275726) (xy 299.634657 -297.227942) (xy 299.653948 -297.182666) (xy 299.680251 -297.14107)
			(xy 299.712886 -297.104233) (xy 299.751007 -297.073108) (xy 299.793628 -297.048501) (xy 299.839644 -297.031049)
			(xy 299.887863 -297.021205) (xy 299.937038 -297.019224) (xy 299.985893 -297.025156) (xy 300.033164 -297.038848)
			(xy 300.077626 -297.059946) (xy 300.118129 -297.087902) (xy 300.153622 -297.121994) (xy 300.183187 -297.161338)
			(xy 300.206058 -297.204915) (xy 300.221642 -297.251596) (xy 300.229537 -297.300173) (xy 300.230032 -297.32478)
			(xy 300.56888 -297.32478) (xy 300.57284 -297.275726) (xy 300.584617 -297.227942) (xy 300.603908 -297.182666)
			(xy 300.630211 -297.14107) (xy 300.662846 -297.104233) (xy 300.700967 -297.073108) (xy 300.743588 -297.048501)
			(xy 300.789604 -297.031049) (xy 300.837823 -297.021205) (xy 300.886998 -297.019224) (xy 300.935853 -297.025156)
			(xy 300.983124 -297.038848) (xy 301.027586 -297.059946) (xy 301.068089 -297.087902) (xy 301.103582 -297.121994)
			(xy 301.133147 -297.161338) (xy 301.156018 -297.204915) (xy 301.171602 -297.251596) (xy 301.179497 -297.300173)
			(xy 301.179992 -297.32478) (xy 301.519094 -297.32478) (xy 301.523054 -297.275726) (xy 301.534831 -297.227942)
			(xy 301.554122 -297.182666) (xy 301.580425 -297.14107) (xy 301.61306 -297.104233) (xy 301.651181 -297.073108)
			(xy 301.693802 -297.048501) (xy 301.739818 -297.031049) (xy 301.788037 -297.021205) (xy 301.837212 -297.019224)
			(xy 301.886067 -297.025156) (xy 301.933338 -297.038848) (xy 301.9778 -297.059946) (xy 302.018303 -297.087902)
			(xy 302.053796 -297.121994) (xy 302.083361 -297.161338) (xy 302.106232 -297.204915) (xy 302.121816 -297.251596)
			(xy 302.129711 -297.300173) (xy 302.130206 -297.32478) (xy 302.469054 -297.32478) (xy 302.473014 -297.275726)
			(xy 302.484791 -297.227942) (xy 302.504082 -297.182666) (xy 302.530385 -297.14107) (xy 302.56302 -297.104233)
			(xy 302.601141 -297.073108) (xy 302.643762 -297.048501) (xy 302.689778 -297.031049) (xy 302.737997 -297.021205)
			(xy 302.787172 -297.019224) (xy 302.836027 -297.025156) (xy 302.883298 -297.038848) (xy 302.92776 -297.059946)
			(xy 302.968263 -297.087902) (xy 303.003756 -297.121994) (xy 303.033321 -297.161338) (xy 303.056192 -297.204915)
			(xy 303.071776 -297.251596) (xy 303.079671 -297.300173) (xy 303.080166 -297.32478) (xy 303.419014 -297.32478)
			(xy 303.422974 -297.275726) (xy 303.434751 -297.227942) (xy 303.454042 -297.182666) (xy 303.480345 -297.14107)
			(xy 303.51298 -297.104233) (xy 303.551101 -297.073108) (xy 303.593722 -297.048501) (xy 303.639738 -297.031049)
			(xy 303.687957 -297.021205) (xy 303.737132 -297.019224) (xy 303.785987 -297.025156) (xy 303.833258 -297.038848)
			(xy 303.87772 -297.059946) (xy 303.918223 -297.087902) (xy 303.953716 -297.121994) (xy 303.983281 -297.161338)
			(xy 304.006152 -297.204915) (xy 304.021736 -297.251596) (xy 304.029631 -297.300173) (xy 304.030126 -297.32478)
			(xy 304.368974 -297.32478) (xy 304.372934 -297.275726) (xy 304.384711 -297.227942) (xy 304.404002 -297.182666)
			(xy 304.430305 -297.14107) (xy 304.46294 -297.104233) (xy 304.501061 -297.073108) (xy 304.543682 -297.048501)
			(xy 304.589698 -297.031049) (xy 304.637917 -297.021205) (xy 304.687092 -297.019224) (xy 304.735947 -297.025156)
			(xy 304.783218 -297.038848) (xy 304.82768 -297.059946) (xy 304.868183 -297.087902) (xy 304.903676 -297.121994)
			(xy 304.933241 -297.161338) (xy 304.956112 -297.204915) (xy 304.971696 -297.251596) (xy 304.979591 -297.300173)
			(xy 304.980086 -297.32478) (xy 305.318934 -297.32478) (xy 305.322894 -297.275726) (xy 305.334671 -297.227942)
			(xy 305.353962 -297.182666) (xy 305.380265 -297.14107) (xy 305.4129 -297.104233) (xy 305.451021 -297.073108)
			(xy 305.493642 -297.048501) (xy 305.539658 -297.031049) (xy 305.587877 -297.021205) (xy 305.637052 -297.019224)
			(xy 305.685907 -297.025156) (xy 305.733178 -297.038848) (xy 305.77764 -297.059946) (xy 305.818143 -297.087902)
			(xy 305.853636 -297.121994) (xy 305.883201 -297.161338) (xy 305.906072 -297.204915) (xy 305.921656 -297.251596)
			(xy 305.929551 -297.300173) (xy 305.930046 -297.32478) (xy 306.269148 -297.32478) (xy 306.273108 -297.275726)
			(xy 306.284885 -297.227942) (xy 306.304176 -297.182666) (xy 306.330479 -297.14107) (xy 306.363114 -297.104233)
			(xy 306.401235 -297.073108) (xy 306.443856 -297.048501) (xy 306.489872 -297.031049) (xy 306.538091 -297.021205)
			(xy 306.587266 -297.019224) (xy 306.636121 -297.025156) (xy 306.683392 -297.038848) (xy 306.727854 -297.059946)
			(xy 306.768357 -297.087902) (xy 306.80385 -297.121994) (xy 306.833415 -297.161338) (xy 306.856286 -297.204915)
			(xy 306.87187 -297.251596) (xy 306.879765 -297.300173) (xy 306.88026 -297.32478) (xy 307.219108 -297.32478)
			(xy 307.223068 -297.275726) (xy 307.234845 -297.227942) (xy 307.254136 -297.182666) (xy 307.280439 -297.14107)
			(xy 307.313074 -297.104233) (xy 307.351195 -297.073108) (xy 307.393816 -297.048501) (xy 307.439832 -297.031049)
			(xy 307.488051 -297.021205) (xy 307.537226 -297.019224) (xy 307.586081 -297.025156) (xy 307.633352 -297.038848)
			(xy 307.677814 -297.059946) (xy 307.718317 -297.087902) (xy 307.75381 -297.121994) (xy 307.783375 -297.161338)
			(xy 307.806246 -297.204915) (xy 307.82183 -297.251596) (xy 307.829725 -297.300173) (xy 307.83022 -297.32478)
			(xy 308.169068 -297.32478) (xy 308.173028 -297.275726) (xy 308.184805 -297.227942) (xy 308.204096 -297.182666)
			(xy 308.230399 -297.14107) (xy 308.263034 -297.104233) (xy 308.301155 -297.073108) (xy 308.343776 -297.048501)
			(xy 308.389792 -297.031049) (xy 308.438011 -297.021205) (xy 308.487186 -297.019224) (xy 308.536041 -297.025156)
			(xy 308.583312 -297.038848) (xy 308.627774 -297.059946) (xy 308.668277 -297.087902) (xy 308.70377 -297.121994)
			(xy 308.733335 -297.161338) (xy 308.756206 -297.204915) (xy 308.77179 -297.251596) (xy 308.779685 -297.300173)
			(xy 308.78018 -297.32478) (xy 309.119028 -297.32478) (xy 309.122988 -297.275726) (xy 309.134765 -297.227942)
			(xy 309.154056 -297.182666) (xy 309.180359 -297.14107) (xy 309.212994 -297.104233) (xy 309.251115 -297.073108)
			(xy 309.293736 -297.048501) (xy 309.339752 -297.031049) (xy 309.387971 -297.021205) (xy 309.437146 -297.019224)
			(xy 309.486001 -297.025156) (xy 309.533272 -297.038848) (xy 309.577734 -297.059946) (xy 309.618237 -297.087902)
			(xy 309.65373 -297.121994) (xy 309.683295 -297.161338) (xy 309.706166 -297.204915) (xy 309.72175 -297.251596)
			(xy 309.729645 -297.300173) (xy 309.73014 -297.32478) (xy 310.068988 -297.32478) (xy 310.072948 -297.275726)
			(xy 310.084725 -297.227942) (xy 310.104016 -297.182666) (xy 310.130319 -297.14107) (xy 310.162954 -297.104233)
			(xy 310.201075 -297.073108) (xy 310.243696 -297.048501) (xy 310.289712 -297.031049) (xy 310.337931 -297.021205)
			(xy 310.387106 -297.019224) (xy 310.435961 -297.025156) (xy 310.483232 -297.038848) (xy 310.527694 -297.059946)
			(xy 310.568197 -297.087902) (xy 310.60369 -297.121994) (xy 310.633255 -297.161338) (xy 310.656126 -297.204915)
			(xy 310.67171 -297.251596) (xy 310.679605 -297.300173) (xy 310.6801 -297.32478) (xy 311.018948 -297.32478)
			(xy 311.022908 -297.275726) (xy 311.034685 -297.227942) (xy 311.053976 -297.182666) (xy 311.080279 -297.14107)
			(xy 311.112914 -297.104233) (xy 311.151035 -297.073108) (xy 311.193656 -297.048501) (xy 311.239672 -297.031049)
			(xy 311.287891 -297.021205) (xy 311.337066 -297.019224) (xy 311.385921 -297.025156) (xy 311.433192 -297.038848)
			(xy 311.477654 -297.059946) (xy 311.518157 -297.087902) (xy 311.55365 -297.121994) (xy 311.583215 -297.161338)
			(xy 311.606086 -297.204915) (xy 311.62167 -297.251596) (xy 311.629565 -297.300173) (xy 311.63006 -297.32478)
			(xy 311.968908 -297.32478) (xy 311.972868 -297.275726) (xy 311.984645 -297.227942) (xy 312.003936 -297.182666)
			(xy 312.030239 -297.14107) (xy 312.062874 -297.104233) (xy 312.100995 -297.073108) (xy 312.143616 -297.048501)
			(xy 312.189632 -297.031049) (xy 312.237851 -297.021205) (xy 312.287026 -297.019224) (xy 312.335881 -297.025156)
			(xy 312.383152 -297.038848) (xy 312.427614 -297.059946) (xy 312.468117 -297.087902) (xy 312.50361 -297.121994)
			(xy 312.533175 -297.161338) (xy 312.556046 -297.204915) (xy 312.57163 -297.251596) (xy 312.579525 -297.300173)
			(xy 312.58002 -297.32478) (xy 312.919122 -297.32478) (xy 312.923082 -297.275726) (xy 312.934859 -297.227942)
			(xy 312.95415 -297.182666) (xy 312.980453 -297.14107) (xy 313.013088 -297.104233) (xy 313.051209 -297.073108)
			(xy 313.09383 -297.048501) (xy 313.139846 -297.031049) (xy 313.188065 -297.021205) (xy 313.23724 -297.019224)
			(xy 313.286095 -297.025156) (xy 313.333366 -297.038848) (xy 313.377828 -297.059946) (xy 313.418331 -297.087902)
			(xy 313.453824 -297.121994) (xy 313.483389 -297.161338) (xy 313.50626 -297.204915) (xy 313.521844 -297.251596)
			(xy 313.529739 -297.300173) (xy 313.530234 -297.32478) (xy 313.869082 -297.32478) (xy 313.873042 -297.275726)
			(xy 313.884819 -297.227942) (xy 313.90411 -297.182666) (xy 313.930413 -297.14107) (xy 313.963048 -297.104233)
			(xy 314.001169 -297.073108) (xy 314.04379 -297.048501) (xy 314.089806 -297.031049) (xy 314.138025 -297.021205)
			(xy 314.1872 -297.019224) (xy 314.236055 -297.025156) (xy 314.283326 -297.038848) (xy 314.327788 -297.059946)
			(xy 314.368291 -297.087902) (xy 314.403784 -297.121994) (xy 314.433349 -297.161338) (xy 314.45622 -297.204915)
			(xy 314.471804 -297.251596) (xy 314.479699 -297.300173) (xy 314.480194 -297.32478) (xy 314.819042 -297.32478)
			(xy 314.823002 -297.275726) (xy 314.834779 -297.227942) (xy 314.85407 -297.182666) (xy 314.880373 -297.14107)
			(xy 314.913008 -297.104233) (xy 314.951129 -297.073108) (xy 314.99375 -297.048501) (xy 315.039766 -297.031049)
			(xy 315.087985 -297.021205) (xy 315.13716 -297.019224) (xy 315.186015 -297.025156) (xy 315.233286 -297.038848)
			(xy 315.277748 -297.059946) (xy 315.318251 -297.087902) (xy 315.353744 -297.121994) (xy 315.383309 -297.161338)
			(xy 315.40618 -297.204915) (xy 315.421764 -297.251596) (xy 315.429659 -297.300173) (xy 315.430154 -297.32478)
			(xy 315.429659 -297.349387) (xy 315.421764 -297.397964) (xy 315.40618 -297.444645) (xy 315.383309 -297.488222)
			(xy 315.353744 -297.527566) (xy 315.318251 -297.561658) (xy 315.277748 -297.589614) (xy 315.233286 -297.610712)
			(xy 315.186015 -297.624404) (xy 315.13716 -297.630336) (xy 315.087985 -297.628355) (xy 315.039766 -297.618511)
			(xy 314.99375 -297.601059) (xy 314.951129 -297.576452) (xy 314.913008 -297.545327) (xy 314.880373 -297.50849)
			(xy 314.85407 -297.466894) (xy 314.834779 -297.421618) (xy 314.823002 -297.373834) (xy 314.819042 -297.32478)
			(xy 314.480194 -297.32478) (xy 314.479699 -297.349387) (xy 314.471804 -297.397964) (xy 314.45622 -297.444645)
			(xy 314.433349 -297.488222) (xy 314.403784 -297.527566) (xy 314.368291 -297.561658) (xy 314.327788 -297.589614)
			(xy 314.283326 -297.610712) (xy 314.236055 -297.624404) (xy 314.1872 -297.630336) (xy 314.138025 -297.628355)
			(xy 314.089806 -297.618511) (xy 314.04379 -297.601059) (xy 314.001169 -297.576452) (xy 313.963048 -297.545327)
			(xy 313.930413 -297.50849) (xy 313.90411 -297.466894) (xy 313.884819 -297.421618) (xy 313.873042 -297.373834)
			(xy 313.869082 -297.32478) (xy 313.530234 -297.32478) (xy 313.529739 -297.349387) (xy 313.521844 -297.397964)
			(xy 313.50626 -297.444645) (xy 313.483389 -297.488222) (xy 313.453824 -297.527566) (xy 313.418331 -297.561658)
			(xy 313.377828 -297.589614) (xy 313.333366 -297.610712) (xy 313.286095 -297.624404) (xy 313.23724 -297.630336)
			(xy 313.188065 -297.628355) (xy 313.139846 -297.618511) (xy 313.09383 -297.601059) (xy 313.051209 -297.576452)
			(xy 313.013088 -297.545327) (xy 312.980453 -297.50849) (xy 312.95415 -297.466894) (xy 312.934859 -297.421618)
			(xy 312.923082 -297.373834) (xy 312.919122 -297.32478) (xy 312.58002 -297.32478) (xy 312.579525 -297.349387)
			(xy 312.57163 -297.397964) (xy 312.556046 -297.444645) (xy 312.533175 -297.488222) (xy 312.50361 -297.527566)
			(xy 312.468117 -297.561658) (xy 312.427614 -297.589614) (xy 312.383152 -297.610712) (xy 312.335881 -297.624404)
			(xy 312.287026 -297.630336) (xy 312.237851 -297.628355) (xy 312.189632 -297.618511) (xy 312.143616 -297.601059)
			(xy 312.100995 -297.576452) (xy 312.062874 -297.545327) (xy 312.030239 -297.50849) (xy 312.003936 -297.466894)
			(xy 311.984645 -297.421618) (xy 311.972868 -297.373834) (xy 311.968908 -297.32478) (xy 311.63006 -297.32478)
			(xy 311.629565 -297.349387) (xy 311.62167 -297.397964) (xy 311.606086 -297.444645) (xy 311.583215 -297.488222)
			(xy 311.55365 -297.527566) (xy 311.518157 -297.561658) (xy 311.477654 -297.589614) (xy 311.433192 -297.610712)
			(xy 311.385921 -297.624404) (xy 311.337066 -297.630336) (xy 311.287891 -297.628355) (xy 311.239672 -297.618511)
			(xy 311.193656 -297.601059) (xy 311.151035 -297.576452) (xy 311.112914 -297.545327) (xy 311.080279 -297.50849)
			(xy 311.053976 -297.466894) (xy 311.034685 -297.421618) (xy 311.022908 -297.373834) (xy 311.018948 -297.32478)
			(xy 310.6801 -297.32478) (xy 310.679605 -297.349387) (xy 310.67171 -297.397964) (xy 310.656126 -297.444645)
			(xy 310.633255 -297.488222) (xy 310.60369 -297.527566) (xy 310.568197 -297.561658) (xy 310.527694 -297.589614)
			(xy 310.483232 -297.610712) (xy 310.435961 -297.624404) (xy 310.387106 -297.630336) (xy 310.337931 -297.628355)
			(xy 310.289712 -297.618511) (xy 310.243696 -297.601059) (xy 310.201075 -297.576452) (xy 310.162954 -297.545327)
			(xy 310.130319 -297.50849) (xy 310.104016 -297.466894) (xy 310.084725 -297.421618) (xy 310.072948 -297.373834)
			(xy 310.068988 -297.32478) (xy 309.73014 -297.32478) (xy 309.729645 -297.349387) (xy 309.72175 -297.397964)
			(xy 309.706166 -297.444645) (xy 309.683295 -297.488222) (xy 309.65373 -297.527566) (xy 309.618237 -297.561658)
			(xy 309.577734 -297.589614) (xy 309.533272 -297.610712) (xy 309.486001 -297.624404) (xy 309.437146 -297.630336)
			(xy 309.387971 -297.628355) (xy 309.339752 -297.618511) (xy 309.293736 -297.601059) (xy 309.251115 -297.576452)
			(xy 309.212994 -297.545327) (xy 309.180359 -297.50849) (xy 309.154056 -297.466894) (xy 309.134765 -297.421618)
			(xy 309.122988 -297.373834) (xy 309.119028 -297.32478) (xy 308.78018 -297.32478) (xy 308.779685 -297.349387)
			(xy 308.77179 -297.397964) (xy 308.756206 -297.444645) (xy 308.733335 -297.488222) (xy 308.70377 -297.527566)
			(xy 308.668277 -297.561658) (xy 308.627774 -297.589614) (xy 308.583312 -297.610712) (xy 308.536041 -297.624404)
			(xy 308.487186 -297.630336) (xy 308.438011 -297.628355) (xy 308.389792 -297.618511) (xy 308.343776 -297.601059)
			(xy 308.301155 -297.576452) (xy 308.263034 -297.545327) (xy 308.230399 -297.50849) (xy 308.204096 -297.466894)
			(xy 308.184805 -297.421618) (xy 308.173028 -297.373834) (xy 308.169068 -297.32478) (xy 307.83022 -297.32478)
			(xy 307.829725 -297.349387) (xy 307.82183 -297.397964) (xy 307.806246 -297.444645) (xy 307.783375 -297.488222)
			(xy 307.75381 -297.527566) (xy 307.718317 -297.561658) (xy 307.677814 -297.589614) (xy 307.633352 -297.610712)
			(xy 307.586081 -297.624404) (xy 307.537226 -297.630336) (xy 307.488051 -297.628355) (xy 307.439832 -297.618511)
			(xy 307.393816 -297.601059) (xy 307.351195 -297.576452) (xy 307.313074 -297.545327) (xy 307.280439 -297.50849)
			(xy 307.254136 -297.466894) (xy 307.234845 -297.421618) (xy 307.223068 -297.373834) (xy 307.219108 -297.32478)
			(xy 306.88026 -297.32478) (xy 306.879765 -297.349387) (xy 306.87187 -297.397964) (xy 306.856286 -297.444645)
			(xy 306.833415 -297.488222) (xy 306.80385 -297.527566) (xy 306.768357 -297.561658) (xy 306.727854 -297.589614)
			(xy 306.683392 -297.610712) (xy 306.636121 -297.624404) (xy 306.587266 -297.630336) (xy 306.538091 -297.628355)
			(xy 306.489872 -297.618511) (xy 306.443856 -297.601059) (xy 306.401235 -297.576452) (xy 306.363114 -297.545327)
			(xy 306.330479 -297.50849) (xy 306.304176 -297.466894) (xy 306.284885 -297.421618) (xy 306.273108 -297.373834)
			(xy 306.269148 -297.32478) (xy 305.930046 -297.32478) (xy 305.929551 -297.349387) (xy 305.921656 -297.397964)
			(xy 305.906072 -297.444645) (xy 305.883201 -297.488222) (xy 305.853636 -297.527566) (xy 305.818143 -297.561658)
			(xy 305.77764 -297.589614) (xy 305.733178 -297.610712) (xy 305.685907 -297.624404) (xy 305.637052 -297.630336)
			(xy 305.587877 -297.628355) (xy 305.539658 -297.618511) (xy 305.493642 -297.601059) (xy 305.451021 -297.576452)
			(xy 305.4129 -297.545327) (xy 305.380265 -297.50849) (xy 305.353962 -297.466894) (xy 305.334671 -297.421618)
			(xy 305.322894 -297.373834) (xy 305.318934 -297.32478) (xy 304.980086 -297.32478) (xy 304.979591 -297.349387)
			(xy 304.971696 -297.397964) (xy 304.956112 -297.444645) (xy 304.933241 -297.488222) (xy 304.903676 -297.527566)
			(xy 304.868183 -297.561658) (xy 304.82768 -297.589614) (xy 304.783218 -297.610712) (xy 304.735947 -297.624404)
			(xy 304.687092 -297.630336) (xy 304.637917 -297.628355) (xy 304.589698 -297.618511) (xy 304.543682 -297.601059)
			(xy 304.501061 -297.576452) (xy 304.46294 -297.545327) (xy 304.430305 -297.50849) (xy 304.404002 -297.466894)
			(xy 304.384711 -297.421618) (xy 304.372934 -297.373834) (xy 304.368974 -297.32478) (xy 304.030126 -297.32478)
			(xy 304.029631 -297.349387) (xy 304.021736 -297.397964) (xy 304.006152 -297.444645) (xy 303.983281 -297.488222)
			(xy 303.953716 -297.527566) (xy 303.918223 -297.561658) (xy 303.87772 -297.589614) (xy 303.833258 -297.610712)
			(xy 303.785987 -297.624404) (xy 303.737132 -297.630336) (xy 303.687957 -297.628355) (xy 303.639738 -297.618511)
			(xy 303.593722 -297.601059) (xy 303.551101 -297.576452) (xy 303.51298 -297.545327) (xy 303.480345 -297.50849)
			(xy 303.454042 -297.466894) (xy 303.434751 -297.421618) (xy 303.422974 -297.373834) (xy 303.419014 -297.32478)
			(xy 303.080166 -297.32478) (xy 303.079671 -297.349387) (xy 303.071776 -297.397964) (xy 303.056192 -297.444645)
			(xy 303.033321 -297.488222) (xy 303.003756 -297.527566) (xy 302.968263 -297.561658) (xy 302.92776 -297.589614)
			(xy 302.883298 -297.610712) (xy 302.836027 -297.624404) (xy 302.787172 -297.630336) (xy 302.737997 -297.628355)
			(xy 302.689778 -297.618511) (xy 302.643762 -297.601059) (xy 302.601141 -297.576452) (xy 302.56302 -297.545327)
			(xy 302.530385 -297.50849) (xy 302.504082 -297.466894) (xy 302.484791 -297.421618) (xy 302.473014 -297.373834)
			(xy 302.469054 -297.32478) (xy 302.130206 -297.32478) (xy 302.129711 -297.349387) (xy 302.121816 -297.397964)
			(xy 302.106232 -297.444645) (xy 302.083361 -297.488222) (xy 302.053796 -297.527566) (xy 302.018303 -297.561658)
			(xy 301.9778 -297.589614) (xy 301.933338 -297.610712) (xy 301.886067 -297.624404) (xy 301.837212 -297.630336)
			(xy 301.788037 -297.628355) (xy 301.739818 -297.618511) (xy 301.693802 -297.601059) (xy 301.651181 -297.576452)
			(xy 301.61306 -297.545327) (xy 301.580425 -297.50849) (xy 301.554122 -297.466894) (xy 301.534831 -297.421618)
			(xy 301.523054 -297.373834) (xy 301.519094 -297.32478) (xy 301.179992 -297.32478) (xy 301.179497 -297.349387)
			(xy 301.171602 -297.397964) (xy 301.156018 -297.444645) (xy 301.133147 -297.488222) (xy 301.103582 -297.527566)
			(xy 301.068089 -297.561658) (xy 301.027586 -297.589614) (xy 300.983124 -297.610712) (xy 300.935853 -297.624404)
			(xy 300.886998 -297.630336) (xy 300.837823 -297.628355) (xy 300.789604 -297.618511) (xy 300.743588 -297.601059)
			(xy 300.700967 -297.576452) (xy 300.662846 -297.545327) (xy 300.630211 -297.50849) (xy 300.603908 -297.466894)
			(xy 300.584617 -297.421618) (xy 300.57284 -297.373834) (xy 300.56888 -297.32478) (xy 300.230032 -297.32478)
			(xy 300.229537 -297.349387) (xy 300.221642 -297.397964) (xy 300.206058 -297.444645) (xy 300.183187 -297.488222)
			(xy 300.153622 -297.527566) (xy 300.118129 -297.561658) (xy 300.077626 -297.589614) (xy 300.033164 -297.610712)
			(xy 299.985893 -297.624404) (xy 299.937038 -297.630336) (xy 299.887863 -297.628355) (xy 299.839644 -297.618511)
			(xy 299.793628 -297.601059) (xy 299.751007 -297.576452) (xy 299.712886 -297.545327) (xy 299.680251 -297.50849)
			(xy 299.653948 -297.466894) (xy 299.634657 -297.421618) (xy 299.62288 -297.373834) (xy 299.61892 -297.32478)
			(xy 299.280072 -297.32478) (xy 299.279577 -297.349387) (xy 299.271682 -297.397964) (xy 299.256098 -297.444645)
			(xy 299.233227 -297.488222) (xy 299.203662 -297.527566) (xy 299.168169 -297.561658) (xy 299.127666 -297.589614)
			(xy 299.083204 -297.610712) (xy 299.035933 -297.624404) (xy 298.987078 -297.630336) (xy 298.937903 -297.628355)
			(xy 298.889684 -297.618511) (xy 298.843668 -297.601059) (xy 298.801047 -297.576452) (xy 298.762926 -297.545327)
			(xy 298.730291 -297.50849) (xy 298.703988 -297.466894) (xy 298.684697 -297.421618) (xy 298.67292 -297.373834)
			(xy 298.66896 -297.32478) (xy 298.330112 -297.32478) (xy 298.329617 -297.349387) (xy 298.321722 -297.397964)
			(xy 298.306138 -297.444645) (xy 298.283267 -297.488222) (xy 298.253702 -297.527566) (xy 298.218209 -297.561658)
			(xy 298.177706 -297.589614) (xy 298.133244 -297.610712) (xy 298.085973 -297.624404) (xy 298.037118 -297.630336)
			(xy 297.987943 -297.628355) (xy 297.939724 -297.618511) (xy 297.893708 -297.601059) (xy 297.851087 -297.576452)
			(xy 297.812966 -297.545327) (xy 297.780331 -297.50849) (xy 297.754028 -297.466894) (xy 297.734737 -297.421618)
			(xy 297.72296 -297.373834) (xy 297.719 -297.32478) (xy 296.430192 -297.32478) (xy 296.429697 -297.349387)
			(xy 296.421802 -297.397964) (xy 296.406218 -297.444645) (xy 296.383347 -297.488222) (xy 296.353782 -297.527566)
			(xy 296.318289 -297.561658) (xy 296.277786 -297.589614) (xy 296.233324 -297.610712) (xy 296.186053 -297.624404)
			(xy 296.137198 -297.630336) (xy 296.088023 -297.628355) (xy 296.039804 -297.618511) (xy 295.993788 -297.601059)
			(xy 295.951167 -297.576452) (xy 295.913046 -297.545327) (xy 295.880411 -297.50849) (xy 295.854108 -297.466894)
			(xy 295.834817 -297.421618) (xy 295.82304 -297.373834) (xy 295.81908 -297.32478) (xy 294.530018 -297.32478)
			(xy 294.529523 -297.349387) (xy 294.521628 -297.397964) (xy 294.506044 -297.444645) (xy 294.483173 -297.488222)
			(xy 294.453608 -297.527566) (xy 294.418115 -297.561658) (xy 294.377612 -297.589614) (xy 294.33315 -297.610712)
			(xy 294.285879 -297.624404) (xy 294.237024 -297.630336) (xy 294.187849 -297.628355) (xy 294.13963 -297.618511)
			(xy 294.093614 -297.601059) (xy 294.050993 -297.576452) (xy 294.012872 -297.545327) (xy 293.980237 -297.50849)
			(xy 293.953934 -297.466894) (xy 293.934643 -297.421618) (xy 293.922866 -297.373834) (xy 293.918906 -297.32478)
			(xy 292.630098 -297.32478) (xy 292.629603 -297.349387) (xy 292.621708 -297.397964) (xy 292.606124 -297.444645)
			(xy 292.583253 -297.488222) (xy 292.553688 -297.527566) (xy 292.518195 -297.561658) (xy 292.477692 -297.589614)
			(xy 292.43323 -297.610712) (xy 292.385959 -297.624404) (xy 292.337104 -297.630336) (xy 292.287929 -297.628355)
			(xy 292.23971 -297.618511) (xy 292.193694 -297.601059) (xy 292.151073 -297.576452) (xy 292.112952 -297.545327)
			(xy 292.080317 -297.50849) (xy 292.054014 -297.466894) (xy 292.034723 -297.421618) (xy 292.022946 -297.373834)
			(xy 292.018986 -297.32478) (xy 289.780218 -297.32478) (xy 289.779723 -297.349387) (xy 289.771828 -297.397964)
			(xy 289.756244 -297.444645) (xy 289.733373 -297.488222) (xy 289.703808 -297.527566) (xy 289.668315 -297.561658)
			(xy 289.627812 -297.589614) (xy 289.58335 -297.610712) (xy 289.536079 -297.624404) (xy 289.487224 -297.630336)
			(xy 289.438049 -297.628355) (xy 289.38983 -297.618511) (xy 289.343814 -297.601059) (xy 289.301193 -297.576452)
			(xy 289.263072 -297.545327) (xy 289.230437 -297.50849) (xy 289.204134 -297.466894) (xy 289.184843 -297.421618)
			(xy 289.173066 -297.373834) (xy 289.169106 -297.32478) (xy 287.880044 -297.32478) (xy 287.879549 -297.349387)
			(xy 287.871654 -297.397964) (xy 287.85607 -297.444645) (xy 287.833199 -297.488222) (xy 287.803634 -297.527566)
			(xy 287.768141 -297.561658) (xy 287.727638 -297.589614) (xy 287.683176 -297.610712) (xy 287.635905 -297.624404)
			(xy 287.58705 -297.630336) (xy 287.537875 -297.628355) (xy 287.489656 -297.618511) (xy 287.44364 -297.601059)
			(xy 287.401019 -297.576452) (xy 287.362898 -297.545327) (xy 287.330263 -297.50849) (xy 287.30396 -297.466894)
			(xy 287.284669 -297.421618) (xy 287.272892 -297.373834) (xy 287.268932 -297.32478) (xy 285.980124 -297.32478)
			(xy 285.979629 -297.349387) (xy 285.971734 -297.397964) (xy 285.95615 -297.444645) (xy 285.933279 -297.488222)
			(xy 285.903714 -297.527566) (xy 285.868221 -297.561658) (xy 285.827718 -297.589614) (xy 285.783256 -297.610712)
			(xy 285.735985 -297.624404) (xy 285.68713 -297.630336) (xy 285.637955 -297.628355) (xy 285.589736 -297.618511)
			(xy 285.54372 -297.601059) (xy 285.501099 -297.576452) (xy 285.462978 -297.545327) (xy 285.430343 -297.50849)
			(xy 285.40404 -297.466894) (xy 285.384749 -297.421618) (xy 285.372972 -297.373834) (xy 285.369012 -297.32478)
			(xy 284.080204 -297.32478) (xy 284.079709 -297.349387) (xy 284.071814 -297.397964) (xy 284.05623 -297.444645)
			(xy 284.033359 -297.488222) (xy 284.003794 -297.527566) (xy 283.968301 -297.561658) (xy 283.927798 -297.589614)
			(xy 283.883336 -297.610712) (xy 283.836065 -297.624404) (xy 283.78721 -297.630336) (xy 283.738035 -297.628355)
			(xy 283.689816 -297.618511) (xy 283.6438 -297.601059) (xy 283.601179 -297.576452) (xy 283.563058 -297.545327)
			(xy 283.530423 -297.50849) (xy 283.50412 -297.466894) (xy 283.484829 -297.421618) (xy 283.473052 -297.373834)
			(xy 283.469092 -297.32478) (xy 282.18003 -297.32478) (xy 282.179535 -297.349387) (xy 282.17164 -297.397964)
			(xy 282.156056 -297.444645) (xy 282.133185 -297.488222) (xy 282.10362 -297.527566) (xy 282.068127 -297.561658)
			(xy 282.027624 -297.589614) (xy 281.983162 -297.610712) (xy 281.935891 -297.624404) (xy 281.887036 -297.630336)
			(xy 281.837861 -297.628355) (xy 281.789642 -297.618511) (xy 281.743626 -297.601059) (xy 281.701005 -297.576452)
			(xy 281.662884 -297.545327) (xy 281.630249 -297.50849) (xy 281.603946 -297.466894) (xy 281.584655 -297.421618)
			(xy 281.572878 -297.373834) (xy 281.568918 -297.32478) (xy 280.28011 -297.32478) (xy 280.28011 -297.34129)
			(xy 280.279602 -297.347132) (xy 280.279602 -297.34764) (xy 280.278332 -297.358562) (xy 280.278332 -297.358816)
			(xy 280.277824 -297.36288) (xy 280.275284 -297.381676) (xy 280.274268 -297.387264) (xy 280.270204 -297.403012)
			(xy 280.268426 -297.415712) (xy 280.268426 -297.427142) (xy 280.26902 -297.438899) (xy 280.279479 -297.459956)
			(xy 280.288492 -297.467528) (xy 280.306526 -297.481244) (xy 280.30678 -297.481244) (xy 280.327862 -297.497246)
			(xy 280.346344 -297.511753) (xy 280.379044 -297.545488) (xy 280.406186 -297.583837) (xy 280.427131 -297.625893)
			(xy 280.441381 -297.670662) (xy 280.448601 -297.717087) (xy 280.44902 -297.740578) (xy 280.44902 -297.95851)
			(xy 316.956184 -297.95851) (xy 316.960255 -297.902888) (xy 316.972381 -297.848451) (xy 316.992304 -297.79636)
			(xy 317.0196 -297.747725) (xy 317.053686 -297.703582) (xy 317.093835 -297.664873) (xy 317.139193 -297.632422)
			(xy 317.188793 -297.606921) (xy 317.241577 -297.588914) (xy 317.29642 -297.578784) (xy 317.352154 -297.576747)
			(xy 317.407591 -297.582847) (xy 317.461548 -297.596953) (xy 317.512877 -297.618765) (xy 317.560483 -297.647819)
			(xy 317.603351 -297.683494) (xy 317.609209 -297.690032) (xy 318.499488 -297.690032) (xy 318.503559 -297.63441)
			(xy 318.515685 -297.579973) (xy 318.535608 -297.527882) (xy 318.562904 -297.479247) (xy 318.59699 -297.435104)
			(xy 318.637139 -297.396395) (xy 318.682497 -297.363944) (xy 318.732097 -297.338443) (xy 318.784881 -297.320436)
			(xy 318.839724 -297.310306) (xy 318.895458 -297.308269) (xy 318.950895 -297.314369) (xy 319.004852 -297.328475)
			(xy 319.056181 -297.350287) (xy 319.096376 -297.374818) (xy 324.815706 -297.374818) (xy 324.819777 -297.319196)
			(xy 324.831903 -297.264759) (xy 324.851826 -297.212668) (xy 324.879122 -297.164033) (xy 324.913208 -297.11989)
			(xy 324.953357 -297.081181) (xy 324.998715 -297.04873) (xy 325.048315 -297.023229) (xy 325.101099 -297.005222)
			(xy 325.155942 -296.995092) (xy 325.211676 -296.993055) (xy 325.267113 -296.999155) (xy 325.32107 -297.013261)
			(xy 325.372399 -297.035073) (xy 325.420005 -297.064127) (xy 325.462873 -297.099802) (xy 325.50009 -297.141339)
			(xy 325.530863 -297.187852) (xy 325.554535 -297.238349) (xy 325.570603 -297.291756) (xy 325.578723 -297.346932)
			(xy 325.579232 -297.374818) (xy 325.578723 -297.402704) (xy 325.570603 -297.45788) (xy 325.554535 -297.511287)
			(xy 325.530863 -297.561784) (xy 325.50009 -297.608297) (xy 325.462873 -297.649834) (xy 325.420005 -297.685509)
			(xy 325.372399 -297.714563) (xy 325.32107 -297.736375) (xy 325.267113 -297.750481) (xy 325.211676 -297.756581)
			(xy 325.155942 -297.754544) (xy 325.101099 -297.744414) (xy 325.048315 -297.726407) (xy 324.998715 -297.700906)
			(xy 324.953357 -297.668455) (xy 324.913208 -297.629746) (xy 324.879122 -297.585603) (xy 324.851826 -297.536968)
			(xy 324.831903 -297.484877) (xy 324.819777 -297.43044) (xy 324.815706 -297.374818) (xy 319.096376 -297.374818)
			(xy 319.103787 -297.379341) (xy 319.146655 -297.415016) (xy 319.183872 -297.456553) (xy 319.214645 -297.503066)
			(xy 319.238317 -297.553563) (xy 319.254385 -297.60697) (xy 319.262505 -297.662146) (xy 319.263014 -297.690032)
			(xy 319.262505 -297.717918) (xy 319.254385 -297.773094) (xy 319.238317 -297.826501) (xy 319.214645 -297.876998)
			(xy 319.183872 -297.923511) (xy 319.146655 -297.965048) (xy 319.103787 -298.000723) (xy 319.056181 -298.029777)
			(xy 319.004852 -298.051589) (xy 318.950895 -298.065695) (xy 318.895458 -298.071795) (xy 318.839724 -298.069758)
			(xy 318.784881 -298.059628) (xy 318.732097 -298.041621) (xy 318.682497 -298.01612) (xy 318.637139 -297.983669)
			(xy 318.59699 -297.94496) (xy 318.562904 -297.900817) (xy 318.535608 -297.852182) (xy 318.515685 -297.800091)
			(xy 318.503559 -297.745654) (xy 318.499488 -297.690032) (xy 317.609209 -297.690032) (xy 317.640568 -297.725031)
			(xy 317.671341 -297.771544) (xy 317.695013 -297.822041) (xy 317.711081 -297.875448) (xy 317.719201 -297.930624)
			(xy 317.71971 -297.95851) (xy 317.719201 -297.986396) (xy 317.711081 -298.041572) (xy 317.695013 -298.094979)
			(xy 317.671341 -298.145476) (xy 317.640568 -298.191989) (xy 317.603351 -298.233526) (xy 317.560483 -298.269201)
			(xy 317.512877 -298.298255) (xy 317.461548 -298.320067) (xy 317.407591 -298.334173) (xy 317.352154 -298.340273)
			(xy 317.29642 -298.338236) (xy 317.241577 -298.328106) (xy 317.188793 -298.310099) (xy 317.139193 -298.284598)
			(xy 317.093835 -298.252147) (xy 317.053686 -298.213438) (xy 317.0196 -298.169295) (xy 316.992304 -298.12066)
			(xy 316.972381 -298.068569) (xy 316.960255 -298.014132) (xy 316.956184 -297.95851) (xy 280.44902 -297.95851)
			(xy 280.44902 -298.27474) (xy 280.618958 -298.27474) (xy 280.622918 -298.225686) (xy 280.634695 -298.177902)
			(xy 280.653986 -298.132626) (xy 280.680289 -298.09103) (xy 280.712924 -298.054193) (xy 280.751045 -298.023068)
			(xy 280.793666 -297.998461) (xy 280.839682 -297.981009) (xy 280.887901 -297.971165) (xy 280.937076 -297.969184)
			(xy 280.985931 -297.975116) (xy 281.033202 -297.988808) (xy 281.077664 -298.009906) (xy 281.118167 -298.037862)
			(xy 281.15366 -298.071954) (xy 281.183225 -298.111298) (xy 281.206096 -298.154875) (xy 281.22168 -298.201556)
			(xy 281.229575 -298.250133) (xy 281.23007 -298.27474) (xy 282.519132 -298.27474) (xy 282.523092 -298.225686)
			(xy 282.534869 -298.177902) (xy 282.55416 -298.132626) (xy 282.580463 -298.09103) (xy 282.613098 -298.054193)
			(xy 282.651219 -298.023068) (xy 282.69384 -297.998461) (xy 282.739856 -297.981009) (xy 282.788075 -297.971165)
			(xy 282.83725 -297.969184) (xy 282.886105 -297.975116) (xy 282.933376 -297.988808) (xy 282.977838 -298.009906)
			(xy 283.018341 -298.037862) (xy 283.053834 -298.071954) (xy 283.083399 -298.111298) (xy 283.10627 -298.154875)
			(xy 283.121854 -298.201556) (xy 283.129749 -298.250133) (xy 283.130244 -298.27474) (xy 284.419052 -298.27474)
			(xy 284.423012 -298.225686) (xy 284.434789 -298.177902) (xy 284.45408 -298.132626) (xy 284.480383 -298.09103)
			(xy 284.513018 -298.054193) (xy 284.551139 -298.023068) (xy 284.59376 -297.998461) (xy 284.639776 -297.981009)
			(xy 284.687995 -297.971165) (xy 284.73717 -297.969184) (xy 284.786025 -297.975116) (xy 284.833296 -297.988808)
			(xy 284.877758 -298.009906) (xy 284.918261 -298.037862) (xy 284.953754 -298.071954) (xy 284.983319 -298.111298)
			(xy 285.00619 -298.154875) (xy 285.021774 -298.201556) (xy 285.029669 -298.250133) (xy 285.030164 -298.27474)
			(xy 286.318972 -298.27474) (xy 286.322932 -298.225686) (xy 286.334709 -298.177902) (xy 286.354 -298.132626)
			(xy 286.380303 -298.09103) (xy 286.412938 -298.054193) (xy 286.451059 -298.023068) (xy 286.49368 -297.998461)
			(xy 286.539696 -297.981009) (xy 286.587915 -297.971165) (xy 286.63709 -297.969184) (xy 286.685945 -297.975116)
			(xy 286.733216 -297.988808) (xy 286.777678 -298.009906) (xy 286.818181 -298.037862) (xy 286.853674 -298.071954)
			(xy 286.883239 -298.111298) (xy 286.90611 -298.154875) (xy 286.921694 -298.201556) (xy 286.929589 -298.250133)
			(xy 286.930084 -298.27474) (xy 288.218892 -298.27474) (xy 288.222852 -298.225686) (xy 288.234629 -298.177902)
			(xy 288.25392 -298.132626) (xy 288.280223 -298.09103) (xy 288.312858 -298.054193) (xy 288.350979 -298.023068)
			(xy 288.3936 -297.998461) (xy 288.439616 -297.981009) (xy 288.487835 -297.971165) (xy 288.53701 -297.969184)
			(xy 288.585865 -297.975116) (xy 288.633136 -297.988808) (xy 288.677598 -298.009906) (xy 288.718101 -298.037862)
			(xy 288.753594 -298.071954) (xy 288.783159 -298.111298) (xy 288.80603 -298.154875) (xy 288.821614 -298.201556)
			(xy 288.829509 -298.250133) (xy 288.830004 -298.27474) (xy 290.119066 -298.27474) (xy 290.123026 -298.225686)
			(xy 290.134803 -298.177902) (xy 290.154094 -298.132626) (xy 290.180397 -298.09103) (xy 290.213032 -298.054193)
			(xy 290.251153 -298.023068) (xy 290.293774 -297.998461) (xy 290.33979 -297.981009) (xy 290.388009 -297.971165)
			(xy 290.437184 -297.969184) (xy 290.486039 -297.975116) (xy 290.53331 -297.988808) (xy 290.577772 -298.009906)
			(xy 290.618275 -298.037862) (xy 290.653768 -298.071954) (xy 290.683333 -298.111298) (xy 290.706204 -298.154875)
			(xy 290.721788 -298.201556) (xy 290.729683 -298.250133) (xy 290.730178 -298.27474) (xy 292.968946 -298.27474)
			(xy 292.972906 -298.225686) (xy 292.984683 -298.177902) (xy 293.003974 -298.132626) (xy 293.030277 -298.09103)
			(xy 293.062912 -298.054193) (xy 293.101033 -298.023068) (xy 293.143654 -297.998461) (xy 293.18967 -297.981009)
			(xy 293.237889 -297.971165) (xy 293.287064 -297.969184) (xy 293.335919 -297.975116) (xy 293.38319 -297.988808)
			(xy 293.427652 -298.009906) (xy 293.468155 -298.037862) (xy 293.503648 -298.071954) (xy 293.533213 -298.111298)
			(xy 293.556084 -298.154875) (xy 293.571668 -298.201556) (xy 293.579563 -298.250133) (xy 293.580058 -298.27474)
			(xy 294.86912 -298.27474) (xy 294.87308 -298.225686) (xy 294.884857 -298.177902) (xy 294.904148 -298.132626)
			(xy 294.930451 -298.09103) (xy 294.963086 -298.054193) (xy 295.001207 -298.023068) (xy 295.043828 -297.998461)
			(xy 295.089844 -297.981009) (xy 295.138063 -297.971165) (xy 295.187238 -297.969184) (xy 295.236093 -297.975116)
			(xy 295.283364 -297.988808) (xy 295.327826 -298.009906) (xy 295.368329 -298.037862) (xy 295.403822 -298.071954)
			(xy 295.433387 -298.111298) (xy 295.456258 -298.154875) (xy 295.471842 -298.201556) (xy 295.479737 -298.250133)
			(xy 295.480232 -298.27474) (xy 296.76904 -298.27474) (xy 296.773 -298.225686) (xy 296.784777 -298.177902)
			(xy 296.804068 -298.132626) (xy 296.830371 -298.09103) (xy 296.863006 -298.054193) (xy 296.901127 -298.023068)
			(xy 296.943748 -297.998461) (xy 296.989764 -297.981009) (xy 297.037983 -297.971165) (xy 297.087158 -297.969184)
			(xy 297.136013 -297.975116) (xy 297.183284 -297.988808) (xy 297.227746 -298.009906) (xy 297.268249 -298.037862)
			(xy 297.303742 -298.071954) (xy 297.333307 -298.111298) (xy 297.356178 -298.154875) (xy 297.371762 -298.201556)
			(xy 297.379657 -298.250133) (xy 297.380152 -298.27474) (xy 298.66896 -298.27474) (xy 298.67292 -298.225686)
			(xy 298.684697 -298.177902) (xy 298.703988 -298.132626) (xy 298.730291 -298.09103) (xy 298.762926 -298.054193)
			(xy 298.801047 -298.023068) (xy 298.843668 -297.998461) (xy 298.889684 -297.981009) (xy 298.937903 -297.971165)
			(xy 298.987078 -297.969184) (xy 299.035933 -297.975116) (xy 299.083204 -297.988808) (xy 299.127666 -298.009906)
			(xy 299.168169 -298.037862) (xy 299.203662 -298.071954) (xy 299.233227 -298.111298) (xy 299.256098 -298.154875)
			(xy 299.271682 -298.201556) (xy 299.279577 -298.250133) (xy 299.280072 -298.27474) (xy 300.56888 -298.27474)
			(xy 300.57284 -298.225686) (xy 300.584617 -298.177902) (xy 300.603908 -298.132626) (xy 300.630211 -298.09103)
			(xy 300.662846 -298.054193) (xy 300.700967 -298.023068) (xy 300.743588 -297.998461) (xy 300.789604 -297.981009)
			(xy 300.837823 -297.971165) (xy 300.886998 -297.969184) (xy 300.935853 -297.975116) (xy 300.983124 -297.988808)
			(xy 301.027586 -298.009906) (xy 301.068089 -298.037862) (xy 301.103582 -298.071954) (xy 301.133147 -298.111298)
			(xy 301.156018 -298.154875) (xy 301.171602 -298.201556) (xy 301.179497 -298.250133) (xy 301.179992 -298.27474)
			(xy 301.519094 -298.27474) (xy 301.523054 -298.225686) (xy 301.534831 -298.177902) (xy 301.554122 -298.132626)
			(xy 301.580425 -298.09103) (xy 301.61306 -298.054193) (xy 301.651181 -298.023068) (xy 301.693802 -297.998461)
			(xy 301.739818 -297.981009) (xy 301.788037 -297.971165) (xy 301.837212 -297.969184) (xy 301.886067 -297.975116)
			(xy 301.933338 -297.988808) (xy 301.9778 -298.009906) (xy 302.018303 -298.037862) (xy 302.053796 -298.071954)
			(xy 302.083361 -298.111298) (xy 302.106232 -298.154875) (xy 302.121816 -298.201556) (xy 302.129711 -298.250133)
			(xy 302.130206 -298.27474) (xy 302.469054 -298.27474) (xy 302.473014 -298.225686) (xy 302.484791 -298.177902)
			(xy 302.504082 -298.132626) (xy 302.530385 -298.09103) (xy 302.56302 -298.054193) (xy 302.601141 -298.023068)
			(xy 302.643762 -297.998461) (xy 302.689778 -297.981009) (xy 302.737997 -297.971165) (xy 302.787172 -297.969184)
			(xy 302.836027 -297.975116) (xy 302.883298 -297.988808) (xy 302.92776 -298.009906) (xy 302.968263 -298.037862)
			(xy 303.003756 -298.071954) (xy 303.033321 -298.111298) (xy 303.056192 -298.154875) (xy 303.071776 -298.201556)
			(xy 303.079671 -298.250133) (xy 303.080166 -298.27474) (xy 303.419014 -298.27474) (xy 303.422974 -298.225686)
			(xy 303.434751 -298.177902) (xy 303.454042 -298.132626) (xy 303.480345 -298.09103) (xy 303.51298 -298.054193)
			(xy 303.551101 -298.023068) (xy 303.593722 -297.998461) (xy 303.639738 -297.981009) (xy 303.687957 -297.971165)
			(xy 303.737132 -297.969184) (xy 303.785987 -297.975116) (xy 303.833258 -297.988808) (xy 303.87772 -298.009906)
			(xy 303.918223 -298.037862) (xy 303.953716 -298.071954) (xy 303.983281 -298.111298) (xy 304.006152 -298.154875)
			(xy 304.021736 -298.201556) (xy 304.029631 -298.250133) (xy 304.030126 -298.27474) (xy 304.368974 -298.27474)
			(xy 304.372934 -298.225686) (xy 304.384711 -298.177902) (xy 304.404002 -298.132626) (xy 304.430305 -298.09103)
			(xy 304.46294 -298.054193) (xy 304.501061 -298.023068) (xy 304.543682 -297.998461) (xy 304.589698 -297.981009)
			(xy 304.637917 -297.971165) (xy 304.687092 -297.969184) (xy 304.735947 -297.975116) (xy 304.783218 -297.988808)
			(xy 304.82768 -298.009906) (xy 304.868183 -298.037862) (xy 304.903676 -298.071954) (xy 304.933241 -298.111298)
			(xy 304.956112 -298.154875) (xy 304.971696 -298.201556) (xy 304.979591 -298.250133) (xy 304.980086 -298.27474)
			(xy 305.318934 -298.27474) (xy 305.322894 -298.225686) (xy 305.334671 -298.177902) (xy 305.353962 -298.132626)
			(xy 305.380265 -298.09103) (xy 305.4129 -298.054193) (xy 305.451021 -298.023068) (xy 305.493642 -297.998461)
			(xy 305.539658 -297.981009) (xy 305.587877 -297.971165) (xy 305.637052 -297.969184) (xy 305.685907 -297.975116)
			(xy 305.733178 -297.988808) (xy 305.77764 -298.009906) (xy 305.818143 -298.037862) (xy 305.853636 -298.071954)
			(xy 305.883201 -298.111298) (xy 305.906072 -298.154875) (xy 305.921656 -298.201556) (xy 305.929551 -298.250133)
			(xy 305.930046 -298.27474) (xy 306.268894 -298.27474) (xy 306.272854 -298.225686) (xy 306.284631 -298.177902)
			(xy 306.303922 -298.132626) (xy 306.330225 -298.09103) (xy 306.36286 -298.054193) (xy 306.400981 -298.023068)
			(xy 306.443602 -297.998461) (xy 306.489618 -297.981009) (xy 306.537837 -297.971165) (xy 306.587012 -297.969184)
			(xy 306.635867 -297.975116) (xy 306.683138 -297.988808) (xy 306.7276 -298.009906) (xy 306.768103 -298.037862)
			(xy 306.803596 -298.071954) (xy 306.833161 -298.111298) (xy 306.856032 -298.154875) (xy 306.871616 -298.201556)
			(xy 306.879511 -298.250133) (xy 306.880006 -298.27474) (xy 307.219108 -298.27474) (xy 307.223068 -298.225686)
			(xy 307.234845 -298.177902) (xy 307.254136 -298.132626) (xy 307.280439 -298.09103) (xy 307.313074 -298.054193)
			(xy 307.351195 -298.023068) (xy 307.393816 -297.998461) (xy 307.439832 -297.981009) (xy 307.488051 -297.971165)
			(xy 307.537226 -297.969184) (xy 307.586081 -297.975116) (xy 307.633352 -297.988808) (xy 307.677814 -298.009906)
			(xy 307.718317 -298.037862) (xy 307.75381 -298.071954) (xy 307.783375 -298.111298) (xy 307.806246 -298.154875)
			(xy 307.82183 -298.201556) (xy 307.829725 -298.250133) (xy 307.83022 -298.27474) (xy 308.169068 -298.27474)
			(xy 308.173028 -298.225686) (xy 308.184805 -298.177902) (xy 308.204096 -298.132626) (xy 308.230399 -298.09103)
			(xy 308.263034 -298.054193) (xy 308.301155 -298.023068) (xy 308.343776 -297.998461) (xy 308.389792 -297.981009)
			(xy 308.438011 -297.971165) (xy 308.487186 -297.969184) (xy 308.536041 -297.975116) (xy 308.583312 -297.988808)
			(xy 308.627774 -298.009906) (xy 308.668277 -298.037862) (xy 308.70377 -298.071954) (xy 308.733335 -298.111298)
			(xy 308.756206 -298.154875) (xy 308.77179 -298.201556) (xy 308.779685 -298.250133) (xy 308.78018 -298.27474)
			(xy 309.119028 -298.27474) (xy 309.122988 -298.225686) (xy 309.134765 -298.177902) (xy 309.154056 -298.132626)
			(xy 309.180359 -298.09103) (xy 309.212994 -298.054193) (xy 309.251115 -298.023068) (xy 309.293736 -297.998461)
			(xy 309.339752 -297.981009) (xy 309.387971 -297.971165) (xy 309.437146 -297.969184) (xy 309.486001 -297.975116)
			(xy 309.533272 -297.988808) (xy 309.577734 -298.009906) (xy 309.618237 -298.037862) (xy 309.65373 -298.071954)
			(xy 309.683295 -298.111298) (xy 309.706166 -298.154875) (xy 309.72175 -298.201556) (xy 309.729645 -298.250133)
			(xy 309.73014 -298.27474) (xy 310.068988 -298.27474) (xy 310.072948 -298.225686) (xy 310.084725 -298.177902)
			(xy 310.104016 -298.132626) (xy 310.130319 -298.09103) (xy 310.162954 -298.054193) (xy 310.201075 -298.023068)
			(xy 310.243696 -297.998461) (xy 310.289712 -297.981009) (xy 310.337931 -297.971165) (xy 310.387106 -297.969184)
			(xy 310.435961 -297.975116) (xy 310.483232 -297.988808) (xy 310.527694 -298.009906) (xy 310.568197 -298.037862)
			(xy 310.60369 -298.071954) (xy 310.633255 -298.111298) (xy 310.656126 -298.154875) (xy 310.67171 -298.201556)
			(xy 310.679605 -298.250133) (xy 310.6801 -298.27474) (xy 311.018948 -298.27474) (xy 311.022908 -298.225686)
			(xy 311.034685 -298.177902) (xy 311.053976 -298.132626) (xy 311.080279 -298.09103) (xy 311.112914 -298.054193)
			(xy 311.151035 -298.023068) (xy 311.193656 -297.998461) (xy 311.239672 -297.981009) (xy 311.287891 -297.971165)
			(xy 311.337066 -297.969184) (xy 311.385921 -297.975116) (xy 311.433192 -297.988808) (xy 311.477654 -298.009906)
			(xy 311.518157 -298.037862) (xy 311.55365 -298.071954) (xy 311.583215 -298.111298) (xy 311.606086 -298.154875)
			(xy 311.62167 -298.201556) (xy 311.629565 -298.250133) (xy 311.63006 -298.27474) (xy 311.968908 -298.27474)
			(xy 311.972868 -298.225686) (xy 311.984645 -298.177902) (xy 312.003936 -298.132626) (xy 312.030239 -298.09103)
			(xy 312.062874 -298.054193) (xy 312.100995 -298.023068) (xy 312.143616 -297.998461) (xy 312.189632 -297.981009)
			(xy 312.237851 -297.971165) (xy 312.287026 -297.969184) (xy 312.335881 -297.975116) (xy 312.383152 -297.988808)
			(xy 312.427614 -298.009906) (xy 312.468117 -298.037862) (xy 312.50361 -298.071954) (xy 312.533175 -298.111298)
			(xy 312.556046 -298.154875) (xy 312.57163 -298.201556) (xy 312.579525 -298.250133) (xy 312.58002 -298.27474)
			(xy 312.919122 -298.27474) (xy 312.923082 -298.225686) (xy 312.934859 -298.177902) (xy 312.95415 -298.132626)
			(xy 312.980453 -298.09103) (xy 313.013088 -298.054193) (xy 313.051209 -298.023068) (xy 313.09383 -297.998461)
			(xy 313.139846 -297.981009) (xy 313.188065 -297.971165) (xy 313.23724 -297.969184) (xy 313.286095 -297.975116)
			(xy 313.333366 -297.988808) (xy 313.377828 -298.009906) (xy 313.418331 -298.037862) (xy 313.453824 -298.071954)
			(xy 313.483389 -298.111298) (xy 313.50626 -298.154875) (xy 313.521844 -298.201556) (xy 313.529739 -298.250133)
			(xy 313.530234 -298.27474) (xy 313.869082 -298.27474) (xy 313.873042 -298.225686) (xy 313.884819 -298.177902)
			(xy 313.90411 -298.132626) (xy 313.930413 -298.09103) (xy 313.963048 -298.054193) (xy 314.001169 -298.023068)
			(xy 314.04379 -297.998461) (xy 314.089806 -297.981009) (xy 314.138025 -297.971165) (xy 314.1872 -297.969184)
			(xy 314.236055 -297.975116) (xy 314.283326 -297.988808) (xy 314.327788 -298.009906) (xy 314.368291 -298.037862)
			(xy 314.403784 -298.071954) (xy 314.433349 -298.111298) (xy 314.45622 -298.154875) (xy 314.471804 -298.201556)
			(xy 314.479699 -298.250133) (xy 314.480194 -298.27474) (xy 314.819042 -298.27474) (xy 314.823002 -298.225686)
			(xy 314.834779 -298.177902) (xy 314.85407 -298.132626) (xy 314.880373 -298.09103) (xy 314.913008 -298.054193)
			(xy 314.951129 -298.023068) (xy 314.99375 -297.998461) (xy 315.039766 -297.981009) (xy 315.087985 -297.971165)
			(xy 315.13716 -297.969184) (xy 315.186015 -297.975116) (xy 315.233286 -297.988808) (xy 315.277748 -298.009906)
			(xy 315.318251 -298.037862) (xy 315.353744 -298.071954) (xy 315.383309 -298.111298) (xy 315.40618 -298.154875)
			(xy 315.421764 -298.201556) (xy 315.429659 -298.250133) (xy 315.430154 -298.27474) (xy 315.429659 -298.299347)
			(xy 315.421764 -298.347924) (xy 315.40618 -298.394605) (xy 315.383309 -298.438182) (xy 315.353744 -298.477526)
			(xy 315.318251 -298.511618) (xy 315.277748 -298.539574) (xy 315.233286 -298.560672) (xy 315.186015 -298.574364)
			(xy 315.13716 -298.580296) (xy 315.087985 -298.578315) (xy 315.039766 -298.568471) (xy 314.99375 -298.551019)
			(xy 314.951129 -298.526412) (xy 314.913008 -298.495287) (xy 314.880373 -298.45845) (xy 314.85407 -298.416854)
			(xy 314.834779 -298.371578) (xy 314.823002 -298.323794) (xy 314.819042 -298.27474) (xy 314.480194 -298.27474)
			(xy 314.479699 -298.299347) (xy 314.471804 -298.347924) (xy 314.45622 -298.394605) (xy 314.433349 -298.438182)
			(xy 314.403784 -298.477526) (xy 314.368291 -298.511618) (xy 314.327788 -298.539574) (xy 314.283326 -298.560672)
			(xy 314.236055 -298.574364) (xy 314.1872 -298.580296) (xy 314.138025 -298.578315) (xy 314.089806 -298.568471)
			(xy 314.04379 -298.551019) (xy 314.001169 -298.526412) (xy 313.963048 -298.495287) (xy 313.930413 -298.45845)
			(xy 313.90411 -298.416854) (xy 313.884819 -298.371578) (xy 313.873042 -298.323794) (xy 313.869082 -298.27474)
			(xy 313.530234 -298.27474) (xy 313.529739 -298.299347) (xy 313.521844 -298.347924) (xy 313.50626 -298.394605)
			(xy 313.483389 -298.438182) (xy 313.453824 -298.477526) (xy 313.418331 -298.511618) (xy 313.377828 -298.539574)
			(xy 313.333366 -298.560672) (xy 313.286095 -298.574364) (xy 313.23724 -298.580296) (xy 313.188065 -298.578315)
			(xy 313.139846 -298.568471) (xy 313.09383 -298.551019) (xy 313.051209 -298.526412) (xy 313.013088 -298.495287)
			(xy 312.980453 -298.45845) (xy 312.95415 -298.416854) (xy 312.934859 -298.371578) (xy 312.923082 -298.323794)
			(xy 312.919122 -298.27474) (xy 312.58002 -298.27474) (xy 312.579525 -298.299347) (xy 312.57163 -298.347924)
			(xy 312.556046 -298.394605) (xy 312.533175 -298.438182) (xy 312.50361 -298.477526) (xy 312.468117 -298.511618)
			(xy 312.427614 -298.539574) (xy 312.383152 -298.560672) (xy 312.335881 -298.574364) (xy 312.287026 -298.580296)
			(xy 312.237851 -298.578315) (xy 312.189632 -298.568471) (xy 312.143616 -298.551019) (xy 312.100995 -298.526412)
			(xy 312.062874 -298.495287) (xy 312.030239 -298.45845) (xy 312.003936 -298.416854) (xy 311.984645 -298.371578)
			(xy 311.972868 -298.323794) (xy 311.968908 -298.27474) (xy 311.63006 -298.27474) (xy 311.629565 -298.299347)
			(xy 311.62167 -298.347924) (xy 311.606086 -298.394605) (xy 311.583215 -298.438182) (xy 311.55365 -298.477526)
			(xy 311.518157 -298.511618) (xy 311.477654 -298.539574) (xy 311.433192 -298.560672) (xy 311.385921 -298.574364)
			(xy 311.337066 -298.580296) (xy 311.287891 -298.578315) (xy 311.239672 -298.568471) (xy 311.193656 -298.551019)
			(xy 311.151035 -298.526412) (xy 311.112914 -298.495287) (xy 311.080279 -298.45845) (xy 311.053976 -298.416854)
			(xy 311.034685 -298.371578) (xy 311.022908 -298.323794) (xy 311.018948 -298.27474) (xy 310.6801 -298.27474)
			(xy 310.679605 -298.299347) (xy 310.67171 -298.347924) (xy 310.656126 -298.394605) (xy 310.633255 -298.438182)
			(xy 310.60369 -298.477526) (xy 310.568197 -298.511618) (xy 310.527694 -298.539574) (xy 310.483232 -298.560672)
			(xy 310.435961 -298.574364) (xy 310.387106 -298.580296) (xy 310.337931 -298.578315) (xy 310.289712 -298.568471)
			(xy 310.243696 -298.551019) (xy 310.201075 -298.526412) (xy 310.162954 -298.495287) (xy 310.130319 -298.45845)
			(xy 310.104016 -298.416854) (xy 310.084725 -298.371578) (xy 310.072948 -298.323794) (xy 310.068988 -298.27474)
			(xy 309.73014 -298.27474) (xy 309.729645 -298.299347) (xy 309.72175 -298.347924) (xy 309.706166 -298.394605)
			(xy 309.683295 -298.438182) (xy 309.65373 -298.477526) (xy 309.618237 -298.511618) (xy 309.577734 -298.539574)
			(xy 309.533272 -298.560672) (xy 309.486001 -298.574364) (xy 309.437146 -298.580296) (xy 309.387971 -298.578315)
			(xy 309.339752 -298.568471) (xy 309.293736 -298.551019) (xy 309.251115 -298.526412) (xy 309.212994 -298.495287)
			(xy 309.180359 -298.45845) (xy 309.154056 -298.416854) (xy 309.134765 -298.371578) (xy 309.122988 -298.323794)
			(xy 309.119028 -298.27474) (xy 308.78018 -298.27474) (xy 308.779685 -298.299347) (xy 308.77179 -298.347924)
			(xy 308.756206 -298.394605) (xy 308.733335 -298.438182) (xy 308.70377 -298.477526) (xy 308.668277 -298.511618)
			(xy 308.627774 -298.539574) (xy 308.583312 -298.560672) (xy 308.536041 -298.574364) (xy 308.487186 -298.580296)
			(xy 308.438011 -298.578315) (xy 308.389792 -298.568471) (xy 308.343776 -298.551019) (xy 308.301155 -298.526412)
			(xy 308.263034 -298.495287) (xy 308.230399 -298.45845) (xy 308.204096 -298.416854) (xy 308.184805 -298.371578)
			(xy 308.173028 -298.323794) (xy 308.169068 -298.27474) (xy 307.83022 -298.27474) (xy 307.829725 -298.299347)
			(xy 307.82183 -298.347924) (xy 307.806246 -298.394605) (xy 307.783375 -298.438182) (xy 307.75381 -298.477526)
			(xy 307.718317 -298.511618) (xy 307.677814 -298.539574) (xy 307.633352 -298.560672) (xy 307.586081 -298.574364)
			(xy 307.537226 -298.580296) (xy 307.488051 -298.578315) (xy 307.439832 -298.568471) (xy 307.393816 -298.551019)
			(xy 307.351195 -298.526412) (xy 307.313074 -298.495287) (xy 307.280439 -298.45845) (xy 307.254136 -298.416854)
			(xy 307.234845 -298.371578) (xy 307.223068 -298.323794) (xy 307.219108 -298.27474) (xy 306.880006 -298.27474)
			(xy 306.879511 -298.299347) (xy 306.871616 -298.347924) (xy 306.856032 -298.394605) (xy 306.833161 -298.438182)
			(xy 306.803596 -298.477526) (xy 306.768103 -298.511618) (xy 306.7276 -298.539574) (xy 306.683138 -298.560672)
			(xy 306.635867 -298.574364) (xy 306.587012 -298.580296) (xy 306.537837 -298.578315) (xy 306.489618 -298.568471)
			(xy 306.443602 -298.551019) (xy 306.400981 -298.526412) (xy 306.36286 -298.495287) (xy 306.330225 -298.45845)
			(xy 306.303922 -298.416854) (xy 306.284631 -298.371578) (xy 306.272854 -298.323794) (xy 306.268894 -298.27474)
			(xy 305.930046 -298.27474) (xy 305.929551 -298.299347) (xy 305.921656 -298.347924) (xy 305.906072 -298.394605)
			(xy 305.883201 -298.438182) (xy 305.853636 -298.477526) (xy 305.818143 -298.511618) (xy 305.77764 -298.539574)
			(xy 305.733178 -298.560672) (xy 305.685907 -298.574364) (xy 305.637052 -298.580296) (xy 305.587877 -298.578315)
			(xy 305.539658 -298.568471) (xy 305.493642 -298.551019) (xy 305.451021 -298.526412) (xy 305.4129 -298.495287)
			(xy 305.380265 -298.45845) (xy 305.353962 -298.416854) (xy 305.334671 -298.371578) (xy 305.322894 -298.323794)
			(xy 305.318934 -298.27474) (xy 304.980086 -298.27474) (xy 304.979591 -298.299347) (xy 304.971696 -298.347924)
			(xy 304.956112 -298.394605) (xy 304.933241 -298.438182) (xy 304.903676 -298.477526) (xy 304.868183 -298.511618)
			(xy 304.82768 -298.539574) (xy 304.783218 -298.560672) (xy 304.735947 -298.574364) (xy 304.687092 -298.580296)
			(xy 304.637917 -298.578315) (xy 304.589698 -298.568471) (xy 304.543682 -298.551019) (xy 304.501061 -298.526412)
			(xy 304.46294 -298.495287) (xy 304.430305 -298.45845) (xy 304.404002 -298.416854) (xy 304.384711 -298.371578)
			(xy 304.372934 -298.323794) (xy 304.368974 -298.27474) (xy 304.030126 -298.27474) (xy 304.029631 -298.299347)
			(xy 304.021736 -298.347924) (xy 304.006152 -298.394605) (xy 303.983281 -298.438182) (xy 303.953716 -298.477526)
			(xy 303.918223 -298.511618) (xy 303.87772 -298.539574) (xy 303.833258 -298.560672) (xy 303.785987 -298.574364)
			(xy 303.737132 -298.580296) (xy 303.687957 -298.578315) (xy 303.639738 -298.568471) (xy 303.593722 -298.551019)
			(xy 303.551101 -298.526412) (xy 303.51298 -298.495287) (xy 303.480345 -298.45845) (xy 303.454042 -298.416854)
			(xy 303.434751 -298.371578) (xy 303.422974 -298.323794) (xy 303.419014 -298.27474) (xy 303.080166 -298.27474)
			(xy 303.079671 -298.299347) (xy 303.071776 -298.347924) (xy 303.056192 -298.394605) (xy 303.033321 -298.438182)
			(xy 303.003756 -298.477526) (xy 302.968263 -298.511618) (xy 302.92776 -298.539574) (xy 302.883298 -298.560672)
			(xy 302.836027 -298.574364) (xy 302.787172 -298.580296) (xy 302.737997 -298.578315) (xy 302.689778 -298.568471)
			(xy 302.643762 -298.551019) (xy 302.601141 -298.526412) (xy 302.56302 -298.495287) (xy 302.530385 -298.45845)
			(xy 302.504082 -298.416854) (xy 302.484791 -298.371578) (xy 302.473014 -298.323794) (xy 302.469054 -298.27474)
			(xy 302.130206 -298.27474) (xy 302.129711 -298.299347) (xy 302.121816 -298.347924) (xy 302.106232 -298.394605)
			(xy 302.083361 -298.438182) (xy 302.053796 -298.477526) (xy 302.018303 -298.511618) (xy 301.9778 -298.539574)
			(xy 301.933338 -298.560672) (xy 301.886067 -298.574364) (xy 301.837212 -298.580296) (xy 301.788037 -298.578315)
			(xy 301.739818 -298.568471) (xy 301.693802 -298.551019) (xy 301.651181 -298.526412) (xy 301.61306 -298.495287)
			(xy 301.580425 -298.45845) (xy 301.554122 -298.416854) (xy 301.534831 -298.371578) (xy 301.523054 -298.323794)
			(xy 301.519094 -298.27474) (xy 301.179992 -298.27474) (xy 301.179497 -298.299347) (xy 301.171602 -298.347924)
			(xy 301.156018 -298.394605) (xy 301.133147 -298.438182) (xy 301.103582 -298.477526) (xy 301.068089 -298.511618)
			(xy 301.027586 -298.539574) (xy 300.983124 -298.560672) (xy 300.935853 -298.574364) (xy 300.886998 -298.580296)
			(xy 300.837823 -298.578315) (xy 300.789604 -298.568471) (xy 300.743588 -298.551019) (xy 300.700967 -298.526412)
			(xy 300.662846 -298.495287) (xy 300.630211 -298.45845) (xy 300.603908 -298.416854) (xy 300.584617 -298.371578)
			(xy 300.57284 -298.323794) (xy 300.56888 -298.27474) (xy 299.280072 -298.27474) (xy 299.279577 -298.299347)
			(xy 299.271682 -298.347924) (xy 299.256098 -298.394605) (xy 299.233227 -298.438182) (xy 299.203662 -298.477526)
			(xy 299.168169 -298.511618) (xy 299.127666 -298.539574) (xy 299.083204 -298.560672) (xy 299.035933 -298.574364)
			(xy 298.987078 -298.580296) (xy 298.937903 -298.578315) (xy 298.889684 -298.568471) (xy 298.843668 -298.551019)
			(xy 298.801047 -298.526412) (xy 298.762926 -298.495287) (xy 298.730291 -298.45845) (xy 298.703988 -298.416854)
			(xy 298.684697 -298.371578) (xy 298.67292 -298.323794) (xy 298.66896 -298.27474) (xy 297.380152 -298.27474)
			(xy 297.379657 -298.299347) (xy 297.371762 -298.347924) (xy 297.356178 -298.394605) (xy 297.333307 -298.438182)
			(xy 297.303742 -298.477526) (xy 297.268249 -298.511618) (xy 297.227746 -298.539574) (xy 297.183284 -298.560672)
			(xy 297.136013 -298.574364) (xy 297.087158 -298.580296) (xy 297.037983 -298.578315) (xy 296.989764 -298.568471)
			(xy 296.943748 -298.551019) (xy 296.901127 -298.526412) (xy 296.863006 -298.495287) (xy 296.830371 -298.45845)
			(xy 296.804068 -298.416854) (xy 296.784777 -298.371578) (xy 296.773 -298.323794) (xy 296.76904 -298.27474)
			(xy 295.480232 -298.27474) (xy 295.479737 -298.299347) (xy 295.471842 -298.347924) (xy 295.456258 -298.394605)
			(xy 295.433387 -298.438182) (xy 295.403822 -298.477526) (xy 295.368329 -298.511618) (xy 295.327826 -298.539574)
			(xy 295.283364 -298.560672) (xy 295.236093 -298.574364) (xy 295.187238 -298.580296) (xy 295.138063 -298.578315)
			(xy 295.089844 -298.568471) (xy 295.043828 -298.551019) (xy 295.001207 -298.526412) (xy 294.963086 -298.495287)
			(xy 294.930451 -298.45845) (xy 294.904148 -298.416854) (xy 294.884857 -298.371578) (xy 294.87308 -298.323794)
			(xy 294.86912 -298.27474) (xy 293.580058 -298.27474) (xy 293.579563 -298.299347) (xy 293.571668 -298.347924)
			(xy 293.556084 -298.394605) (xy 293.533213 -298.438182) (xy 293.503648 -298.477526) (xy 293.468155 -298.511618)
			(xy 293.427652 -298.539574) (xy 293.38319 -298.560672) (xy 293.335919 -298.574364) (xy 293.287064 -298.580296)
			(xy 293.237889 -298.578315) (xy 293.18967 -298.568471) (xy 293.143654 -298.551019) (xy 293.101033 -298.526412)
			(xy 293.062912 -298.495287) (xy 293.030277 -298.45845) (xy 293.003974 -298.416854) (xy 292.984683 -298.371578)
			(xy 292.972906 -298.323794) (xy 292.968946 -298.27474) (xy 290.730178 -298.27474) (xy 290.729683 -298.299347)
			(xy 290.721788 -298.347924) (xy 290.706204 -298.394605) (xy 290.683333 -298.438182) (xy 290.653768 -298.477526)
			(xy 290.618275 -298.511618) (xy 290.577772 -298.539574) (xy 290.53331 -298.560672) (xy 290.486039 -298.574364)
			(xy 290.437184 -298.580296) (xy 290.388009 -298.578315) (xy 290.33979 -298.568471) (xy 290.293774 -298.551019)
			(xy 290.251153 -298.526412) (xy 290.213032 -298.495287) (xy 290.180397 -298.45845) (xy 290.154094 -298.416854)
			(xy 290.134803 -298.371578) (xy 290.123026 -298.323794) (xy 290.119066 -298.27474) (xy 288.830004 -298.27474)
			(xy 288.829509 -298.299347) (xy 288.821614 -298.347924) (xy 288.80603 -298.394605) (xy 288.783159 -298.438182)
			(xy 288.753594 -298.477526) (xy 288.718101 -298.511618) (xy 288.677598 -298.539574) (xy 288.633136 -298.560672)
			(xy 288.585865 -298.574364) (xy 288.53701 -298.580296) (xy 288.487835 -298.578315) (xy 288.439616 -298.568471)
			(xy 288.3936 -298.551019) (xy 288.350979 -298.526412) (xy 288.312858 -298.495287) (xy 288.280223 -298.45845)
			(xy 288.25392 -298.416854) (xy 288.234629 -298.371578) (xy 288.222852 -298.323794) (xy 288.218892 -298.27474)
			(xy 286.930084 -298.27474) (xy 286.929589 -298.299347) (xy 286.921694 -298.347924) (xy 286.90611 -298.394605)
			(xy 286.883239 -298.438182) (xy 286.853674 -298.477526) (xy 286.818181 -298.511618) (xy 286.777678 -298.539574)
			(xy 286.733216 -298.560672) (xy 286.685945 -298.574364) (xy 286.63709 -298.580296) (xy 286.587915 -298.578315)
			(xy 286.539696 -298.568471) (xy 286.49368 -298.551019) (xy 286.451059 -298.526412) (xy 286.412938 -298.495287)
			(xy 286.380303 -298.45845) (xy 286.354 -298.416854) (xy 286.334709 -298.371578) (xy 286.322932 -298.323794)
			(xy 286.318972 -298.27474) (xy 285.030164 -298.27474) (xy 285.029669 -298.299347) (xy 285.021774 -298.347924)
			(xy 285.00619 -298.394605) (xy 284.983319 -298.438182) (xy 284.953754 -298.477526) (xy 284.918261 -298.511618)
			(xy 284.877758 -298.539574) (xy 284.833296 -298.560672) (xy 284.786025 -298.574364) (xy 284.73717 -298.580296)
			(xy 284.687995 -298.578315) (xy 284.639776 -298.568471) (xy 284.59376 -298.551019) (xy 284.551139 -298.526412)
			(xy 284.513018 -298.495287) (xy 284.480383 -298.45845) (xy 284.45408 -298.416854) (xy 284.434789 -298.371578)
			(xy 284.423012 -298.323794) (xy 284.419052 -298.27474) (xy 283.130244 -298.27474) (xy 283.129749 -298.299347)
			(xy 283.121854 -298.347924) (xy 283.10627 -298.394605) (xy 283.083399 -298.438182) (xy 283.053834 -298.477526)
			(xy 283.018341 -298.511618) (xy 282.977838 -298.539574) (xy 282.933376 -298.560672) (xy 282.886105 -298.574364)
			(xy 282.83725 -298.580296) (xy 282.788075 -298.578315) (xy 282.739856 -298.568471) (xy 282.69384 -298.551019)
			(xy 282.651219 -298.526412) (xy 282.613098 -298.495287) (xy 282.580463 -298.45845) (xy 282.55416 -298.416854)
			(xy 282.534869 -298.371578) (xy 282.523092 -298.323794) (xy 282.519132 -298.27474) (xy 281.23007 -298.27474)
			(xy 281.229575 -298.299347) (xy 281.22168 -298.347924) (xy 281.206096 -298.394605) (xy 281.183225 -298.438182)
			(xy 281.15366 -298.477526) (xy 281.118167 -298.511618) (xy 281.077664 -298.539574) (xy 281.033202 -298.560672)
			(xy 280.985931 -298.574364) (xy 280.937076 -298.580296) (xy 280.887901 -298.578315) (xy 280.839682 -298.568471)
			(xy 280.793666 -298.551019) (xy 280.751045 -298.526412) (xy 280.712924 -298.495287) (xy 280.680289 -298.45845)
			(xy 280.653986 -298.416854) (xy 280.634695 -298.371578) (xy 280.622918 -298.323794) (xy 280.618958 -298.27474)
			(xy 280.44902 -298.27474) (xy 280.44902 -298.700698) (xy 318.697354 -298.700698) (xy 318.701425 -298.645076)
			(xy 318.713551 -298.590639) (xy 318.733474 -298.538548) (xy 318.76077 -298.489913) (xy 318.794856 -298.44577)
			(xy 318.835005 -298.407061) (xy 318.880363 -298.37461) (xy 318.929963 -298.349109) (xy 318.982747 -298.331102)
			(xy 319.03759 -298.320972) (xy 319.093324 -298.318935) (xy 319.148761 -298.325035) (xy 319.202718 -298.339141)
			(xy 319.254047 -298.360953) (xy 319.301653 -298.390007) (xy 319.344521 -298.425682) (xy 319.381738 -298.467219)
			(xy 319.412511 -298.513732) (xy 319.436183 -298.564229) (xy 319.452251 -298.617636) (xy 319.460371 -298.672812)
			(xy 319.46088 -298.700698) (xy 319.460371 -298.728584) (xy 319.452251 -298.78376) (xy 319.436183 -298.837167)
			(xy 319.412511 -298.887664) (xy 319.381738 -298.934177) (xy 319.344521 -298.975714) (xy 319.301653 -299.011389)
			(xy 319.254047 -299.040443) (xy 319.202718 -299.062255) (xy 319.148761 -299.076361) (xy 319.093324 -299.082461)
			(xy 319.03759 -299.080424) (xy 318.982747 -299.070294) (xy 318.929963 -299.052287) (xy 318.880363 -299.026786)
			(xy 318.835005 -298.994335) (xy 318.794856 -298.955626) (xy 318.76077 -298.911483) (xy 318.733474 -298.862848)
			(xy 318.713551 -298.810757) (xy 318.701425 -298.75632) (xy 318.697354 -298.700698) (xy 280.44902 -298.700698)
			(xy 280.44902 -298.809156) (xy 280.448562 -298.832642) (xy 280.441319 -298.879052) (xy 280.427058 -298.923807)
			(xy 280.406114 -298.965852) (xy 280.378983 -299.004195) (xy 280.346302 -299.037935) (xy 280.327862 -299.052488)
			(xy 280.291286 -299.080174) (xy 280.285952 -299.084746) (xy 280.283412 -299.087286) (xy 280.276578 -299.094689)
			(xy 280.268873 -299.113287) (xy 280.268426 -299.123354) (xy 280.268426 -299.133514) (xy 280.270204 -299.147484)
			(xy 280.270966 -299.150786) (xy 280.270966 -299.151294) (xy 280.27522 -299.169412) (xy 280.27981 -299.206346)
			(xy 280.28011 -299.224954) (xy 281.568918 -299.224954) (xy 281.572878 -299.1759) (xy 281.584655 -299.128116)
			(xy 281.603946 -299.08284) (xy 281.630249 -299.041244) (xy 281.662884 -299.004407) (xy 281.701005 -298.973282)
			(xy 281.743626 -298.948675) (xy 281.789642 -298.931223) (xy 281.837861 -298.921379) (xy 281.887036 -298.919398)
			(xy 281.935891 -298.92533) (xy 281.983162 -298.939022) (xy 282.027624 -298.96012) (xy 282.068127 -298.988076)
			(xy 282.10362 -299.022168) (xy 282.133185 -299.061512) (xy 282.156056 -299.105089) (xy 282.17164 -299.15177)
			(xy 282.179535 -299.200347) (xy 282.18003 -299.224954) (xy 282.519132 -299.224954) (xy 282.523092 -299.1759)
			(xy 282.534869 -299.128116) (xy 282.55416 -299.08284) (xy 282.580463 -299.041244) (xy 282.613098 -299.004407)
			(xy 282.651219 -298.973282) (xy 282.69384 -298.948675) (xy 282.739856 -298.931223) (xy 282.788075 -298.921379)
			(xy 282.83725 -298.919398) (xy 282.886105 -298.92533) (xy 282.933376 -298.939022) (xy 282.977838 -298.96012)
			(xy 283.018341 -298.988076) (xy 283.053834 -299.022168) (xy 283.083399 -299.061512) (xy 283.10627 -299.105089)
			(xy 283.121854 -299.15177) (xy 283.129749 -299.200347) (xy 283.130244 -299.224954) (xy 283.469092 -299.224954)
			(xy 283.473052 -299.1759) (xy 283.484829 -299.128116) (xy 283.50412 -299.08284) (xy 283.530423 -299.041244)
			(xy 283.563058 -299.004407) (xy 283.601179 -298.973282) (xy 283.6438 -298.948675) (xy 283.689816 -298.931223)
			(xy 283.738035 -298.921379) (xy 283.78721 -298.919398) (xy 283.836065 -298.92533) (xy 283.883336 -298.939022)
			(xy 283.927798 -298.96012) (xy 283.968301 -298.988076) (xy 284.003794 -299.022168) (xy 284.033359 -299.061512)
			(xy 284.05623 -299.105089) (xy 284.071814 -299.15177) (xy 284.079709 -299.200347) (xy 284.080204 -299.224954)
			(xy 284.419052 -299.224954) (xy 284.423012 -299.1759) (xy 284.434789 -299.128116) (xy 284.45408 -299.08284)
			(xy 284.480383 -299.041244) (xy 284.513018 -299.004407) (xy 284.551139 -298.973282) (xy 284.59376 -298.948675)
			(xy 284.639776 -298.931223) (xy 284.687995 -298.921379) (xy 284.73717 -298.919398) (xy 284.786025 -298.92533)
			(xy 284.833296 -298.939022) (xy 284.877758 -298.96012) (xy 284.918261 -298.988076) (xy 284.953754 -299.022168)
			(xy 284.983319 -299.061512) (xy 285.00619 -299.105089) (xy 285.021774 -299.15177) (xy 285.029669 -299.200347)
			(xy 285.030164 -299.224954) (xy 285.369012 -299.224954) (xy 285.372972 -299.1759) (xy 285.384749 -299.128116)
			(xy 285.40404 -299.08284) (xy 285.430343 -299.041244) (xy 285.462978 -299.004407) (xy 285.501099 -298.973282)
			(xy 285.54372 -298.948675) (xy 285.589736 -298.931223) (xy 285.637955 -298.921379) (xy 285.68713 -298.919398)
			(xy 285.735985 -298.92533) (xy 285.783256 -298.939022) (xy 285.827718 -298.96012) (xy 285.868221 -298.988076)
			(xy 285.903714 -299.022168) (xy 285.933279 -299.061512) (xy 285.95615 -299.105089) (xy 285.971734 -299.15177)
			(xy 285.979629 -299.200347) (xy 285.980124 -299.224954) (xy 286.318972 -299.224954) (xy 286.322932 -299.1759)
			(xy 286.334709 -299.128116) (xy 286.354 -299.08284) (xy 286.380303 -299.041244) (xy 286.412938 -299.004407)
			(xy 286.451059 -298.973282) (xy 286.49368 -298.948675) (xy 286.539696 -298.931223) (xy 286.587915 -298.921379)
			(xy 286.63709 -298.919398) (xy 286.685945 -298.92533) (xy 286.733216 -298.939022) (xy 286.777678 -298.96012)
			(xy 286.818181 -298.988076) (xy 286.853674 -299.022168) (xy 286.883239 -299.061512) (xy 286.90611 -299.105089)
			(xy 286.921694 -299.15177) (xy 286.929589 -299.200347) (xy 286.930084 -299.224954) (xy 287.268932 -299.224954)
			(xy 287.272892 -299.1759) (xy 287.284669 -299.128116) (xy 287.30396 -299.08284) (xy 287.330263 -299.041244)
			(xy 287.362898 -299.004407) (xy 287.401019 -298.973282) (xy 287.44364 -298.948675) (xy 287.489656 -298.931223)
			(xy 287.537875 -298.921379) (xy 287.58705 -298.919398) (xy 287.635905 -298.92533) (xy 287.683176 -298.939022)
			(xy 287.727638 -298.96012) (xy 287.768141 -298.988076) (xy 287.803634 -299.022168) (xy 287.833199 -299.061512)
			(xy 287.85607 -299.105089) (xy 287.871654 -299.15177) (xy 287.879549 -299.200347) (xy 287.880044 -299.224954)
			(xy 288.218892 -299.224954) (xy 288.222852 -299.1759) (xy 288.234629 -299.128116) (xy 288.25392 -299.08284)
			(xy 288.280223 -299.041244) (xy 288.312858 -299.004407) (xy 288.350979 -298.973282) (xy 288.3936 -298.948675)
			(xy 288.439616 -298.931223) (xy 288.487835 -298.921379) (xy 288.53701 -298.919398) (xy 288.585865 -298.92533)
			(xy 288.633136 -298.939022) (xy 288.677598 -298.96012) (xy 288.718101 -298.988076) (xy 288.753594 -299.022168)
			(xy 288.783159 -299.061512) (xy 288.80603 -299.105089) (xy 288.821614 -299.15177) (xy 288.829509 -299.200347)
			(xy 288.830004 -299.224954) (xy 289.169106 -299.224954) (xy 289.173066 -299.1759) (xy 289.184843 -299.128116)
			(xy 289.204134 -299.08284) (xy 289.230437 -299.041244) (xy 289.263072 -299.004407) (xy 289.301193 -298.973282)
			(xy 289.343814 -298.948675) (xy 289.38983 -298.931223) (xy 289.438049 -298.921379) (xy 289.487224 -298.919398)
			(xy 289.536079 -298.92533) (xy 289.58335 -298.939022) (xy 289.627812 -298.96012) (xy 289.668315 -298.988076)
			(xy 289.703808 -299.022168) (xy 289.733373 -299.061512) (xy 289.756244 -299.105089) (xy 289.771828 -299.15177)
			(xy 289.779723 -299.200347) (xy 289.780218 -299.224954) (xy 290.119066 -299.224954) (xy 290.123026 -299.1759)
			(xy 290.134803 -299.128116) (xy 290.154094 -299.08284) (xy 290.180397 -299.041244) (xy 290.213032 -299.004407)
			(xy 290.251153 -298.973282) (xy 290.293774 -298.948675) (xy 290.33979 -298.931223) (xy 290.388009 -298.921379)
			(xy 290.437184 -298.919398) (xy 290.486039 -298.92533) (xy 290.53331 -298.939022) (xy 290.577772 -298.96012)
			(xy 290.618275 -298.988076) (xy 290.653768 -299.022168) (xy 290.683333 -299.061512) (xy 290.706204 -299.105089)
			(xy 290.721788 -299.15177) (xy 290.729683 -299.200347) (xy 290.730178 -299.224954) (xy 292.018986 -299.224954)
			(xy 292.022946 -299.1759) (xy 292.034723 -299.128116) (xy 292.054014 -299.08284) (xy 292.080317 -299.041244)
			(xy 292.112952 -299.004407) (xy 292.151073 -298.973282) (xy 292.193694 -298.948675) (xy 292.23971 -298.931223)
			(xy 292.287929 -298.921379) (xy 292.337104 -298.919398) (xy 292.385959 -298.92533) (xy 292.43323 -298.939022)
			(xy 292.477692 -298.96012) (xy 292.518195 -298.988076) (xy 292.553688 -299.022168) (xy 292.583253 -299.061512)
			(xy 292.606124 -299.105089) (xy 292.621708 -299.15177) (xy 292.629603 -299.200347) (xy 292.630098 -299.224954)
			(xy 292.968946 -299.224954) (xy 292.972906 -299.1759) (xy 292.984683 -299.128116) (xy 293.003974 -299.08284)
			(xy 293.030277 -299.041244) (xy 293.062912 -299.004407) (xy 293.101033 -298.973282) (xy 293.143654 -298.948675)
			(xy 293.18967 -298.931223) (xy 293.237889 -298.921379) (xy 293.287064 -298.919398) (xy 293.335919 -298.92533)
			(xy 293.38319 -298.939022) (xy 293.427652 -298.96012) (xy 293.468155 -298.988076) (xy 293.503648 -299.022168)
			(xy 293.533213 -299.061512) (xy 293.556084 -299.105089) (xy 293.571668 -299.15177) (xy 293.579563 -299.200347)
			(xy 293.580058 -299.224954) (xy 293.918906 -299.224954) (xy 293.922866 -299.1759) (xy 293.934643 -299.128116)
			(xy 293.953934 -299.08284) (xy 293.980237 -299.041244) (xy 294.012872 -299.004407) (xy 294.050993 -298.973282)
			(xy 294.093614 -298.948675) (xy 294.13963 -298.931223) (xy 294.187849 -298.921379) (xy 294.237024 -298.919398)
			(xy 294.285879 -298.92533) (xy 294.33315 -298.939022) (xy 294.377612 -298.96012) (xy 294.418115 -298.988076)
			(xy 294.453608 -299.022168) (xy 294.483173 -299.061512) (xy 294.506044 -299.105089) (xy 294.521628 -299.15177)
			(xy 294.529523 -299.200347) (xy 294.530018 -299.224954) (xy 294.86912 -299.224954) (xy 294.87308 -299.1759)
			(xy 294.884857 -299.128116) (xy 294.904148 -299.08284) (xy 294.930451 -299.041244) (xy 294.963086 -299.004407)
			(xy 295.001207 -298.973282) (xy 295.043828 -298.948675) (xy 295.089844 -298.931223) (xy 295.138063 -298.921379)
			(xy 295.187238 -298.919398) (xy 295.236093 -298.92533) (xy 295.283364 -298.939022) (xy 295.327826 -298.96012)
			(xy 295.368329 -298.988076) (xy 295.403822 -299.022168) (xy 295.433387 -299.061512) (xy 295.456258 -299.105089)
			(xy 295.471842 -299.15177) (xy 295.479737 -299.200347) (xy 295.480232 -299.224954) (xy 295.81908 -299.224954)
			(xy 295.82304 -299.1759) (xy 295.834817 -299.128116) (xy 295.854108 -299.08284) (xy 295.880411 -299.041244)
			(xy 295.913046 -299.004407) (xy 295.951167 -298.973282) (xy 295.993788 -298.948675) (xy 296.039804 -298.931223)
			(xy 296.088023 -298.921379) (xy 296.137198 -298.919398) (xy 296.186053 -298.92533) (xy 296.233324 -298.939022)
			(xy 296.277786 -298.96012) (xy 296.318289 -298.988076) (xy 296.353782 -299.022168) (xy 296.383347 -299.061512)
			(xy 296.406218 -299.105089) (xy 296.421802 -299.15177) (xy 296.429697 -299.200347) (xy 296.430192 -299.224954)
			(xy 296.76904 -299.224954) (xy 296.773 -299.1759) (xy 296.784777 -299.128116) (xy 296.804068 -299.08284)
			(xy 296.830371 -299.041244) (xy 296.863006 -299.004407) (xy 296.901127 -298.973282) (xy 296.943748 -298.948675)
			(xy 296.989764 -298.931223) (xy 297.037983 -298.921379) (xy 297.087158 -298.919398) (xy 297.136013 -298.92533)
			(xy 297.183284 -298.939022) (xy 297.227746 -298.96012) (xy 297.268249 -298.988076) (xy 297.303742 -299.022168)
			(xy 297.333307 -299.061512) (xy 297.356178 -299.105089) (xy 297.371762 -299.15177) (xy 297.379657 -299.200347)
			(xy 297.380152 -299.224954) (xy 297.719 -299.224954) (xy 297.72296 -299.1759) (xy 297.734737 -299.128116)
			(xy 297.754028 -299.08284) (xy 297.780331 -299.041244) (xy 297.812966 -299.004407) (xy 297.851087 -298.973282)
			(xy 297.893708 -298.948675) (xy 297.939724 -298.931223) (xy 297.987943 -298.921379) (xy 298.037118 -298.919398)
			(xy 298.085973 -298.92533) (xy 298.133244 -298.939022) (xy 298.177706 -298.96012) (xy 298.218209 -298.988076)
			(xy 298.253702 -299.022168) (xy 298.283267 -299.061512) (xy 298.306138 -299.105089) (xy 298.321722 -299.15177)
			(xy 298.329617 -299.200347) (xy 298.330112 -299.224954) (xy 298.66896 -299.224954) (xy 298.67292 -299.1759)
			(xy 298.684697 -299.128116) (xy 298.703988 -299.08284) (xy 298.730291 -299.041244) (xy 298.762926 -299.004407)
			(xy 298.801047 -298.973282) (xy 298.843668 -298.948675) (xy 298.889684 -298.931223) (xy 298.937903 -298.921379)
			(xy 298.987078 -298.919398) (xy 299.035933 -298.92533) (xy 299.083204 -298.939022) (xy 299.127666 -298.96012)
			(xy 299.168169 -298.988076) (xy 299.203662 -299.022168) (xy 299.233227 -299.061512) (xy 299.256098 -299.105089)
			(xy 299.271682 -299.15177) (xy 299.279577 -299.200347) (xy 299.280072 -299.224954) (xy 299.61892 -299.224954)
			(xy 299.62288 -299.1759) (xy 299.634657 -299.128116) (xy 299.653948 -299.08284) (xy 299.680251 -299.041244)
			(xy 299.712886 -299.004407) (xy 299.751007 -298.973282) (xy 299.793628 -298.948675) (xy 299.839644 -298.931223)
			(xy 299.887863 -298.921379) (xy 299.937038 -298.919398) (xy 299.985893 -298.92533) (xy 300.033164 -298.939022)
			(xy 300.077626 -298.96012) (xy 300.118129 -298.988076) (xy 300.153622 -299.022168) (xy 300.183187 -299.061512)
			(xy 300.206058 -299.105089) (xy 300.221642 -299.15177) (xy 300.229537 -299.200347) (xy 300.230032 -299.224954)
			(xy 300.56888 -299.224954) (xy 300.57284 -299.1759) (xy 300.584617 -299.128116) (xy 300.603908 -299.08284)
			(xy 300.630211 -299.041244) (xy 300.662846 -299.004407) (xy 300.700967 -298.973282) (xy 300.743588 -298.948675)
			(xy 300.789604 -298.931223) (xy 300.837823 -298.921379) (xy 300.886998 -298.919398) (xy 300.935853 -298.92533)
			(xy 300.983124 -298.939022) (xy 301.027586 -298.96012) (xy 301.068089 -298.988076) (xy 301.103582 -299.022168)
			(xy 301.133147 -299.061512) (xy 301.156018 -299.105089) (xy 301.171602 -299.15177) (xy 301.179497 -299.200347)
			(xy 301.179992 -299.224954) (xy 301.519094 -299.224954) (xy 301.523054 -299.1759) (xy 301.534831 -299.128116)
			(xy 301.554122 -299.08284) (xy 301.580425 -299.041244) (xy 301.61306 -299.004407) (xy 301.651181 -298.973282)
			(xy 301.693802 -298.948675) (xy 301.739818 -298.931223) (xy 301.788037 -298.921379) (xy 301.837212 -298.919398)
			(xy 301.886067 -298.92533) (xy 301.933338 -298.939022) (xy 301.9778 -298.96012) (xy 302.018303 -298.988076)
			(xy 302.053796 -299.022168) (xy 302.083361 -299.061512) (xy 302.106232 -299.105089) (xy 302.121816 -299.15177)
			(xy 302.129711 -299.200347) (xy 302.130206 -299.224954) (xy 302.469054 -299.224954) (xy 302.473014 -299.1759)
			(xy 302.484791 -299.128116) (xy 302.504082 -299.08284) (xy 302.530385 -299.041244) (xy 302.56302 -299.004407)
			(xy 302.601141 -298.973282) (xy 302.643762 -298.948675) (xy 302.689778 -298.931223) (xy 302.737997 -298.921379)
			(xy 302.787172 -298.919398) (xy 302.836027 -298.92533) (xy 302.883298 -298.939022) (xy 302.92776 -298.96012)
			(xy 302.968263 -298.988076) (xy 303.003756 -299.022168) (xy 303.033321 -299.061512) (xy 303.056192 -299.105089)
			(xy 303.071776 -299.15177) (xy 303.079671 -299.200347) (xy 303.080166 -299.224954) (xy 303.419014 -299.224954)
			(xy 303.422974 -299.1759) (xy 303.434751 -299.128116) (xy 303.454042 -299.08284) (xy 303.480345 -299.041244)
			(xy 303.51298 -299.004407) (xy 303.551101 -298.973282) (xy 303.593722 -298.948675) (xy 303.639738 -298.931223)
			(xy 303.687957 -298.921379) (xy 303.737132 -298.919398) (xy 303.785987 -298.92533) (xy 303.833258 -298.939022)
			(xy 303.87772 -298.96012) (xy 303.918223 -298.988076) (xy 303.953716 -299.022168) (xy 303.983281 -299.061512)
			(xy 304.006152 -299.105089) (xy 304.021736 -299.15177) (xy 304.029631 -299.200347) (xy 304.030126 -299.224954)
			(xy 304.368974 -299.224954) (xy 304.372934 -299.1759) (xy 304.384711 -299.128116) (xy 304.404002 -299.08284)
			(xy 304.430305 -299.041244) (xy 304.46294 -299.004407) (xy 304.501061 -298.973282) (xy 304.543682 -298.948675)
			(xy 304.589698 -298.931223) (xy 304.637917 -298.921379) (xy 304.687092 -298.919398) (xy 304.735947 -298.92533)
			(xy 304.783218 -298.939022) (xy 304.82768 -298.96012) (xy 304.868183 -298.988076) (xy 304.903676 -299.022168)
			(xy 304.933241 -299.061512) (xy 304.956112 -299.105089) (xy 304.971696 -299.15177) (xy 304.979591 -299.200347)
			(xy 304.980086 -299.224954) (xy 305.318934 -299.224954) (xy 305.322894 -299.1759) (xy 305.334671 -299.128116)
			(xy 305.353962 -299.08284) (xy 305.380265 -299.041244) (xy 305.4129 -299.004407) (xy 305.451021 -298.973282)
			(xy 305.493642 -298.948675) (xy 305.539658 -298.931223) (xy 305.587877 -298.921379) (xy 305.637052 -298.919398)
			(xy 305.685907 -298.92533) (xy 305.733178 -298.939022) (xy 305.77764 -298.96012) (xy 305.818143 -298.988076)
			(xy 305.853636 -299.022168) (xy 305.883201 -299.061512) (xy 305.906072 -299.105089) (xy 305.921656 -299.15177)
			(xy 305.929551 -299.200347) (xy 305.930046 -299.224954) (xy 308.169068 -299.224954) (xy 308.173028 -299.1759)
			(xy 308.184805 -299.128116) (xy 308.204096 -299.08284) (xy 308.230399 -299.041244) (xy 308.263034 -299.004407)
			(xy 308.301155 -298.973282) (xy 308.343776 -298.948675) (xy 308.389792 -298.931223) (xy 308.438011 -298.921379)
			(xy 308.487186 -298.919398) (xy 308.536041 -298.92533) (xy 308.583312 -298.939022) (xy 308.627774 -298.96012)
			(xy 308.668277 -298.988076) (xy 308.70377 -299.022168) (xy 308.733335 -299.061512) (xy 308.756206 -299.105089)
			(xy 308.77179 -299.15177) (xy 308.779685 -299.200347) (xy 308.78018 -299.224954) (xy 309.119028 -299.224954)
			(xy 309.122988 -299.1759) (xy 309.134765 -299.128116) (xy 309.154056 -299.08284) (xy 309.180359 -299.041244)
			(xy 309.212994 -299.004407) (xy 309.251115 -298.973282) (xy 309.293736 -298.948675) (xy 309.339752 -298.931223)
			(xy 309.387971 -298.921379) (xy 309.437146 -298.919398) (xy 309.486001 -298.92533) (xy 309.533272 -298.939022)
			(xy 309.577734 -298.96012) (xy 309.618237 -298.988076) (xy 309.65373 -299.022168) (xy 309.683295 -299.061512)
			(xy 309.706166 -299.105089) (xy 309.72175 -299.15177) (xy 309.729645 -299.200347) (xy 309.73014 -299.224954)
			(xy 310.068988 -299.224954) (xy 310.072948 -299.1759) (xy 310.084725 -299.128116) (xy 310.104016 -299.08284)
			(xy 310.130319 -299.041244) (xy 310.162954 -299.004407) (xy 310.201075 -298.973282) (xy 310.243696 -298.948675)
			(xy 310.289712 -298.931223) (xy 310.337931 -298.921379) (xy 310.387106 -298.919398) (xy 310.435961 -298.92533)
			(xy 310.483232 -298.939022) (xy 310.527694 -298.96012) (xy 310.568197 -298.988076) (xy 310.60369 -299.022168)
			(xy 310.633255 -299.061512) (xy 310.656126 -299.105089) (xy 310.67171 -299.15177) (xy 310.679605 -299.200347)
			(xy 310.6801 -299.224954) (xy 311.018948 -299.224954) (xy 311.022908 -299.1759) (xy 311.034685 -299.128116)
			(xy 311.053976 -299.08284) (xy 311.080279 -299.041244) (xy 311.112914 -299.004407) (xy 311.151035 -298.973282)
			(xy 311.193656 -298.948675) (xy 311.239672 -298.931223) (xy 311.287891 -298.921379) (xy 311.337066 -298.919398)
			(xy 311.385921 -298.92533) (xy 311.433192 -298.939022) (xy 311.477654 -298.96012) (xy 311.518157 -298.988076)
			(xy 311.55365 -299.022168) (xy 311.583215 -299.061512) (xy 311.606086 -299.105089) (xy 311.62167 -299.15177)
			(xy 311.629565 -299.200347) (xy 311.63006 -299.224954) (xy 311.968908 -299.224954) (xy 311.972868 -299.1759)
			(xy 311.984645 -299.128116) (xy 312.003936 -299.08284) (xy 312.030239 -299.041244) (xy 312.062874 -299.004407)
			(xy 312.100995 -298.973282) (xy 312.143616 -298.948675) (xy 312.189632 -298.931223) (xy 312.237851 -298.921379)
			(xy 312.287026 -298.919398) (xy 312.335881 -298.92533) (xy 312.383152 -298.939022) (xy 312.427614 -298.96012)
			(xy 312.468117 -298.988076) (xy 312.50361 -299.022168) (xy 312.533175 -299.061512) (xy 312.556046 -299.105089)
			(xy 312.57163 -299.15177) (xy 312.579525 -299.200347) (xy 312.58002 -299.224954) (xy 312.919122 -299.224954)
			(xy 312.923082 -299.1759) (xy 312.934859 -299.128116) (xy 312.95415 -299.08284) (xy 312.980453 -299.041244)
			(xy 313.013088 -299.004407) (xy 313.051209 -298.973282) (xy 313.09383 -298.948675) (xy 313.139846 -298.931223)
			(xy 313.188065 -298.921379) (xy 313.23724 -298.919398) (xy 313.286095 -298.92533) (xy 313.333366 -298.939022)
			(xy 313.377828 -298.96012) (xy 313.418331 -298.988076) (xy 313.453824 -299.022168) (xy 313.483389 -299.061512)
			(xy 313.50626 -299.105089) (xy 313.521844 -299.15177) (xy 313.529739 -299.200347) (xy 313.530234 -299.224954)
			(xy 313.869082 -299.224954) (xy 313.873042 -299.1759) (xy 313.884819 -299.128116) (xy 313.90411 -299.08284)
			(xy 313.930413 -299.041244) (xy 313.963048 -299.004407) (xy 314.001169 -298.973282) (xy 314.04379 -298.948675)
			(xy 314.089806 -298.931223) (xy 314.138025 -298.921379) (xy 314.1872 -298.919398) (xy 314.236055 -298.92533)
			(xy 314.283326 -298.939022) (xy 314.327788 -298.96012) (xy 314.368291 -298.988076) (xy 314.403784 -299.022168)
			(xy 314.433349 -299.061512) (xy 314.45622 -299.105089) (xy 314.471804 -299.15177) (xy 314.479699 -299.200347)
			(xy 314.480194 -299.224954) (xy 314.819042 -299.224954) (xy 314.823002 -299.1759) (xy 314.834779 -299.128116)
			(xy 314.85407 -299.08284) (xy 314.880373 -299.041244) (xy 314.913008 -299.004407) (xy 314.951129 -298.973282)
			(xy 314.99375 -298.948675) (xy 315.039766 -298.931223) (xy 315.087985 -298.921379) (xy 315.13716 -298.919398)
			(xy 315.186015 -298.92533) (xy 315.233286 -298.939022) (xy 315.277748 -298.96012) (xy 315.318251 -298.988076)
			(xy 315.353744 -299.022168) (xy 315.383309 -299.061512) (xy 315.40618 -299.105089) (xy 315.421764 -299.15177)
			(xy 315.429659 -299.200347) (xy 315.430154 -299.224954) (xy 315.429659 -299.249561) (xy 315.425856 -299.27296)
			(xy 322.514466 -299.27296) (xy 322.518537 -299.217338) (xy 322.530663 -299.162901) (xy 322.550586 -299.11081)
			(xy 322.577882 -299.062175) (xy 322.611968 -299.018032) (xy 322.652117 -298.979323) (xy 322.697475 -298.946872)
			(xy 322.747075 -298.921371) (xy 322.799859 -298.903364) (xy 322.854702 -298.893234) (xy 322.910436 -298.891197)
			(xy 322.965873 -298.897297) (xy 323.01983 -298.911403) (xy 323.071159 -298.933215) (xy 323.118765 -298.962269)
			(xy 323.161633 -298.997944) (xy 323.19885 -299.039481) (xy 323.229623 -299.085994) (xy 323.253295 -299.136491)
			(xy 323.269363 -299.189898) (xy 323.277483 -299.245074) (xy 323.277992 -299.27296) (xy 323.277483 -299.300846)
			(xy 323.269363 -299.356022) (xy 323.253295 -299.409429) (xy 323.229623 -299.459926) (xy 323.19885 -299.506439)
			(xy 323.161633 -299.547976) (xy 323.118765 -299.583651) (xy 323.071159 -299.612705) (xy 323.01983 -299.634517)
			(xy 322.965873 -299.648623) (xy 322.910436 -299.654723) (xy 322.854702 -299.652686) (xy 322.799859 -299.642556)
			(xy 322.747075 -299.624549) (xy 322.697475 -299.599048) (xy 322.652117 -299.566597) (xy 322.611968 -299.527888)
			(xy 322.577882 -299.483745) (xy 322.550586 -299.43511) (xy 322.530663 -299.383019) (xy 322.518537 -299.328582)
			(xy 322.514466 -299.27296) (xy 315.425856 -299.27296) (xy 315.421764 -299.298138) (xy 315.40618 -299.344819)
			(xy 315.383309 -299.388396) (xy 315.353744 -299.42774) (xy 315.318251 -299.461832) (xy 315.277748 -299.489788)
			(xy 315.233286 -299.510886) (xy 315.186015 -299.524578) (xy 315.13716 -299.53051) (xy 315.087985 -299.528529)
			(xy 315.039766 -299.518685) (xy 314.99375 -299.501233) (xy 314.951129 -299.476626) (xy 314.913008 -299.445501)
			(xy 314.880373 -299.408664) (xy 314.85407 -299.367068) (xy 314.834779 -299.321792) (xy 314.823002 -299.274008)
			(xy 314.819042 -299.224954) (xy 314.480194 -299.224954) (xy 314.479699 -299.249561) (xy 314.471804 -299.298138)
			(xy 314.45622 -299.344819) (xy 314.433349 -299.388396) (xy 314.403784 -299.42774) (xy 314.368291 -299.461832)
			(xy 314.327788 -299.489788) (xy 314.283326 -299.510886) (xy 314.236055 -299.524578) (xy 314.1872 -299.53051)
			(xy 314.138025 -299.528529) (xy 314.089806 -299.518685) (xy 314.04379 -299.501233) (xy 314.001169 -299.476626)
			(xy 313.963048 -299.445501) (xy 313.930413 -299.408664) (xy 313.90411 -299.367068) (xy 313.884819 -299.321792)
			(xy 313.873042 -299.274008) (xy 313.869082 -299.224954) (xy 313.530234 -299.224954) (xy 313.529739 -299.249561)
			(xy 313.521844 -299.298138) (xy 313.50626 -299.344819) (xy 313.483389 -299.388396) (xy 313.453824 -299.42774)
			(xy 313.418331 -299.461832) (xy 313.377828 -299.489788) (xy 313.333366 -299.510886) (xy 313.286095 -299.524578)
			(xy 313.23724 -299.53051) (xy 313.188065 -299.528529) (xy 313.139846 -299.518685) (xy 313.09383 -299.501233)
			(xy 313.051209 -299.476626) (xy 313.013088 -299.445501) (xy 312.980453 -299.408664) (xy 312.95415 -299.367068)
			(xy 312.934859 -299.321792) (xy 312.923082 -299.274008) (xy 312.919122 -299.224954) (xy 312.58002 -299.224954)
			(xy 312.579525 -299.249561) (xy 312.57163 -299.298138) (xy 312.556046 -299.344819) (xy 312.533175 -299.388396)
			(xy 312.50361 -299.42774) (xy 312.468117 -299.461832) (xy 312.427614 -299.489788) (xy 312.383152 -299.510886)
			(xy 312.335881 -299.524578) (xy 312.287026 -299.53051) (xy 312.237851 -299.528529) (xy 312.189632 -299.518685)
			(xy 312.143616 -299.501233) (xy 312.100995 -299.476626) (xy 312.062874 -299.445501) (xy 312.030239 -299.408664)
			(xy 312.003936 -299.367068) (xy 311.984645 -299.321792) (xy 311.972868 -299.274008) (xy 311.968908 -299.224954)
			(xy 311.63006 -299.224954) (xy 311.629565 -299.249561) (xy 311.62167 -299.298138) (xy 311.606086 -299.344819)
			(xy 311.583215 -299.388396) (xy 311.55365 -299.42774) (xy 311.518157 -299.461832) (xy 311.477654 -299.489788)
			(xy 311.433192 -299.510886) (xy 311.385921 -299.524578) (xy 311.337066 -299.53051) (xy 311.287891 -299.528529)
			(xy 311.239672 -299.518685) (xy 311.193656 -299.501233) (xy 311.151035 -299.476626) (xy 311.112914 -299.445501)
			(xy 311.080279 -299.408664) (xy 311.053976 -299.367068) (xy 311.034685 -299.321792) (xy 311.022908 -299.274008)
			(xy 311.018948 -299.224954) (xy 310.6801 -299.224954) (xy 310.679605 -299.249561) (xy 310.67171 -299.298138)
			(xy 310.656126 -299.344819) (xy 310.633255 -299.388396) (xy 310.60369 -299.42774) (xy 310.568197 -299.461832)
			(xy 310.527694 -299.489788) (xy 310.483232 -299.510886) (xy 310.435961 -299.524578) (xy 310.387106 -299.53051)
			(xy 310.337931 -299.528529) (xy 310.289712 -299.518685) (xy 310.243696 -299.501233) (xy 310.201075 -299.476626)
			(xy 310.162954 -299.445501) (xy 310.130319 -299.408664) (xy 310.104016 -299.367068) (xy 310.084725 -299.321792)
			(xy 310.072948 -299.274008) (xy 310.068988 -299.224954) (xy 309.73014 -299.224954) (xy 309.729645 -299.249561)
			(xy 309.72175 -299.298138) (xy 309.706166 -299.344819) (xy 309.683295 -299.388396) (xy 309.65373 -299.42774)
			(xy 309.618237 -299.461832) (xy 309.577734 -299.489788) (xy 309.533272 -299.510886) (xy 309.486001 -299.524578)
			(xy 309.437146 -299.53051) (xy 309.387971 -299.528529) (xy 309.339752 -299.518685) (xy 309.293736 -299.501233)
			(xy 309.251115 -299.476626) (xy 309.212994 -299.445501) (xy 309.180359 -299.408664) (xy 309.154056 -299.367068)
			(xy 309.134765 -299.321792) (xy 309.122988 -299.274008) (xy 309.119028 -299.224954) (xy 308.78018 -299.224954)
			(xy 308.779685 -299.249561) (xy 308.77179 -299.298138) (xy 308.756206 -299.344819) (xy 308.733335 -299.388396)
			(xy 308.70377 -299.42774) (xy 308.668277 -299.461832) (xy 308.627774 -299.489788) (xy 308.583312 -299.510886)
			(xy 308.536041 -299.524578) (xy 308.487186 -299.53051) (xy 308.438011 -299.528529) (xy 308.389792 -299.518685)
			(xy 308.343776 -299.501233) (xy 308.301155 -299.476626) (xy 308.263034 -299.445501) (xy 308.230399 -299.408664)
			(xy 308.204096 -299.367068) (xy 308.184805 -299.321792) (xy 308.173028 -299.274008) (xy 308.169068 -299.224954)
			(xy 305.930046 -299.224954) (xy 305.929551 -299.249561) (xy 305.921656 -299.298138) (xy 305.906072 -299.344819)
			(xy 305.883201 -299.388396) (xy 305.853636 -299.42774) (xy 305.818143 -299.461832) (xy 305.77764 -299.489788)
			(xy 305.733178 -299.510886) (xy 305.685907 -299.524578) (xy 305.637052 -299.53051) (xy 305.587877 -299.528529)
			(xy 305.539658 -299.518685) (xy 305.493642 -299.501233) (xy 305.451021 -299.476626) (xy 305.4129 -299.445501)
			(xy 305.380265 -299.408664) (xy 305.353962 -299.367068) (xy 305.334671 -299.321792) (xy 305.322894 -299.274008)
			(xy 305.318934 -299.224954) (xy 304.980086 -299.224954) (xy 304.979591 -299.249561) (xy 304.971696 -299.298138)
			(xy 304.956112 -299.344819) (xy 304.933241 -299.388396) (xy 304.903676 -299.42774) (xy 304.868183 -299.461832)
			(xy 304.82768 -299.489788) (xy 304.783218 -299.510886) (xy 304.735947 -299.524578) (xy 304.687092 -299.53051)
			(xy 304.637917 -299.528529) (xy 304.589698 -299.518685) (xy 304.543682 -299.501233) (xy 304.501061 -299.476626)
			(xy 304.46294 -299.445501) (xy 304.430305 -299.408664) (xy 304.404002 -299.367068) (xy 304.384711 -299.321792)
			(xy 304.372934 -299.274008) (xy 304.368974 -299.224954) (xy 304.030126 -299.224954) (xy 304.029631 -299.249561)
			(xy 304.021736 -299.298138) (xy 304.006152 -299.344819) (xy 303.983281 -299.388396) (xy 303.953716 -299.42774)
			(xy 303.918223 -299.461832) (xy 303.87772 -299.489788) (xy 303.833258 -299.510886) (xy 303.785987 -299.524578)
			(xy 303.737132 -299.53051) (xy 303.687957 -299.528529) (xy 303.639738 -299.518685) (xy 303.593722 -299.501233)
			(xy 303.551101 -299.476626) (xy 303.51298 -299.445501) (xy 303.480345 -299.408664) (xy 303.454042 -299.367068)
			(xy 303.434751 -299.321792) (xy 303.422974 -299.274008) (xy 303.419014 -299.224954) (xy 303.080166 -299.224954)
			(xy 303.079671 -299.249561) (xy 303.071776 -299.298138) (xy 303.056192 -299.344819) (xy 303.033321 -299.388396)
			(xy 303.003756 -299.42774) (xy 302.968263 -299.461832) (xy 302.92776 -299.489788) (xy 302.883298 -299.510886)
			(xy 302.836027 -299.524578) (xy 302.787172 -299.53051) (xy 302.737997 -299.528529) (xy 302.689778 -299.518685)
			(xy 302.643762 -299.501233) (xy 302.601141 -299.476626) (xy 302.56302 -299.445501) (xy 302.530385 -299.408664)
			(xy 302.504082 -299.367068) (xy 302.484791 -299.321792) (xy 302.473014 -299.274008) (xy 302.469054 -299.224954)
			(xy 302.130206 -299.224954) (xy 302.129711 -299.249561) (xy 302.121816 -299.298138) (xy 302.106232 -299.344819)
			(xy 302.083361 -299.388396) (xy 302.053796 -299.42774) (xy 302.018303 -299.461832) (xy 301.9778 -299.489788)
			(xy 301.933338 -299.510886) (xy 301.886067 -299.524578) (xy 301.837212 -299.53051) (xy 301.788037 -299.528529)
			(xy 301.739818 -299.518685) (xy 301.693802 -299.501233) (xy 301.651181 -299.476626) (xy 301.61306 -299.445501)
			(xy 301.580425 -299.408664) (xy 301.554122 -299.367068) (xy 301.534831 -299.321792) (xy 301.523054 -299.274008)
			(xy 301.519094 -299.224954) (xy 301.179992 -299.224954) (xy 301.179497 -299.249561) (xy 301.171602 -299.298138)
			(xy 301.156018 -299.344819) (xy 301.133147 -299.388396) (xy 301.103582 -299.42774) (xy 301.068089 -299.461832)
			(xy 301.027586 -299.489788) (xy 300.983124 -299.510886) (xy 300.935853 -299.524578) (xy 300.886998 -299.53051)
			(xy 300.837823 -299.528529) (xy 300.789604 -299.518685) (xy 300.743588 -299.501233) (xy 300.700967 -299.476626)
			(xy 300.662846 -299.445501) (xy 300.630211 -299.408664) (xy 300.603908 -299.367068) (xy 300.584617 -299.321792)
			(xy 300.57284 -299.274008) (xy 300.56888 -299.224954) (xy 300.230032 -299.224954) (xy 300.229537 -299.249561)
			(xy 300.221642 -299.298138) (xy 300.206058 -299.344819) (xy 300.183187 -299.388396) (xy 300.153622 -299.42774)
			(xy 300.118129 -299.461832) (xy 300.077626 -299.489788) (xy 300.033164 -299.510886) (xy 299.985893 -299.524578)
			(xy 299.937038 -299.53051) (xy 299.887863 -299.528529) (xy 299.839644 -299.518685) (xy 299.793628 -299.501233)
			(xy 299.751007 -299.476626) (xy 299.712886 -299.445501) (xy 299.680251 -299.408664) (xy 299.653948 -299.367068)
			(xy 299.634657 -299.321792) (xy 299.62288 -299.274008) (xy 299.61892 -299.224954) (xy 299.280072 -299.224954)
			(xy 299.279577 -299.249561) (xy 299.271682 -299.298138) (xy 299.256098 -299.344819) (xy 299.233227 -299.388396)
			(xy 299.203662 -299.42774) (xy 299.168169 -299.461832) (xy 299.127666 -299.489788) (xy 299.083204 -299.510886)
			(xy 299.035933 -299.524578) (xy 298.987078 -299.53051) (xy 298.937903 -299.528529) (xy 298.889684 -299.518685)
			(xy 298.843668 -299.501233) (xy 298.801047 -299.476626) (xy 298.762926 -299.445501) (xy 298.730291 -299.408664)
			(xy 298.703988 -299.367068) (xy 298.684697 -299.321792) (xy 298.67292 -299.274008) (xy 298.66896 -299.224954)
			(xy 298.330112 -299.224954) (xy 298.329617 -299.249561) (xy 298.321722 -299.298138) (xy 298.306138 -299.344819)
			(xy 298.283267 -299.388396) (xy 298.253702 -299.42774) (xy 298.218209 -299.461832) (xy 298.177706 -299.489788)
			(xy 298.133244 -299.510886) (xy 298.085973 -299.524578) (xy 298.037118 -299.53051) (xy 297.987943 -299.528529)
			(xy 297.939724 -299.518685) (xy 297.893708 -299.501233) (xy 297.851087 -299.476626) (xy 297.812966 -299.445501)
			(xy 297.780331 -299.408664) (xy 297.754028 -299.367068) (xy 297.734737 -299.321792) (xy 297.72296 -299.274008)
			(xy 297.719 -299.224954) (xy 297.380152 -299.224954) (xy 297.379657 -299.249561) (xy 297.371762 -299.298138)
			(xy 297.356178 -299.344819) (xy 297.333307 -299.388396) (xy 297.303742 -299.42774) (xy 297.268249 -299.461832)
			(xy 297.227746 -299.489788) (xy 297.183284 -299.510886) (xy 297.136013 -299.524578) (xy 297.087158 -299.53051)
			(xy 297.037983 -299.528529) (xy 296.989764 -299.518685) (xy 296.943748 -299.501233) (xy 296.901127 -299.476626)
			(xy 296.863006 -299.445501) (xy 296.830371 -299.408664) (xy 296.804068 -299.367068) (xy 296.784777 -299.321792)
			(xy 296.773 -299.274008) (xy 296.76904 -299.224954) (xy 296.430192 -299.224954) (xy 296.429697 -299.249561)
			(xy 296.421802 -299.298138) (xy 296.406218 -299.344819) (xy 296.383347 -299.388396) (xy 296.353782 -299.42774)
			(xy 296.318289 -299.461832) (xy 296.277786 -299.489788) (xy 296.233324 -299.510886) (xy 296.186053 -299.524578)
			(xy 296.137198 -299.53051) (xy 296.088023 -299.528529) (xy 296.039804 -299.518685) (xy 295.993788 -299.501233)
			(xy 295.951167 -299.476626) (xy 295.913046 -299.445501) (xy 295.880411 -299.408664) (xy 295.854108 -299.367068)
			(xy 295.834817 -299.321792) (xy 295.82304 -299.274008) (xy 295.81908 -299.224954) (xy 295.480232 -299.224954)
			(xy 295.479737 -299.249561) (xy 295.471842 -299.298138) (xy 295.456258 -299.344819) (xy 295.433387 -299.388396)
			(xy 295.403822 -299.42774) (xy 295.368329 -299.461832) (xy 295.327826 -299.489788) (xy 295.283364 -299.510886)
			(xy 295.236093 -299.524578) (xy 295.187238 -299.53051) (xy 295.138063 -299.528529) (xy 295.089844 -299.518685)
			(xy 295.043828 -299.501233) (xy 295.001207 -299.476626) (xy 294.963086 -299.445501) (xy 294.930451 -299.408664)
			(xy 294.904148 -299.367068) (xy 294.884857 -299.321792) (xy 294.87308 -299.274008) (xy 294.86912 -299.224954)
			(xy 294.530018 -299.224954) (xy 294.529523 -299.249561) (xy 294.521628 -299.298138) (xy 294.506044 -299.344819)
			(xy 294.483173 -299.388396) (xy 294.453608 -299.42774) (xy 294.418115 -299.461832) (xy 294.377612 -299.489788)
			(xy 294.33315 -299.510886) (xy 294.285879 -299.524578) (xy 294.237024 -299.53051) (xy 294.187849 -299.528529)
			(xy 294.13963 -299.518685) (xy 294.093614 -299.501233) (xy 294.050993 -299.476626) (xy 294.012872 -299.445501)
			(xy 293.980237 -299.408664) (xy 293.953934 -299.367068) (xy 293.934643 -299.321792) (xy 293.922866 -299.274008)
			(xy 293.918906 -299.224954) (xy 293.580058 -299.224954) (xy 293.579563 -299.249561) (xy 293.571668 -299.298138)
			(xy 293.556084 -299.344819) (xy 293.533213 -299.388396) (xy 293.503648 -299.42774) (xy 293.468155 -299.461832)
			(xy 293.427652 -299.489788) (xy 293.38319 -299.510886) (xy 293.335919 -299.524578) (xy 293.287064 -299.53051)
			(xy 293.237889 -299.528529) (xy 293.18967 -299.518685) (xy 293.143654 -299.501233) (xy 293.101033 -299.476626)
			(xy 293.062912 -299.445501) (xy 293.030277 -299.408664) (xy 293.003974 -299.367068) (xy 292.984683 -299.321792)
			(xy 292.972906 -299.274008) (xy 292.968946 -299.224954) (xy 292.630098 -299.224954) (xy 292.629603 -299.249561)
			(xy 292.621708 -299.298138) (xy 292.606124 -299.344819) (xy 292.583253 -299.388396) (xy 292.553688 -299.42774)
			(xy 292.518195 -299.461832) (xy 292.477692 -299.489788) (xy 292.43323 -299.510886) (xy 292.385959 -299.524578)
			(xy 292.337104 -299.53051) (xy 292.287929 -299.528529) (xy 292.23971 -299.518685) (xy 292.193694 -299.501233)
			(xy 292.151073 -299.476626) (xy 292.112952 -299.445501) (xy 292.080317 -299.408664) (xy 292.054014 -299.367068)
			(xy 292.034723 -299.321792) (xy 292.022946 -299.274008) (xy 292.018986 -299.224954) (xy 290.730178 -299.224954)
			(xy 290.729683 -299.249561) (xy 290.721788 -299.298138) (xy 290.706204 -299.344819) (xy 290.683333 -299.388396)
			(xy 290.653768 -299.42774) (xy 290.618275 -299.461832) (xy 290.577772 -299.489788) (xy 290.53331 -299.510886)
			(xy 290.486039 -299.524578) (xy 290.437184 -299.53051) (xy 290.388009 -299.528529) (xy 290.33979 -299.518685)
			(xy 290.293774 -299.501233) (xy 290.251153 -299.476626) (xy 290.213032 -299.445501) (xy 290.180397 -299.408664)
			(xy 290.154094 -299.367068) (xy 290.134803 -299.321792) (xy 290.123026 -299.274008) (xy 290.119066 -299.224954)
			(xy 289.780218 -299.224954) (xy 289.779723 -299.249561) (xy 289.771828 -299.298138) (xy 289.756244 -299.344819)
			(xy 289.733373 -299.388396) (xy 289.703808 -299.42774) (xy 289.668315 -299.461832) (xy 289.627812 -299.489788)
			(xy 289.58335 -299.510886) (xy 289.536079 -299.524578) (xy 289.487224 -299.53051) (xy 289.438049 -299.528529)
			(xy 289.38983 -299.518685) (xy 289.343814 -299.501233) (xy 289.301193 -299.476626) (xy 289.263072 -299.445501)
			(xy 289.230437 -299.408664) (xy 289.204134 -299.367068) (xy 289.184843 -299.321792) (xy 289.173066 -299.274008)
			(xy 289.169106 -299.224954) (xy 288.830004 -299.224954) (xy 288.829509 -299.249561) (xy 288.821614 -299.298138)
			(xy 288.80603 -299.344819) (xy 288.783159 -299.388396) (xy 288.753594 -299.42774) (xy 288.718101 -299.461832)
			(xy 288.677598 -299.489788) (xy 288.633136 -299.510886) (xy 288.585865 -299.524578) (xy 288.53701 -299.53051)
			(xy 288.487835 -299.528529) (xy 288.439616 -299.518685) (xy 288.3936 -299.501233) (xy 288.350979 -299.476626)
			(xy 288.312858 -299.445501) (xy 288.280223 -299.408664) (xy 288.25392 -299.367068) (xy 288.234629 -299.321792)
			(xy 288.222852 -299.274008) (xy 288.218892 -299.224954) (xy 287.880044 -299.224954) (xy 287.879549 -299.249561)
			(xy 287.871654 -299.298138) (xy 287.85607 -299.344819) (xy 287.833199 -299.388396) (xy 287.803634 -299.42774)
			(xy 287.768141 -299.461832) (xy 287.727638 -299.489788) (xy 287.683176 -299.510886) (xy 287.635905 -299.524578)
			(xy 287.58705 -299.53051) (xy 287.537875 -299.528529) (xy 287.489656 -299.518685) (xy 287.44364 -299.501233)
			(xy 287.401019 -299.476626) (xy 287.362898 -299.445501) (xy 287.330263 -299.408664) (xy 287.30396 -299.367068)
			(xy 287.284669 -299.321792) (xy 287.272892 -299.274008) (xy 287.268932 -299.224954) (xy 286.930084 -299.224954)
			(xy 286.929589 -299.249561) (xy 286.921694 -299.298138) (xy 286.90611 -299.344819) (xy 286.883239 -299.388396)
			(xy 286.853674 -299.42774) (xy 286.818181 -299.461832) (xy 286.777678 -299.489788) (xy 286.733216 -299.510886)
			(xy 286.685945 -299.524578) (xy 286.63709 -299.53051) (xy 286.587915 -299.528529) (xy 286.539696 -299.518685)
			(xy 286.49368 -299.501233) (xy 286.451059 -299.476626) (xy 286.412938 -299.445501) (xy 286.380303 -299.408664)
			(xy 286.354 -299.367068) (xy 286.334709 -299.321792) (xy 286.322932 -299.274008) (xy 286.318972 -299.224954)
			(xy 285.980124 -299.224954) (xy 285.979629 -299.249561) (xy 285.971734 -299.298138) (xy 285.95615 -299.344819)
			(xy 285.933279 -299.388396) (xy 285.903714 -299.42774) (xy 285.868221 -299.461832) (xy 285.827718 -299.489788)
			(xy 285.783256 -299.510886) (xy 285.735985 -299.524578) (xy 285.68713 -299.53051) (xy 285.637955 -299.528529)
			(xy 285.589736 -299.518685) (xy 285.54372 -299.501233) (xy 285.501099 -299.476626) (xy 285.462978 -299.445501)
			(xy 285.430343 -299.408664) (xy 285.40404 -299.367068) (xy 285.384749 -299.321792) (xy 285.372972 -299.274008)
			(xy 285.369012 -299.224954) (xy 285.030164 -299.224954) (xy 285.029669 -299.249561) (xy 285.021774 -299.298138)
			(xy 285.00619 -299.344819) (xy 284.983319 -299.388396) (xy 284.953754 -299.42774) (xy 284.918261 -299.461832)
			(xy 284.877758 -299.489788) (xy 284.833296 -299.510886) (xy 284.786025 -299.524578) (xy 284.73717 -299.53051)
			(xy 284.687995 -299.528529) (xy 284.639776 -299.518685) (xy 284.59376 -299.501233) (xy 284.551139 -299.476626)
			(xy 284.513018 -299.445501) (xy 284.480383 -299.408664) (xy 284.45408 -299.367068) (xy 284.434789 -299.321792)
			(xy 284.423012 -299.274008) (xy 284.419052 -299.224954) (xy 284.080204 -299.224954) (xy 284.079709 -299.249561)
			(xy 284.071814 -299.298138) (xy 284.05623 -299.344819) (xy 284.033359 -299.388396) (xy 284.003794 -299.42774)
			(xy 283.968301 -299.461832) (xy 283.927798 -299.489788) (xy 283.883336 -299.510886) (xy 283.836065 -299.524578)
			(xy 283.78721 -299.53051) (xy 283.738035 -299.528529) (xy 283.689816 -299.518685) (xy 283.6438 -299.501233)
			(xy 283.601179 -299.476626) (xy 283.563058 -299.445501) (xy 283.530423 -299.408664) (xy 283.50412 -299.367068)
			(xy 283.484829 -299.321792) (xy 283.473052 -299.274008) (xy 283.469092 -299.224954) (xy 283.130244 -299.224954)
			(xy 283.129749 -299.249561) (xy 283.121854 -299.298138) (xy 283.10627 -299.344819) (xy 283.083399 -299.388396)
			(xy 283.053834 -299.42774) (xy 283.018341 -299.461832) (xy 282.977838 -299.489788) (xy 282.933376 -299.510886)
			(xy 282.886105 -299.524578) (xy 282.83725 -299.53051) (xy 282.788075 -299.528529) (xy 282.739856 -299.518685)
			(xy 282.69384 -299.501233) (xy 282.651219 -299.476626) (xy 282.613098 -299.445501) (xy 282.580463 -299.408664)
			(xy 282.55416 -299.367068) (xy 282.534869 -299.321792) (xy 282.523092 -299.274008) (xy 282.519132 -299.224954)
			(xy 282.18003 -299.224954) (xy 282.179535 -299.249561) (xy 282.17164 -299.298138) (xy 282.156056 -299.344819)
			(xy 282.133185 -299.388396) (xy 282.10362 -299.42774) (xy 282.068127 -299.461832) (xy 282.027624 -299.489788)
			(xy 281.983162 -299.510886) (xy 281.935891 -299.524578) (xy 281.887036 -299.53051) (xy 281.837861 -299.528529)
			(xy 281.789642 -299.518685) (xy 281.743626 -299.501233) (xy 281.701005 -299.476626) (xy 281.662884 -299.445501)
			(xy 281.630249 -299.408664) (xy 281.603946 -299.367068) (xy 281.584655 -299.321792) (xy 281.572878 -299.274008)
			(xy 281.568918 -299.224954) (xy 280.28011 -299.224954) (xy 280.28011 -299.241464) (xy 280.279602 -299.247306)
			(xy 280.279602 -299.247814) (xy 280.278332 -299.258736) (xy 280.278332 -299.25899) (xy 280.277824 -299.263054)
			(xy 280.275284 -299.28185) (xy 280.274268 -299.287438) (xy 280.270204 -299.303186) (xy 280.268426 -299.315886)
			(xy 280.268426 -299.76445) (xy 320.241674 -299.76445) (xy 320.245745 -299.708828) (xy 320.257871 -299.654391)
			(xy 320.277794 -299.6023) (xy 320.30509 -299.553665) (xy 320.339176 -299.509522) (xy 320.379325 -299.470813)
			(xy 320.424683 -299.438362) (xy 320.474283 -299.412861) (xy 320.527067 -299.394854) (xy 320.58191 -299.384724)
			(xy 320.637644 -299.382687) (xy 320.693081 -299.388787) (xy 320.747038 -299.402893) (xy 320.798367 -299.424705)
			(xy 320.845973 -299.453759) (xy 320.888841 -299.489434) (xy 320.926058 -299.530971) (xy 320.956831 -299.577484)
			(xy 320.980503 -299.627981) (xy 320.996571 -299.681388) (xy 321.004691 -299.736564) (xy 321.0052 -299.76445)
			(xy 321.004922 -299.77969) (xy 324.838312 -299.77969) (xy 324.842383 -299.724068) (xy 324.854509 -299.669631)
			(xy 324.874432 -299.61754) (xy 324.901728 -299.568905) (xy 324.935814 -299.524762) (xy 324.975963 -299.486053)
			(xy 325.021321 -299.453602) (xy 325.070921 -299.428101) (xy 325.123705 -299.410094) (xy 325.178548 -299.399964)
			(xy 325.234282 -299.397927) (xy 325.289719 -299.404027) (xy 325.343676 -299.418133) (xy 325.395005 -299.439945)
			(xy 325.442611 -299.468999) (xy 325.485479 -299.504674) (xy 325.522696 -299.546211) (xy 325.553469 -299.592724)
			(xy 325.577141 -299.643221) (xy 325.593209 -299.696628) (xy 325.601329 -299.751804) (xy 325.601838 -299.77969)
			(xy 325.601329 -299.807576) (xy 325.593209 -299.862752) (xy 325.577141 -299.916159) (xy 325.553469 -299.966656)
			(xy 325.522696 -300.013169) (xy 325.485479 -300.054706) (xy 325.442611 -300.090381) (xy 325.395005 -300.119435)
			(xy 325.343676 -300.141247) (xy 325.289719 -300.155353) (xy 325.234282 -300.161453) (xy 325.178548 -300.159416)
			(xy 325.123705 -300.149286) (xy 325.070921 -300.131279) (xy 325.021321 -300.105778) (xy 324.975963 -300.073327)
			(xy 324.935814 -300.034618) (xy 324.901728 -299.990475) (xy 324.874432 -299.94184) (xy 324.854509 -299.889749)
			(xy 324.842383 -299.835312) (xy 324.838312 -299.77969) (xy 321.004922 -299.77969) (xy 321.004691 -299.792336)
			(xy 320.996571 -299.847512) (xy 320.980503 -299.900919) (xy 320.956831 -299.951416) (xy 320.926058 -299.997929)
			(xy 320.888841 -300.039466) (xy 320.845973 -300.075141) (xy 320.798367 -300.104195) (xy 320.747038 -300.126007)
			(xy 320.693081 -300.140113) (xy 320.637644 -300.146213) (xy 320.58191 -300.144176) (xy 320.527067 -300.134046)
			(xy 320.474283 -300.116039) (xy 320.424683 -300.090538) (xy 320.379325 -300.058087) (xy 320.339176 -300.019378)
			(xy 320.30509 -299.975235) (xy 320.277794 -299.9266) (xy 320.257871 -299.874509) (xy 320.245745 -299.820072)
			(xy 320.241674 -299.76445) (xy 280.268426 -299.76445) (xy 280.268426 -300.080172) (xy 280.268934 -300.086268)
			(xy 280.270204 -300.097444) (xy 280.270966 -300.100746) (xy 280.270966 -300.101254) (xy 280.275216 -300.119373)
			(xy 280.279799 -300.156306) (xy 280.28011 -300.174914) (xy 280.618958 -300.174914) (xy 280.622918 -300.12586)
			(xy 280.634695 -300.078076) (xy 280.653986 -300.0328) (xy 280.680289 -299.991204) (xy 280.712924 -299.954367)
			(xy 280.751045 -299.923242) (xy 280.793666 -299.898635) (xy 280.839682 -299.881183) (xy 280.887901 -299.871339)
			(xy 280.937076 -299.869358) (xy 280.985931 -299.87529) (xy 281.033202 -299.888982) (xy 281.077664 -299.91008)
			(xy 281.118167 -299.938036) (xy 281.15366 -299.972128) (xy 281.183225 -300.011472) (xy 281.206096 -300.055049)
			(xy 281.22168 -300.10173) (xy 281.229575 -300.150307) (xy 281.23007 -300.174914) (xy 282.519132 -300.174914)
			(xy 282.523092 -300.12586) (xy 282.534869 -300.078076) (xy 282.55416 -300.0328) (xy 282.580463 -299.991204)
			(xy 282.613098 -299.954367) (xy 282.651219 -299.923242) (xy 282.69384 -299.898635) (xy 282.739856 -299.881183)
			(xy 282.788075 -299.871339) (xy 282.83725 -299.869358) (xy 282.886105 -299.87529) (xy 282.933376 -299.888982)
			(xy 282.977838 -299.91008) (xy 283.018341 -299.938036) (xy 283.053834 -299.972128) (xy 283.083399 -300.011472)
			(xy 283.10627 -300.055049) (xy 283.121854 -300.10173) (xy 283.129749 -300.150307) (xy 283.130244 -300.174914)
			(xy 283.469092 -300.174914) (xy 283.473052 -300.12586) (xy 283.484829 -300.078076) (xy 283.50412 -300.0328)
			(xy 283.530423 -299.991204) (xy 283.563058 -299.954367) (xy 283.601179 -299.923242) (xy 283.6438 -299.898635)
			(xy 283.689816 -299.881183) (xy 283.738035 -299.871339) (xy 283.78721 -299.869358) (xy 283.836065 -299.87529)
			(xy 283.883336 -299.888982) (xy 283.927798 -299.91008) (xy 283.968301 -299.938036) (xy 284.003794 -299.972128)
			(xy 284.033359 -300.011472) (xy 284.05623 -300.055049) (xy 284.071814 -300.10173) (xy 284.079709 -300.150307)
			(xy 284.080204 -300.174914) (xy 284.419052 -300.174914) (xy 284.423012 -300.12586) (xy 284.434789 -300.078076)
			(xy 284.45408 -300.0328) (xy 284.480383 -299.991204) (xy 284.513018 -299.954367) (xy 284.551139 -299.923242)
			(xy 284.59376 -299.898635) (xy 284.639776 -299.881183) (xy 284.687995 -299.871339) (xy 284.73717 -299.869358)
			(xy 284.786025 -299.87529) (xy 284.833296 -299.888982) (xy 284.877758 -299.91008) (xy 284.918261 -299.938036)
			(xy 284.953754 -299.972128) (xy 284.983319 -300.011472) (xy 285.00619 -300.055049) (xy 285.021774 -300.10173)
			(xy 285.029669 -300.150307) (xy 285.030164 -300.174914) (xy 285.369012 -300.174914) (xy 285.372972 -300.12586)
			(xy 285.384749 -300.078076) (xy 285.40404 -300.0328) (xy 285.430343 -299.991204) (xy 285.462978 -299.954367)
			(xy 285.501099 -299.923242) (xy 285.54372 -299.898635) (xy 285.589736 -299.881183) (xy 285.637955 -299.871339)
			(xy 285.68713 -299.869358) (xy 285.735985 -299.87529) (xy 285.783256 -299.888982) (xy 285.827718 -299.91008)
			(xy 285.868221 -299.938036) (xy 285.903714 -299.972128) (xy 285.933279 -300.011472) (xy 285.95615 -300.055049)
			(xy 285.971734 -300.10173) (xy 285.979629 -300.150307) (xy 285.980124 -300.174914) (xy 286.318972 -300.174914)
			(xy 286.322932 -300.12586) (xy 286.334709 -300.078076) (xy 286.354 -300.0328) (xy 286.380303 -299.991204)
			(xy 286.412938 -299.954367) (xy 286.451059 -299.923242) (xy 286.49368 -299.898635) (xy 286.539696 -299.881183)
			(xy 286.587915 -299.871339) (xy 286.63709 -299.869358) (xy 286.685945 -299.87529) (xy 286.733216 -299.888982)
			(xy 286.777678 -299.91008) (xy 286.818181 -299.938036) (xy 286.853674 -299.972128) (xy 286.883239 -300.011472)
			(xy 286.90611 -300.055049) (xy 286.921694 -300.10173) (xy 286.929589 -300.150307) (xy 286.930084 -300.174914)
			(xy 287.268932 -300.174914) (xy 287.272892 -300.12586) (xy 287.284669 -300.078076) (xy 287.30396 -300.0328)
			(xy 287.330263 -299.991204) (xy 287.362898 -299.954367) (xy 287.401019 -299.923242) (xy 287.44364 -299.898635)
			(xy 287.489656 -299.881183) (xy 287.537875 -299.871339) (xy 287.58705 -299.869358) (xy 287.635905 -299.87529)
			(xy 287.683176 -299.888982) (xy 287.727638 -299.91008) (xy 287.768141 -299.938036) (xy 287.803634 -299.972128)
			(xy 287.833199 -300.011472) (xy 287.85607 -300.055049) (xy 287.871654 -300.10173) (xy 287.879549 -300.150307)
			(xy 287.880044 -300.174914) (xy 288.218892 -300.174914) (xy 288.222852 -300.12586) (xy 288.234629 -300.078076)
			(xy 288.25392 -300.0328) (xy 288.280223 -299.991204) (xy 288.312858 -299.954367) (xy 288.350979 -299.923242)
			(xy 288.3936 -299.898635) (xy 288.439616 -299.881183) (xy 288.487835 -299.871339) (xy 288.53701 -299.869358)
			(xy 288.585865 -299.87529) (xy 288.633136 -299.888982) (xy 288.677598 -299.91008) (xy 288.718101 -299.938036)
			(xy 288.753594 -299.972128) (xy 288.783159 -300.011472) (xy 288.80603 -300.055049) (xy 288.821614 -300.10173)
			(xy 288.829509 -300.150307) (xy 288.830004 -300.174914) (xy 289.169106 -300.174914) (xy 289.173066 -300.12586)
			(xy 289.184843 -300.078076) (xy 289.204134 -300.0328) (xy 289.230437 -299.991204) (xy 289.263072 -299.954367)
			(xy 289.301193 -299.923242) (xy 289.343814 -299.898635) (xy 289.38983 -299.881183) (xy 289.438049 -299.871339)
			(xy 289.487224 -299.869358) (xy 289.536079 -299.87529) (xy 289.58335 -299.888982) (xy 289.627812 -299.91008)
			(xy 289.668315 -299.938036) (xy 289.703808 -299.972128) (xy 289.733373 -300.011472) (xy 289.756244 -300.055049)
			(xy 289.771828 -300.10173) (xy 289.779723 -300.150307) (xy 289.780218 -300.174914) (xy 290.119066 -300.174914)
			(xy 290.123026 -300.12586) (xy 290.134803 -300.078076) (xy 290.154094 -300.0328) (xy 290.180397 -299.991204)
			(xy 290.213032 -299.954367) (xy 290.251153 -299.923242) (xy 290.293774 -299.898635) (xy 290.33979 -299.881183)
			(xy 290.388009 -299.871339) (xy 290.437184 -299.869358) (xy 290.486039 -299.87529) (xy 290.53331 -299.888982)
			(xy 290.577772 -299.91008) (xy 290.618275 -299.938036) (xy 290.653768 -299.972128) (xy 290.683333 -300.011472)
			(xy 290.706204 -300.055049) (xy 290.721788 -300.10173) (xy 290.729683 -300.150307) (xy 290.730178 -300.174914)
			(xy 292.018986 -300.174914) (xy 292.022946 -300.12586) (xy 292.034723 -300.078076) (xy 292.054014 -300.0328)
			(xy 292.080317 -299.991204) (xy 292.112952 -299.954367) (xy 292.151073 -299.923242) (xy 292.193694 -299.898635)
			(xy 292.23971 -299.881183) (xy 292.287929 -299.871339) (xy 292.337104 -299.869358) (xy 292.385959 -299.87529)
			(xy 292.43323 -299.888982) (xy 292.477692 -299.91008) (xy 292.518195 -299.938036) (xy 292.553688 -299.972128)
			(xy 292.583253 -300.011472) (xy 292.606124 -300.055049) (xy 292.621708 -300.10173) (xy 292.629603 -300.150307)
			(xy 292.630098 -300.174914) (xy 292.968946 -300.174914) (xy 292.972906 -300.12586) (xy 292.984683 -300.078076)
			(xy 293.003974 -300.0328) (xy 293.030277 -299.991204) (xy 293.062912 -299.954367) (xy 293.101033 -299.923242)
			(xy 293.143654 -299.898635) (xy 293.18967 -299.881183) (xy 293.237889 -299.871339) (xy 293.287064 -299.869358)
			(xy 293.335919 -299.87529) (xy 293.38319 -299.888982) (xy 293.427652 -299.91008) (xy 293.468155 -299.938036)
			(xy 293.503648 -299.972128) (xy 293.533213 -300.011472) (xy 293.556084 -300.055049) (xy 293.571668 -300.10173)
			(xy 293.579563 -300.150307) (xy 293.580058 -300.174914) (xy 293.918906 -300.174914) (xy 293.922866 -300.12586)
			(xy 293.934643 -300.078076) (xy 293.953934 -300.0328) (xy 293.980237 -299.991204) (xy 294.012872 -299.954367)
			(xy 294.050993 -299.923242) (xy 294.093614 -299.898635) (xy 294.13963 -299.881183) (xy 294.187849 -299.871339)
			(xy 294.237024 -299.869358) (xy 294.285879 -299.87529) (xy 294.33315 -299.888982) (xy 294.377612 -299.91008)
			(xy 294.418115 -299.938036) (xy 294.453608 -299.972128) (xy 294.483173 -300.011472) (xy 294.506044 -300.055049)
			(xy 294.521628 -300.10173) (xy 294.529523 -300.150307) (xy 294.530018 -300.174914) (xy 294.86912 -300.174914)
			(xy 294.87308 -300.12586) (xy 294.884857 -300.078076) (xy 294.904148 -300.0328) (xy 294.930451 -299.991204)
			(xy 294.963086 -299.954367) (xy 295.001207 -299.923242) (xy 295.043828 -299.898635) (xy 295.089844 -299.881183)
			(xy 295.138063 -299.871339) (xy 295.187238 -299.869358) (xy 295.236093 -299.87529) (xy 295.283364 -299.888982)
			(xy 295.327826 -299.91008) (xy 295.368329 -299.938036) (xy 295.403822 -299.972128) (xy 295.433387 -300.011472)
			(xy 295.456258 -300.055049) (xy 295.471842 -300.10173) (xy 295.479737 -300.150307) (xy 295.480232 -300.174914)
			(xy 295.81908 -300.174914) (xy 295.82304 -300.12586) (xy 295.834817 -300.078076) (xy 295.854108 -300.0328)
			(xy 295.880411 -299.991204) (xy 295.913046 -299.954367) (xy 295.951167 -299.923242) (xy 295.993788 -299.898635)
			(xy 296.039804 -299.881183) (xy 296.088023 -299.871339) (xy 296.137198 -299.869358) (xy 296.186053 -299.87529)
			(xy 296.233324 -299.888982) (xy 296.277786 -299.91008) (xy 296.318289 -299.938036) (xy 296.353782 -299.972128)
			(xy 296.383347 -300.011472) (xy 296.406218 -300.055049) (xy 296.421802 -300.10173) (xy 296.429697 -300.150307)
			(xy 296.430192 -300.174914) (xy 296.76904 -300.174914) (xy 296.773 -300.12586) (xy 296.784777 -300.078076)
			(xy 296.804068 -300.0328) (xy 296.830371 -299.991204) (xy 296.863006 -299.954367) (xy 296.901127 -299.923242)
			(xy 296.943748 -299.898635) (xy 296.989764 -299.881183) (xy 297.037983 -299.871339) (xy 297.087158 -299.869358)
			(xy 297.136013 -299.87529) (xy 297.183284 -299.888982) (xy 297.227746 -299.91008) (xy 297.268249 -299.938036)
			(xy 297.303742 -299.972128) (xy 297.333307 -300.011472) (xy 297.356178 -300.055049) (xy 297.371762 -300.10173)
			(xy 297.379657 -300.150307) (xy 297.380152 -300.174914) (xy 297.719 -300.174914) (xy 297.72296 -300.12586)
			(xy 297.734737 -300.078076) (xy 297.754028 -300.0328) (xy 297.780331 -299.991204) (xy 297.812966 -299.954367)
			(xy 297.851087 -299.923242) (xy 297.893708 -299.898635) (xy 297.939724 -299.881183) (xy 297.987943 -299.871339)
			(xy 298.037118 -299.869358) (xy 298.085973 -299.87529) (xy 298.133244 -299.888982) (xy 298.177706 -299.91008)
			(xy 298.218209 -299.938036) (xy 298.253702 -299.972128) (xy 298.283267 -300.011472) (xy 298.306138 -300.055049)
			(xy 298.321722 -300.10173) (xy 298.329617 -300.150307) (xy 298.330112 -300.174914) (xy 298.66896 -300.174914)
			(xy 298.67292 -300.12586) (xy 298.684697 -300.078076) (xy 298.703988 -300.0328) (xy 298.730291 -299.991204)
			(xy 298.762926 -299.954367) (xy 298.801047 -299.923242) (xy 298.843668 -299.898635) (xy 298.889684 -299.881183)
			(xy 298.937903 -299.871339) (xy 298.987078 -299.869358) (xy 299.035933 -299.87529) (xy 299.083204 -299.888982)
			(xy 299.127666 -299.91008) (xy 299.168169 -299.938036) (xy 299.203662 -299.972128) (xy 299.233227 -300.011472)
			(xy 299.256098 -300.055049) (xy 299.271682 -300.10173) (xy 299.279577 -300.150307) (xy 299.280072 -300.174914)
			(xy 299.61892 -300.174914) (xy 299.62288 -300.12586) (xy 299.634657 -300.078076) (xy 299.653948 -300.0328)
			(xy 299.680251 -299.991204) (xy 299.712886 -299.954367) (xy 299.751007 -299.923242) (xy 299.793628 -299.898635)
			(xy 299.839644 -299.881183) (xy 299.887863 -299.871339) (xy 299.937038 -299.869358) (xy 299.985893 -299.87529)
			(xy 300.033164 -299.888982) (xy 300.077626 -299.91008) (xy 300.118129 -299.938036) (xy 300.153622 -299.972128)
			(xy 300.183187 -300.011472) (xy 300.206058 -300.055049) (xy 300.221642 -300.10173) (xy 300.229537 -300.150307)
			(xy 300.230032 -300.174914) (xy 300.56888 -300.174914) (xy 300.57284 -300.12586) (xy 300.584617 -300.078076)
			(xy 300.603908 -300.0328) (xy 300.630211 -299.991204) (xy 300.662846 -299.954367) (xy 300.700967 -299.923242)
			(xy 300.743588 -299.898635) (xy 300.789604 -299.881183) (xy 300.837823 -299.871339) (xy 300.886998 -299.869358)
			(xy 300.935853 -299.87529) (xy 300.983124 -299.888982) (xy 301.027586 -299.91008) (xy 301.068089 -299.938036)
			(xy 301.103582 -299.972128) (xy 301.133147 -300.011472) (xy 301.156018 -300.055049) (xy 301.171602 -300.10173)
			(xy 301.179497 -300.150307) (xy 301.179992 -300.174914) (xy 301.519094 -300.174914) (xy 301.523054 -300.12586)
			(xy 301.534831 -300.078076) (xy 301.554122 -300.0328) (xy 301.580425 -299.991204) (xy 301.61306 -299.954367)
			(xy 301.651181 -299.923242) (xy 301.693802 -299.898635) (xy 301.739818 -299.881183) (xy 301.788037 -299.871339)
			(xy 301.837212 -299.869358) (xy 301.886067 -299.87529) (xy 301.933338 -299.888982) (xy 301.9778 -299.91008)
			(xy 302.018303 -299.938036) (xy 302.053796 -299.972128) (xy 302.083361 -300.011472) (xy 302.106232 -300.055049)
			(xy 302.121816 -300.10173) (xy 302.129711 -300.150307) (xy 302.130206 -300.174914) (xy 302.469054 -300.174914)
			(xy 302.473014 -300.12586) (xy 302.484791 -300.078076) (xy 302.504082 -300.0328) (xy 302.530385 -299.991204)
			(xy 302.56302 -299.954367) (xy 302.601141 -299.923242) (xy 302.643762 -299.898635) (xy 302.689778 -299.881183)
			(xy 302.737997 -299.871339) (xy 302.787172 -299.869358) (xy 302.836027 -299.87529) (xy 302.883298 -299.888982)
			(xy 302.92776 -299.91008) (xy 302.968263 -299.938036) (xy 303.003756 -299.972128) (xy 303.033321 -300.011472)
			(xy 303.056192 -300.055049) (xy 303.071776 -300.10173) (xy 303.079671 -300.150307) (xy 303.080166 -300.174914)
			(xy 303.419014 -300.174914) (xy 303.422974 -300.12586) (xy 303.434751 -300.078076) (xy 303.454042 -300.0328)
			(xy 303.480345 -299.991204) (xy 303.51298 -299.954367) (xy 303.551101 -299.923242) (xy 303.593722 -299.898635)
			(xy 303.639738 -299.881183) (xy 303.687957 -299.871339) (xy 303.737132 -299.869358) (xy 303.785987 -299.87529)
			(xy 303.833258 -299.888982) (xy 303.87772 -299.91008) (xy 303.918223 -299.938036) (xy 303.953716 -299.972128)
			(xy 303.983281 -300.011472) (xy 304.006152 -300.055049) (xy 304.021736 -300.10173) (xy 304.029631 -300.150307)
			(xy 304.030126 -300.174914) (xy 304.368974 -300.174914) (xy 304.372934 -300.12586) (xy 304.384711 -300.078076)
			(xy 304.404002 -300.0328) (xy 304.430305 -299.991204) (xy 304.46294 -299.954367) (xy 304.501061 -299.923242)
			(xy 304.543682 -299.898635) (xy 304.589698 -299.881183) (xy 304.637917 -299.871339) (xy 304.687092 -299.869358)
			(xy 304.735947 -299.87529) (xy 304.783218 -299.888982) (xy 304.82768 -299.91008) (xy 304.868183 -299.938036)
			(xy 304.903676 -299.972128) (xy 304.933241 -300.011472) (xy 304.956112 -300.055049) (xy 304.971696 -300.10173)
			(xy 304.979591 -300.150307) (xy 304.980086 -300.174914) (xy 305.318934 -300.174914) (xy 305.322894 -300.12586)
			(xy 305.334671 -300.078076) (xy 305.353962 -300.0328) (xy 305.380265 -299.991204) (xy 305.4129 -299.954367)
			(xy 305.451021 -299.923242) (xy 305.493642 -299.898635) (xy 305.539658 -299.881183) (xy 305.587877 -299.871339)
			(xy 305.637052 -299.869358) (xy 305.685907 -299.87529) (xy 305.733178 -299.888982) (xy 305.77764 -299.91008)
			(xy 305.818143 -299.938036) (xy 305.853636 -299.972128) (xy 305.883201 -300.011472) (xy 305.906072 -300.055049)
			(xy 305.921656 -300.10173) (xy 305.929551 -300.150307) (xy 305.930046 -300.174914) (xy 306.268894 -300.174914)
			(xy 306.272854 -300.12586) (xy 306.284631 -300.078076) (xy 306.303922 -300.0328) (xy 306.330225 -299.991204)
			(xy 306.36286 -299.954367) (xy 306.400981 -299.923242) (xy 306.443602 -299.898635) (xy 306.489618 -299.881183)
			(xy 306.537837 -299.871339) (xy 306.587012 -299.869358) (xy 306.635867 -299.87529) (xy 306.683138 -299.888982)
			(xy 306.7276 -299.91008) (xy 306.768103 -299.938036) (xy 306.803596 -299.972128) (xy 306.833161 -300.011472)
			(xy 306.856032 -300.055049) (xy 306.871616 -300.10173) (xy 306.879511 -300.150307) (xy 306.880006 -300.174914)
			(xy 307.219108 -300.174914) (xy 307.223068 -300.12586) (xy 307.234845 -300.078076) (xy 307.254136 -300.0328)
			(xy 307.280439 -299.991204) (xy 307.313074 -299.954367) (xy 307.351195 -299.923242) (xy 307.393816 -299.898635)
			(xy 307.439832 -299.881183) (xy 307.488051 -299.871339) (xy 307.537226 -299.869358) (xy 307.586081 -299.87529)
			(xy 307.633352 -299.888982) (xy 307.677814 -299.91008) (xy 307.718317 -299.938036) (xy 307.75381 -299.972128)
			(xy 307.783375 -300.011472) (xy 307.806246 -300.055049) (xy 307.82183 -300.10173) (xy 307.829725 -300.150307)
			(xy 307.83022 -300.174914) (xy 308.169068 -300.174914) (xy 308.173028 -300.12586) (xy 308.184805 -300.078076)
			(xy 308.204096 -300.0328) (xy 308.230399 -299.991204) (xy 308.263034 -299.954367) (xy 308.301155 -299.923242)
			(xy 308.343776 -299.898635) (xy 308.389792 -299.881183) (xy 308.438011 -299.871339) (xy 308.487186 -299.869358)
			(xy 308.536041 -299.87529) (xy 308.583312 -299.888982) (xy 308.627774 -299.91008) (xy 308.668277 -299.938036)
			(xy 308.70377 -299.972128) (xy 308.733335 -300.011472) (xy 308.756206 -300.055049) (xy 308.77179 -300.10173)
			(xy 308.779685 -300.150307) (xy 308.78018 -300.174914) (xy 309.119028 -300.174914) (xy 309.122988 -300.12586)
			(xy 309.134765 -300.078076) (xy 309.154056 -300.0328) (xy 309.180359 -299.991204) (xy 309.212994 -299.954367)
			(xy 309.251115 -299.923242) (xy 309.293736 -299.898635) (xy 309.339752 -299.881183) (xy 309.387971 -299.871339)
			(xy 309.437146 -299.869358) (xy 309.486001 -299.87529) (xy 309.533272 -299.888982) (xy 309.577734 -299.91008)
			(xy 309.618237 -299.938036) (xy 309.65373 -299.972128) (xy 309.683295 -300.011472) (xy 309.706166 -300.055049)
			(xy 309.72175 -300.10173) (xy 309.729645 -300.150307) (xy 309.73014 -300.174914) (xy 310.068988 -300.174914)
			(xy 310.072948 -300.12586) (xy 310.084725 -300.078076) (xy 310.104016 -300.0328) (xy 310.130319 -299.991204)
			(xy 310.162954 -299.954367) (xy 310.201075 -299.923242) (xy 310.243696 -299.898635) (xy 310.289712 -299.881183)
			(xy 310.337931 -299.871339) (xy 310.387106 -299.869358) (xy 310.435961 -299.87529) (xy 310.483232 -299.888982)
			(xy 310.527694 -299.91008) (xy 310.568197 -299.938036) (xy 310.60369 -299.972128) (xy 310.633255 -300.011472)
			(xy 310.656126 -300.055049) (xy 310.67171 -300.10173) (xy 310.679605 -300.150307) (xy 310.6801 -300.174914)
			(xy 311.018948 -300.174914) (xy 311.022908 -300.12586) (xy 311.034685 -300.078076) (xy 311.053976 -300.0328)
			(xy 311.080279 -299.991204) (xy 311.112914 -299.954367) (xy 311.151035 -299.923242) (xy 311.193656 -299.898635)
			(xy 311.239672 -299.881183) (xy 311.287891 -299.871339) (xy 311.337066 -299.869358) (xy 311.385921 -299.87529)
			(xy 311.433192 -299.888982) (xy 311.477654 -299.91008) (xy 311.518157 -299.938036) (xy 311.55365 -299.972128)
			(xy 311.583215 -300.011472) (xy 311.606086 -300.055049) (xy 311.62167 -300.10173) (xy 311.629565 -300.150307)
			(xy 311.63006 -300.174914) (xy 311.968908 -300.174914) (xy 311.972868 -300.12586) (xy 311.984645 -300.078076)
			(xy 312.003936 -300.0328) (xy 312.030239 -299.991204) (xy 312.062874 -299.954367) (xy 312.100995 -299.923242)
			(xy 312.143616 -299.898635) (xy 312.189632 -299.881183) (xy 312.237851 -299.871339) (xy 312.287026 -299.869358)
			(xy 312.335881 -299.87529) (xy 312.383152 -299.888982) (xy 312.427614 -299.91008) (xy 312.468117 -299.938036)
			(xy 312.50361 -299.972128) (xy 312.533175 -300.011472) (xy 312.556046 -300.055049) (xy 312.57163 -300.10173)
			(xy 312.579525 -300.150307) (xy 312.58002 -300.174914) (xy 312.919122 -300.174914) (xy 312.923082 -300.12586)
			(xy 312.934859 -300.078076) (xy 312.95415 -300.0328) (xy 312.980453 -299.991204) (xy 313.013088 -299.954367)
			(xy 313.051209 -299.923242) (xy 313.09383 -299.898635) (xy 313.139846 -299.881183) (xy 313.188065 -299.871339)
			(xy 313.23724 -299.869358) (xy 313.286095 -299.87529) (xy 313.333366 -299.888982) (xy 313.377828 -299.91008)
			(xy 313.418331 -299.938036) (xy 313.453824 -299.972128) (xy 313.483389 -300.011472) (xy 313.50626 -300.055049)
			(xy 313.521844 -300.10173) (xy 313.529739 -300.150307) (xy 313.530234 -300.174914) (xy 313.869082 -300.174914)
			(xy 313.873042 -300.12586) (xy 313.884819 -300.078076) (xy 313.90411 -300.0328) (xy 313.930413 -299.991204)
			(xy 313.963048 -299.954367) (xy 314.001169 -299.923242) (xy 314.04379 -299.898635) (xy 314.089806 -299.881183)
			(xy 314.138025 -299.871339) (xy 314.1872 -299.869358) (xy 314.236055 -299.87529) (xy 314.283326 -299.888982)
			(xy 314.327788 -299.91008) (xy 314.368291 -299.938036) (xy 314.403784 -299.972128) (xy 314.433349 -300.011472)
			(xy 314.45622 -300.055049) (xy 314.471804 -300.10173) (xy 314.479699 -300.150307) (xy 314.480194 -300.174914)
			(xy 314.819042 -300.174914) (xy 314.823002 -300.12586) (xy 314.834779 -300.078076) (xy 314.85407 -300.0328)
			(xy 314.880373 -299.991204) (xy 314.913008 -299.954367) (xy 314.951129 -299.923242) (xy 314.99375 -299.898635)
			(xy 315.039766 -299.881183) (xy 315.087985 -299.871339) (xy 315.13716 -299.869358) (xy 315.186015 -299.87529)
			(xy 315.233286 -299.888982) (xy 315.277748 -299.91008) (xy 315.318251 -299.938036) (xy 315.353744 -299.972128)
			(xy 315.383309 -300.011472) (xy 315.40618 -300.055049) (xy 315.421764 -300.10173) (xy 315.429659 -300.150307)
			(xy 315.430154 -300.174914) (xy 315.429659 -300.199521) (xy 315.421764 -300.248098) (xy 315.40618 -300.294779)
			(xy 315.383309 -300.338356) (xy 315.353744 -300.3777) (xy 315.318251 -300.411792) (xy 315.277748 -300.439748)
			(xy 315.233286 -300.460846) (xy 315.186015 -300.474538) (xy 315.13716 -300.48047) (xy 315.087985 -300.478489)
			(xy 315.039766 -300.468645) (xy 314.99375 -300.451193) (xy 314.951129 -300.426586) (xy 314.913008 -300.395461)
			(xy 314.880373 -300.358624) (xy 314.85407 -300.317028) (xy 314.834779 -300.271752) (xy 314.823002 -300.223968)
			(xy 314.819042 -300.174914) (xy 314.480194 -300.174914) (xy 314.479699 -300.199521) (xy 314.471804 -300.248098)
			(xy 314.45622 -300.294779) (xy 314.433349 -300.338356) (xy 314.403784 -300.3777) (xy 314.368291 -300.411792)
			(xy 314.327788 -300.439748) (xy 314.283326 -300.460846) (xy 314.236055 -300.474538) (xy 314.1872 -300.48047)
			(xy 314.138025 -300.478489) (xy 314.089806 -300.468645) (xy 314.04379 -300.451193) (xy 314.001169 -300.426586)
			(xy 313.963048 -300.395461) (xy 313.930413 -300.358624) (xy 313.90411 -300.317028) (xy 313.884819 -300.271752)
			(xy 313.873042 -300.223968) (xy 313.869082 -300.174914) (xy 313.530234 -300.174914) (xy 313.529739 -300.199521)
			(xy 313.521844 -300.248098) (xy 313.50626 -300.294779) (xy 313.483389 -300.338356) (xy 313.453824 -300.3777)
			(xy 313.418331 -300.411792) (xy 313.377828 -300.439748) (xy 313.333366 -300.460846) (xy 313.286095 -300.474538)
			(xy 313.23724 -300.48047) (xy 313.188065 -300.478489) (xy 313.139846 -300.468645) (xy 313.09383 -300.451193)
			(xy 313.051209 -300.426586) (xy 313.013088 -300.395461) (xy 312.980453 -300.358624) (xy 312.95415 -300.317028)
			(xy 312.934859 -300.271752) (xy 312.923082 -300.223968) (xy 312.919122 -300.174914) (xy 312.58002 -300.174914)
			(xy 312.579525 -300.199521) (xy 312.57163 -300.248098) (xy 312.556046 -300.294779) (xy 312.533175 -300.338356)
			(xy 312.50361 -300.3777) (xy 312.468117 -300.411792) (xy 312.427614 -300.439748) (xy 312.383152 -300.460846)
			(xy 312.335881 -300.474538) (xy 312.287026 -300.48047) (xy 312.237851 -300.478489) (xy 312.189632 -300.468645)
			(xy 312.143616 -300.451193) (xy 312.100995 -300.426586) (xy 312.062874 -300.395461) (xy 312.030239 -300.358624)
			(xy 312.003936 -300.317028) (xy 311.984645 -300.271752) (xy 311.972868 -300.223968) (xy 311.968908 -300.174914)
			(xy 311.63006 -300.174914) (xy 311.629565 -300.199521) (xy 311.62167 -300.248098) (xy 311.606086 -300.294779)
			(xy 311.583215 -300.338356) (xy 311.55365 -300.3777) (xy 311.518157 -300.411792) (xy 311.477654 -300.439748)
			(xy 311.433192 -300.460846) (xy 311.385921 -300.474538) (xy 311.337066 -300.48047) (xy 311.287891 -300.478489)
			(xy 311.239672 -300.468645) (xy 311.193656 -300.451193) (xy 311.151035 -300.426586) (xy 311.112914 -300.395461)
			(xy 311.080279 -300.358624) (xy 311.053976 -300.317028) (xy 311.034685 -300.271752) (xy 311.022908 -300.223968)
			(xy 311.018948 -300.174914) (xy 310.6801 -300.174914) (xy 310.679605 -300.199521) (xy 310.67171 -300.248098)
			(xy 310.656126 -300.294779) (xy 310.633255 -300.338356) (xy 310.60369 -300.3777) (xy 310.568197 -300.411792)
			(xy 310.527694 -300.439748) (xy 310.483232 -300.460846) (xy 310.435961 -300.474538) (xy 310.387106 -300.48047)
			(xy 310.337931 -300.478489) (xy 310.289712 -300.468645) (xy 310.243696 -300.451193) (xy 310.201075 -300.426586)
			(xy 310.162954 -300.395461) (xy 310.130319 -300.358624) (xy 310.104016 -300.317028) (xy 310.084725 -300.271752)
			(xy 310.072948 -300.223968) (xy 310.068988 -300.174914) (xy 309.73014 -300.174914) (xy 309.729645 -300.199521)
			(xy 309.72175 -300.248098) (xy 309.706166 -300.294779) (xy 309.683295 -300.338356) (xy 309.65373 -300.3777)
			(xy 309.618237 -300.411792) (xy 309.577734 -300.439748) (xy 309.533272 -300.460846) (xy 309.486001 -300.474538)
			(xy 309.437146 -300.48047) (xy 309.387971 -300.478489) (xy 309.339752 -300.468645) (xy 309.293736 -300.451193)
			(xy 309.251115 -300.426586) (xy 309.212994 -300.395461) (xy 309.180359 -300.358624) (xy 309.154056 -300.317028)
			(xy 309.134765 -300.271752) (xy 309.122988 -300.223968) (xy 309.119028 -300.174914) (xy 308.78018 -300.174914)
			(xy 308.779685 -300.199521) (xy 308.77179 -300.248098) (xy 308.756206 -300.294779) (xy 308.733335 -300.338356)
			(xy 308.70377 -300.3777) (xy 308.668277 -300.411792) (xy 308.627774 -300.439748) (xy 308.583312 -300.460846)
			(xy 308.536041 -300.474538) (xy 308.487186 -300.48047) (xy 308.438011 -300.478489) (xy 308.389792 -300.468645)
			(xy 308.343776 -300.451193) (xy 308.301155 -300.426586) (xy 308.263034 -300.395461) (xy 308.230399 -300.358624)
			(xy 308.204096 -300.317028) (xy 308.184805 -300.271752) (xy 308.173028 -300.223968) (xy 308.169068 -300.174914)
			(xy 307.83022 -300.174914) (xy 307.829725 -300.199521) (xy 307.82183 -300.248098) (xy 307.806246 -300.294779)
			(xy 307.783375 -300.338356) (xy 307.75381 -300.3777) (xy 307.718317 -300.411792) (xy 307.677814 -300.439748)
			(xy 307.633352 -300.460846) (xy 307.586081 -300.474538) (xy 307.537226 -300.48047) (xy 307.488051 -300.478489)
			(xy 307.439832 -300.468645) (xy 307.393816 -300.451193) (xy 307.351195 -300.426586) (xy 307.313074 -300.395461)
			(xy 307.280439 -300.358624) (xy 307.254136 -300.317028) (xy 307.234845 -300.271752) (xy 307.223068 -300.223968)
			(xy 307.219108 -300.174914) (xy 306.880006 -300.174914) (xy 306.879511 -300.199521) (xy 306.871616 -300.248098)
			(xy 306.856032 -300.294779) (xy 306.833161 -300.338356) (xy 306.803596 -300.3777) (xy 306.768103 -300.411792)
			(xy 306.7276 -300.439748) (xy 306.683138 -300.460846) (xy 306.635867 -300.474538) (xy 306.587012 -300.48047)
			(xy 306.537837 -300.478489) (xy 306.489618 -300.468645) (xy 306.443602 -300.451193) (xy 306.400981 -300.426586)
			(xy 306.36286 -300.395461) (xy 306.330225 -300.358624) (xy 306.303922 -300.317028) (xy 306.284631 -300.271752)
			(xy 306.272854 -300.223968) (xy 306.268894 -300.174914) (xy 305.930046 -300.174914) (xy 305.929551 -300.199521)
			(xy 305.921656 -300.248098) (xy 305.906072 -300.294779) (xy 305.883201 -300.338356) (xy 305.853636 -300.3777)
			(xy 305.818143 -300.411792) (xy 305.77764 -300.439748) (xy 305.733178 -300.460846) (xy 305.685907 -300.474538)
			(xy 305.637052 -300.48047) (xy 305.587877 -300.478489) (xy 305.539658 -300.468645) (xy 305.493642 -300.451193)
			(xy 305.451021 -300.426586) (xy 305.4129 -300.395461) (xy 305.380265 -300.358624) (xy 305.353962 -300.317028)
			(xy 305.334671 -300.271752) (xy 305.322894 -300.223968) (xy 305.318934 -300.174914) (xy 304.980086 -300.174914)
			(xy 304.979591 -300.199521) (xy 304.971696 -300.248098) (xy 304.956112 -300.294779) (xy 304.933241 -300.338356)
			(xy 304.903676 -300.3777) (xy 304.868183 -300.411792) (xy 304.82768 -300.439748) (xy 304.783218 -300.460846)
			(xy 304.735947 -300.474538) (xy 304.687092 -300.48047) (xy 304.637917 -300.478489) (xy 304.589698 -300.468645)
			(xy 304.543682 -300.451193) (xy 304.501061 -300.426586) (xy 304.46294 -300.395461) (xy 304.430305 -300.358624)
			(xy 304.404002 -300.317028) (xy 304.384711 -300.271752) (xy 304.372934 -300.223968) (xy 304.368974 -300.174914)
			(xy 304.030126 -300.174914) (xy 304.029631 -300.199521) (xy 304.021736 -300.248098) (xy 304.006152 -300.294779)
			(xy 303.983281 -300.338356) (xy 303.953716 -300.3777) (xy 303.918223 -300.411792) (xy 303.87772 -300.439748)
			(xy 303.833258 -300.460846) (xy 303.785987 -300.474538) (xy 303.737132 -300.48047) (xy 303.687957 -300.478489)
			(xy 303.639738 -300.468645) (xy 303.593722 -300.451193) (xy 303.551101 -300.426586) (xy 303.51298 -300.395461)
			(xy 303.480345 -300.358624) (xy 303.454042 -300.317028) (xy 303.434751 -300.271752) (xy 303.422974 -300.223968)
			(xy 303.419014 -300.174914) (xy 303.080166 -300.174914) (xy 303.079671 -300.199521) (xy 303.071776 -300.248098)
			(xy 303.056192 -300.294779) (xy 303.033321 -300.338356) (xy 303.003756 -300.3777) (xy 302.968263 -300.411792)
			(xy 302.92776 -300.439748) (xy 302.883298 -300.460846) (xy 302.836027 -300.474538) (xy 302.787172 -300.48047)
			(xy 302.737997 -300.478489) (xy 302.689778 -300.468645) (xy 302.643762 -300.451193) (xy 302.601141 -300.426586)
			(xy 302.56302 -300.395461) (xy 302.530385 -300.358624) (xy 302.504082 -300.317028) (xy 302.484791 -300.271752)
			(xy 302.473014 -300.223968) (xy 302.469054 -300.174914) (xy 302.130206 -300.174914) (xy 302.129711 -300.199521)
			(xy 302.121816 -300.248098) (xy 302.106232 -300.294779) (xy 302.083361 -300.338356) (xy 302.053796 -300.3777)
			(xy 302.018303 -300.411792) (xy 301.9778 -300.439748) (xy 301.933338 -300.460846) (xy 301.886067 -300.474538)
			(xy 301.837212 -300.48047) (xy 301.788037 -300.478489) (xy 301.739818 -300.468645) (xy 301.693802 -300.451193)
			(xy 301.651181 -300.426586) (xy 301.61306 -300.395461) (xy 301.580425 -300.358624) (xy 301.554122 -300.317028)
			(xy 301.534831 -300.271752) (xy 301.523054 -300.223968) (xy 301.519094 -300.174914) (xy 301.179992 -300.174914)
			(xy 301.179497 -300.199521) (xy 301.171602 -300.248098) (xy 301.156018 -300.294779) (xy 301.133147 -300.338356)
			(xy 301.103582 -300.3777) (xy 301.068089 -300.411792) (xy 301.027586 -300.439748) (xy 300.983124 -300.460846)
			(xy 300.935853 -300.474538) (xy 300.886998 -300.48047) (xy 300.837823 -300.478489) (xy 300.789604 -300.468645)
			(xy 300.743588 -300.451193) (xy 300.700967 -300.426586) (xy 300.662846 -300.395461) (xy 300.630211 -300.358624)
			(xy 300.603908 -300.317028) (xy 300.584617 -300.271752) (xy 300.57284 -300.223968) (xy 300.56888 -300.174914)
			(xy 300.230032 -300.174914) (xy 300.229537 -300.199521) (xy 300.221642 -300.248098) (xy 300.206058 -300.294779)
			(xy 300.183187 -300.338356) (xy 300.153622 -300.3777) (xy 300.118129 -300.411792) (xy 300.077626 -300.439748)
			(xy 300.033164 -300.460846) (xy 299.985893 -300.474538) (xy 299.937038 -300.48047) (xy 299.887863 -300.478489)
			(xy 299.839644 -300.468645) (xy 299.793628 -300.451193) (xy 299.751007 -300.426586) (xy 299.712886 -300.395461)
			(xy 299.680251 -300.358624) (xy 299.653948 -300.317028) (xy 299.634657 -300.271752) (xy 299.62288 -300.223968)
			(xy 299.61892 -300.174914) (xy 299.280072 -300.174914) (xy 299.279577 -300.199521) (xy 299.271682 -300.248098)
			(xy 299.256098 -300.294779) (xy 299.233227 -300.338356) (xy 299.203662 -300.3777) (xy 299.168169 -300.411792)
			(xy 299.127666 -300.439748) (xy 299.083204 -300.460846) (xy 299.035933 -300.474538) (xy 298.987078 -300.48047)
			(xy 298.937903 -300.478489) (xy 298.889684 -300.468645) (xy 298.843668 -300.451193) (xy 298.801047 -300.426586)
			(xy 298.762926 -300.395461) (xy 298.730291 -300.358624) (xy 298.703988 -300.317028) (xy 298.684697 -300.271752)
			(xy 298.67292 -300.223968) (xy 298.66896 -300.174914) (xy 298.330112 -300.174914) (xy 298.329617 -300.199521)
			(xy 298.321722 -300.248098) (xy 298.306138 -300.294779) (xy 298.283267 -300.338356) (xy 298.253702 -300.3777)
			(xy 298.218209 -300.411792) (xy 298.177706 -300.439748) (xy 298.133244 -300.460846) (xy 298.085973 -300.474538)
			(xy 298.037118 -300.48047) (xy 297.987943 -300.478489) (xy 297.939724 -300.468645) (xy 297.893708 -300.451193)
			(xy 297.851087 -300.426586) (xy 297.812966 -300.395461) (xy 297.780331 -300.358624) (xy 297.754028 -300.317028)
			(xy 297.734737 -300.271752) (xy 297.72296 -300.223968) (xy 297.719 -300.174914) (xy 297.380152 -300.174914)
			(xy 297.379657 -300.199521) (xy 297.371762 -300.248098) (xy 297.356178 -300.294779) (xy 297.333307 -300.338356)
			(xy 297.303742 -300.3777) (xy 297.268249 -300.411792) (xy 297.227746 -300.439748) (xy 297.183284 -300.460846)
			(xy 297.136013 -300.474538) (xy 297.087158 -300.48047) (xy 297.037983 -300.478489) (xy 296.989764 -300.468645)
			(xy 296.943748 -300.451193) (xy 296.901127 -300.426586) (xy 296.863006 -300.395461) (xy 296.830371 -300.358624)
			(xy 296.804068 -300.317028) (xy 296.784777 -300.271752) (xy 296.773 -300.223968) (xy 296.76904 -300.174914)
			(xy 296.430192 -300.174914) (xy 296.429697 -300.199521) (xy 296.421802 -300.248098) (xy 296.406218 -300.294779)
			(xy 296.383347 -300.338356) (xy 296.353782 -300.3777) (xy 296.318289 -300.411792) (xy 296.277786 -300.439748)
			(xy 296.233324 -300.460846) (xy 296.186053 -300.474538) (xy 296.137198 -300.48047) (xy 296.088023 -300.478489)
			(xy 296.039804 -300.468645) (xy 295.993788 -300.451193) (xy 295.951167 -300.426586) (xy 295.913046 -300.395461)
			(xy 295.880411 -300.358624) (xy 295.854108 -300.317028) (xy 295.834817 -300.271752) (xy 295.82304 -300.223968)
			(xy 295.81908 -300.174914) (xy 295.480232 -300.174914) (xy 295.479737 -300.199521) (xy 295.471842 -300.248098)
			(xy 295.456258 -300.294779) (xy 295.433387 -300.338356) (xy 295.403822 -300.3777) (xy 295.368329 -300.411792)
			(xy 295.327826 -300.439748) (xy 295.283364 -300.460846) (xy 295.236093 -300.474538) (xy 295.187238 -300.48047)
			(xy 295.138063 -300.478489) (xy 295.089844 -300.468645) (xy 295.043828 -300.451193) (xy 295.001207 -300.426586)
			(xy 294.963086 -300.395461) (xy 294.930451 -300.358624) (xy 294.904148 -300.317028) (xy 294.884857 -300.271752)
			(xy 294.87308 -300.223968) (xy 294.86912 -300.174914) (xy 294.530018 -300.174914) (xy 294.529523 -300.199521)
			(xy 294.521628 -300.248098) (xy 294.506044 -300.294779) (xy 294.483173 -300.338356) (xy 294.453608 -300.3777)
			(xy 294.418115 -300.411792) (xy 294.377612 -300.439748) (xy 294.33315 -300.460846) (xy 294.285879 -300.474538)
			(xy 294.237024 -300.48047) (xy 294.187849 -300.478489) (xy 294.13963 -300.468645) (xy 294.093614 -300.451193)
			(xy 294.050993 -300.426586) (xy 294.012872 -300.395461) (xy 293.980237 -300.358624) (xy 293.953934 -300.317028)
			(xy 293.934643 -300.271752) (xy 293.922866 -300.223968) (xy 293.918906 -300.174914) (xy 293.580058 -300.174914)
			(xy 293.579563 -300.199521) (xy 293.571668 -300.248098) (xy 293.556084 -300.294779) (xy 293.533213 -300.338356)
			(xy 293.503648 -300.3777) (xy 293.468155 -300.411792) (xy 293.427652 -300.439748) (xy 293.38319 -300.460846)
			(xy 293.335919 -300.474538) (xy 293.287064 -300.48047) (xy 293.237889 -300.478489) (xy 293.18967 -300.468645)
			(xy 293.143654 -300.451193) (xy 293.101033 -300.426586) (xy 293.062912 -300.395461) (xy 293.030277 -300.358624)
			(xy 293.003974 -300.317028) (xy 292.984683 -300.271752) (xy 292.972906 -300.223968) (xy 292.968946 -300.174914)
			(xy 292.630098 -300.174914) (xy 292.629603 -300.199521) (xy 292.621708 -300.248098) (xy 292.606124 -300.294779)
			(xy 292.583253 -300.338356) (xy 292.553688 -300.3777) (xy 292.518195 -300.411792) (xy 292.477692 -300.439748)
			(xy 292.43323 -300.460846) (xy 292.385959 -300.474538) (xy 292.337104 -300.48047) (xy 292.287929 -300.478489)
			(xy 292.23971 -300.468645) (xy 292.193694 -300.451193) (xy 292.151073 -300.426586) (xy 292.112952 -300.395461)
			(xy 292.080317 -300.358624) (xy 292.054014 -300.317028) (xy 292.034723 -300.271752) (xy 292.022946 -300.223968)
			(xy 292.018986 -300.174914) (xy 290.730178 -300.174914) (xy 290.729683 -300.199521) (xy 290.721788 -300.248098)
			(xy 290.706204 -300.294779) (xy 290.683333 -300.338356) (xy 290.653768 -300.3777) (xy 290.618275 -300.411792)
			(xy 290.577772 -300.439748) (xy 290.53331 -300.460846) (xy 290.486039 -300.474538) (xy 290.437184 -300.48047)
			(xy 290.388009 -300.478489) (xy 290.33979 -300.468645) (xy 290.293774 -300.451193) (xy 290.251153 -300.426586)
			(xy 290.213032 -300.395461) (xy 290.180397 -300.358624) (xy 290.154094 -300.317028) (xy 290.134803 -300.271752)
			(xy 290.123026 -300.223968) (xy 290.119066 -300.174914) (xy 289.780218 -300.174914) (xy 289.779723 -300.199521)
			(xy 289.771828 -300.248098) (xy 289.756244 -300.294779) (xy 289.733373 -300.338356) (xy 289.703808 -300.3777)
			(xy 289.668315 -300.411792) (xy 289.627812 -300.439748) (xy 289.58335 -300.460846) (xy 289.536079 -300.474538)
			(xy 289.487224 -300.48047) (xy 289.438049 -300.478489) (xy 289.38983 -300.468645) (xy 289.343814 -300.451193)
			(xy 289.301193 -300.426586) (xy 289.263072 -300.395461) (xy 289.230437 -300.358624) (xy 289.204134 -300.317028)
			(xy 289.184843 -300.271752) (xy 289.173066 -300.223968) (xy 289.169106 -300.174914) (xy 288.830004 -300.174914)
			(xy 288.829509 -300.199521) (xy 288.821614 -300.248098) (xy 288.80603 -300.294779) (xy 288.783159 -300.338356)
			(xy 288.753594 -300.3777) (xy 288.718101 -300.411792) (xy 288.677598 -300.439748) (xy 288.633136 -300.460846)
			(xy 288.585865 -300.474538) (xy 288.53701 -300.48047) (xy 288.487835 -300.478489) (xy 288.439616 -300.468645)
			(xy 288.3936 -300.451193) (xy 288.350979 -300.426586) (xy 288.312858 -300.395461) (xy 288.280223 -300.358624)
			(xy 288.25392 -300.317028) (xy 288.234629 -300.271752) (xy 288.222852 -300.223968) (xy 288.218892 -300.174914)
			(xy 287.880044 -300.174914) (xy 287.879549 -300.199521) (xy 287.871654 -300.248098) (xy 287.85607 -300.294779)
			(xy 287.833199 -300.338356) (xy 287.803634 -300.3777) (xy 287.768141 -300.411792) (xy 287.727638 -300.439748)
			(xy 287.683176 -300.460846) (xy 287.635905 -300.474538) (xy 287.58705 -300.48047) (xy 287.537875 -300.478489)
			(xy 287.489656 -300.468645) (xy 287.44364 -300.451193) (xy 287.401019 -300.426586) (xy 287.362898 -300.395461)
			(xy 287.330263 -300.358624) (xy 287.30396 -300.317028) (xy 287.284669 -300.271752) (xy 287.272892 -300.223968)
			(xy 287.268932 -300.174914) (xy 286.930084 -300.174914) (xy 286.929589 -300.199521) (xy 286.921694 -300.248098)
			(xy 286.90611 -300.294779) (xy 286.883239 -300.338356) (xy 286.853674 -300.3777) (xy 286.818181 -300.411792)
			(xy 286.777678 -300.439748) (xy 286.733216 -300.460846) (xy 286.685945 -300.474538) (xy 286.63709 -300.48047)
			(xy 286.587915 -300.478489) (xy 286.539696 -300.468645) (xy 286.49368 -300.451193) (xy 286.451059 -300.426586)
			(xy 286.412938 -300.395461) (xy 286.380303 -300.358624) (xy 286.354 -300.317028) (xy 286.334709 -300.271752)
			(xy 286.322932 -300.223968) (xy 286.318972 -300.174914) (xy 285.980124 -300.174914) (xy 285.979629 -300.199521)
			(xy 285.971734 -300.248098) (xy 285.95615 -300.294779) (xy 285.933279 -300.338356) (xy 285.903714 -300.3777)
			(xy 285.868221 -300.411792) (xy 285.827718 -300.439748) (xy 285.783256 -300.460846) (xy 285.735985 -300.474538)
			(xy 285.68713 -300.48047) (xy 285.637955 -300.478489) (xy 285.589736 -300.468645) (xy 285.54372 -300.451193)
			(xy 285.501099 -300.426586) (xy 285.462978 -300.395461) (xy 285.430343 -300.358624) (xy 285.40404 -300.317028)
			(xy 285.384749 -300.271752) (xy 285.372972 -300.223968) (xy 285.369012 -300.174914) (xy 285.030164 -300.174914)
			(xy 285.029669 -300.199521) (xy 285.021774 -300.248098) (xy 285.00619 -300.294779) (xy 284.983319 -300.338356)
			(xy 284.953754 -300.3777) (xy 284.918261 -300.411792) (xy 284.877758 -300.439748) (xy 284.833296 -300.460846)
			(xy 284.786025 -300.474538) (xy 284.73717 -300.48047) (xy 284.687995 -300.478489) (xy 284.639776 -300.468645)
			(xy 284.59376 -300.451193) (xy 284.551139 -300.426586) (xy 284.513018 -300.395461) (xy 284.480383 -300.358624)
			(xy 284.45408 -300.317028) (xy 284.434789 -300.271752) (xy 284.423012 -300.223968) (xy 284.419052 -300.174914)
			(xy 284.080204 -300.174914) (xy 284.079709 -300.199521) (xy 284.071814 -300.248098) (xy 284.05623 -300.294779)
			(xy 284.033359 -300.338356) (xy 284.003794 -300.3777) (xy 283.968301 -300.411792) (xy 283.927798 -300.439748)
			(xy 283.883336 -300.460846) (xy 283.836065 -300.474538) (xy 283.78721 -300.48047) (xy 283.738035 -300.478489)
			(xy 283.689816 -300.468645) (xy 283.6438 -300.451193) (xy 283.601179 -300.426586) (xy 283.563058 -300.395461)
			(xy 283.530423 -300.358624) (xy 283.50412 -300.317028) (xy 283.484829 -300.271752) (xy 283.473052 -300.223968)
			(xy 283.469092 -300.174914) (xy 283.130244 -300.174914) (xy 283.129749 -300.199521) (xy 283.121854 -300.248098)
			(xy 283.10627 -300.294779) (xy 283.083399 -300.338356) (xy 283.053834 -300.3777) (xy 283.018341 -300.411792)
			(xy 282.977838 -300.439748) (xy 282.933376 -300.460846) (xy 282.886105 -300.474538) (xy 282.83725 -300.48047)
			(xy 282.788075 -300.478489) (xy 282.739856 -300.468645) (xy 282.69384 -300.451193) (xy 282.651219 -300.426586)
			(xy 282.613098 -300.395461) (xy 282.580463 -300.358624) (xy 282.55416 -300.317028) (xy 282.534869 -300.271752)
			(xy 282.523092 -300.223968) (xy 282.519132 -300.174914) (xy 281.23007 -300.174914) (xy 281.229575 -300.199521)
			(xy 281.22168 -300.248098) (xy 281.206096 -300.294779) (xy 281.183225 -300.338356) (xy 281.15366 -300.3777)
			(xy 281.118167 -300.411792) (xy 281.077664 -300.439748) (xy 281.033202 -300.460846) (xy 280.985931 -300.474538)
			(xy 280.937076 -300.48047) (xy 280.887901 -300.478489) (xy 280.839682 -300.468645) (xy 280.793666 -300.451193)
			(xy 280.751045 -300.426586) (xy 280.712924 -300.395461) (xy 280.680289 -300.358624) (xy 280.653986 -300.317028)
			(xy 280.634695 -300.271752) (xy 280.622918 -300.223968) (xy 280.618958 -300.174914) (xy 280.28011 -300.174914)
			(xy 280.28011 -300.191424) (xy 280.279602 -300.197266) (xy 280.279602 -300.197774) (xy 280.278332 -300.208696)
			(xy 280.278332 -300.20895) (xy 280.277824 -300.213014) (xy 280.275284 -300.23181) (xy 280.274268 -300.237398)
			(xy 280.270204 -300.253146) (xy 280.268426 -300.265846) (xy 280.268426 -301.030132) (xy 280.268934 -301.036228)
			(xy 280.270204 -301.047404) (xy 280.270966 -301.050706) (xy 280.270966 -301.051214) (xy 280.275219 -301.069332)
			(xy 280.279806 -301.106266) (xy 280.28011 -301.124874) (xy 281.568918 -301.124874) (xy 281.572878 -301.07582)
			(xy 281.584655 -301.028036) (xy 281.603946 -300.98276) (xy 281.630249 -300.941164) (xy 281.662884 -300.904327)
			(xy 281.701005 -300.873202) (xy 281.743626 -300.848595) (xy 281.789642 -300.831143) (xy 281.837861 -300.821299)
			(xy 281.887036 -300.819318) (xy 281.935891 -300.82525) (xy 281.983162 -300.838942) (xy 282.027624 -300.86004)
			(xy 282.068127 -300.887996) (xy 282.10362 -300.922088) (xy 282.133185 -300.961432) (xy 282.156056 -301.005009)
			(xy 282.17164 -301.05169) (xy 282.179535 -301.100267) (xy 282.18003 -301.124874) (xy 282.519132 -301.124874)
			(xy 282.523092 -301.07582) (xy 282.534869 -301.028036) (xy 282.55416 -300.98276) (xy 282.580463 -300.941164)
			(xy 282.613098 -300.904327) (xy 282.651219 -300.873202) (xy 282.69384 -300.848595) (xy 282.739856 -300.831143)
			(xy 282.788075 -300.821299) (xy 282.83725 -300.819318) (xy 282.886105 -300.82525) (xy 282.933376 -300.838942)
			(xy 282.977838 -300.86004) (xy 283.018341 -300.887996) (xy 283.053834 -300.922088) (xy 283.083399 -300.961432)
			(xy 283.10627 -301.005009) (xy 283.121854 -301.05169) (xy 283.129749 -301.100267) (xy 283.130244 -301.124874)
			(xy 283.469092 -301.124874) (xy 283.473052 -301.07582) (xy 283.484829 -301.028036) (xy 283.50412 -300.98276)
			(xy 283.530423 -300.941164) (xy 283.563058 -300.904327) (xy 283.601179 -300.873202) (xy 283.6438 -300.848595)
			(xy 283.689816 -300.831143) (xy 283.738035 -300.821299) (xy 283.78721 -300.819318) (xy 283.836065 -300.82525)
			(xy 283.883336 -300.838942) (xy 283.927798 -300.86004) (xy 283.968301 -300.887996) (xy 284.003794 -300.922088)
			(xy 284.033359 -300.961432) (xy 284.05623 -301.005009) (xy 284.071814 -301.05169) (xy 284.079709 -301.100267)
			(xy 284.080204 -301.124874) (xy 284.419052 -301.124874) (xy 284.423012 -301.07582) (xy 284.434789 -301.028036)
			(xy 284.45408 -300.98276) (xy 284.480383 -300.941164) (xy 284.513018 -300.904327) (xy 284.551139 -300.873202)
			(xy 284.59376 -300.848595) (xy 284.639776 -300.831143) (xy 284.687995 -300.821299) (xy 284.73717 -300.819318)
			(xy 284.786025 -300.82525) (xy 284.833296 -300.838942) (xy 284.877758 -300.86004) (xy 284.918261 -300.887996)
			(xy 284.953754 -300.922088) (xy 284.983319 -300.961432) (xy 285.00619 -301.005009) (xy 285.021774 -301.05169)
			(xy 285.029669 -301.100267) (xy 285.030164 -301.124874) (xy 285.369012 -301.124874) (xy 285.372972 -301.07582)
			(xy 285.384749 -301.028036) (xy 285.40404 -300.98276) (xy 285.430343 -300.941164) (xy 285.462978 -300.904327)
			(xy 285.501099 -300.873202) (xy 285.54372 -300.848595) (xy 285.589736 -300.831143) (xy 285.637955 -300.821299)
			(xy 285.68713 -300.819318) (xy 285.735985 -300.82525) (xy 285.783256 -300.838942) (xy 285.827718 -300.86004)
			(xy 285.868221 -300.887996) (xy 285.903714 -300.922088) (xy 285.933279 -300.961432) (xy 285.95615 -301.005009)
			(xy 285.971734 -301.05169) (xy 285.979629 -301.100267) (xy 285.980124 -301.124874) (xy 286.318972 -301.124874)
			(xy 286.322932 -301.07582) (xy 286.334709 -301.028036) (xy 286.354 -300.98276) (xy 286.380303 -300.941164)
			(xy 286.412938 -300.904327) (xy 286.451059 -300.873202) (xy 286.49368 -300.848595) (xy 286.539696 -300.831143)
			(xy 286.587915 -300.821299) (xy 286.63709 -300.819318) (xy 286.685945 -300.82525) (xy 286.733216 -300.838942)
			(xy 286.777678 -300.86004) (xy 286.818181 -300.887996) (xy 286.853674 -300.922088) (xy 286.883239 -300.961432)
			(xy 286.90611 -301.005009) (xy 286.921694 -301.05169) (xy 286.929589 -301.100267) (xy 286.930084 -301.124874)
			(xy 287.268932 -301.124874) (xy 287.272892 -301.07582) (xy 287.284669 -301.028036) (xy 287.30396 -300.98276)
			(xy 287.330263 -300.941164) (xy 287.362898 -300.904327) (xy 287.401019 -300.873202) (xy 287.44364 -300.848595)
			(xy 287.489656 -300.831143) (xy 287.537875 -300.821299) (xy 287.58705 -300.819318) (xy 287.635905 -300.82525)
			(xy 287.683176 -300.838942) (xy 287.727638 -300.86004) (xy 287.768141 -300.887996) (xy 287.803634 -300.922088)
			(xy 287.833199 -300.961432) (xy 287.85607 -301.005009) (xy 287.871654 -301.05169) (xy 287.879549 -301.100267)
			(xy 287.880044 -301.124874) (xy 288.218892 -301.124874) (xy 288.222852 -301.07582) (xy 288.234629 -301.028036)
			(xy 288.25392 -300.98276) (xy 288.280223 -300.941164) (xy 288.312858 -300.904327) (xy 288.350979 -300.873202)
			(xy 288.3936 -300.848595) (xy 288.439616 -300.831143) (xy 288.487835 -300.821299) (xy 288.53701 -300.819318)
			(xy 288.585865 -300.82525) (xy 288.633136 -300.838942) (xy 288.677598 -300.86004) (xy 288.718101 -300.887996)
			(xy 288.753594 -300.922088) (xy 288.783159 -300.961432) (xy 288.80603 -301.005009) (xy 288.821614 -301.05169)
			(xy 288.829509 -301.100267) (xy 288.830004 -301.124874) (xy 289.169106 -301.124874) (xy 289.173066 -301.07582)
			(xy 289.184843 -301.028036) (xy 289.204134 -300.98276) (xy 289.230437 -300.941164) (xy 289.263072 -300.904327)
			(xy 289.301193 -300.873202) (xy 289.343814 -300.848595) (xy 289.38983 -300.831143) (xy 289.438049 -300.821299)
			(xy 289.487224 -300.819318) (xy 289.536079 -300.82525) (xy 289.58335 -300.838942) (xy 289.627812 -300.86004)
			(xy 289.668315 -300.887996) (xy 289.703808 -300.922088) (xy 289.733373 -300.961432) (xy 289.756244 -301.005009)
			(xy 289.771828 -301.05169) (xy 289.779723 -301.100267) (xy 289.780218 -301.124874) (xy 290.119066 -301.124874)
			(xy 290.123026 -301.07582) (xy 290.134803 -301.028036) (xy 290.154094 -300.98276) (xy 290.180397 -300.941164)
			(xy 290.213032 -300.904327) (xy 290.251153 -300.873202) (xy 290.293774 -300.848595) (xy 290.33979 -300.831143)
			(xy 290.388009 -300.821299) (xy 290.437184 -300.819318) (xy 290.486039 -300.82525) (xy 290.53331 -300.838942)
			(xy 290.577772 -300.86004) (xy 290.618275 -300.887996) (xy 290.653768 -300.922088) (xy 290.683333 -300.961432)
			(xy 290.706204 -301.005009) (xy 290.721788 -301.05169) (xy 290.729683 -301.100267) (xy 290.730178 -301.124874)
			(xy 292.018986 -301.124874) (xy 292.022946 -301.07582) (xy 292.034723 -301.028036) (xy 292.054014 -300.98276)
			(xy 292.080317 -300.941164) (xy 292.112952 -300.904327) (xy 292.151073 -300.873202) (xy 292.193694 -300.848595)
			(xy 292.23971 -300.831143) (xy 292.287929 -300.821299) (xy 292.337104 -300.819318) (xy 292.385959 -300.82525)
			(xy 292.43323 -300.838942) (xy 292.477692 -300.86004) (xy 292.518195 -300.887996) (xy 292.553688 -300.922088)
			(xy 292.583253 -300.961432) (xy 292.606124 -301.005009) (xy 292.621708 -301.05169) (xy 292.629603 -301.100267)
			(xy 292.630098 -301.124874) (xy 292.968946 -301.124874) (xy 292.972906 -301.07582) (xy 292.984683 -301.028036)
			(xy 293.003974 -300.98276) (xy 293.030277 -300.941164) (xy 293.062912 -300.904327) (xy 293.101033 -300.873202)
			(xy 293.143654 -300.848595) (xy 293.18967 -300.831143) (xy 293.237889 -300.821299) (xy 293.287064 -300.819318)
			(xy 293.335919 -300.82525) (xy 293.38319 -300.838942) (xy 293.427652 -300.86004) (xy 293.468155 -300.887996)
			(xy 293.503648 -300.922088) (xy 293.533213 -300.961432) (xy 293.556084 -301.005009) (xy 293.571668 -301.05169)
			(xy 293.579563 -301.100267) (xy 293.580058 -301.124874) (xy 293.918906 -301.124874) (xy 293.922866 -301.07582)
			(xy 293.934643 -301.028036) (xy 293.953934 -300.98276) (xy 293.980237 -300.941164) (xy 294.012872 -300.904327)
			(xy 294.050993 -300.873202) (xy 294.093614 -300.848595) (xy 294.13963 -300.831143) (xy 294.187849 -300.821299)
			(xy 294.237024 -300.819318) (xy 294.285879 -300.82525) (xy 294.33315 -300.838942) (xy 294.377612 -300.86004)
			(xy 294.418115 -300.887996) (xy 294.453608 -300.922088) (xy 294.483173 -300.961432) (xy 294.506044 -301.005009)
			(xy 294.521628 -301.05169) (xy 294.529523 -301.100267) (xy 294.530018 -301.124874) (xy 294.86912 -301.124874)
			(xy 294.87308 -301.07582) (xy 294.884857 -301.028036) (xy 294.904148 -300.98276) (xy 294.930451 -300.941164)
			(xy 294.963086 -300.904327) (xy 295.001207 -300.873202) (xy 295.043828 -300.848595) (xy 295.089844 -300.831143)
			(xy 295.138063 -300.821299) (xy 295.187238 -300.819318) (xy 295.236093 -300.82525) (xy 295.283364 -300.838942)
			(xy 295.327826 -300.86004) (xy 295.368329 -300.887996) (xy 295.403822 -300.922088) (xy 295.433387 -300.961432)
			(xy 295.456258 -301.005009) (xy 295.471842 -301.05169) (xy 295.479737 -301.100267) (xy 295.480232 -301.124874)
			(xy 295.81908 -301.124874) (xy 295.82304 -301.07582) (xy 295.834817 -301.028036) (xy 295.854108 -300.98276)
			(xy 295.880411 -300.941164) (xy 295.913046 -300.904327) (xy 295.951167 -300.873202) (xy 295.993788 -300.848595)
			(xy 296.039804 -300.831143) (xy 296.088023 -300.821299) (xy 296.137198 -300.819318) (xy 296.186053 -300.82525)
			(xy 296.233324 -300.838942) (xy 296.277786 -300.86004) (xy 296.318289 -300.887996) (xy 296.353782 -300.922088)
			(xy 296.383347 -300.961432) (xy 296.406218 -301.005009) (xy 296.421802 -301.05169) (xy 296.429697 -301.100267)
			(xy 296.430192 -301.124874) (xy 296.76904 -301.124874) (xy 296.773 -301.07582) (xy 296.784777 -301.028036)
			(xy 296.804068 -300.98276) (xy 296.830371 -300.941164) (xy 296.863006 -300.904327) (xy 296.901127 -300.873202)
			(xy 296.943748 -300.848595) (xy 296.989764 -300.831143) (xy 297.037983 -300.821299) (xy 297.087158 -300.819318)
			(xy 297.136013 -300.82525) (xy 297.183284 -300.838942) (xy 297.227746 -300.86004) (xy 297.268249 -300.887996)
			(xy 297.303742 -300.922088) (xy 297.333307 -300.961432) (xy 297.356178 -301.005009) (xy 297.371762 -301.05169)
			(xy 297.379657 -301.100267) (xy 297.380152 -301.124874) (xy 297.719 -301.124874) (xy 297.72296 -301.07582)
			(xy 297.734737 -301.028036) (xy 297.754028 -300.98276) (xy 297.780331 -300.941164) (xy 297.812966 -300.904327)
			(xy 297.851087 -300.873202) (xy 297.893708 -300.848595) (xy 297.939724 -300.831143) (xy 297.987943 -300.821299)
			(xy 298.037118 -300.819318) (xy 298.085973 -300.82525) (xy 298.133244 -300.838942) (xy 298.177706 -300.86004)
			(xy 298.218209 -300.887996) (xy 298.253702 -300.922088) (xy 298.283267 -300.961432) (xy 298.306138 -301.005009)
			(xy 298.321722 -301.05169) (xy 298.329617 -301.100267) (xy 298.330112 -301.124874) (xy 298.66896 -301.124874)
			(xy 298.67292 -301.07582) (xy 298.684697 -301.028036) (xy 298.703988 -300.98276) (xy 298.730291 -300.941164)
			(xy 298.762926 -300.904327) (xy 298.801047 -300.873202) (xy 298.843668 -300.848595) (xy 298.889684 -300.831143)
			(xy 298.937903 -300.821299) (xy 298.987078 -300.819318) (xy 299.035933 -300.82525) (xy 299.083204 -300.838942)
			(xy 299.127666 -300.86004) (xy 299.168169 -300.887996) (xy 299.203662 -300.922088) (xy 299.233227 -300.961432)
			(xy 299.256098 -301.005009) (xy 299.271682 -301.05169) (xy 299.279577 -301.100267) (xy 299.280072 -301.124874)
			(xy 299.61892 -301.124874) (xy 299.62288 -301.07582) (xy 299.634657 -301.028036) (xy 299.653948 -300.98276)
			(xy 299.680251 -300.941164) (xy 299.712886 -300.904327) (xy 299.751007 -300.873202) (xy 299.793628 -300.848595)
			(xy 299.839644 -300.831143) (xy 299.887863 -300.821299) (xy 299.937038 -300.819318) (xy 299.985893 -300.82525)
			(xy 300.033164 -300.838942) (xy 300.077626 -300.86004) (xy 300.118129 -300.887996) (xy 300.153622 -300.922088)
			(xy 300.183187 -300.961432) (xy 300.206058 -301.005009) (xy 300.221642 -301.05169) (xy 300.229537 -301.100267)
			(xy 300.230032 -301.124874) (xy 300.56888 -301.124874) (xy 300.57284 -301.07582) (xy 300.584617 -301.028036)
			(xy 300.603908 -300.98276) (xy 300.630211 -300.941164) (xy 300.662846 -300.904327) (xy 300.700967 -300.873202)
			(xy 300.743588 -300.848595) (xy 300.789604 -300.831143) (xy 300.837823 -300.821299) (xy 300.886998 -300.819318)
			(xy 300.935853 -300.82525) (xy 300.983124 -300.838942) (xy 301.027586 -300.86004) (xy 301.068089 -300.887996)
			(xy 301.103582 -300.922088) (xy 301.133147 -300.961432) (xy 301.156018 -301.005009) (xy 301.171602 -301.05169)
			(xy 301.179497 -301.100267) (xy 301.179992 -301.124874) (xy 301.519094 -301.124874) (xy 301.523054 -301.07582)
			(xy 301.534831 -301.028036) (xy 301.554122 -300.98276) (xy 301.580425 -300.941164) (xy 301.61306 -300.904327)
			(xy 301.651181 -300.873202) (xy 301.693802 -300.848595) (xy 301.739818 -300.831143) (xy 301.788037 -300.821299)
			(xy 301.837212 -300.819318) (xy 301.886067 -300.82525) (xy 301.933338 -300.838942) (xy 301.9778 -300.86004)
			(xy 302.018303 -300.887996) (xy 302.053796 -300.922088) (xy 302.083361 -300.961432) (xy 302.106232 -301.005009)
			(xy 302.121816 -301.05169) (xy 302.129711 -301.100267) (xy 302.130206 -301.124874) (xy 302.469054 -301.124874)
			(xy 302.473014 -301.07582) (xy 302.484791 -301.028036) (xy 302.504082 -300.98276) (xy 302.530385 -300.941164)
			(xy 302.56302 -300.904327) (xy 302.601141 -300.873202) (xy 302.643762 -300.848595) (xy 302.689778 -300.831143)
			(xy 302.737997 -300.821299) (xy 302.787172 -300.819318) (xy 302.836027 -300.82525) (xy 302.883298 -300.838942)
			(xy 302.92776 -300.86004) (xy 302.968263 -300.887996) (xy 303.003756 -300.922088) (xy 303.033321 -300.961432)
			(xy 303.056192 -301.005009) (xy 303.071776 -301.05169) (xy 303.079671 -301.100267) (xy 303.080166 -301.124874)
			(xy 303.419014 -301.124874) (xy 303.422974 -301.07582) (xy 303.434751 -301.028036) (xy 303.454042 -300.98276)
			(xy 303.480345 -300.941164) (xy 303.51298 -300.904327) (xy 303.551101 -300.873202) (xy 303.593722 -300.848595)
			(xy 303.639738 -300.831143) (xy 303.687957 -300.821299) (xy 303.737132 -300.819318) (xy 303.785987 -300.82525)
			(xy 303.833258 -300.838942) (xy 303.87772 -300.86004) (xy 303.918223 -300.887996) (xy 303.953716 -300.922088)
			(xy 303.983281 -300.961432) (xy 304.006152 -301.005009) (xy 304.021736 -301.05169) (xy 304.029631 -301.100267)
			(xy 304.030126 -301.124874) (xy 304.368974 -301.124874) (xy 304.372934 -301.07582) (xy 304.384711 -301.028036)
			(xy 304.404002 -300.98276) (xy 304.430305 -300.941164) (xy 304.46294 -300.904327) (xy 304.501061 -300.873202)
			(xy 304.543682 -300.848595) (xy 304.589698 -300.831143) (xy 304.637917 -300.821299) (xy 304.687092 -300.819318)
			(xy 304.735947 -300.82525) (xy 304.783218 -300.838942) (xy 304.82768 -300.86004) (xy 304.868183 -300.887996)
			(xy 304.903676 -300.922088) (xy 304.933241 -300.961432) (xy 304.956112 -301.005009) (xy 304.971696 -301.05169)
			(xy 304.979591 -301.100267) (xy 304.980086 -301.124874) (xy 305.318934 -301.124874) (xy 305.322894 -301.07582)
			(xy 305.334671 -301.028036) (xy 305.353962 -300.98276) (xy 305.380265 -300.941164) (xy 305.4129 -300.904327)
			(xy 305.451021 -300.873202) (xy 305.493642 -300.848595) (xy 305.539658 -300.831143) (xy 305.587877 -300.821299)
			(xy 305.637052 -300.819318) (xy 305.685907 -300.82525) (xy 305.733178 -300.838942) (xy 305.77764 -300.86004)
			(xy 305.818143 -300.887996) (xy 305.853636 -300.922088) (xy 305.883201 -300.961432) (xy 305.906072 -301.005009)
			(xy 305.921656 -301.05169) (xy 305.929551 -301.100267) (xy 305.930046 -301.124874) (xy 308.169068 -301.124874)
			(xy 308.173028 -301.07582) (xy 308.184805 -301.028036) (xy 308.204096 -300.98276) (xy 308.230399 -300.941164)
			(xy 308.263034 -300.904327) (xy 308.301155 -300.873202) (xy 308.343776 -300.848595) (xy 308.389792 -300.831143)
			(xy 308.438011 -300.821299) (xy 308.487186 -300.819318) (xy 308.536041 -300.82525) (xy 308.583312 -300.838942)
			(xy 308.627774 -300.86004) (xy 308.668277 -300.887996) (xy 308.70377 -300.922088) (xy 308.733335 -300.961432)
			(xy 308.756206 -301.005009) (xy 308.77179 -301.05169) (xy 308.779685 -301.100267) (xy 308.78018 -301.124874)
			(xy 309.119028 -301.124874) (xy 309.122988 -301.07582) (xy 309.134765 -301.028036) (xy 309.154056 -300.98276)
			(xy 309.180359 -300.941164) (xy 309.212994 -300.904327) (xy 309.251115 -300.873202) (xy 309.293736 -300.848595)
			(xy 309.339752 -300.831143) (xy 309.387971 -300.821299) (xy 309.437146 -300.819318) (xy 309.486001 -300.82525)
			(xy 309.533272 -300.838942) (xy 309.577734 -300.86004) (xy 309.618237 -300.887996) (xy 309.65373 -300.922088)
			(xy 309.683295 -300.961432) (xy 309.706166 -301.005009) (xy 309.72175 -301.05169) (xy 309.729645 -301.100267)
			(xy 309.73014 -301.124874) (xy 310.068988 -301.124874) (xy 310.072948 -301.07582) (xy 310.084725 -301.028036)
			(xy 310.104016 -300.98276) (xy 310.130319 -300.941164) (xy 310.162954 -300.904327) (xy 310.201075 -300.873202)
			(xy 310.243696 -300.848595) (xy 310.289712 -300.831143) (xy 310.337931 -300.821299) (xy 310.387106 -300.819318)
			(xy 310.435961 -300.82525) (xy 310.483232 -300.838942) (xy 310.527694 -300.86004) (xy 310.568197 -300.887996)
			(xy 310.60369 -300.922088) (xy 310.633255 -300.961432) (xy 310.656126 -301.005009) (xy 310.67171 -301.05169)
			(xy 310.679605 -301.100267) (xy 310.6801 -301.124874) (xy 311.018948 -301.124874) (xy 311.022908 -301.07582)
			(xy 311.034685 -301.028036) (xy 311.053976 -300.98276) (xy 311.080279 -300.941164) (xy 311.112914 -300.904327)
			(xy 311.151035 -300.873202) (xy 311.193656 -300.848595) (xy 311.239672 -300.831143) (xy 311.287891 -300.821299)
			(xy 311.337066 -300.819318) (xy 311.385921 -300.82525) (xy 311.433192 -300.838942) (xy 311.477654 -300.86004)
			(xy 311.518157 -300.887996) (xy 311.55365 -300.922088) (xy 311.583215 -300.961432) (xy 311.606086 -301.005009)
			(xy 311.62167 -301.05169) (xy 311.629565 -301.100267) (xy 311.63006 -301.124874) (xy 311.968908 -301.124874)
			(xy 311.972868 -301.07582) (xy 311.984645 -301.028036) (xy 312.003936 -300.98276) (xy 312.030239 -300.941164)
			(xy 312.062874 -300.904327) (xy 312.100995 -300.873202) (xy 312.143616 -300.848595) (xy 312.189632 -300.831143)
			(xy 312.237851 -300.821299) (xy 312.287026 -300.819318) (xy 312.335881 -300.82525) (xy 312.383152 -300.838942)
			(xy 312.427614 -300.86004) (xy 312.468117 -300.887996) (xy 312.50361 -300.922088) (xy 312.533175 -300.961432)
			(xy 312.556046 -301.005009) (xy 312.57163 -301.05169) (xy 312.579525 -301.100267) (xy 312.58002 -301.124874)
			(xy 312.919122 -301.124874) (xy 312.923082 -301.07582) (xy 312.934859 -301.028036) (xy 312.95415 -300.98276)
			(xy 312.980453 -300.941164) (xy 313.013088 -300.904327) (xy 313.051209 -300.873202) (xy 313.09383 -300.848595)
			(xy 313.139846 -300.831143) (xy 313.188065 -300.821299) (xy 313.23724 -300.819318) (xy 313.286095 -300.82525)
			(xy 313.333366 -300.838942) (xy 313.377828 -300.86004) (xy 313.418331 -300.887996) (xy 313.453824 -300.922088)
			(xy 313.483389 -300.961432) (xy 313.50626 -301.005009) (xy 313.521844 -301.05169) (xy 313.529739 -301.100267)
			(xy 313.530234 -301.124874) (xy 313.869082 -301.124874) (xy 313.873042 -301.07582) (xy 313.884819 -301.028036)
			(xy 313.90411 -300.98276) (xy 313.930413 -300.941164) (xy 313.963048 -300.904327) (xy 314.001169 -300.873202)
			(xy 314.04379 -300.848595) (xy 314.089806 -300.831143) (xy 314.138025 -300.821299) (xy 314.1872 -300.819318)
			(xy 314.236055 -300.82525) (xy 314.283326 -300.838942) (xy 314.327788 -300.86004) (xy 314.368291 -300.887996)
			(xy 314.403784 -300.922088) (xy 314.433349 -300.961432) (xy 314.45622 -301.005009) (xy 314.471804 -301.05169)
			(xy 314.479699 -301.100267) (xy 314.480194 -301.124874) (xy 314.819042 -301.124874) (xy 314.823002 -301.07582)
			(xy 314.834779 -301.028036) (xy 314.85407 -300.98276) (xy 314.880373 -300.941164) (xy 314.913008 -300.904327)
			(xy 314.951129 -300.873202) (xy 314.99375 -300.848595) (xy 315.039766 -300.831143) (xy 315.087985 -300.821299)
			(xy 315.13716 -300.819318) (xy 315.186015 -300.82525) (xy 315.233286 -300.838942) (xy 315.277748 -300.86004)
			(xy 315.318251 -300.887996) (xy 315.353744 -300.922088) (xy 315.383309 -300.961432) (xy 315.40618 -301.005009)
			(xy 315.421764 -301.05169) (xy 315.429659 -301.100267) (xy 315.430154 -301.124874) (xy 315.429659 -301.149481)
			(xy 315.421764 -301.198058) (xy 315.40618 -301.244739) (xy 315.397103 -301.262034) (xy 317.57569 -301.262034)
			(xy 317.579761 -301.206412) (xy 317.591887 -301.151975) (xy 317.61181 -301.099884) (xy 317.639106 -301.051249)
			(xy 317.673192 -301.007106) (xy 317.713341 -300.968397) (xy 317.758699 -300.935946) (xy 317.808299 -300.910445)
			(xy 317.861083 -300.892438) (xy 317.915926 -300.882308) (xy 317.97166 -300.880271) (xy 318.027097 -300.886371)
			(xy 318.081054 -300.900477) (xy 318.132383 -300.922289) (xy 318.179989 -300.951343) (xy 318.222857 -300.987018)
			(xy 318.260074 -301.028555) (xy 318.269016 -301.04207) (xy 322.517006 -301.04207) (xy 322.521077 -300.986448)
			(xy 322.533203 -300.932011) (xy 322.553126 -300.87992) (xy 322.580422 -300.831285) (xy 322.614508 -300.787142)
			(xy 322.654657 -300.748433) (xy 322.700015 -300.715982) (xy 322.749615 -300.690481) (xy 322.802399 -300.672474)
			(xy 322.857242 -300.662344) (xy 322.912976 -300.660307) (xy 322.968413 -300.666407) (xy 323.02237 -300.680513)
			(xy 323.073699 -300.702325) (xy 323.121305 -300.731379) (xy 323.164173 -300.767054) (xy 323.20139 -300.808591)
			(xy 323.232163 -300.855104) (xy 323.255835 -300.905601) (xy 323.271903 -300.959008) (xy 323.280023 -301.014184)
			(xy 323.280532 -301.04207) (xy 323.280379 -301.050452) (xy 324.89089 -301.050452) (xy 324.894961 -300.99483)
			(xy 324.907087 -300.940393) (xy 324.92701 -300.888302) (xy 324.954306 -300.839667) (xy 324.988392 -300.795524)
			(xy 325.028541 -300.756815) (xy 325.073899 -300.724364) (xy 325.123499 -300.698863) (xy 325.176283 -300.680856)
			(xy 325.231126 -300.670726) (xy 325.28686 -300.668689) (xy 325.342297 -300.674789) (xy 325.396254 -300.688895)
			(xy 325.447583 -300.710707) (xy 325.495189 -300.739761) (xy 325.538057 -300.775436) (xy 325.575274 -300.816973)
			(xy 325.606047 -300.863486) (xy 325.629719 -300.913983) (xy 325.645787 -300.96739) (xy 325.653907 -301.022566)
			(xy 325.654416 -301.050452) (xy 325.653907 -301.078338) (xy 325.645787 -301.133514) (xy 325.629719 -301.186921)
			(xy 325.606047 -301.237418) (xy 325.575274 -301.283931) (xy 325.538057 -301.325468) (xy 325.495189 -301.361143)
			(xy 325.447583 -301.390197) (xy 325.396254 -301.412009) (xy 325.342297 -301.426115) (xy 325.28686 -301.432215)
			(xy 325.231126 -301.430178) (xy 325.176283 -301.420048) (xy 325.123499 -301.402041) (xy 325.073899 -301.37654)
			(xy 325.028541 -301.344089) (xy 324.988392 -301.30538) (xy 324.954306 -301.261237) (xy 324.92701 -301.212602)
			(xy 324.907087 -301.160511) (xy 324.894961 -301.106074) (xy 324.89089 -301.050452) (xy 323.280379 -301.050452)
			(xy 323.280023 -301.069956) (xy 323.271903 -301.125132) (xy 323.255835 -301.178539) (xy 323.232163 -301.229036)
			(xy 323.20139 -301.275549) (xy 323.164173 -301.317086) (xy 323.121305 -301.352761) (xy 323.073699 -301.381815)
			(xy 323.02237 -301.403627) (xy 322.968413 -301.417733) (xy 322.912976 -301.423833) (xy 322.857242 -301.421796)
			(xy 322.802399 -301.411666) (xy 322.749615 -301.393659) (xy 322.700015 -301.368158) (xy 322.654657 -301.335707)
			(xy 322.614508 -301.296998) (xy 322.580422 -301.252855) (xy 322.553126 -301.20422) (xy 322.533203 -301.152129)
			(xy 322.521077 -301.097692) (xy 322.517006 -301.04207) (xy 318.269016 -301.04207) (xy 318.290847 -301.075068)
			(xy 318.314519 -301.125565) (xy 318.330587 -301.178972) (xy 318.338707 -301.234148) (xy 318.339216 -301.262034)
			(xy 318.338707 -301.28992) (xy 318.330587 -301.345096) (xy 318.314519 -301.398503) (xy 318.290847 -301.449)
			(xy 318.260074 -301.495513) (xy 318.222857 -301.53705) (xy 318.179989 -301.572725) (xy 318.132383 -301.601779)
			(xy 318.081054 -301.623591) (xy 318.027097 -301.637697) (xy 317.97166 -301.643797) (xy 317.915926 -301.64176)
			(xy 317.861083 -301.63163) (xy 317.808299 -301.613623) (xy 317.758699 -301.588122) (xy 317.713341 -301.555671)
			(xy 317.673192 -301.516962) (xy 317.639106 -301.472819) (xy 317.61181 -301.424184) (xy 317.591887 -301.372093)
			(xy 317.579761 -301.317656) (xy 317.57569 -301.262034) (xy 315.397103 -301.262034) (xy 315.383309 -301.288316)
			(xy 315.353744 -301.32766) (xy 315.318251 -301.361752) (xy 315.277748 -301.389708) (xy 315.233286 -301.410806)
			(xy 315.186015 -301.424498) (xy 315.13716 -301.43043) (xy 315.087985 -301.428449) (xy 315.039766 -301.418605)
			(xy 314.99375 -301.401153) (xy 314.951129 -301.376546) (xy 314.913008 -301.345421) (xy 314.880373 -301.308584)
			(xy 314.85407 -301.266988) (xy 314.834779 -301.221712) (xy 314.823002 -301.173928) (xy 314.819042 -301.124874)
			(xy 314.480194 -301.124874) (xy 314.479699 -301.149481) (xy 314.471804 -301.198058) (xy 314.45622 -301.244739)
			(xy 314.433349 -301.288316) (xy 314.403784 -301.32766) (xy 314.368291 -301.361752) (xy 314.327788 -301.389708)
			(xy 314.283326 -301.410806) (xy 314.236055 -301.424498) (xy 314.1872 -301.43043) (xy 314.138025 -301.428449)
			(xy 314.089806 -301.418605) (xy 314.04379 -301.401153) (xy 314.001169 -301.376546) (xy 313.963048 -301.345421)
			(xy 313.930413 -301.308584) (xy 313.90411 -301.266988) (xy 313.884819 -301.221712) (xy 313.873042 -301.173928)
			(xy 313.869082 -301.124874) (xy 313.530234 -301.124874) (xy 313.529739 -301.149481) (xy 313.521844 -301.198058)
			(xy 313.50626 -301.244739) (xy 313.483389 -301.288316) (xy 313.453824 -301.32766) (xy 313.418331 -301.361752)
			(xy 313.377828 -301.389708) (xy 313.333366 -301.410806) (xy 313.286095 -301.424498) (xy 313.23724 -301.43043)
			(xy 313.188065 -301.428449) (xy 313.139846 -301.418605) (xy 313.09383 -301.401153) (xy 313.051209 -301.376546)
			(xy 313.013088 -301.345421) (xy 312.980453 -301.308584) (xy 312.95415 -301.266988) (xy 312.934859 -301.221712)
			(xy 312.923082 -301.173928) (xy 312.919122 -301.124874) (xy 312.58002 -301.124874) (xy 312.579525 -301.149481)
			(xy 312.57163 -301.198058) (xy 312.556046 -301.244739) (xy 312.533175 -301.288316) (xy 312.50361 -301.32766)
			(xy 312.468117 -301.361752) (xy 312.427614 -301.389708) (xy 312.383152 -301.410806) (xy 312.335881 -301.424498)
			(xy 312.287026 -301.43043) (xy 312.237851 -301.428449) (xy 312.189632 -301.418605) (xy 312.143616 -301.401153)
			(xy 312.100995 -301.376546) (xy 312.062874 -301.345421) (xy 312.030239 -301.308584) (xy 312.003936 -301.266988)
			(xy 311.984645 -301.221712) (xy 311.972868 -301.173928) (xy 311.968908 -301.124874) (xy 311.63006 -301.124874)
			(xy 311.629565 -301.149481) (xy 311.62167 -301.198058) (xy 311.606086 -301.244739) (xy 311.583215 -301.288316)
			(xy 311.55365 -301.32766) (xy 311.518157 -301.361752) (xy 311.477654 -301.389708) (xy 311.433192 -301.410806)
			(xy 311.385921 -301.424498) (xy 311.337066 -301.43043) (xy 311.287891 -301.428449) (xy 311.239672 -301.418605)
			(xy 311.193656 -301.401153) (xy 311.151035 -301.376546) (xy 311.112914 -301.345421) (xy 311.080279 -301.308584)
			(xy 311.053976 -301.266988) (xy 311.034685 -301.221712) (xy 311.022908 -301.173928) (xy 311.018948 -301.124874)
			(xy 310.6801 -301.124874) (xy 310.679605 -301.149481) (xy 310.67171 -301.198058) (xy 310.656126 -301.244739)
			(xy 310.633255 -301.288316) (xy 310.60369 -301.32766) (xy 310.568197 -301.361752) (xy 310.527694 -301.389708)
			(xy 310.483232 -301.410806) (xy 310.435961 -301.424498) (xy 310.387106 -301.43043) (xy 310.337931 -301.428449)
			(xy 310.289712 -301.418605) (xy 310.243696 -301.401153) (xy 310.201075 -301.376546) (xy 310.162954 -301.345421)
			(xy 310.130319 -301.308584) (xy 310.104016 -301.266988) (xy 310.084725 -301.221712) (xy 310.072948 -301.173928)
			(xy 310.068988 -301.124874) (xy 309.73014 -301.124874) (xy 309.729645 -301.149481) (xy 309.72175 -301.198058)
			(xy 309.706166 -301.244739) (xy 309.683295 -301.288316) (xy 309.65373 -301.32766) (xy 309.618237 -301.361752)
			(xy 309.577734 -301.389708) (xy 309.533272 -301.410806) (xy 309.486001 -301.424498) (xy 309.437146 -301.43043)
			(xy 309.387971 -301.428449) (xy 309.339752 -301.418605) (xy 309.293736 -301.401153) (xy 309.251115 -301.376546)
			(xy 309.212994 -301.345421) (xy 309.180359 -301.308584) (xy 309.154056 -301.266988) (xy 309.134765 -301.221712)
			(xy 309.122988 -301.173928) (xy 309.119028 -301.124874) (xy 308.78018 -301.124874) (xy 308.779685 -301.149481)
			(xy 308.77179 -301.198058) (xy 308.756206 -301.244739) (xy 308.733335 -301.288316) (xy 308.70377 -301.32766)
			(xy 308.668277 -301.361752) (xy 308.627774 -301.389708) (xy 308.583312 -301.410806) (xy 308.536041 -301.424498)
			(xy 308.487186 -301.43043) (xy 308.438011 -301.428449) (xy 308.389792 -301.418605) (xy 308.343776 -301.401153)
			(xy 308.301155 -301.376546) (xy 308.263034 -301.345421) (xy 308.230399 -301.308584) (xy 308.204096 -301.266988)
			(xy 308.184805 -301.221712) (xy 308.173028 -301.173928) (xy 308.169068 -301.124874) (xy 305.930046 -301.124874)
			(xy 305.929551 -301.149481) (xy 305.921656 -301.198058) (xy 305.906072 -301.244739) (xy 305.883201 -301.288316)
			(xy 305.853636 -301.32766) (xy 305.818143 -301.361752) (xy 305.77764 -301.389708) (xy 305.733178 -301.410806)
			(xy 305.685907 -301.424498) (xy 305.637052 -301.43043) (xy 305.587877 -301.428449) (xy 305.539658 -301.418605)
			(xy 305.493642 -301.401153) (xy 305.451021 -301.376546) (xy 305.4129 -301.345421) (xy 305.380265 -301.308584)
			(xy 305.353962 -301.266988) (xy 305.334671 -301.221712) (xy 305.322894 -301.173928) (xy 305.318934 -301.124874)
			(xy 304.980086 -301.124874) (xy 304.979591 -301.149481) (xy 304.971696 -301.198058) (xy 304.956112 -301.244739)
			(xy 304.933241 -301.288316) (xy 304.903676 -301.32766) (xy 304.868183 -301.361752) (xy 304.82768 -301.389708)
			(xy 304.783218 -301.410806) (xy 304.735947 -301.424498) (xy 304.687092 -301.43043) (xy 304.637917 -301.428449)
			(xy 304.589698 -301.418605) (xy 304.543682 -301.401153) (xy 304.501061 -301.376546) (xy 304.46294 -301.345421)
			(xy 304.430305 -301.308584) (xy 304.404002 -301.266988) (xy 304.384711 -301.221712) (xy 304.372934 -301.173928)
			(xy 304.368974 -301.124874) (xy 304.030126 -301.124874) (xy 304.029631 -301.149481) (xy 304.021736 -301.198058)
			(xy 304.006152 -301.244739) (xy 303.983281 -301.288316) (xy 303.953716 -301.32766) (xy 303.918223 -301.361752)
			(xy 303.87772 -301.389708) (xy 303.833258 -301.410806) (xy 303.785987 -301.424498) (xy 303.737132 -301.43043)
			(xy 303.687957 -301.428449) (xy 303.639738 -301.418605) (xy 303.593722 -301.401153) (xy 303.551101 -301.376546)
			(xy 303.51298 -301.345421) (xy 303.480345 -301.308584) (xy 303.454042 -301.266988) (xy 303.434751 -301.221712)
			(xy 303.422974 -301.173928) (xy 303.419014 -301.124874) (xy 303.080166 -301.124874) (xy 303.079671 -301.149481)
			(xy 303.071776 -301.198058) (xy 303.056192 -301.244739) (xy 303.033321 -301.288316) (xy 303.003756 -301.32766)
			(xy 302.968263 -301.361752) (xy 302.92776 -301.389708) (xy 302.883298 -301.410806) (xy 302.836027 -301.424498)
			(xy 302.787172 -301.43043) (xy 302.737997 -301.428449) (xy 302.689778 -301.418605) (xy 302.643762 -301.401153)
			(xy 302.601141 -301.376546) (xy 302.56302 -301.345421) (xy 302.530385 -301.308584) (xy 302.504082 -301.266988)
			(xy 302.484791 -301.221712) (xy 302.473014 -301.173928) (xy 302.469054 -301.124874) (xy 302.130206 -301.124874)
			(xy 302.129711 -301.149481) (xy 302.121816 -301.198058) (xy 302.106232 -301.244739) (xy 302.083361 -301.288316)
			(xy 302.053796 -301.32766) (xy 302.018303 -301.361752) (xy 301.9778 -301.389708) (xy 301.933338 -301.410806)
			(xy 301.886067 -301.424498) (xy 301.837212 -301.43043) (xy 301.788037 -301.428449) (xy 301.739818 -301.418605)
			(xy 301.693802 -301.401153) (xy 301.651181 -301.376546) (xy 301.61306 -301.345421) (xy 301.580425 -301.308584)
			(xy 301.554122 -301.266988) (xy 301.534831 -301.221712) (xy 301.523054 -301.173928) (xy 301.519094 -301.124874)
			(xy 301.179992 -301.124874) (xy 301.179497 -301.149481) (xy 301.171602 -301.198058) (xy 301.156018 -301.244739)
			(xy 301.133147 -301.288316) (xy 301.103582 -301.32766) (xy 301.068089 -301.361752) (xy 301.027586 -301.389708)
			(xy 300.983124 -301.410806) (xy 300.935853 -301.424498) (xy 300.886998 -301.43043) (xy 300.837823 -301.428449)
			(xy 300.789604 -301.418605) (xy 300.743588 -301.401153) (xy 300.700967 -301.376546) (xy 300.662846 -301.345421)
			(xy 300.630211 -301.308584) (xy 300.603908 -301.266988) (xy 300.584617 -301.221712) (xy 300.57284 -301.173928)
			(xy 300.56888 -301.124874) (xy 300.230032 -301.124874) (xy 300.229537 -301.149481) (xy 300.221642 -301.198058)
			(xy 300.206058 -301.244739) (xy 300.183187 -301.288316) (xy 300.153622 -301.32766) (xy 300.118129 -301.361752)
			(xy 300.077626 -301.389708) (xy 300.033164 -301.410806) (xy 299.985893 -301.424498) (xy 299.937038 -301.43043)
			(xy 299.887863 -301.428449) (xy 299.839644 -301.418605) (xy 299.793628 -301.401153) (xy 299.751007 -301.376546)
			(xy 299.712886 -301.345421) (xy 299.680251 -301.308584) (xy 299.653948 -301.266988) (xy 299.634657 -301.221712)
			(xy 299.62288 -301.173928) (xy 299.61892 -301.124874) (xy 299.280072 -301.124874) (xy 299.279577 -301.149481)
			(xy 299.271682 -301.198058) (xy 299.256098 -301.244739) (xy 299.233227 -301.288316) (xy 299.203662 -301.32766)
			(xy 299.168169 -301.361752) (xy 299.127666 -301.389708) (xy 299.083204 -301.410806) (xy 299.035933 -301.424498)
			(xy 298.987078 -301.43043) (xy 298.937903 -301.428449) (xy 298.889684 -301.418605) (xy 298.843668 -301.401153)
			(xy 298.801047 -301.376546) (xy 298.762926 -301.345421) (xy 298.730291 -301.308584) (xy 298.703988 -301.266988)
			(xy 298.684697 -301.221712) (xy 298.67292 -301.173928) (xy 298.66896 -301.124874) (xy 298.330112 -301.124874)
			(xy 298.329617 -301.149481) (xy 298.321722 -301.198058) (xy 298.306138 -301.244739) (xy 298.283267 -301.288316)
			(xy 298.253702 -301.32766) (xy 298.218209 -301.361752) (xy 298.177706 -301.389708) (xy 298.133244 -301.410806)
			(xy 298.085973 -301.424498) (xy 298.037118 -301.43043) (xy 297.987943 -301.428449) (xy 297.939724 -301.418605)
			(xy 297.893708 -301.401153) (xy 297.851087 -301.376546) (xy 297.812966 -301.345421) (xy 297.780331 -301.308584)
			(xy 297.754028 -301.266988) (xy 297.734737 -301.221712) (xy 297.72296 -301.173928) (xy 297.719 -301.124874)
			(xy 297.380152 -301.124874) (xy 297.379657 -301.149481) (xy 297.371762 -301.198058) (xy 297.356178 -301.244739)
			(xy 297.333307 -301.288316) (xy 297.303742 -301.32766) (xy 297.268249 -301.361752) (xy 297.227746 -301.389708)
			(xy 297.183284 -301.410806) (xy 297.136013 -301.424498) (xy 297.087158 -301.43043) (xy 297.037983 -301.428449)
			(xy 296.989764 -301.418605) (xy 296.943748 -301.401153) (xy 296.901127 -301.376546) (xy 296.863006 -301.345421)
			(xy 296.830371 -301.308584) (xy 296.804068 -301.266988) (xy 296.784777 -301.221712) (xy 296.773 -301.173928)
			(xy 296.76904 -301.124874) (xy 296.430192 -301.124874) (xy 296.429697 -301.149481) (xy 296.421802 -301.198058)
			(xy 296.406218 -301.244739) (xy 296.383347 -301.288316) (xy 296.353782 -301.32766) (xy 296.318289 -301.361752)
			(xy 296.277786 -301.389708) (xy 296.233324 -301.410806) (xy 296.186053 -301.424498) (xy 296.137198 -301.43043)
			(xy 296.088023 -301.428449) (xy 296.039804 -301.418605) (xy 295.993788 -301.401153) (xy 295.951167 -301.376546)
			(xy 295.913046 -301.345421) (xy 295.880411 -301.308584) (xy 295.854108 -301.266988) (xy 295.834817 -301.221712)
			(xy 295.82304 -301.173928) (xy 295.81908 -301.124874) (xy 295.480232 -301.124874) (xy 295.479737 -301.149481)
			(xy 295.471842 -301.198058) (xy 295.456258 -301.244739) (xy 295.433387 -301.288316) (xy 295.403822 -301.32766)
			(xy 295.368329 -301.361752) (xy 295.327826 -301.389708) (xy 295.283364 -301.410806) (xy 295.236093 -301.424498)
			(xy 295.187238 -301.43043) (xy 295.138063 -301.428449) (xy 295.089844 -301.418605) (xy 295.043828 -301.401153)
			(xy 295.001207 -301.376546) (xy 294.963086 -301.345421) (xy 294.930451 -301.308584) (xy 294.904148 -301.266988)
			(xy 294.884857 -301.221712) (xy 294.87308 -301.173928) (xy 294.86912 -301.124874) (xy 294.530018 -301.124874)
			(xy 294.529523 -301.149481) (xy 294.521628 -301.198058) (xy 294.506044 -301.244739) (xy 294.483173 -301.288316)
			(xy 294.453608 -301.32766) (xy 294.418115 -301.361752) (xy 294.377612 -301.389708) (xy 294.33315 -301.410806)
			(xy 294.285879 -301.424498) (xy 294.237024 -301.43043) (xy 294.187849 -301.428449) (xy 294.13963 -301.418605)
			(xy 294.093614 -301.401153) (xy 294.050993 -301.376546) (xy 294.012872 -301.345421) (xy 293.980237 -301.308584)
			(xy 293.953934 -301.266988) (xy 293.934643 -301.221712) (xy 293.922866 -301.173928) (xy 293.918906 -301.124874)
			(xy 293.580058 -301.124874) (xy 293.579563 -301.149481) (xy 293.571668 -301.198058) (xy 293.556084 -301.244739)
			(xy 293.533213 -301.288316) (xy 293.503648 -301.32766) (xy 293.468155 -301.361752) (xy 293.427652 -301.389708)
			(xy 293.38319 -301.410806) (xy 293.335919 -301.424498) (xy 293.287064 -301.43043) (xy 293.237889 -301.428449)
			(xy 293.18967 -301.418605) (xy 293.143654 -301.401153) (xy 293.101033 -301.376546) (xy 293.062912 -301.345421)
			(xy 293.030277 -301.308584) (xy 293.003974 -301.266988) (xy 292.984683 -301.221712) (xy 292.972906 -301.173928)
			(xy 292.968946 -301.124874) (xy 292.630098 -301.124874) (xy 292.629603 -301.149481) (xy 292.621708 -301.198058)
			(xy 292.606124 -301.244739) (xy 292.583253 -301.288316) (xy 292.553688 -301.32766) (xy 292.518195 -301.361752)
			(xy 292.477692 -301.389708) (xy 292.43323 -301.410806) (xy 292.385959 -301.424498) (xy 292.337104 -301.43043)
			(xy 292.287929 -301.428449) (xy 292.23971 -301.418605) (xy 292.193694 -301.401153) (xy 292.151073 -301.376546)
			(xy 292.112952 -301.345421) (xy 292.080317 -301.308584) (xy 292.054014 -301.266988) (xy 292.034723 -301.221712)
			(xy 292.022946 -301.173928) (xy 292.018986 -301.124874) (xy 290.730178 -301.124874) (xy 290.729683 -301.149481)
			(xy 290.721788 -301.198058) (xy 290.706204 -301.244739) (xy 290.683333 -301.288316) (xy 290.653768 -301.32766)
			(xy 290.618275 -301.361752) (xy 290.577772 -301.389708) (xy 290.53331 -301.410806) (xy 290.486039 -301.424498)
			(xy 290.437184 -301.43043) (xy 290.388009 -301.428449) (xy 290.33979 -301.418605) (xy 290.293774 -301.401153)
			(xy 290.251153 -301.376546) (xy 290.213032 -301.345421) (xy 290.180397 -301.308584) (xy 290.154094 -301.266988)
			(xy 290.134803 -301.221712) (xy 290.123026 -301.173928) (xy 290.119066 -301.124874) (xy 289.780218 -301.124874)
			(xy 289.779723 -301.149481) (xy 289.771828 -301.198058) (xy 289.756244 -301.244739) (xy 289.733373 -301.288316)
			(xy 289.703808 -301.32766) (xy 289.668315 -301.361752) (xy 289.627812 -301.389708) (xy 289.58335 -301.410806)
			(xy 289.536079 -301.424498) (xy 289.487224 -301.43043) (xy 289.438049 -301.428449) (xy 289.38983 -301.418605)
			(xy 289.343814 -301.401153) (xy 289.301193 -301.376546) (xy 289.263072 -301.345421) (xy 289.230437 -301.308584)
			(xy 289.204134 -301.266988) (xy 289.184843 -301.221712) (xy 289.173066 -301.173928) (xy 289.169106 -301.124874)
			(xy 288.830004 -301.124874) (xy 288.829509 -301.149481) (xy 288.821614 -301.198058) (xy 288.80603 -301.244739)
			(xy 288.783159 -301.288316) (xy 288.753594 -301.32766) (xy 288.718101 -301.361752) (xy 288.677598 -301.389708)
			(xy 288.633136 -301.410806) (xy 288.585865 -301.424498) (xy 288.53701 -301.43043) (xy 288.487835 -301.428449)
			(xy 288.439616 -301.418605) (xy 288.3936 -301.401153) (xy 288.350979 -301.376546) (xy 288.312858 -301.345421)
			(xy 288.280223 -301.308584) (xy 288.25392 -301.266988) (xy 288.234629 -301.221712) (xy 288.222852 -301.173928)
			(xy 288.218892 -301.124874) (xy 287.880044 -301.124874) (xy 287.879549 -301.149481) (xy 287.871654 -301.198058)
			(xy 287.85607 -301.244739) (xy 287.833199 -301.288316) (xy 287.803634 -301.32766) (xy 287.768141 -301.361752)
			(xy 287.727638 -301.389708) (xy 287.683176 -301.410806) (xy 287.635905 -301.424498) (xy 287.58705 -301.43043)
			(xy 287.537875 -301.428449) (xy 287.489656 -301.418605) (xy 287.44364 -301.401153) (xy 287.401019 -301.376546)
			(xy 287.362898 -301.345421) (xy 287.330263 -301.308584) (xy 287.30396 -301.266988) (xy 287.284669 -301.221712)
			(xy 287.272892 -301.173928) (xy 287.268932 -301.124874) (xy 286.930084 -301.124874) (xy 286.929589 -301.149481)
			(xy 286.921694 -301.198058) (xy 286.90611 -301.244739) (xy 286.883239 -301.288316) (xy 286.853674 -301.32766)
			(xy 286.818181 -301.361752) (xy 286.777678 -301.389708) (xy 286.733216 -301.410806) (xy 286.685945 -301.424498)
			(xy 286.63709 -301.43043) (xy 286.587915 -301.428449) (xy 286.539696 -301.418605) (xy 286.49368 -301.401153)
			(xy 286.451059 -301.376546) (xy 286.412938 -301.345421) (xy 286.380303 -301.308584) (xy 286.354 -301.266988)
			(xy 286.334709 -301.221712) (xy 286.322932 -301.173928) (xy 286.318972 -301.124874) (xy 285.980124 -301.124874)
			(xy 285.979629 -301.149481) (xy 285.971734 -301.198058) (xy 285.95615 -301.244739) (xy 285.933279 -301.288316)
			(xy 285.903714 -301.32766) (xy 285.868221 -301.361752) (xy 285.827718 -301.389708) (xy 285.783256 -301.410806)
			(xy 285.735985 -301.424498) (xy 285.68713 -301.43043) (xy 285.637955 -301.428449) (xy 285.589736 -301.418605)
			(xy 285.54372 -301.401153) (xy 285.501099 -301.376546) (xy 285.462978 -301.345421) (xy 285.430343 -301.308584)
			(xy 285.40404 -301.266988) (xy 285.384749 -301.221712) (xy 285.372972 -301.173928) (xy 285.369012 -301.124874)
			(xy 285.030164 -301.124874) (xy 285.029669 -301.149481) (xy 285.021774 -301.198058) (xy 285.00619 -301.244739)
			(xy 284.983319 -301.288316) (xy 284.953754 -301.32766) (xy 284.918261 -301.361752) (xy 284.877758 -301.389708)
			(xy 284.833296 -301.410806) (xy 284.786025 -301.424498) (xy 284.73717 -301.43043) (xy 284.687995 -301.428449)
			(xy 284.639776 -301.418605) (xy 284.59376 -301.401153) (xy 284.551139 -301.376546) (xy 284.513018 -301.345421)
			(xy 284.480383 -301.308584) (xy 284.45408 -301.266988) (xy 284.434789 -301.221712) (xy 284.423012 -301.173928)
			(xy 284.419052 -301.124874) (xy 284.080204 -301.124874) (xy 284.079709 -301.149481) (xy 284.071814 -301.198058)
			(xy 284.05623 -301.244739) (xy 284.033359 -301.288316) (xy 284.003794 -301.32766) (xy 283.968301 -301.361752)
			(xy 283.927798 -301.389708) (xy 283.883336 -301.410806) (xy 283.836065 -301.424498) (xy 283.78721 -301.43043)
			(xy 283.738035 -301.428449) (xy 283.689816 -301.418605) (xy 283.6438 -301.401153) (xy 283.601179 -301.376546)
			(xy 283.563058 -301.345421) (xy 283.530423 -301.308584) (xy 283.50412 -301.266988) (xy 283.484829 -301.221712)
			(xy 283.473052 -301.173928) (xy 283.469092 -301.124874) (xy 283.130244 -301.124874) (xy 283.129749 -301.149481)
			(xy 283.121854 -301.198058) (xy 283.10627 -301.244739) (xy 283.083399 -301.288316) (xy 283.053834 -301.32766)
			(xy 283.018341 -301.361752) (xy 282.977838 -301.389708) (xy 282.933376 -301.410806) (xy 282.886105 -301.424498)
			(xy 282.83725 -301.43043) (xy 282.788075 -301.428449) (xy 282.739856 -301.418605) (xy 282.69384 -301.401153)
			(xy 282.651219 -301.376546) (xy 282.613098 -301.345421) (xy 282.580463 -301.308584) (xy 282.55416 -301.266988)
			(xy 282.534869 -301.221712) (xy 282.523092 -301.173928) (xy 282.519132 -301.124874) (xy 282.18003 -301.124874)
			(xy 282.179535 -301.149481) (xy 282.17164 -301.198058) (xy 282.156056 -301.244739) (xy 282.133185 -301.288316)
			(xy 282.10362 -301.32766) (xy 282.068127 -301.361752) (xy 282.027624 -301.389708) (xy 281.983162 -301.410806)
			(xy 281.935891 -301.424498) (xy 281.887036 -301.43043) (xy 281.837861 -301.428449) (xy 281.789642 -301.418605)
			(xy 281.743626 -301.401153) (xy 281.701005 -301.376546) (xy 281.662884 -301.345421) (xy 281.630249 -301.308584)
			(xy 281.603946 -301.266988) (xy 281.584655 -301.221712) (xy 281.572878 -301.173928) (xy 281.568918 -301.124874)
			(xy 280.28011 -301.124874) (xy 280.28011 -301.141384) (xy 280.279602 -301.147226) (xy 280.279602 -301.147734)
			(xy 280.278332 -301.158656) (xy 280.278332 -301.15891) (xy 280.277824 -301.162974) (xy 280.275284 -301.18177)
			(xy 280.274268 -301.187358) (xy 280.270204 -301.203106) (xy 280.268426 -301.215806) (xy 280.268426 -302.074834)
			(xy 281.568918 -302.074834) (xy 281.572878 -302.02578) (xy 281.584655 -301.977996) (xy 281.603946 -301.93272)
			(xy 281.630249 -301.891124) (xy 281.662884 -301.854287) (xy 281.701005 -301.823162) (xy 281.743626 -301.798555)
			(xy 281.789642 -301.781103) (xy 281.837861 -301.771259) (xy 281.887036 -301.769278) (xy 281.935891 -301.77521)
			(xy 281.983162 -301.788902) (xy 282.027624 -301.81) (xy 282.068127 -301.837956) (xy 282.10362 -301.872048)
			(xy 282.133185 -301.911392) (xy 282.156056 -301.954969) (xy 282.17164 -302.00165) (xy 282.179535 -302.050227)
			(xy 282.18003 -302.074834) (xy 282.519132 -302.074834) (xy 282.523092 -302.02578) (xy 282.534869 -301.977996)
			(xy 282.55416 -301.93272) (xy 282.580463 -301.891124) (xy 282.613098 -301.854287) (xy 282.651219 -301.823162)
			(xy 282.69384 -301.798555) (xy 282.739856 -301.781103) (xy 282.788075 -301.771259) (xy 282.83725 -301.769278)
			(xy 282.886105 -301.77521) (xy 282.933376 -301.788902) (xy 282.977838 -301.81) (xy 283.018341 -301.837956)
			(xy 283.053834 -301.872048) (xy 283.083399 -301.911392) (xy 283.10627 -301.954969) (xy 283.121854 -302.00165)
			(xy 283.129749 -302.050227) (xy 283.130244 -302.074834) (xy 283.469092 -302.074834) (xy 283.473052 -302.02578)
			(xy 283.484829 -301.977996) (xy 283.50412 -301.93272) (xy 283.530423 -301.891124) (xy 283.563058 -301.854287)
			(xy 283.601179 -301.823162) (xy 283.6438 -301.798555) (xy 283.689816 -301.781103) (xy 283.738035 -301.771259)
			(xy 283.78721 -301.769278) (xy 283.836065 -301.77521) (xy 283.883336 -301.788902) (xy 283.927798 -301.81)
			(xy 283.968301 -301.837956) (xy 284.003794 -301.872048) (xy 284.033359 -301.911392) (xy 284.05623 -301.954969)
			(xy 284.071814 -302.00165) (xy 284.079709 -302.050227) (xy 284.080204 -302.074834) (xy 284.419052 -302.074834)
			(xy 284.423012 -302.02578) (xy 284.434789 -301.977996) (xy 284.45408 -301.93272) (xy 284.480383 -301.891124)
			(xy 284.513018 -301.854287) (xy 284.551139 -301.823162) (xy 284.59376 -301.798555) (xy 284.639776 -301.781103)
			(xy 284.687995 -301.771259) (xy 284.73717 -301.769278) (xy 284.786025 -301.77521) (xy 284.833296 -301.788902)
			(xy 284.877758 -301.81) (xy 284.918261 -301.837956) (xy 284.953754 -301.872048) (xy 284.983319 -301.911392)
			(xy 285.00619 -301.954969) (xy 285.021774 -302.00165) (xy 285.029669 -302.050227) (xy 285.030164 -302.074834)
			(xy 285.369012 -302.074834) (xy 285.372972 -302.02578) (xy 285.384749 -301.977996) (xy 285.40404 -301.93272)
			(xy 285.430343 -301.891124) (xy 285.462978 -301.854287) (xy 285.501099 -301.823162) (xy 285.54372 -301.798555)
			(xy 285.589736 -301.781103) (xy 285.637955 -301.771259) (xy 285.68713 -301.769278) (xy 285.735985 -301.77521)
			(xy 285.783256 -301.788902) (xy 285.827718 -301.81) (xy 285.868221 -301.837956) (xy 285.903714 -301.872048)
			(xy 285.933279 -301.911392) (xy 285.95615 -301.954969) (xy 285.971734 -302.00165) (xy 285.979629 -302.050227)
			(xy 285.980124 -302.074834) (xy 286.318972 -302.074834) (xy 286.322932 -302.02578) (xy 286.334709 -301.977996)
			(xy 286.354 -301.93272) (xy 286.380303 -301.891124) (xy 286.412938 -301.854287) (xy 286.451059 -301.823162)
			(xy 286.49368 -301.798555) (xy 286.539696 -301.781103) (xy 286.587915 -301.771259) (xy 286.63709 -301.769278)
			(xy 286.685945 -301.77521) (xy 286.733216 -301.788902) (xy 286.777678 -301.81) (xy 286.818181 -301.837956)
			(xy 286.853674 -301.872048) (xy 286.883239 -301.911392) (xy 286.90611 -301.954969) (xy 286.921694 -302.00165)
			(xy 286.929589 -302.050227) (xy 286.930084 -302.074834) (xy 287.268932 -302.074834) (xy 287.272892 -302.02578)
			(xy 287.284669 -301.977996) (xy 287.30396 -301.93272) (xy 287.330263 -301.891124) (xy 287.362898 -301.854287)
			(xy 287.401019 -301.823162) (xy 287.44364 -301.798555) (xy 287.489656 -301.781103) (xy 287.537875 -301.771259)
			(xy 287.58705 -301.769278) (xy 287.635905 -301.77521) (xy 287.683176 -301.788902) (xy 287.727638 -301.81)
			(xy 287.768141 -301.837956) (xy 287.803634 -301.872048) (xy 287.833199 -301.911392) (xy 287.85607 -301.954969)
			(xy 287.871654 -302.00165) (xy 287.879549 -302.050227) (xy 287.880044 -302.074834) (xy 288.218892 -302.074834)
			(xy 288.222852 -302.02578) (xy 288.234629 -301.977996) (xy 288.25392 -301.93272) (xy 288.280223 -301.891124)
			(xy 288.312858 -301.854287) (xy 288.350979 -301.823162) (xy 288.3936 -301.798555) (xy 288.439616 -301.781103)
			(xy 288.487835 -301.771259) (xy 288.53701 -301.769278) (xy 288.585865 -301.77521) (xy 288.633136 -301.788902)
			(xy 288.677598 -301.81) (xy 288.718101 -301.837956) (xy 288.753594 -301.872048) (xy 288.783159 -301.911392)
			(xy 288.80603 -301.954969) (xy 288.821614 -302.00165) (xy 288.829509 -302.050227) (xy 288.830004 -302.074834)
			(xy 289.169106 -302.074834) (xy 289.173066 -302.02578) (xy 289.184843 -301.977996) (xy 289.204134 -301.93272)
			(xy 289.230437 -301.891124) (xy 289.263072 -301.854287) (xy 289.301193 -301.823162) (xy 289.343814 -301.798555)
			(xy 289.38983 -301.781103) (xy 289.438049 -301.771259) (xy 289.487224 -301.769278) (xy 289.536079 -301.77521)
			(xy 289.58335 -301.788902) (xy 289.627812 -301.81) (xy 289.668315 -301.837956) (xy 289.703808 -301.872048)
			(xy 289.733373 -301.911392) (xy 289.756244 -301.954969) (xy 289.771828 -302.00165) (xy 289.779723 -302.050227)
			(xy 289.780218 -302.074834) (xy 290.119066 -302.074834) (xy 290.123026 -302.02578) (xy 290.134803 -301.977996)
			(xy 290.154094 -301.93272) (xy 290.180397 -301.891124) (xy 290.213032 -301.854287) (xy 290.251153 -301.823162)
			(xy 290.293774 -301.798555) (xy 290.33979 -301.781103) (xy 290.388009 -301.771259) (xy 290.437184 -301.769278)
			(xy 290.486039 -301.77521) (xy 290.53331 -301.788902) (xy 290.577772 -301.81) (xy 290.618275 -301.837956)
			(xy 290.653768 -301.872048) (xy 290.683333 -301.911392) (xy 290.706204 -301.954969) (xy 290.721788 -302.00165)
			(xy 290.729683 -302.050227) (xy 290.730178 -302.074834) (xy 292.018986 -302.074834) (xy 292.022946 -302.02578)
			(xy 292.034723 -301.977996) (xy 292.054014 -301.93272) (xy 292.080317 -301.891124) (xy 292.112952 -301.854287)
			(xy 292.151073 -301.823162) (xy 292.193694 -301.798555) (xy 292.23971 -301.781103) (xy 292.287929 -301.771259)
			(xy 292.337104 -301.769278) (xy 292.385959 -301.77521) (xy 292.43323 -301.788902) (xy 292.477692 -301.81)
			(xy 292.518195 -301.837956) (xy 292.553688 -301.872048) (xy 292.583253 -301.911392) (xy 292.606124 -301.954969)
			(xy 292.621708 -302.00165) (xy 292.629603 -302.050227) (xy 292.630098 -302.074834) (xy 292.968946 -302.074834)
			(xy 292.972906 -302.02578) (xy 292.984683 -301.977996) (xy 293.003974 -301.93272) (xy 293.030277 -301.891124)
			(xy 293.062912 -301.854287) (xy 293.101033 -301.823162) (xy 293.143654 -301.798555) (xy 293.18967 -301.781103)
			(xy 293.237889 -301.771259) (xy 293.287064 -301.769278) (xy 293.335919 -301.77521) (xy 293.38319 -301.788902)
			(xy 293.427652 -301.81) (xy 293.468155 -301.837956) (xy 293.503648 -301.872048) (xy 293.533213 -301.911392)
			(xy 293.556084 -301.954969) (xy 293.571668 -302.00165) (xy 293.579563 -302.050227) (xy 293.580058 -302.074834)
			(xy 293.918906 -302.074834) (xy 293.922866 -302.02578) (xy 293.934643 -301.977996) (xy 293.953934 -301.93272)
			(xy 293.980237 -301.891124) (xy 294.012872 -301.854287) (xy 294.050993 -301.823162) (xy 294.093614 -301.798555)
			(xy 294.13963 -301.781103) (xy 294.187849 -301.771259) (xy 294.237024 -301.769278) (xy 294.285879 -301.77521)
			(xy 294.33315 -301.788902) (xy 294.377612 -301.81) (xy 294.418115 -301.837956) (xy 294.453608 -301.872048)
			(xy 294.483173 -301.911392) (xy 294.506044 -301.954969) (xy 294.521628 -302.00165) (xy 294.529523 -302.050227)
			(xy 294.530018 -302.074834) (xy 294.86912 -302.074834) (xy 294.87308 -302.02578) (xy 294.884857 -301.977996)
			(xy 294.904148 -301.93272) (xy 294.930451 -301.891124) (xy 294.963086 -301.854287) (xy 295.001207 -301.823162)
			(xy 295.043828 -301.798555) (xy 295.089844 -301.781103) (xy 295.138063 -301.771259) (xy 295.187238 -301.769278)
			(xy 295.236093 -301.77521) (xy 295.283364 -301.788902) (xy 295.327826 -301.81) (xy 295.368329 -301.837956)
			(xy 295.403822 -301.872048) (xy 295.433387 -301.911392) (xy 295.456258 -301.954969) (xy 295.471842 -302.00165)
			(xy 295.479737 -302.050227) (xy 295.480232 -302.074834) (xy 295.81908 -302.074834) (xy 295.82304 -302.02578)
			(xy 295.834817 -301.977996) (xy 295.854108 -301.93272) (xy 295.880411 -301.891124) (xy 295.913046 -301.854287)
			(xy 295.951167 -301.823162) (xy 295.993788 -301.798555) (xy 296.039804 -301.781103) (xy 296.088023 -301.771259)
			(xy 296.137198 -301.769278) (xy 296.186053 -301.77521) (xy 296.233324 -301.788902) (xy 296.277786 -301.81)
			(xy 296.318289 -301.837956) (xy 296.353782 -301.872048) (xy 296.383347 -301.911392) (xy 296.406218 -301.954969)
			(xy 296.421802 -302.00165) (xy 296.429697 -302.050227) (xy 296.430192 -302.074834) (xy 296.76904 -302.074834)
			(xy 296.773 -302.02578) (xy 296.784777 -301.977996) (xy 296.804068 -301.93272) (xy 296.830371 -301.891124)
			(xy 296.863006 -301.854287) (xy 296.901127 -301.823162) (xy 296.943748 -301.798555) (xy 296.989764 -301.781103)
			(xy 297.037983 -301.771259) (xy 297.087158 -301.769278) (xy 297.136013 -301.77521) (xy 297.183284 -301.788902)
			(xy 297.227746 -301.81) (xy 297.268249 -301.837956) (xy 297.303742 -301.872048) (xy 297.333307 -301.911392)
			(xy 297.356178 -301.954969) (xy 297.371762 -302.00165) (xy 297.379657 -302.050227) (xy 297.380152 -302.074834)
			(xy 297.719 -302.074834) (xy 297.72296 -302.02578) (xy 297.734737 -301.977996) (xy 297.754028 -301.93272)
			(xy 297.780331 -301.891124) (xy 297.812966 -301.854287) (xy 297.851087 -301.823162) (xy 297.893708 -301.798555)
			(xy 297.939724 -301.781103) (xy 297.987943 -301.771259) (xy 298.037118 -301.769278) (xy 298.085973 -301.77521)
			(xy 298.133244 -301.788902) (xy 298.177706 -301.81) (xy 298.218209 -301.837956) (xy 298.253702 -301.872048)
			(xy 298.283267 -301.911392) (xy 298.306138 -301.954969) (xy 298.321722 -302.00165) (xy 298.329617 -302.050227)
			(xy 298.330112 -302.074834) (xy 298.66896 -302.074834) (xy 298.67292 -302.02578) (xy 298.684697 -301.977996)
			(xy 298.703988 -301.93272) (xy 298.730291 -301.891124) (xy 298.762926 -301.854287) (xy 298.801047 -301.823162)
			(xy 298.843668 -301.798555) (xy 298.889684 -301.781103) (xy 298.937903 -301.771259) (xy 298.987078 -301.769278)
			(xy 299.035933 -301.77521) (xy 299.083204 -301.788902) (xy 299.127666 -301.81) (xy 299.168169 -301.837956)
			(xy 299.203662 -301.872048) (xy 299.233227 -301.911392) (xy 299.256098 -301.954969) (xy 299.271682 -302.00165)
			(xy 299.279577 -302.050227) (xy 299.280072 -302.074834) (xy 299.61892 -302.074834) (xy 299.62288 -302.02578)
			(xy 299.634657 -301.977996) (xy 299.653948 -301.93272) (xy 299.680251 -301.891124) (xy 299.712886 -301.854287)
			(xy 299.751007 -301.823162) (xy 299.793628 -301.798555) (xy 299.839644 -301.781103) (xy 299.887863 -301.771259)
			(xy 299.937038 -301.769278) (xy 299.985893 -301.77521) (xy 300.033164 -301.788902) (xy 300.077626 -301.81)
			(xy 300.118129 -301.837956) (xy 300.153622 -301.872048) (xy 300.183187 -301.911392) (xy 300.206058 -301.954969)
			(xy 300.221642 -302.00165) (xy 300.229537 -302.050227) (xy 300.230032 -302.074834) (xy 300.56888 -302.074834)
			(xy 300.57284 -302.02578) (xy 300.584617 -301.977996) (xy 300.603908 -301.93272) (xy 300.630211 -301.891124)
			(xy 300.662846 -301.854287) (xy 300.700967 -301.823162) (xy 300.743588 -301.798555) (xy 300.789604 -301.781103)
			(xy 300.837823 -301.771259) (xy 300.886998 -301.769278) (xy 300.935853 -301.77521) (xy 300.983124 -301.788902)
			(xy 301.027586 -301.81) (xy 301.068089 -301.837956) (xy 301.103582 -301.872048) (xy 301.133147 -301.911392)
			(xy 301.156018 -301.954969) (xy 301.171602 -302.00165) (xy 301.179497 -302.050227) (xy 301.179992 -302.074834)
			(xy 301.519094 -302.074834) (xy 301.523054 -302.02578) (xy 301.534831 -301.977996) (xy 301.554122 -301.93272)
			(xy 301.580425 -301.891124) (xy 301.61306 -301.854287) (xy 301.651181 -301.823162) (xy 301.693802 -301.798555)
			(xy 301.739818 -301.781103) (xy 301.788037 -301.771259) (xy 301.837212 -301.769278) (xy 301.886067 -301.77521)
			(xy 301.933338 -301.788902) (xy 301.9778 -301.81) (xy 302.018303 -301.837956) (xy 302.053796 -301.872048)
			(xy 302.083361 -301.911392) (xy 302.106232 -301.954969) (xy 302.121816 -302.00165) (xy 302.129711 -302.050227)
			(xy 302.130206 -302.074834) (xy 302.469054 -302.074834) (xy 302.473014 -302.02578) (xy 302.484791 -301.977996)
			(xy 302.504082 -301.93272) (xy 302.530385 -301.891124) (xy 302.56302 -301.854287) (xy 302.601141 -301.823162)
			(xy 302.643762 -301.798555) (xy 302.689778 -301.781103) (xy 302.737997 -301.771259) (xy 302.787172 -301.769278)
			(xy 302.836027 -301.77521) (xy 302.883298 -301.788902) (xy 302.92776 -301.81) (xy 302.968263 -301.837956)
			(xy 303.003756 -301.872048) (xy 303.033321 -301.911392) (xy 303.056192 -301.954969) (xy 303.071776 -302.00165)
			(xy 303.079671 -302.050227) (xy 303.080166 -302.074834) (xy 303.419014 -302.074834) (xy 303.422974 -302.02578)
			(xy 303.434751 -301.977996) (xy 303.454042 -301.93272) (xy 303.480345 -301.891124) (xy 303.51298 -301.854287)
			(xy 303.551101 -301.823162) (xy 303.593722 -301.798555) (xy 303.639738 -301.781103) (xy 303.687957 -301.771259)
			(xy 303.737132 -301.769278) (xy 303.785987 -301.77521) (xy 303.833258 -301.788902) (xy 303.87772 -301.81)
			(xy 303.918223 -301.837956) (xy 303.953716 -301.872048) (xy 303.983281 -301.911392) (xy 304.006152 -301.954969)
			(xy 304.021736 -302.00165) (xy 304.029631 -302.050227) (xy 304.030126 -302.074834) (xy 304.368974 -302.074834)
			(xy 304.372934 -302.02578) (xy 304.384711 -301.977996) (xy 304.404002 -301.93272) (xy 304.430305 -301.891124)
			(xy 304.46294 -301.854287) (xy 304.501061 -301.823162) (xy 304.543682 -301.798555) (xy 304.589698 -301.781103)
			(xy 304.637917 -301.771259) (xy 304.687092 -301.769278) (xy 304.735947 -301.77521) (xy 304.783218 -301.788902)
			(xy 304.82768 -301.81) (xy 304.868183 -301.837956) (xy 304.903676 -301.872048) (xy 304.933241 -301.911392)
			(xy 304.956112 -301.954969) (xy 304.971696 -302.00165) (xy 304.979591 -302.050227) (xy 304.980086 -302.074834)
			(xy 305.318934 -302.074834) (xy 305.322894 -302.02578) (xy 305.334671 -301.977996) (xy 305.353962 -301.93272)
			(xy 305.380265 -301.891124) (xy 305.4129 -301.854287) (xy 305.451021 -301.823162) (xy 305.493642 -301.798555)
			(xy 305.539658 -301.781103) (xy 305.587877 -301.771259) (xy 305.637052 -301.769278) (xy 305.685907 -301.77521)
			(xy 305.733178 -301.788902) (xy 305.77764 -301.81) (xy 305.818143 -301.837956) (xy 305.853636 -301.872048)
			(xy 305.883201 -301.911392) (xy 305.906072 -301.954969) (xy 305.921656 -302.00165) (xy 305.929551 -302.050227)
			(xy 305.930046 -302.074834) (xy 306.268894 -302.074834) (xy 306.272854 -302.02578) (xy 306.284631 -301.977996)
			(xy 306.303922 -301.93272) (xy 306.330225 -301.891124) (xy 306.36286 -301.854287) (xy 306.400981 -301.823162)
			(xy 306.443602 -301.798555) (xy 306.489618 -301.781103) (xy 306.537837 -301.771259) (xy 306.587012 -301.769278)
			(xy 306.635867 -301.77521) (xy 306.683138 -301.788902) (xy 306.7276 -301.81) (xy 306.768103 -301.837956)
			(xy 306.803596 -301.872048) (xy 306.833161 -301.911392) (xy 306.856032 -301.954969) (xy 306.871616 -302.00165)
			(xy 306.879511 -302.050227) (xy 306.880006 -302.074834) (xy 307.219108 -302.074834) (xy 307.223068 -302.02578)
			(xy 307.234845 -301.977996) (xy 307.254136 -301.93272) (xy 307.280439 -301.891124) (xy 307.313074 -301.854287)
			(xy 307.351195 -301.823162) (xy 307.393816 -301.798555) (xy 307.439832 -301.781103) (xy 307.488051 -301.771259)
			(xy 307.537226 -301.769278) (xy 307.586081 -301.77521) (xy 307.633352 -301.788902) (xy 307.677814 -301.81)
			(xy 307.718317 -301.837956) (xy 307.75381 -301.872048) (xy 307.783375 -301.911392) (xy 307.806246 -301.954969)
			(xy 307.82183 -302.00165) (xy 307.829725 -302.050227) (xy 307.83022 -302.074834) (xy 308.169068 -302.074834)
			(xy 308.173028 -302.02578) (xy 308.184805 -301.977996) (xy 308.204096 -301.93272) (xy 308.230399 -301.891124)
			(xy 308.263034 -301.854287) (xy 308.301155 -301.823162) (xy 308.343776 -301.798555) (xy 308.389792 -301.781103)
			(xy 308.438011 -301.771259) (xy 308.487186 -301.769278) (xy 308.536041 -301.77521) (xy 308.583312 -301.788902)
			(xy 308.627774 -301.81) (xy 308.668277 -301.837956) (xy 308.70377 -301.872048) (xy 308.733335 -301.911392)
			(xy 308.756206 -301.954969) (xy 308.77179 -302.00165) (xy 308.779685 -302.050227) (xy 308.78018 -302.074834)
			(xy 309.119028 -302.074834) (xy 309.122988 -302.02578) (xy 309.134765 -301.977996) (xy 309.154056 -301.93272)
			(xy 309.180359 -301.891124) (xy 309.212994 -301.854287) (xy 309.251115 -301.823162) (xy 309.293736 -301.798555)
			(xy 309.339752 -301.781103) (xy 309.387971 -301.771259) (xy 309.437146 -301.769278) (xy 309.486001 -301.77521)
			(xy 309.533272 -301.788902) (xy 309.577734 -301.81) (xy 309.618237 -301.837956) (xy 309.65373 -301.872048)
			(xy 309.683295 -301.911392) (xy 309.706166 -301.954969) (xy 309.72175 -302.00165) (xy 309.729645 -302.050227)
			(xy 309.73014 -302.074834) (xy 310.068988 -302.074834) (xy 310.072948 -302.02578) (xy 310.084725 -301.977996)
			(xy 310.104016 -301.93272) (xy 310.130319 -301.891124) (xy 310.162954 -301.854287) (xy 310.201075 -301.823162)
			(xy 310.243696 -301.798555) (xy 310.289712 -301.781103) (xy 310.337931 -301.771259) (xy 310.387106 -301.769278)
			(xy 310.435961 -301.77521) (xy 310.483232 -301.788902) (xy 310.527694 -301.81) (xy 310.568197 -301.837956)
			(xy 310.60369 -301.872048) (xy 310.633255 -301.911392) (xy 310.656126 -301.954969) (xy 310.67171 -302.00165)
			(xy 310.679605 -302.050227) (xy 310.6801 -302.074834) (xy 311.018948 -302.074834) (xy 311.022908 -302.02578)
			(xy 311.034685 -301.977996) (xy 311.053976 -301.93272) (xy 311.080279 -301.891124) (xy 311.112914 -301.854287)
			(xy 311.151035 -301.823162) (xy 311.193656 -301.798555) (xy 311.239672 -301.781103) (xy 311.287891 -301.771259)
			(xy 311.337066 -301.769278) (xy 311.385921 -301.77521) (xy 311.433192 -301.788902) (xy 311.477654 -301.81)
			(xy 311.518157 -301.837956) (xy 311.55365 -301.872048) (xy 311.583215 -301.911392) (xy 311.606086 -301.954969)
			(xy 311.62167 -302.00165) (xy 311.629565 -302.050227) (xy 311.63006 -302.074834) (xy 311.968908 -302.074834)
			(xy 311.972868 -302.02578) (xy 311.984645 -301.977996) (xy 312.003936 -301.93272) (xy 312.030239 -301.891124)
			(xy 312.062874 -301.854287) (xy 312.100995 -301.823162) (xy 312.143616 -301.798555) (xy 312.189632 -301.781103)
			(xy 312.237851 -301.771259) (xy 312.287026 -301.769278) (xy 312.335881 -301.77521) (xy 312.383152 -301.788902)
			(xy 312.427614 -301.81) (xy 312.468117 -301.837956) (xy 312.50361 -301.872048) (xy 312.533175 -301.911392)
			(xy 312.556046 -301.954969) (xy 312.57163 -302.00165) (xy 312.579525 -302.050227) (xy 312.58002 -302.074834)
			(xy 312.919122 -302.074834) (xy 312.923082 -302.02578) (xy 312.934859 -301.977996) (xy 312.95415 -301.93272)
			(xy 312.980453 -301.891124) (xy 313.013088 -301.854287) (xy 313.051209 -301.823162) (xy 313.09383 -301.798555)
			(xy 313.139846 -301.781103) (xy 313.188065 -301.771259) (xy 313.23724 -301.769278) (xy 313.286095 -301.77521)
			(xy 313.333366 -301.788902) (xy 313.377828 -301.81) (xy 313.418331 -301.837956) (xy 313.453824 -301.872048)
			(xy 313.483389 -301.911392) (xy 313.50626 -301.954969) (xy 313.521844 -302.00165) (xy 313.529739 -302.050227)
			(xy 313.530234 -302.074834) (xy 313.869082 -302.074834) (xy 313.873042 -302.02578) (xy 313.884819 -301.977996)
			(xy 313.90411 -301.93272) (xy 313.930413 -301.891124) (xy 313.963048 -301.854287) (xy 314.001169 -301.823162)
			(xy 314.04379 -301.798555) (xy 314.089806 -301.781103) (xy 314.138025 -301.771259) (xy 314.1872 -301.769278)
			(xy 314.236055 -301.77521) (xy 314.283326 -301.788902) (xy 314.327788 -301.81) (xy 314.368291 -301.837956)
			(xy 314.403784 -301.872048) (xy 314.433349 -301.911392) (xy 314.45622 -301.954969) (xy 314.471804 -302.00165)
			(xy 314.479699 -302.050227) (xy 314.480194 -302.074834) (xy 314.819042 -302.074834) (xy 314.823002 -302.02578)
			(xy 314.834779 -301.977996) (xy 314.85407 -301.93272) (xy 314.880373 -301.891124) (xy 314.913008 -301.854287)
			(xy 314.951129 -301.823162) (xy 314.99375 -301.798555) (xy 315.039766 -301.781103) (xy 315.087985 -301.771259)
			(xy 315.13716 -301.769278) (xy 315.186015 -301.77521) (xy 315.233286 -301.788902) (xy 315.277748 -301.81)
			(xy 315.318251 -301.837956) (xy 315.348333 -301.866851) (xy 318.548485 -301.866851) (xy 318.548485 -301.812349)
			(xy 318.556242 -301.758401) (xy 318.571597 -301.706106) (xy 318.594239 -301.656529) (xy 318.623706 -301.610679)
			(xy 318.659398 -301.569489) (xy 318.700589 -301.533799) (xy 318.74644 -301.504333) (xy 318.796018 -301.481693)
			(xy 318.848313 -301.466339) (xy 318.902261 -301.458584) (xy 318.929512 -301.458122) (xy 318.958713 -301.458699)
			(xy 319.016433 -301.467594) (xy 319.07212 -301.485191) (xy 319.124471 -301.511077) (xy 319.17226 -301.544646)
			(xy 319.214369 -301.585112) (xy 319.232534 -301.607982) (xy 319.241381 -301.618749) (xy 319.263653 -301.63548)
			(xy 319.289615 -301.645572) (xy 319.317339 -301.648275) (xy 319.344762 -301.64339) (xy 319.369846 -301.631278)
			(xy 319.390726 -301.61284) (xy 319.39865 -301.601378) (xy 319.413795 -301.57882) (xy 319.449486 -301.537853)
			(xy 319.490628 -301.502365) (xy 319.53639 -301.473073) (xy 319.585845 -301.450571) (xy 319.637993 -301.435314)
			(xy 319.691777 -301.427611) (xy 319.718944 -301.427134) (xy 319.746196 -301.427539) (xy 319.800145 -301.435301)
			(xy 319.85244 -301.450662) (xy 319.902017 -301.473308) (xy 319.947867 -301.502779) (xy 319.989057 -301.538474)
			(xy 320.001305 -301.55261) (xy 320.319652 -301.55261) (xy 320.323723 -301.496988) (xy 320.335849 -301.442551)
			(xy 320.355772 -301.39046) (xy 320.383068 -301.341825) (xy 320.417154 -301.297682) (xy 320.457303 -301.258973)
			(xy 320.502661 -301.226522) (xy 320.552261 -301.201021) (xy 320.605045 -301.183014) (xy 320.659888 -301.172884)
			(xy 320.715622 -301.170847) (xy 320.771059 -301.176947) (xy 320.825016 -301.191053) (xy 320.876345 -301.212865)
			(xy 320.923951 -301.241919) (xy 320.966819 -301.277594) (xy 321.004036 -301.319131) (xy 321.034809 -301.365644)
			(xy 321.058481 -301.416141) (xy 321.074549 -301.469548) (xy 321.082669 -301.524724) (xy 321.083178 -301.55261)
			(xy 321.083099 -301.556928) (xy 323.713092 -301.556928) (xy 323.717163 -301.501306) (xy 323.729289 -301.446869)
			(xy 323.749212 -301.394778) (xy 323.776508 -301.346143) (xy 323.810594 -301.302) (xy 323.850743 -301.263291)
			(xy 323.896101 -301.23084) (xy 323.945701 -301.205339) (xy 323.998485 -301.187332) (xy 324.053328 -301.177202)
			(xy 324.109062 -301.175165) (xy 324.164499 -301.181265) (xy 324.218456 -301.195371) (xy 324.269785 -301.217183)
			(xy 324.317391 -301.246237) (xy 324.360259 -301.281912) (xy 324.397476 -301.323449) (xy 324.428249 -301.369962)
			(xy 324.451921 -301.420459) (xy 324.467989 -301.473866) (xy 324.476109 -301.529042) (xy 324.476618 -301.556928)
			(xy 324.476109 -301.584814) (xy 324.467989 -301.63999) (xy 324.451921 -301.693397) (xy 324.428249 -301.743894)
			(xy 324.397476 -301.790407) (xy 324.360259 -301.831944) (xy 324.317391 -301.867619) (xy 324.269785 -301.896673)
			(xy 324.218456 -301.918485) (xy 324.164499 -301.932591) (xy 324.109062 -301.938691) (xy 324.053328 -301.936654)
			(xy 323.998485 -301.926524) (xy 323.945701 -301.908517) (xy 323.896101 -301.883016) (xy 323.850743 -301.850565)
			(xy 323.810594 -301.811856) (xy 323.776508 -301.767713) (xy 323.749212 -301.719078) (xy 323.729289 -301.666987)
			(xy 323.717163 -301.61255) (xy 323.713092 -301.556928) (xy 321.083099 -301.556928) (xy 321.082669 -301.580496)
			(xy 321.074549 -301.635672) (xy 321.058481 -301.689079) (xy 321.034809 -301.739576) (xy 321.004036 -301.786089)
			(xy 320.966819 -301.827626) (xy 320.923951 -301.863301) (xy 320.876345 -301.892355) (xy 320.825016 -301.914167)
			(xy 320.771059 -301.928273) (xy 320.715622 -301.934373) (xy 320.659888 -301.932336) (xy 320.605045 -301.922206)
			(xy 320.552261 -301.904199) (xy 320.502661 -301.878698) (xy 320.457303 -301.846247) (xy 320.417154 -301.807538)
			(xy 320.383068 -301.763395) (xy 320.355772 -301.71476) (xy 320.335849 -301.662669) (xy 320.323723 -301.608232)
			(xy 320.319652 -301.55261) (xy 320.001305 -301.55261) (xy 320.024748 -301.579668) (xy 320.054213 -301.625521)
			(xy 320.076853 -301.675101) (xy 320.092208 -301.727398) (xy 320.099964 -301.781348) (xy 320.099964 -301.835852)
			(xy 320.092208 -301.889802) (xy 320.076853 -301.942099) (xy 320.054213 -301.991679) (xy 320.024748 -302.037532)
			(xy 319.989057 -302.078726) (xy 319.947867 -302.114421) (xy 319.902017 -302.143892) (xy 319.85244 -302.166538)
			(xy 319.800145 -302.181899) (xy 319.746196 -302.189661) (xy 319.718944 -302.19015) (xy 319.689742 -302.189616)
			(xy 319.632019 -302.180713) (xy 319.576331 -302.163108) (xy 319.52398 -302.137215) (xy 319.476192 -302.103638)
			(xy 319.434085 -302.063164) (xy 319.415922 -302.04029) (xy 319.407123 -302.029481) (xy 319.384839 -302.012756)
			(xy 319.358866 -302.00267) (xy 319.331134 -301.999973) (xy 319.303704 -302.004866) (xy 319.278615 -302.016984)
			(xy 319.257731 -302.035429) (xy 319.249806 -302.046894) (xy 319.234649 -302.069443) (xy 319.198957 -302.110407)
			(xy 319.157816 -302.145893) (xy 319.112056 -302.175184) (xy 319.062604 -302.197688) (xy 319.01046 -302.212948)
			(xy 318.956678 -302.220658) (xy 318.929512 -302.221138) (xy 318.902261 -302.220616) (xy 318.848313 -302.212861)
			(xy 318.796018 -302.197507) (xy 318.74644 -302.174867) (xy 318.700589 -302.145401) (xy 318.659398 -302.109711)
			(xy 318.623706 -302.068521) (xy 318.594239 -302.022671) (xy 318.571597 -301.973094) (xy 318.556242 -301.920799)
			(xy 318.548485 -301.866851) (xy 315.348333 -301.866851) (xy 315.353744 -301.872048) (xy 315.383309 -301.911392)
			(xy 315.40618 -301.954969) (xy 315.421764 -302.00165) (xy 315.429659 -302.050227) (xy 315.430154 -302.074834)
			(xy 315.429659 -302.099441) (xy 315.421764 -302.148018) (xy 315.40618 -302.194699) (xy 315.383309 -302.238276)
			(xy 315.353744 -302.27762) (xy 315.318251 -302.311712) (xy 315.277748 -302.339668) (xy 315.233286 -302.360766)
			(xy 315.186015 -302.374458) (xy 315.13716 -302.38039) (xy 315.087985 -302.378409) (xy 315.039766 -302.368565)
			(xy 314.99375 -302.351113) (xy 314.951129 -302.326506) (xy 314.913008 -302.295381) (xy 314.880373 -302.258544)
			(xy 314.85407 -302.216948) (xy 314.834779 -302.171672) (xy 314.823002 -302.123888) (xy 314.819042 -302.074834)
			(xy 314.480194 -302.074834) (xy 314.479699 -302.099441) (xy 314.471804 -302.148018) (xy 314.45622 -302.194699)
			(xy 314.433349 -302.238276) (xy 314.403784 -302.27762) (xy 314.368291 -302.311712) (xy 314.327788 -302.339668)
			(xy 314.283326 -302.360766) (xy 314.236055 -302.374458) (xy 314.1872 -302.38039) (xy 314.138025 -302.378409)
			(xy 314.089806 -302.368565) (xy 314.04379 -302.351113) (xy 314.001169 -302.326506) (xy 313.963048 -302.295381)
			(xy 313.930413 -302.258544) (xy 313.90411 -302.216948) (xy 313.884819 -302.171672) (xy 313.873042 -302.123888)
			(xy 313.869082 -302.074834) (xy 313.530234 -302.074834) (xy 313.529739 -302.099441) (xy 313.521844 -302.148018)
			(xy 313.50626 -302.194699) (xy 313.483389 -302.238276) (xy 313.453824 -302.27762) (xy 313.418331 -302.311712)
			(xy 313.377828 -302.339668) (xy 313.333366 -302.360766) (xy 313.286095 -302.374458) (xy 313.23724 -302.38039)
			(xy 313.188065 -302.378409) (xy 313.139846 -302.368565) (xy 313.09383 -302.351113) (xy 313.051209 -302.326506)
			(xy 313.013088 -302.295381) (xy 312.980453 -302.258544) (xy 312.95415 -302.216948) (xy 312.934859 -302.171672)
			(xy 312.923082 -302.123888) (xy 312.919122 -302.074834) (xy 312.58002 -302.074834) (xy 312.579525 -302.099441)
			(xy 312.57163 -302.148018) (xy 312.556046 -302.194699) (xy 312.533175 -302.238276) (xy 312.50361 -302.27762)
			(xy 312.468117 -302.311712) (xy 312.427614 -302.339668) (xy 312.383152 -302.360766) (xy 312.335881 -302.374458)
			(xy 312.287026 -302.38039) (xy 312.237851 -302.378409) (xy 312.189632 -302.368565) (xy 312.143616 -302.351113)
			(xy 312.100995 -302.326506) (xy 312.062874 -302.295381) (xy 312.030239 -302.258544) (xy 312.003936 -302.216948)
			(xy 311.984645 -302.171672) (xy 311.972868 -302.123888) (xy 311.968908 -302.074834) (xy 311.63006 -302.074834)
			(xy 311.629565 -302.099441) (xy 311.62167 -302.148018) (xy 311.606086 -302.194699) (xy 311.583215 -302.238276)
			(xy 311.55365 -302.27762) (xy 311.518157 -302.311712) (xy 311.477654 -302.339668) (xy 311.433192 -302.360766)
			(xy 311.385921 -302.374458) (xy 311.337066 -302.38039) (xy 311.287891 -302.378409) (xy 311.239672 -302.368565)
			(xy 311.193656 -302.351113) (xy 311.151035 -302.326506) (xy 311.112914 -302.295381) (xy 311.080279 -302.258544)
			(xy 311.053976 -302.216948) (xy 311.034685 -302.171672) (xy 311.022908 -302.123888) (xy 311.018948 -302.074834)
			(xy 310.6801 -302.074834) (xy 310.679605 -302.099441) (xy 310.67171 -302.148018) (xy 310.656126 -302.194699)
			(xy 310.633255 -302.238276) (xy 310.60369 -302.27762) (xy 310.568197 -302.311712) (xy 310.527694 -302.339668)
			(xy 310.483232 -302.360766) (xy 310.435961 -302.374458) (xy 310.387106 -302.38039) (xy 310.337931 -302.378409)
			(xy 310.289712 -302.368565) (xy 310.243696 -302.351113) (xy 310.201075 -302.326506) (xy 310.162954 -302.295381)
			(xy 310.130319 -302.258544) (xy 310.104016 -302.216948) (xy 310.084725 -302.171672) (xy 310.072948 -302.123888)
			(xy 310.068988 -302.074834) (xy 309.73014 -302.074834) (xy 309.729645 -302.099441) (xy 309.72175 -302.148018)
			(xy 309.706166 -302.194699) (xy 309.683295 -302.238276) (xy 309.65373 -302.27762) (xy 309.618237 -302.311712)
			(xy 309.577734 -302.339668) (xy 309.533272 -302.360766) (xy 309.486001 -302.374458) (xy 309.437146 -302.38039)
			(xy 309.387971 -302.378409) (xy 309.339752 -302.368565) (xy 309.293736 -302.351113) (xy 309.251115 -302.326506)
			(xy 309.212994 -302.295381) (xy 309.180359 -302.258544) (xy 309.154056 -302.216948) (xy 309.134765 -302.171672)
			(xy 309.122988 -302.123888) (xy 309.119028 -302.074834) (xy 308.78018 -302.074834) (xy 308.779685 -302.099441)
			(xy 308.77179 -302.148018) (xy 308.756206 -302.194699) (xy 308.733335 -302.238276) (xy 308.70377 -302.27762)
			(xy 308.668277 -302.311712) (xy 308.627774 -302.339668) (xy 308.583312 -302.360766) (xy 308.536041 -302.374458)
			(xy 308.487186 -302.38039) (xy 308.438011 -302.378409) (xy 308.389792 -302.368565) (xy 308.343776 -302.351113)
			(xy 308.301155 -302.326506) (xy 308.263034 -302.295381) (xy 308.230399 -302.258544) (xy 308.204096 -302.216948)
			(xy 308.184805 -302.171672) (xy 308.173028 -302.123888) (xy 308.169068 -302.074834) (xy 307.83022 -302.074834)
			(xy 307.829725 -302.099441) (xy 307.82183 -302.148018) (xy 307.806246 -302.194699) (xy 307.783375 -302.238276)
			(xy 307.75381 -302.27762) (xy 307.718317 -302.311712) (xy 307.677814 -302.339668) (xy 307.633352 -302.360766)
			(xy 307.586081 -302.374458) (xy 307.537226 -302.38039) (xy 307.488051 -302.378409) (xy 307.439832 -302.368565)
			(xy 307.393816 -302.351113) (xy 307.351195 -302.326506) (xy 307.313074 -302.295381) (xy 307.280439 -302.258544)
			(xy 307.254136 -302.216948) (xy 307.234845 -302.171672) (xy 307.223068 -302.123888) (xy 307.219108 -302.074834)
			(xy 306.880006 -302.074834) (xy 306.879511 -302.099441) (xy 306.871616 -302.148018) (xy 306.856032 -302.194699)
			(xy 306.833161 -302.238276) (xy 306.803596 -302.27762) (xy 306.768103 -302.311712) (xy 306.7276 -302.339668)
			(xy 306.683138 -302.360766) (xy 306.635867 -302.374458) (xy 306.587012 -302.38039) (xy 306.537837 -302.378409)
			(xy 306.489618 -302.368565) (xy 306.443602 -302.351113) (xy 306.400981 -302.326506) (xy 306.36286 -302.295381)
			(xy 306.330225 -302.258544) (xy 306.303922 -302.216948) (xy 306.284631 -302.171672) (xy 306.272854 -302.123888)
			(xy 306.268894 -302.074834) (xy 305.930046 -302.074834) (xy 305.929551 -302.099441) (xy 305.921656 -302.148018)
			(xy 305.906072 -302.194699) (xy 305.883201 -302.238276) (xy 305.853636 -302.27762) (xy 305.818143 -302.311712)
			(xy 305.77764 -302.339668) (xy 305.733178 -302.360766) (xy 305.685907 -302.374458) (xy 305.637052 -302.38039)
			(xy 305.587877 -302.378409) (xy 305.539658 -302.368565) (xy 305.493642 -302.351113) (xy 305.451021 -302.326506)
			(xy 305.4129 -302.295381) (xy 305.380265 -302.258544) (xy 305.353962 -302.216948) (xy 305.334671 -302.171672)
			(xy 305.322894 -302.123888) (xy 305.318934 -302.074834) (xy 304.980086 -302.074834) (xy 304.979591 -302.099441)
			(xy 304.971696 -302.148018) (xy 304.956112 -302.194699) (xy 304.933241 -302.238276) (xy 304.903676 -302.27762)
			(xy 304.868183 -302.311712) (xy 304.82768 -302.339668) (xy 304.783218 -302.360766) (xy 304.735947 -302.374458)
			(xy 304.687092 -302.38039) (xy 304.637917 -302.378409) (xy 304.589698 -302.368565) (xy 304.543682 -302.351113)
			(xy 304.501061 -302.326506) (xy 304.46294 -302.295381) (xy 304.430305 -302.258544) (xy 304.404002 -302.216948)
			(xy 304.384711 -302.171672) (xy 304.372934 -302.123888) (xy 304.368974 -302.074834) (xy 304.030126 -302.074834)
			(xy 304.029631 -302.099441) (xy 304.021736 -302.148018) (xy 304.006152 -302.194699) (xy 303.983281 -302.238276)
			(xy 303.953716 -302.27762) (xy 303.918223 -302.311712) (xy 303.87772 -302.339668) (xy 303.833258 -302.360766)
			(xy 303.785987 -302.374458) (xy 303.737132 -302.38039) (xy 303.687957 -302.378409) (xy 303.639738 -302.368565)
			(xy 303.593722 -302.351113) (xy 303.551101 -302.326506) (xy 303.51298 -302.295381) (xy 303.480345 -302.258544)
			(xy 303.454042 -302.216948) (xy 303.434751 -302.171672) (xy 303.422974 -302.123888) (xy 303.419014 -302.074834)
			(xy 303.080166 -302.074834) (xy 303.079671 -302.099441) (xy 303.071776 -302.148018) (xy 303.056192 -302.194699)
			(xy 303.033321 -302.238276) (xy 303.003756 -302.27762) (xy 302.968263 -302.311712) (xy 302.92776 -302.339668)
			(xy 302.883298 -302.360766) (xy 302.836027 -302.374458) (xy 302.787172 -302.38039) (xy 302.737997 -302.378409)
			(xy 302.689778 -302.368565) (xy 302.643762 -302.351113) (xy 302.601141 -302.326506) (xy 302.56302 -302.295381)
			(xy 302.530385 -302.258544) (xy 302.504082 -302.216948) (xy 302.484791 -302.171672) (xy 302.473014 -302.123888)
			(xy 302.469054 -302.074834) (xy 302.130206 -302.074834) (xy 302.129711 -302.099441) (xy 302.121816 -302.148018)
			(xy 302.106232 -302.194699) (xy 302.083361 -302.238276) (xy 302.053796 -302.27762) (xy 302.018303 -302.311712)
			(xy 301.9778 -302.339668) (xy 301.933338 -302.360766) (xy 301.886067 -302.374458) (xy 301.837212 -302.38039)
			(xy 301.788037 -302.378409) (xy 301.739818 -302.368565) (xy 301.693802 -302.351113) (xy 301.651181 -302.326506)
			(xy 301.61306 -302.295381) (xy 301.580425 -302.258544) (xy 301.554122 -302.216948) (xy 301.534831 -302.171672)
			(xy 301.523054 -302.123888) (xy 301.519094 -302.074834) (xy 301.179992 -302.074834) (xy 301.179497 -302.099441)
			(xy 301.171602 -302.148018) (xy 301.156018 -302.194699) (xy 301.133147 -302.238276) (xy 301.103582 -302.27762)
			(xy 301.068089 -302.311712) (xy 301.027586 -302.339668) (xy 300.983124 -302.360766) (xy 300.935853 -302.374458)
			(xy 300.886998 -302.38039) (xy 300.837823 -302.378409) (xy 300.789604 -302.368565) (xy 300.743588 -302.351113)
			(xy 300.700967 -302.326506) (xy 300.662846 -302.295381) (xy 300.630211 -302.258544) (xy 300.603908 -302.216948)
			(xy 300.584617 -302.171672) (xy 300.57284 -302.123888) (xy 300.56888 -302.074834) (xy 300.230032 -302.074834)
			(xy 300.229537 -302.099441) (xy 300.221642 -302.148018) (xy 300.206058 -302.194699) (xy 300.183187 -302.238276)
			(xy 300.153622 -302.27762) (xy 300.118129 -302.311712) (xy 300.077626 -302.339668) (xy 300.033164 -302.360766)
			(xy 299.985893 -302.374458) (xy 299.937038 -302.38039) (xy 299.887863 -302.378409) (xy 299.839644 -302.368565)
			(xy 299.793628 -302.351113) (xy 299.751007 -302.326506) (xy 299.712886 -302.295381) (xy 299.680251 -302.258544)
			(xy 299.653948 -302.216948) (xy 299.634657 -302.171672) (xy 299.62288 -302.123888) (xy 299.61892 -302.074834)
			(xy 299.280072 -302.074834) (xy 299.279577 -302.099441) (xy 299.271682 -302.148018) (xy 299.256098 -302.194699)
			(xy 299.233227 -302.238276) (xy 299.203662 -302.27762) (xy 299.168169 -302.311712) (xy 299.127666 -302.339668)
			(xy 299.083204 -302.360766) (xy 299.035933 -302.374458) (xy 298.987078 -302.38039) (xy 298.937903 -302.378409)
			(xy 298.889684 -302.368565) (xy 298.843668 -302.351113) (xy 298.801047 -302.326506) (xy 298.762926 -302.295381)
			(xy 298.730291 -302.258544) (xy 298.703988 -302.216948) (xy 298.684697 -302.171672) (xy 298.67292 -302.123888)
			(xy 298.66896 -302.074834) (xy 298.330112 -302.074834) (xy 298.329617 -302.099441) (xy 298.321722 -302.148018)
			(xy 298.306138 -302.194699) (xy 298.283267 -302.238276) (xy 298.253702 -302.27762) (xy 298.218209 -302.311712)
			(xy 298.177706 -302.339668) (xy 298.133244 -302.360766) (xy 298.085973 -302.374458) (xy 298.037118 -302.38039)
			(xy 297.987943 -302.378409) (xy 297.939724 -302.368565) (xy 297.893708 -302.351113) (xy 297.851087 -302.326506)
			(xy 297.812966 -302.295381) (xy 297.780331 -302.258544) (xy 297.754028 -302.216948) (xy 297.734737 -302.171672)
			(xy 297.72296 -302.123888) (xy 297.719 -302.074834) (xy 297.380152 -302.074834) (xy 297.379657 -302.099441)
			(xy 297.371762 -302.148018) (xy 297.356178 -302.194699) (xy 297.333307 -302.238276) (xy 297.303742 -302.27762)
			(xy 297.268249 -302.311712) (xy 297.227746 -302.339668) (xy 297.183284 -302.360766) (xy 297.136013 -302.374458)
			(xy 297.087158 -302.38039) (xy 297.037983 -302.378409) (xy 296.989764 -302.368565) (xy 296.943748 -302.351113)
			(xy 296.901127 -302.326506) (xy 296.863006 -302.295381) (xy 296.830371 -302.258544) (xy 296.804068 -302.216948)
			(xy 296.784777 -302.171672) (xy 296.773 -302.123888) (xy 296.76904 -302.074834) (xy 296.430192 -302.074834)
			(xy 296.429697 -302.099441) (xy 296.421802 -302.148018) (xy 296.406218 -302.194699) (xy 296.383347 -302.238276)
			(xy 296.353782 -302.27762) (xy 296.318289 -302.311712) (xy 296.277786 -302.339668) (xy 296.233324 -302.360766)
			(xy 296.186053 -302.374458) (xy 296.137198 -302.38039) (xy 296.088023 -302.378409) (xy 296.039804 -302.368565)
			(xy 295.993788 -302.351113) (xy 295.951167 -302.326506) (xy 295.913046 -302.295381) (xy 295.880411 -302.258544)
			(xy 295.854108 -302.216948) (xy 295.834817 -302.171672) (xy 295.82304 -302.123888) (xy 295.81908 -302.074834)
			(xy 295.480232 -302.074834) (xy 295.479737 -302.099441) (xy 295.471842 -302.148018) (xy 295.456258 -302.194699)
			(xy 295.433387 -302.238276) (xy 295.403822 -302.27762) (xy 295.368329 -302.311712) (xy 295.327826 -302.339668)
			(xy 295.283364 -302.360766) (xy 295.236093 -302.374458) (xy 295.187238 -302.38039) (xy 295.138063 -302.378409)
			(xy 295.089844 -302.368565) (xy 295.043828 -302.351113) (xy 295.001207 -302.326506) (xy 294.963086 -302.295381)
			(xy 294.930451 -302.258544) (xy 294.904148 -302.216948) (xy 294.884857 -302.171672) (xy 294.87308 -302.123888)
			(xy 294.86912 -302.074834) (xy 294.530018 -302.074834) (xy 294.529523 -302.099441) (xy 294.521628 -302.148018)
			(xy 294.506044 -302.194699) (xy 294.483173 -302.238276) (xy 294.453608 -302.27762) (xy 294.418115 -302.311712)
			(xy 294.377612 -302.339668) (xy 294.33315 -302.360766) (xy 294.285879 -302.374458) (xy 294.237024 -302.38039)
			(xy 294.187849 -302.378409) (xy 294.13963 -302.368565) (xy 294.093614 -302.351113) (xy 294.050993 -302.326506)
			(xy 294.012872 -302.295381) (xy 293.980237 -302.258544) (xy 293.953934 -302.216948) (xy 293.934643 -302.171672)
			(xy 293.922866 -302.123888) (xy 293.918906 -302.074834) (xy 293.580058 -302.074834) (xy 293.579563 -302.099441)
			(xy 293.571668 -302.148018) (xy 293.556084 -302.194699) (xy 293.533213 -302.238276) (xy 293.503648 -302.27762)
			(xy 293.468155 -302.311712) (xy 293.427652 -302.339668) (xy 293.38319 -302.360766) (xy 293.335919 -302.374458)
			(xy 293.287064 -302.38039) (xy 293.237889 -302.378409) (xy 293.18967 -302.368565) (xy 293.143654 -302.351113)
			(xy 293.101033 -302.326506) (xy 293.062912 -302.295381) (xy 293.030277 -302.258544) (xy 293.003974 -302.216948)
			(xy 292.984683 -302.171672) (xy 292.972906 -302.123888) (xy 292.968946 -302.074834) (xy 292.630098 -302.074834)
			(xy 292.629603 -302.099441) (xy 292.621708 -302.148018) (xy 292.606124 -302.194699) (xy 292.583253 -302.238276)
			(xy 292.553688 -302.27762) (xy 292.518195 -302.311712) (xy 292.477692 -302.339668) (xy 292.43323 -302.360766)
			(xy 292.385959 -302.374458) (xy 292.337104 -302.38039) (xy 292.287929 -302.378409) (xy 292.23971 -302.368565)
			(xy 292.193694 -302.351113) (xy 292.151073 -302.326506) (xy 292.112952 -302.295381) (xy 292.080317 -302.258544)
			(xy 292.054014 -302.216948) (xy 292.034723 -302.171672) (xy 292.022946 -302.123888) (xy 292.018986 -302.074834)
			(xy 290.730178 -302.074834) (xy 290.729683 -302.099441) (xy 290.721788 -302.148018) (xy 290.706204 -302.194699)
			(xy 290.683333 -302.238276) (xy 290.653768 -302.27762) (xy 290.618275 -302.311712) (xy 290.577772 -302.339668)
			(xy 290.53331 -302.360766) (xy 290.486039 -302.374458) (xy 290.437184 -302.38039) (xy 290.388009 -302.378409)
			(xy 290.33979 -302.368565) (xy 290.293774 -302.351113) (xy 290.251153 -302.326506) (xy 290.213032 -302.295381)
			(xy 290.180397 -302.258544) (xy 290.154094 -302.216948) (xy 290.134803 -302.171672) (xy 290.123026 -302.123888)
			(xy 290.119066 -302.074834) (xy 289.780218 -302.074834) (xy 289.779723 -302.099441) (xy 289.771828 -302.148018)
			(xy 289.756244 -302.194699) (xy 289.733373 -302.238276) (xy 289.703808 -302.27762) (xy 289.668315 -302.311712)
			(xy 289.627812 -302.339668) (xy 289.58335 -302.360766) (xy 289.536079 -302.374458) (xy 289.487224 -302.38039)
			(xy 289.438049 -302.378409) (xy 289.38983 -302.368565) (xy 289.343814 -302.351113) (xy 289.301193 -302.326506)
			(xy 289.263072 -302.295381) (xy 289.230437 -302.258544) (xy 289.204134 -302.216948) (xy 289.184843 -302.171672)
			(xy 289.173066 -302.123888) (xy 289.169106 -302.074834) (xy 288.830004 -302.074834) (xy 288.829509 -302.099441)
			(xy 288.821614 -302.148018) (xy 288.80603 -302.194699) (xy 288.783159 -302.238276) (xy 288.753594 -302.27762)
			(xy 288.718101 -302.311712) (xy 288.677598 -302.339668) (xy 288.633136 -302.360766) (xy 288.585865 -302.374458)
			(xy 288.53701 -302.38039) (xy 288.487835 -302.378409) (xy 288.439616 -302.368565) (xy 288.3936 -302.351113)
			(xy 288.350979 -302.326506) (xy 288.312858 -302.295381) (xy 288.280223 -302.258544) (xy 288.25392 -302.216948)
			(xy 288.234629 -302.171672) (xy 288.222852 -302.123888) (xy 288.218892 -302.074834) (xy 287.880044 -302.074834)
			(xy 287.879549 -302.099441) (xy 287.871654 -302.148018) (xy 287.85607 -302.194699) (xy 287.833199 -302.238276)
			(xy 287.803634 -302.27762) (xy 287.768141 -302.311712) (xy 287.727638 -302.339668) (xy 287.683176 -302.360766)
			(xy 287.635905 -302.374458) (xy 287.58705 -302.38039) (xy 287.537875 -302.378409) (xy 287.489656 -302.368565)
			(xy 287.44364 -302.351113) (xy 287.401019 -302.326506) (xy 287.362898 -302.295381) (xy 287.330263 -302.258544)
			(xy 287.30396 -302.216948) (xy 287.284669 -302.171672) (xy 287.272892 -302.123888) (xy 287.268932 -302.074834)
			(xy 286.930084 -302.074834) (xy 286.929589 -302.099441) (xy 286.921694 -302.148018) (xy 286.90611 -302.194699)
			(xy 286.883239 -302.238276) (xy 286.853674 -302.27762) (xy 286.818181 -302.311712) (xy 286.777678 -302.339668)
			(xy 286.733216 -302.360766) (xy 286.685945 -302.374458) (xy 286.63709 -302.38039) (xy 286.587915 -302.378409)
			(xy 286.539696 -302.368565) (xy 286.49368 -302.351113) (xy 286.451059 -302.326506) (xy 286.412938 -302.295381)
			(xy 286.380303 -302.258544) (xy 286.354 -302.216948) (xy 286.334709 -302.171672) (xy 286.322932 -302.123888)
			(xy 286.318972 -302.074834) (xy 285.980124 -302.074834) (xy 285.979629 -302.099441) (xy 285.971734 -302.148018)
			(xy 285.95615 -302.194699) (xy 285.933279 -302.238276) (xy 285.903714 -302.27762) (xy 285.868221 -302.311712)
			(xy 285.827718 -302.339668) (xy 285.783256 -302.360766) (xy 285.735985 -302.374458) (xy 285.68713 -302.38039)
			(xy 285.637955 -302.378409) (xy 285.589736 -302.368565) (xy 285.54372 -302.351113) (xy 285.501099 -302.326506)
			(xy 285.462978 -302.295381) (xy 285.430343 -302.258544) (xy 285.40404 -302.216948) (xy 285.384749 -302.171672)
			(xy 285.372972 -302.123888) (xy 285.369012 -302.074834) (xy 285.030164 -302.074834) (xy 285.029669 -302.099441)
			(xy 285.021774 -302.148018) (xy 285.00619 -302.194699) (xy 284.983319 -302.238276) (xy 284.953754 -302.27762)
			(xy 284.918261 -302.311712) (xy 284.877758 -302.339668) (xy 284.833296 -302.360766) (xy 284.786025 -302.374458)
			(xy 284.73717 -302.38039) (xy 284.687995 -302.378409) (xy 284.639776 -302.368565) (xy 284.59376 -302.351113)
			(xy 284.551139 -302.326506) (xy 284.513018 -302.295381) (xy 284.480383 -302.258544) (xy 284.45408 -302.216948)
			(xy 284.434789 -302.171672) (xy 284.423012 -302.123888) (xy 284.419052 -302.074834) (xy 284.080204 -302.074834)
			(xy 284.079709 -302.099441) (xy 284.071814 -302.148018) (xy 284.05623 -302.194699) (xy 284.033359 -302.238276)
			(xy 284.003794 -302.27762) (xy 283.968301 -302.311712) (xy 283.927798 -302.339668) (xy 283.883336 -302.360766)
			(xy 283.836065 -302.374458) (xy 283.78721 -302.38039) (xy 283.738035 -302.378409) (xy 283.689816 -302.368565)
			(xy 283.6438 -302.351113) (xy 283.601179 -302.326506) (xy 283.563058 -302.295381) (xy 283.530423 -302.258544)
			(xy 283.50412 -302.216948) (xy 283.484829 -302.171672) (xy 283.473052 -302.123888) (xy 283.469092 -302.074834)
			(xy 283.130244 -302.074834) (xy 283.129749 -302.099441) (xy 283.121854 -302.148018) (xy 283.10627 -302.194699)
			(xy 283.083399 -302.238276) (xy 283.053834 -302.27762) (xy 283.018341 -302.311712) (xy 282.977838 -302.339668)
			(xy 282.933376 -302.360766) (xy 282.886105 -302.374458) (xy 282.83725 -302.38039) (xy 282.788075 -302.378409)
			(xy 282.739856 -302.368565) (xy 282.69384 -302.351113) (xy 282.651219 -302.326506) (xy 282.613098 -302.295381)
			(xy 282.580463 -302.258544) (xy 282.55416 -302.216948) (xy 282.534869 -302.171672) (xy 282.523092 -302.123888)
			(xy 282.519132 -302.074834) (xy 282.18003 -302.074834) (xy 282.179535 -302.099441) (xy 282.17164 -302.148018)
			(xy 282.156056 -302.194699) (xy 282.133185 -302.238276) (xy 282.10362 -302.27762) (xy 282.068127 -302.311712)
			(xy 282.027624 -302.339668) (xy 281.983162 -302.360766) (xy 281.935891 -302.374458) (xy 281.887036 -302.38039)
			(xy 281.837861 -302.378409) (xy 281.789642 -302.368565) (xy 281.743626 -302.351113) (xy 281.701005 -302.326506)
			(xy 281.662884 -302.295381) (xy 281.630249 -302.258544) (xy 281.603946 -302.216948) (xy 281.584655 -302.171672)
			(xy 281.572878 -302.123888) (xy 281.568918 -302.074834) (xy 280.268426 -302.074834) (xy 280.268426 -302.538384)
			(xy 319.861182 -302.538384) (xy 319.865253 -302.482762) (xy 319.877379 -302.428325) (xy 319.897302 -302.376234)
			(xy 319.924598 -302.327599) (xy 319.958684 -302.283456) (xy 319.998833 -302.244747) (xy 320.044191 -302.212296)
			(xy 320.093791 -302.186795) (xy 320.146575 -302.168788) (xy 320.201418 -302.158658) (xy 320.257152 -302.156621)
			(xy 320.312589 -302.162721) (xy 320.366546 -302.176827) (xy 320.417875 -302.198639) (xy 320.465481 -302.227693)
			(xy 320.508349 -302.263368) (xy 320.545566 -302.304905) (xy 320.576339 -302.351418) (xy 320.600011 -302.401915)
			(xy 320.616079 -302.455322) (xy 320.624199 -302.510498) (xy 320.624708 -302.538384) (xy 320.624199 -302.56627)
			(xy 320.616079 -302.621446) (xy 320.600011 -302.674853) (xy 320.576339 -302.72535) (xy 320.545566 -302.771863)
			(xy 320.508349 -302.8134) (xy 320.465481 -302.849075) (xy 320.417875 -302.878129) (xy 320.366546 -302.899941)
			(xy 320.312589 -302.914047) (xy 320.257152 -302.920147) (xy 320.201418 -302.91811) (xy 320.146575 -302.90798)
			(xy 320.093791 -302.889973) (xy 320.044191 -302.864472) (xy 319.998833 -302.832021) (xy 319.958684 -302.793312)
			(xy 319.924598 -302.749169) (xy 319.897302 -302.700534) (xy 319.877379 -302.648443) (xy 319.865253 -302.594006)
			(xy 319.861182 -302.538384) (xy 280.268426 -302.538384) (xy 280.268426 -302.930052) (xy 280.268934 -302.936148)
			(xy 280.270204 -302.947324) (xy 280.270966 -302.950626) (xy 280.270966 -302.951134) (xy 280.275218 -302.969252)
			(xy 280.279803 -303.006186) (xy 280.28011 -303.024794) (xy 280.618958 -303.024794) (xy 280.622918 -302.97574)
			(xy 280.634695 -302.927956) (xy 280.653986 -302.88268) (xy 280.680289 -302.841084) (xy 280.712924 -302.804247)
			(xy 280.751045 -302.773122) (xy 280.793666 -302.748515) (xy 280.839682 -302.731063) (xy 280.887901 -302.721219)
			(xy 280.937076 -302.719238) (xy 280.985931 -302.72517) (xy 281.033202 -302.738862) (xy 281.077664 -302.75996)
			(xy 281.118167 -302.787916) (xy 281.15366 -302.822008) (xy 281.183225 -302.861352) (xy 281.206096 -302.904929)
			(xy 281.22168 -302.95161) (xy 281.229575 -303.000187) (xy 281.23007 -303.024794) (xy 281.568918 -303.024794)
			(xy 281.572878 -302.97574) (xy 281.584655 -302.927956) (xy 281.603946 -302.88268) (xy 281.630249 -302.841084)
			(xy 281.662884 -302.804247) (xy 281.701005 -302.773122) (xy 281.743626 -302.748515) (xy 281.789642 -302.731063)
			(xy 281.837861 -302.721219) (xy 281.887036 -302.719238) (xy 281.935891 -302.72517) (xy 281.983162 -302.738862)
			(xy 282.027624 -302.75996) (xy 282.068127 -302.787916) (xy 282.10362 -302.822008) (xy 282.133185 -302.861352)
			(xy 282.156056 -302.904929) (xy 282.17164 -302.95161) (xy 282.179535 -303.000187) (xy 282.18003 -303.024794)
			(xy 282.519132 -303.024794) (xy 282.523092 -302.97574) (xy 282.534869 -302.927956) (xy 282.55416 -302.88268)
			(xy 282.580463 -302.841084) (xy 282.613098 -302.804247) (xy 282.651219 -302.773122) (xy 282.69384 -302.748515)
			(xy 282.739856 -302.731063) (xy 282.788075 -302.721219) (xy 282.83725 -302.719238) (xy 282.886105 -302.72517)
			(xy 282.933376 -302.738862) (xy 282.977838 -302.75996) (xy 283.018341 -302.787916) (xy 283.053834 -302.822008)
			(xy 283.083399 -302.861352) (xy 283.10627 -302.904929) (xy 283.121854 -302.95161) (xy 283.129749 -303.000187)
			(xy 283.130244 -303.024794) (xy 283.469092 -303.024794) (xy 283.473052 -302.97574) (xy 283.484829 -302.927956)
			(xy 283.50412 -302.88268) (xy 283.530423 -302.841084) (xy 283.563058 -302.804247) (xy 283.601179 -302.773122)
			(xy 283.6438 -302.748515) (xy 283.689816 -302.731063) (xy 283.738035 -302.721219) (xy 283.78721 -302.719238)
			(xy 283.836065 -302.72517) (xy 283.883336 -302.738862) (xy 283.927798 -302.75996) (xy 283.968301 -302.787916)
			(xy 284.003794 -302.822008) (xy 284.033359 -302.861352) (xy 284.05623 -302.904929) (xy 284.071814 -302.95161)
			(xy 284.079709 -303.000187) (xy 284.080204 -303.024794) (xy 284.419052 -303.024794) (xy 284.423012 -302.97574)
			(xy 284.434789 -302.927956) (xy 284.45408 -302.88268) (xy 284.480383 -302.841084) (xy 284.513018 -302.804247)
			(xy 284.551139 -302.773122) (xy 284.59376 -302.748515) (xy 284.639776 -302.731063) (xy 284.687995 -302.721219)
			(xy 284.73717 -302.719238) (xy 284.786025 -302.72517) (xy 284.833296 -302.738862) (xy 284.877758 -302.75996)
			(xy 284.918261 -302.787916) (xy 284.953754 -302.822008) (xy 284.983319 -302.861352) (xy 285.00619 -302.904929)
			(xy 285.021774 -302.95161) (xy 285.029669 -303.000187) (xy 285.030164 -303.024794) (xy 285.369012 -303.024794)
			(xy 285.372972 -302.97574) (xy 285.384749 -302.927956) (xy 285.40404 -302.88268) (xy 285.430343 -302.841084)
			(xy 285.462978 -302.804247) (xy 285.501099 -302.773122) (xy 285.54372 -302.748515) (xy 285.589736 -302.731063)
			(xy 285.637955 -302.721219) (xy 285.68713 -302.719238) (xy 285.735985 -302.72517) (xy 285.783256 -302.738862)
			(xy 285.827718 -302.75996) (xy 285.868221 -302.787916) (xy 285.903714 -302.822008) (xy 285.933279 -302.861352)
			(xy 285.95615 -302.904929) (xy 285.971734 -302.95161) (xy 285.979629 -303.000187) (xy 285.980124 -303.024794)
			(xy 286.318972 -303.024794) (xy 286.322932 -302.97574) (xy 286.334709 -302.927956) (xy 286.354 -302.88268)
			(xy 286.380303 -302.841084) (xy 286.412938 -302.804247) (xy 286.451059 -302.773122) (xy 286.49368 -302.748515)
			(xy 286.539696 -302.731063) (xy 286.587915 -302.721219) (xy 286.63709 -302.719238) (xy 286.685945 -302.72517)
			(xy 286.733216 -302.738862) (xy 286.777678 -302.75996) (xy 286.818181 -302.787916) (xy 286.853674 -302.822008)
			(xy 286.883239 -302.861352) (xy 286.90611 -302.904929) (xy 286.921694 -302.95161) (xy 286.929589 -303.000187)
			(xy 286.930084 -303.024794) (xy 287.268932 -303.024794) (xy 287.272892 -302.97574) (xy 287.284669 -302.927956)
			(xy 287.30396 -302.88268) (xy 287.330263 -302.841084) (xy 287.362898 -302.804247) (xy 287.401019 -302.773122)
			(xy 287.44364 -302.748515) (xy 287.489656 -302.731063) (xy 287.537875 -302.721219) (xy 287.58705 -302.719238)
			(xy 287.635905 -302.72517) (xy 287.683176 -302.738862) (xy 287.727638 -302.75996) (xy 287.768141 -302.787916)
			(xy 287.803634 -302.822008) (xy 287.833199 -302.861352) (xy 287.85607 -302.904929) (xy 287.871654 -302.95161)
			(xy 287.879549 -303.000187) (xy 287.880044 -303.024794) (xy 288.218892 -303.024794) (xy 288.222852 -302.97574)
			(xy 288.234629 -302.927956) (xy 288.25392 -302.88268) (xy 288.280223 -302.841084) (xy 288.312858 -302.804247)
			(xy 288.350979 -302.773122) (xy 288.3936 -302.748515) (xy 288.439616 -302.731063) (xy 288.487835 -302.721219)
			(xy 288.53701 -302.719238) (xy 288.585865 -302.72517) (xy 288.633136 -302.738862) (xy 288.677598 -302.75996)
			(xy 288.718101 -302.787916) (xy 288.753594 -302.822008) (xy 288.783159 -302.861352) (xy 288.80603 -302.904929)
			(xy 288.821614 -302.95161) (xy 288.829509 -303.000187) (xy 288.830004 -303.024794) (xy 289.169106 -303.024794)
			(xy 289.173066 -302.97574) (xy 289.184843 -302.927956) (xy 289.204134 -302.88268) (xy 289.230437 -302.841084)
			(xy 289.263072 -302.804247) (xy 289.301193 -302.773122) (xy 289.343814 -302.748515) (xy 289.38983 -302.731063)
			(xy 289.438049 -302.721219) (xy 289.487224 -302.719238) (xy 289.536079 -302.72517) (xy 289.58335 -302.738862)
			(xy 289.627812 -302.75996) (xy 289.668315 -302.787916) (xy 289.703808 -302.822008) (xy 289.733373 -302.861352)
			(xy 289.756244 -302.904929) (xy 289.771828 -302.95161) (xy 289.779723 -303.000187) (xy 289.780218 -303.024794)
			(xy 290.119066 -303.024794) (xy 290.123026 -302.97574) (xy 290.134803 -302.927956) (xy 290.154094 -302.88268)
			(xy 290.180397 -302.841084) (xy 290.213032 -302.804247) (xy 290.251153 -302.773122) (xy 290.293774 -302.748515)
			(xy 290.33979 -302.731063) (xy 290.388009 -302.721219) (xy 290.437184 -302.719238) (xy 290.486039 -302.72517)
			(xy 290.53331 -302.738862) (xy 290.577772 -302.75996) (xy 290.618275 -302.787916) (xy 290.653768 -302.822008)
			(xy 290.683333 -302.861352) (xy 290.706204 -302.904929) (xy 290.721788 -302.95161) (xy 290.729683 -303.000187)
			(xy 290.730178 -303.024794) (xy 292.018986 -303.024794) (xy 292.022946 -302.97574) (xy 292.034723 -302.927956)
			(xy 292.054014 -302.88268) (xy 292.080317 -302.841084) (xy 292.112952 -302.804247) (xy 292.151073 -302.773122)
			(xy 292.193694 -302.748515) (xy 292.23971 -302.731063) (xy 292.287929 -302.721219) (xy 292.337104 -302.719238)
			(xy 292.385959 -302.72517) (xy 292.43323 -302.738862) (xy 292.477692 -302.75996) (xy 292.518195 -302.787916)
			(xy 292.553688 -302.822008) (xy 292.583253 -302.861352) (xy 292.606124 -302.904929) (xy 292.621708 -302.95161)
			(xy 292.629603 -303.000187) (xy 292.630098 -303.024794) (xy 292.968946 -303.024794) (xy 292.972906 -302.97574)
			(xy 292.984683 -302.927956) (xy 293.003974 -302.88268) (xy 293.030277 -302.841084) (xy 293.062912 -302.804247)
			(xy 293.101033 -302.773122) (xy 293.143654 -302.748515) (xy 293.18967 -302.731063) (xy 293.237889 -302.721219)
			(xy 293.287064 -302.719238) (xy 293.335919 -302.72517) (xy 293.38319 -302.738862) (xy 293.427652 -302.75996)
			(xy 293.468155 -302.787916) (xy 293.503648 -302.822008) (xy 293.533213 -302.861352) (xy 293.556084 -302.904929)
			(xy 293.571668 -302.95161) (xy 293.579563 -303.000187) (xy 293.580058 -303.024794) (xy 293.918906 -303.024794)
			(xy 293.922866 -302.97574) (xy 293.934643 -302.927956) (xy 293.953934 -302.88268) (xy 293.980237 -302.841084)
			(xy 294.012872 -302.804247) (xy 294.050993 -302.773122) (xy 294.093614 -302.748515) (xy 294.13963 -302.731063)
			(xy 294.187849 -302.721219) (xy 294.237024 -302.719238) (xy 294.285879 -302.72517) (xy 294.33315 -302.738862)
			(xy 294.377612 -302.75996) (xy 294.418115 -302.787916) (xy 294.453608 -302.822008) (xy 294.483173 -302.861352)
			(xy 294.506044 -302.904929) (xy 294.521628 -302.95161) (xy 294.529523 -303.000187) (xy 294.530018 -303.024794)
			(xy 294.86912 -303.024794) (xy 294.87308 -302.97574) (xy 294.884857 -302.927956) (xy 294.904148 -302.88268)
			(xy 294.930451 -302.841084) (xy 294.963086 -302.804247) (xy 295.001207 -302.773122) (xy 295.043828 -302.748515)
			(xy 295.089844 -302.731063) (xy 295.138063 -302.721219) (xy 295.187238 -302.719238) (xy 295.236093 -302.72517)
			(xy 295.283364 -302.738862) (xy 295.327826 -302.75996) (xy 295.368329 -302.787916) (xy 295.403822 -302.822008)
			(xy 295.433387 -302.861352) (xy 295.456258 -302.904929) (xy 295.471842 -302.95161) (xy 295.479737 -303.000187)
			(xy 295.480232 -303.024794) (xy 295.81908 -303.024794) (xy 295.82304 -302.97574) (xy 295.834817 -302.927956)
			(xy 295.854108 -302.88268) (xy 295.880411 -302.841084) (xy 295.913046 -302.804247) (xy 295.951167 -302.773122)
			(xy 295.993788 -302.748515) (xy 296.039804 -302.731063) (xy 296.088023 -302.721219) (xy 296.137198 -302.719238)
			(xy 296.186053 -302.72517) (xy 296.233324 -302.738862) (xy 296.277786 -302.75996) (xy 296.318289 -302.787916)
			(xy 296.353782 -302.822008) (xy 296.383347 -302.861352) (xy 296.406218 -302.904929) (xy 296.421802 -302.95161)
			(xy 296.429697 -303.000187) (xy 296.430192 -303.024794) (xy 296.76904 -303.024794) (xy 296.773 -302.97574)
			(xy 296.784777 -302.927956) (xy 296.804068 -302.88268) (xy 296.830371 -302.841084) (xy 296.863006 -302.804247)
			(xy 296.901127 -302.773122) (xy 296.943748 -302.748515) (xy 296.989764 -302.731063) (xy 297.037983 -302.721219)
			(xy 297.087158 -302.719238) (xy 297.136013 -302.72517) (xy 297.183284 -302.738862) (xy 297.227746 -302.75996)
			(xy 297.268249 -302.787916) (xy 297.303742 -302.822008) (xy 297.333307 -302.861352) (xy 297.356178 -302.904929)
			(xy 297.371762 -302.95161) (xy 297.379657 -303.000187) (xy 297.380152 -303.024794) (xy 297.719 -303.024794)
			(xy 297.72296 -302.97574) (xy 297.734737 -302.927956) (xy 297.754028 -302.88268) (xy 297.780331 -302.841084)
			(xy 297.812966 -302.804247) (xy 297.851087 -302.773122) (xy 297.893708 -302.748515) (xy 297.939724 -302.731063)
			(xy 297.987943 -302.721219) (xy 298.037118 -302.719238) (xy 298.085973 -302.72517) (xy 298.133244 -302.738862)
			(xy 298.177706 -302.75996) (xy 298.218209 -302.787916) (xy 298.253702 -302.822008) (xy 298.283267 -302.861352)
			(xy 298.306138 -302.904929) (xy 298.321722 -302.95161) (xy 298.329617 -303.000187) (xy 298.330112 -303.024794)
			(xy 298.66896 -303.024794) (xy 298.67292 -302.97574) (xy 298.684697 -302.927956) (xy 298.703988 -302.88268)
			(xy 298.730291 -302.841084) (xy 298.762926 -302.804247) (xy 298.801047 -302.773122) (xy 298.843668 -302.748515)
			(xy 298.889684 -302.731063) (xy 298.937903 -302.721219) (xy 298.987078 -302.719238) (xy 299.035933 -302.72517)
			(xy 299.083204 -302.738862) (xy 299.127666 -302.75996) (xy 299.168169 -302.787916) (xy 299.203662 -302.822008)
			(xy 299.233227 -302.861352) (xy 299.256098 -302.904929) (xy 299.271682 -302.95161) (xy 299.279577 -303.000187)
			(xy 299.280072 -303.024794) (xy 299.61892 -303.024794) (xy 299.62288 -302.97574) (xy 299.634657 -302.927956)
			(xy 299.653948 -302.88268) (xy 299.680251 -302.841084) (xy 299.712886 -302.804247) (xy 299.751007 -302.773122)
			(xy 299.793628 -302.748515) (xy 299.839644 -302.731063) (xy 299.887863 -302.721219) (xy 299.937038 -302.719238)
			(xy 299.985893 -302.72517) (xy 300.033164 -302.738862) (xy 300.077626 -302.75996) (xy 300.118129 -302.787916)
			(xy 300.153622 -302.822008) (xy 300.183187 -302.861352) (xy 300.206058 -302.904929) (xy 300.221642 -302.95161)
			(xy 300.229537 -303.000187) (xy 300.230032 -303.024794) (xy 300.56888 -303.024794) (xy 300.57284 -302.97574)
			(xy 300.584617 -302.927956) (xy 300.603908 -302.88268) (xy 300.630211 -302.841084) (xy 300.662846 -302.804247)
			(xy 300.700967 -302.773122) (xy 300.743588 -302.748515) (xy 300.789604 -302.731063) (xy 300.837823 -302.721219)
			(xy 300.886998 -302.719238) (xy 300.935853 -302.72517) (xy 300.983124 -302.738862) (xy 301.027586 -302.75996)
			(xy 301.068089 -302.787916) (xy 301.103582 -302.822008) (xy 301.133147 -302.861352) (xy 301.156018 -302.904929)
			(xy 301.171602 -302.95161) (xy 301.179497 -303.000187) (xy 301.179992 -303.024794) (xy 301.519094 -303.024794)
			(xy 301.523054 -302.97574) (xy 301.534831 -302.927956) (xy 301.554122 -302.88268) (xy 301.580425 -302.841084)
			(xy 301.61306 -302.804247) (xy 301.651181 -302.773122) (xy 301.693802 -302.748515) (xy 301.739818 -302.731063)
			(xy 301.788037 -302.721219) (xy 301.837212 -302.719238) (xy 301.886067 -302.72517) (xy 301.933338 -302.738862)
			(xy 301.9778 -302.75996) (xy 302.018303 -302.787916) (xy 302.053796 -302.822008) (xy 302.083361 -302.861352)
			(xy 302.106232 -302.904929) (xy 302.121816 -302.95161) (xy 302.129711 -303.000187) (xy 302.130206 -303.024794)
			(xy 302.469054 -303.024794) (xy 302.473014 -302.97574) (xy 302.484791 -302.927956) (xy 302.504082 -302.88268)
			(xy 302.530385 -302.841084) (xy 302.56302 -302.804247) (xy 302.601141 -302.773122) (xy 302.643762 -302.748515)
			(xy 302.689778 -302.731063) (xy 302.737997 -302.721219) (xy 302.787172 -302.719238) (xy 302.836027 -302.72517)
			(xy 302.883298 -302.738862) (xy 302.92776 -302.75996) (xy 302.968263 -302.787916) (xy 303.003756 -302.822008)
			(xy 303.033321 -302.861352) (xy 303.056192 -302.904929) (xy 303.071776 -302.95161) (xy 303.079671 -303.000187)
			(xy 303.080166 -303.024794) (xy 303.419014 -303.024794) (xy 303.422974 -302.97574) (xy 303.434751 -302.927956)
			(xy 303.454042 -302.88268) (xy 303.480345 -302.841084) (xy 303.51298 -302.804247) (xy 303.551101 -302.773122)
			(xy 303.593722 -302.748515) (xy 303.639738 -302.731063) (xy 303.687957 -302.721219) (xy 303.737132 -302.719238)
			(xy 303.785987 -302.72517) (xy 303.833258 -302.738862) (xy 303.87772 -302.75996) (xy 303.918223 -302.787916)
			(xy 303.953716 -302.822008) (xy 303.983281 -302.861352) (xy 304.006152 -302.904929) (xy 304.021736 -302.95161)
			(xy 304.029631 -303.000187) (xy 304.030126 -303.024794) (xy 304.368974 -303.024794) (xy 304.372934 -302.97574)
			(xy 304.384711 -302.927956) (xy 304.404002 -302.88268) (xy 304.430305 -302.841084) (xy 304.46294 -302.804247)
			(xy 304.501061 -302.773122) (xy 304.543682 -302.748515) (xy 304.589698 -302.731063) (xy 304.637917 -302.721219)
			(xy 304.687092 -302.719238) (xy 304.735947 -302.72517) (xy 304.783218 -302.738862) (xy 304.82768 -302.75996)
			(xy 304.868183 -302.787916) (xy 304.903676 -302.822008) (xy 304.933241 -302.861352) (xy 304.956112 -302.904929)
			(xy 304.971696 -302.95161) (xy 304.979591 -303.000187) (xy 304.980086 -303.024794) (xy 305.318934 -303.024794)
			(xy 305.322894 -302.97574) (xy 305.334671 -302.927956) (xy 305.353962 -302.88268) (xy 305.380265 -302.841084)
			(xy 305.4129 -302.804247) (xy 305.451021 -302.773122) (xy 305.493642 -302.748515) (xy 305.539658 -302.731063)
			(xy 305.587877 -302.721219) (xy 305.637052 -302.719238) (xy 305.685907 -302.72517) (xy 305.733178 -302.738862)
			(xy 305.77764 -302.75996) (xy 305.818143 -302.787916) (xy 305.853636 -302.822008) (xy 305.883201 -302.861352)
			(xy 305.906072 -302.904929) (xy 305.921656 -302.95161) (xy 305.929551 -303.000187) (xy 305.930046 -303.024794)
			(xy 305.929551 -303.049401) (xy 305.921656 -303.097978) (xy 305.906072 -303.144659) (xy 305.883201 -303.188236)
			(xy 305.853636 -303.22758) (xy 305.818143 -303.261672) (xy 305.77764 -303.289628) (xy 305.733178 -303.310726)
			(xy 305.685907 -303.324418) (xy 305.637052 -303.33035) (xy 305.587877 -303.328369) (xy 305.539658 -303.318525)
			(xy 305.493642 -303.301073) (xy 305.451021 -303.276466) (xy 305.4129 -303.245341) (xy 305.380265 -303.208504)
			(xy 305.353962 -303.166908) (xy 305.334671 -303.121632) (xy 305.322894 -303.073848) (xy 305.318934 -303.024794)
			(xy 304.980086 -303.024794) (xy 304.979591 -303.049401) (xy 304.971696 -303.097978) (xy 304.956112 -303.144659)
			(xy 304.933241 -303.188236) (xy 304.903676 -303.22758) (xy 304.868183 -303.261672) (xy 304.82768 -303.289628)
			(xy 304.783218 -303.310726) (xy 304.735947 -303.324418) (xy 304.687092 -303.33035) (xy 304.637917 -303.328369)
			(xy 304.589698 -303.318525) (xy 304.543682 -303.301073) (xy 304.501061 -303.276466) (xy 304.46294 -303.245341)
			(xy 304.430305 -303.208504) (xy 304.404002 -303.166908) (xy 304.384711 -303.121632) (xy 304.372934 -303.073848)
			(xy 304.368974 -303.024794) (xy 304.030126 -303.024794) (xy 304.029631 -303.049401) (xy 304.021736 -303.097978)
			(xy 304.006152 -303.144659) (xy 303.983281 -303.188236) (xy 303.953716 -303.22758) (xy 303.918223 -303.261672)
			(xy 303.87772 -303.289628) (xy 303.833258 -303.310726) (xy 303.785987 -303.324418) (xy 303.737132 -303.33035)
			(xy 303.687957 -303.328369) (xy 303.639738 -303.318525) (xy 303.593722 -303.301073) (xy 303.551101 -303.276466)
			(xy 303.51298 -303.245341) (xy 303.480345 -303.208504) (xy 303.454042 -303.166908) (xy 303.434751 -303.121632)
			(xy 303.422974 -303.073848) (xy 303.419014 -303.024794) (xy 303.080166 -303.024794) (xy 303.079671 -303.049401)
			(xy 303.071776 -303.097978) (xy 303.056192 -303.144659) (xy 303.033321 -303.188236) (xy 303.003756 -303.22758)
			(xy 302.968263 -303.261672) (xy 302.92776 -303.289628) (xy 302.883298 -303.310726) (xy 302.836027 -303.324418)
			(xy 302.787172 -303.33035) (xy 302.737997 -303.328369) (xy 302.689778 -303.318525) (xy 302.643762 -303.301073)
			(xy 302.601141 -303.276466) (xy 302.56302 -303.245341) (xy 302.530385 -303.208504) (xy 302.504082 -303.166908)
			(xy 302.484791 -303.121632) (xy 302.473014 -303.073848) (xy 302.469054 -303.024794) (xy 302.130206 -303.024794)
			(xy 302.129711 -303.049401) (xy 302.121816 -303.097978) (xy 302.106232 -303.144659) (xy 302.083361 -303.188236)
			(xy 302.053796 -303.22758) (xy 302.018303 -303.261672) (xy 301.9778 -303.289628) (xy 301.933338 -303.310726)
			(xy 301.886067 -303.324418) (xy 301.837212 -303.33035) (xy 301.788037 -303.328369) (xy 301.739818 -303.318525)
			(xy 301.693802 -303.301073) (xy 301.651181 -303.276466) (xy 301.61306 -303.245341) (xy 301.580425 -303.208504)
			(xy 301.554122 -303.166908) (xy 301.534831 -303.121632) (xy 301.523054 -303.073848) (xy 301.519094 -303.024794)
			(xy 301.179992 -303.024794) (xy 301.179497 -303.049401) (xy 301.171602 -303.097978) (xy 301.156018 -303.144659)
			(xy 301.133147 -303.188236) (xy 301.103582 -303.22758) (xy 301.068089 -303.261672) (xy 301.027586 -303.289628)
			(xy 300.983124 -303.310726) (xy 300.935853 -303.324418) (xy 300.886998 -303.33035) (xy 300.837823 -303.328369)
			(xy 300.789604 -303.318525) (xy 300.743588 -303.301073) (xy 300.700967 -303.276466) (xy 300.662846 -303.245341)
			(xy 300.630211 -303.208504) (xy 300.603908 -303.166908) (xy 300.584617 -303.121632) (xy 300.57284 -303.073848)
			(xy 300.56888 -303.024794) (xy 300.230032 -303.024794) (xy 300.229537 -303.049401) (xy 300.221642 -303.097978)
			(xy 300.206058 -303.144659) (xy 300.183187 -303.188236) (xy 300.153622 -303.22758) (xy 300.118129 -303.261672)
			(xy 300.077626 -303.289628) (xy 300.033164 -303.310726) (xy 299.985893 -303.324418) (xy 299.937038 -303.33035)
			(xy 299.887863 -303.328369) (xy 299.839644 -303.318525) (xy 299.793628 -303.301073) (xy 299.751007 -303.276466)
			(xy 299.712886 -303.245341) (xy 299.680251 -303.208504) (xy 299.653948 -303.166908) (xy 299.634657 -303.121632)
			(xy 299.62288 -303.073848) (xy 299.61892 -303.024794) (xy 299.280072 -303.024794) (xy 299.279577 -303.049401)
			(xy 299.271682 -303.097978) (xy 299.256098 -303.144659) (xy 299.233227 -303.188236) (xy 299.203662 -303.22758)
			(xy 299.168169 -303.261672) (xy 299.127666 -303.289628) (xy 299.083204 -303.310726) (xy 299.035933 -303.324418)
			(xy 298.987078 -303.33035) (xy 298.937903 -303.328369) (xy 298.889684 -303.318525) (xy 298.843668 -303.301073)
			(xy 298.801047 -303.276466) (xy 298.762926 -303.245341) (xy 298.730291 -303.208504) (xy 298.703988 -303.166908)
			(xy 298.684697 -303.121632) (xy 298.67292 -303.073848) (xy 298.66896 -303.024794) (xy 298.330112 -303.024794)
			(xy 298.329617 -303.049401) (xy 298.321722 -303.097978) (xy 298.306138 -303.144659) (xy 298.283267 -303.188236)
			(xy 298.253702 -303.22758) (xy 298.218209 -303.261672) (xy 298.177706 -303.289628) (xy 298.133244 -303.310726)
			(xy 298.085973 -303.324418) (xy 298.037118 -303.33035) (xy 297.987943 -303.328369) (xy 297.939724 -303.318525)
			(xy 297.893708 -303.301073) (xy 297.851087 -303.276466) (xy 297.812966 -303.245341) (xy 297.780331 -303.208504)
			(xy 297.754028 -303.166908) (xy 297.734737 -303.121632) (xy 297.72296 -303.073848) (xy 297.719 -303.024794)
			(xy 297.380152 -303.024794) (xy 297.379657 -303.049401) (xy 297.371762 -303.097978) (xy 297.356178 -303.144659)
			(xy 297.333307 -303.188236) (xy 297.303742 -303.22758) (xy 297.268249 -303.261672) (xy 297.227746 -303.289628)
			(xy 297.183284 -303.310726) (xy 297.136013 -303.324418) (xy 297.087158 -303.33035) (xy 297.037983 -303.328369)
			(xy 296.989764 -303.318525) (xy 296.943748 -303.301073) (xy 296.901127 -303.276466) (xy 296.863006 -303.245341)
			(xy 296.830371 -303.208504) (xy 296.804068 -303.166908) (xy 296.784777 -303.121632) (xy 296.773 -303.073848)
			(xy 296.76904 -303.024794) (xy 296.430192 -303.024794) (xy 296.429697 -303.049401) (xy 296.421802 -303.097978)
			(xy 296.406218 -303.144659) (xy 296.383347 -303.188236) (xy 296.353782 -303.22758) (xy 296.318289 -303.261672)
			(xy 296.277786 -303.289628) (xy 296.233324 -303.310726) (xy 296.186053 -303.324418) (xy 296.137198 -303.33035)
			(xy 296.088023 -303.328369) (xy 296.039804 -303.318525) (xy 295.993788 -303.301073) (xy 295.951167 -303.276466)
			(xy 295.913046 -303.245341) (xy 295.880411 -303.208504) (xy 295.854108 -303.166908) (xy 295.834817 -303.121632)
			(xy 295.82304 -303.073848) (xy 295.81908 -303.024794) (xy 295.480232 -303.024794) (xy 295.479737 -303.049401)
			(xy 295.471842 -303.097978) (xy 295.456258 -303.144659) (xy 295.433387 -303.188236) (xy 295.403822 -303.22758)
			(xy 295.368329 -303.261672) (xy 295.327826 -303.289628) (xy 295.283364 -303.310726) (xy 295.236093 -303.324418)
			(xy 295.187238 -303.33035) (xy 295.138063 -303.328369) (xy 295.089844 -303.318525) (xy 295.043828 -303.301073)
			(xy 295.001207 -303.276466) (xy 294.963086 -303.245341) (xy 294.930451 -303.208504) (xy 294.904148 -303.166908)
			(xy 294.884857 -303.121632) (xy 294.87308 -303.073848) (xy 294.86912 -303.024794) (xy 294.530018 -303.024794)
			(xy 294.529523 -303.049401) (xy 294.521628 -303.097978) (xy 294.506044 -303.144659) (xy 294.483173 -303.188236)
			(xy 294.453608 -303.22758) (xy 294.418115 -303.261672) (xy 294.377612 -303.289628) (xy 294.33315 -303.310726)
			(xy 294.285879 -303.324418) (xy 294.237024 -303.33035) (xy 294.187849 -303.328369) (xy 294.13963 -303.318525)
			(xy 294.093614 -303.301073) (xy 294.050993 -303.276466) (xy 294.012872 -303.245341) (xy 293.980237 -303.208504)
			(xy 293.953934 -303.166908) (xy 293.934643 -303.121632) (xy 293.922866 -303.073848) (xy 293.918906 -303.024794)
			(xy 293.580058 -303.024794) (xy 293.579563 -303.049401) (xy 293.571668 -303.097978) (xy 293.556084 -303.144659)
			(xy 293.533213 -303.188236) (xy 293.503648 -303.22758) (xy 293.468155 -303.261672) (xy 293.427652 -303.289628)
			(xy 293.38319 -303.310726) (xy 293.335919 -303.324418) (xy 293.287064 -303.33035) (xy 293.237889 -303.328369)
			(xy 293.18967 -303.318525) (xy 293.143654 -303.301073) (xy 293.101033 -303.276466) (xy 293.062912 -303.245341)
			(xy 293.030277 -303.208504) (xy 293.003974 -303.166908) (xy 292.984683 -303.121632) (xy 292.972906 -303.073848)
			(xy 292.968946 -303.024794) (xy 292.630098 -303.024794) (xy 292.629603 -303.049401) (xy 292.621708 -303.097978)
			(xy 292.606124 -303.144659) (xy 292.583253 -303.188236) (xy 292.553688 -303.22758) (xy 292.518195 -303.261672)
			(xy 292.477692 -303.289628) (xy 292.43323 -303.310726) (xy 292.385959 -303.324418) (xy 292.337104 -303.33035)
			(xy 292.287929 -303.328369) (xy 292.23971 -303.318525) (xy 292.193694 -303.301073) (xy 292.151073 -303.276466)
			(xy 292.112952 -303.245341) (xy 292.080317 -303.208504) (xy 292.054014 -303.166908) (xy 292.034723 -303.121632)
			(xy 292.022946 -303.073848) (xy 292.018986 -303.024794) (xy 290.730178 -303.024794) (xy 290.729683 -303.049401)
			(xy 290.721788 -303.097978) (xy 290.706204 -303.144659) (xy 290.683333 -303.188236) (xy 290.653768 -303.22758)
			(xy 290.618275 -303.261672) (xy 290.577772 -303.289628) (xy 290.53331 -303.310726) (xy 290.486039 -303.324418)
			(xy 290.437184 -303.33035) (xy 290.388009 -303.328369) (xy 290.33979 -303.318525) (xy 290.293774 -303.301073)
			(xy 290.251153 -303.276466) (xy 290.213032 -303.245341) (xy 290.180397 -303.208504) (xy 290.154094 -303.166908)
			(xy 290.134803 -303.121632) (xy 290.123026 -303.073848) (xy 290.119066 -303.024794) (xy 289.780218 -303.024794)
			(xy 289.779723 -303.049401) (xy 289.771828 -303.097978) (xy 289.756244 -303.144659) (xy 289.733373 -303.188236)
			(xy 289.703808 -303.22758) (xy 289.668315 -303.261672) (xy 289.627812 -303.289628) (xy 289.58335 -303.310726)
			(xy 289.536079 -303.324418) (xy 289.487224 -303.33035) (xy 289.438049 -303.328369) (xy 289.38983 -303.318525)
			(xy 289.343814 -303.301073) (xy 289.301193 -303.276466) (xy 289.263072 -303.245341) (xy 289.230437 -303.208504)
			(xy 289.204134 -303.166908) (xy 289.184843 -303.121632) (xy 289.173066 -303.073848) (xy 289.169106 -303.024794)
			(xy 288.830004 -303.024794) (xy 288.829509 -303.049401) (xy 288.821614 -303.097978) (xy 288.80603 -303.144659)
			(xy 288.783159 -303.188236) (xy 288.753594 -303.22758) (xy 288.718101 -303.261672) (xy 288.677598 -303.289628)
			(xy 288.633136 -303.310726) (xy 288.585865 -303.324418) (xy 288.53701 -303.33035) (xy 288.487835 -303.328369)
			(xy 288.439616 -303.318525) (xy 288.3936 -303.301073) (xy 288.350979 -303.276466) (xy 288.312858 -303.245341)
			(xy 288.280223 -303.208504) (xy 288.25392 -303.166908) (xy 288.234629 -303.121632) (xy 288.222852 -303.073848)
			(xy 288.218892 -303.024794) (xy 287.880044 -303.024794) (xy 287.879549 -303.049401) (xy 287.871654 -303.097978)
			(xy 287.85607 -303.144659) (xy 287.833199 -303.188236) (xy 287.803634 -303.22758) (xy 287.768141 -303.261672)
			(xy 287.727638 -303.289628) (xy 287.683176 -303.310726) (xy 287.635905 -303.324418) (xy 287.58705 -303.33035)
			(xy 287.537875 -303.328369) (xy 287.489656 -303.318525) (xy 287.44364 -303.301073) (xy 287.401019 -303.276466)
			(xy 287.362898 -303.245341) (xy 287.330263 -303.208504) (xy 287.30396 -303.166908) (xy 287.284669 -303.121632)
			(xy 287.272892 -303.073848) (xy 287.268932 -303.024794) (xy 286.930084 -303.024794) (xy 286.929589 -303.049401)
			(xy 286.921694 -303.097978) (xy 286.90611 -303.144659) (xy 286.883239 -303.188236) (xy 286.853674 -303.22758)
			(xy 286.818181 -303.261672) (xy 286.777678 -303.289628) (xy 286.733216 -303.310726) (xy 286.685945 -303.324418)
			(xy 286.63709 -303.33035) (xy 286.587915 -303.328369) (xy 286.539696 -303.318525) (xy 286.49368 -303.301073)
			(xy 286.451059 -303.276466) (xy 286.412938 -303.245341) (xy 286.380303 -303.208504) (xy 286.354 -303.166908)
			(xy 286.334709 -303.121632) (xy 286.322932 -303.073848) (xy 286.318972 -303.024794) (xy 285.980124 -303.024794)
			(xy 285.979629 -303.049401) (xy 285.971734 -303.097978) (xy 285.95615 -303.144659) (xy 285.933279 -303.188236)
			(xy 285.903714 -303.22758) (xy 285.868221 -303.261672) (xy 285.827718 -303.289628) (xy 285.783256 -303.310726)
			(xy 285.735985 -303.324418) (xy 285.68713 -303.33035) (xy 285.637955 -303.328369) (xy 285.589736 -303.318525)
			(xy 285.54372 -303.301073) (xy 285.501099 -303.276466) (xy 285.462978 -303.245341) (xy 285.430343 -303.208504)
			(xy 285.40404 -303.166908) (xy 285.384749 -303.121632) (xy 285.372972 -303.073848) (xy 285.369012 -303.024794)
			(xy 285.030164 -303.024794) (xy 285.029669 -303.049401) (xy 285.021774 -303.097978) (xy 285.00619 -303.144659)
			(xy 284.983319 -303.188236) (xy 284.953754 -303.22758) (xy 284.918261 -303.261672) (xy 284.877758 -303.289628)
			(xy 284.833296 -303.310726) (xy 284.786025 -303.324418) (xy 284.73717 -303.33035) (xy 284.687995 -303.328369)
			(xy 284.639776 -303.318525) (xy 284.59376 -303.301073) (xy 284.551139 -303.276466) (xy 284.513018 -303.245341)
			(xy 284.480383 -303.208504) (xy 284.45408 -303.166908) (xy 284.434789 -303.121632) (xy 284.423012 -303.073848)
			(xy 284.419052 -303.024794) (xy 284.080204 -303.024794) (xy 284.079709 -303.049401) (xy 284.071814 -303.097978)
			(xy 284.05623 -303.144659) (xy 284.033359 -303.188236) (xy 284.003794 -303.22758) (xy 283.968301 -303.261672)
			(xy 283.927798 -303.289628) (xy 283.883336 -303.310726) (xy 283.836065 -303.324418) (xy 283.78721 -303.33035)
			(xy 283.738035 -303.328369) (xy 283.689816 -303.318525) (xy 283.6438 -303.301073) (xy 283.601179 -303.276466)
			(xy 283.563058 -303.245341) (xy 283.530423 -303.208504) (xy 283.50412 -303.166908) (xy 283.484829 -303.121632)
			(xy 283.473052 -303.073848) (xy 283.469092 -303.024794) (xy 283.130244 -303.024794) (xy 283.129749 -303.049401)
			(xy 283.121854 -303.097978) (xy 283.10627 -303.144659) (xy 283.083399 -303.188236) (xy 283.053834 -303.22758)
			(xy 283.018341 -303.261672) (xy 282.977838 -303.289628) (xy 282.933376 -303.310726) (xy 282.886105 -303.324418)
			(xy 282.83725 -303.33035) (xy 282.788075 -303.328369) (xy 282.739856 -303.318525) (xy 282.69384 -303.301073)
			(xy 282.651219 -303.276466) (xy 282.613098 -303.245341) (xy 282.580463 -303.208504) (xy 282.55416 -303.166908)
			(xy 282.534869 -303.121632) (xy 282.523092 -303.073848) (xy 282.519132 -303.024794) (xy 282.18003 -303.024794)
			(xy 282.179535 -303.049401) (xy 282.17164 -303.097978) (xy 282.156056 -303.144659) (xy 282.133185 -303.188236)
			(xy 282.10362 -303.22758) (xy 282.068127 -303.261672) (xy 282.027624 -303.289628) (xy 281.983162 -303.310726)
			(xy 281.935891 -303.324418) (xy 281.887036 -303.33035) (xy 281.837861 -303.328369) (xy 281.789642 -303.318525)
			(xy 281.743626 -303.301073) (xy 281.701005 -303.276466) (xy 281.662884 -303.245341) (xy 281.630249 -303.208504)
			(xy 281.603946 -303.166908) (xy 281.584655 -303.121632) (xy 281.572878 -303.073848) (xy 281.568918 -303.024794)
			(xy 281.23007 -303.024794) (xy 281.229575 -303.049401) (xy 281.22168 -303.097978) (xy 281.206096 -303.144659)
			(xy 281.183225 -303.188236) (xy 281.15366 -303.22758) (xy 281.118167 -303.261672) (xy 281.077664 -303.289628)
			(xy 281.033202 -303.310726) (xy 280.985931 -303.324418) (xy 280.937076 -303.33035) (xy 280.887901 -303.328369)
			(xy 280.839682 -303.318525) (xy 280.793666 -303.301073) (xy 280.751045 -303.276466) (xy 280.712924 -303.245341)
			(xy 280.680289 -303.208504) (xy 280.653986 -303.166908) (xy 280.634695 -303.121632) (xy 280.622918 -303.073848)
			(xy 280.618958 -303.024794) (xy 280.28011 -303.024794) (xy 280.28011 -303.041304) (xy 280.279602 -303.047146)
			(xy 280.279602 -303.047654) (xy 280.278332 -303.058576) (xy 280.278332 -303.05883) (xy 280.277824 -303.062894)
			(xy 280.275284 -303.08169) (xy 280.274268 -303.087278) (xy 280.270204 -303.103026) (xy 280.268426 -303.115726)
			(xy 280.268426 -303.499774) (xy 306.744128 -303.499774) (xy 306.748088 -303.45072) (xy 306.759865 -303.402936)
			(xy 306.779156 -303.35766) (xy 306.805459 -303.316064) (xy 306.838094 -303.279227) (xy 306.876215 -303.248102)
			(xy 306.918836 -303.223495) (xy 306.964852 -303.206043) (xy 307.013071 -303.196199) (xy 307.062246 -303.194218)
			(xy 307.111101 -303.20015) (xy 307.158372 -303.213842) (xy 307.202834 -303.23494) (xy 307.243337 -303.262896)
			(xy 307.27883 -303.296988) (xy 307.308395 -303.336332) (xy 307.331266 -303.379909) (xy 307.34685 -303.42659)
			(xy 307.354745 -303.475167) (xy 307.355074 -303.491531) (xy 307.694155 -303.491531) (xy 307.69952 -303.442176)
			(xy 307.7128 -303.394338) (xy 307.733644 -303.349279) (xy 307.761504 -303.308186) (xy 307.795644 -303.272142)
			(xy 307.835167 -303.242096) (xy 307.879029 -303.21884) (xy 307.926076 -303.202986) (xy 307.975069 -303.194953)
			(xy 307.999892 -303.194466) (xy 308.014075 -303.194644) (xy 308.042315 -303.197315) (xy 308.05628 -303.1998)
			(xy 308.070247 -303.201963) (xy 308.09838 -303.199389) (xy 308.124731 -303.189201) (xy 308.14728 -303.172181)
			(xy 308.1643 -303.149632) (xy 308.174488 -303.123282) (xy 308.177063 -303.095148) (xy 308.174898 -303.081182)
			(xy 308.172423 -303.067216) (xy 308.16975 -303.038976) (xy 308.169564 -303.024794) (xy 308.170084 -302.999973)
			(xy 308.178117 -302.950986) (xy 308.193968 -302.903943) (xy 308.217222 -302.860085) (xy 308.247265 -302.820567)
			(xy 308.283306 -302.78643) (xy 308.324394 -302.758573) (xy 308.369448 -302.737731) (xy 308.417281 -302.724452)
			(xy 308.466632 -302.719087) (xy 308.5162 -302.721777) (xy 308.564681 -302.73245) (xy 308.610796 -302.750827)
			(xy 308.65333 -302.776422) (xy 308.691163 -302.808561) (xy 308.723298 -302.846398) (xy 308.748888 -302.888935)
			(xy 308.76726 -302.935052) (xy 308.777928 -302.983534) (xy 308.780162 -303.024794) (xy 309.119028 -303.024794)
			(xy 309.122988 -302.97574) (xy 309.134765 -302.927956) (xy 309.154056 -302.88268) (xy 309.180359 -302.841084)
			(xy 309.212994 -302.804247) (xy 309.251115 -302.773122) (xy 309.293736 -302.748515) (xy 309.339752 -302.731063)
			(xy 309.387971 -302.721219) (xy 309.437146 -302.719238) (xy 309.486001 -302.72517) (xy 309.533272 -302.738862)
			(xy 309.577734 -302.75996) (xy 309.618237 -302.787916) (xy 309.65373 -302.822008) (xy 309.683295 -302.861352)
			(xy 309.706166 -302.904929) (xy 309.72175 -302.95161) (xy 309.729645 -303.000187) (xy 309.73014 -303.024794)
			(xy 309.729973 -303.033078) (xy 310.069089 -303.033078) (xy 310.071777 -302.983511) (xy 310.082449 -302.935032)
			(xy 310.100823 -302.888917) (xy 310.126415 -302.846383) (xy 310.158551 -302.80855) (xy 310.196385 -302.776414)
			(xy 310.238919 -302.750822) (xy 310.285034 -302.732448) (xy 310.333513 -302.721777) (xy 310.38308 -302.719089)
			(xy 310.432429 -302.724456) (xy 310.48026 -302.737736) (xy 310.525312 -302.758578) (xy 310.566399 -302.786435)
			(xy 310.602437 -302.820572) (xy 310.632479 -302.86009) (xy 310.655731 -302.903947) (xy 310.671582 -302.950988)
			(xy 310.679614 -302.999974) (xy 310.6801 -303.024794) (xy 310.679923 -303.038977) (xy 310.677251 -303.067217)
			(xy 310.674766 -303.081182) (xy 310.67248 -303.093628) (xy 310.679846 -303.11725) (xy 310.757316 -303.19472)
			(xy 310.780938 -303.202086) (xy 310.793384 -303.1998) (xy 310.807349 -303.197316) (xy 310.835589 -303.194649)
			(xy 310.849772 -303.194466) (xy 310.863955 -303.194647) (xy 310.892195 -303.197316) (xy 310.90616 -303.1998)
			(xy 310.918606 -303.202086) (xy 310.942228 -303.19472) (xy 311.019698 -303.11725) (xy 311.027064 -303.093628)
			(xy 311.024778 -303.081182) (xy 311.022303 -303.067216) (xy 311.01963 -303.038976) (xy 311.019444 -303.024794)
			(xy 311.019984 -302.999973) (xy 311.028017 -302.950985) (xy 311.043869 -302.903942) (xy 311.067123 -302.860083)
			(xy 311.097167 -302.820564) (xy 311.133208 -302.786427) (xy 311.174298 -302.758571) (xy 311.219353 -302.737729)
			(xy 311.267187 -302.724451) (xy 311.316538 -302.719087) (xy 311.366107 -302.721778) (xy 311.414588 -302.732453)
			(xy 311.460703 -302.750831) (xy 311.503237 -302.776427) (xy 311.54107 -302.808568) (xy 311.573204 -302.846406)
			(xy 311.598793 -302.888945) (xy 311.617163 -302.935063) (xy 311.62783 -302.983546) (xy 311.630062 -303.024794)
			(xy 311.968908 -303.024794) (xy 311.972868 -302.97574) (xy 311.984645 -302.927956) (xy 312.003936 -302.88268)
			(xy 312.030239 -302.841084) (xy 312.062874 -302.804247) (xy 312.100995 -302.773122) (xy 312.143616 -302.748515)
			(xy 312.189632 -302.731063) (xy 312.237851 -302.721219) (xy 312.287026 -302.719238) (xy 312.335881 -302.72517)
			(xy 312.383152 -302.738862) (xy 312.427614 -302.75996) (xy 312.468117 -302.787916) (xy 312.50361 -302.822008)
			(xy 312.533175 -302.861352) (xy 312.556046 -302.904929) (xy 312.57163 -302.95161) (xy 312.579525 -303.000187)
			(xy 312.58002 -303.024794) (xy 312.919122 -303.024794) (xy 312.923082 -302.97574) (xy 312.934859 -302.927956)
			(xy 312.95415 -302.88268) (xy 312.980453 -302.841084) (xy 313.013088 -302.804247) (xy 313.051209 -302.773122)
			(xy 313.09383 -302.748515) (xy 313.139846 -302.731063) (xy 313.188065 -302.721219) (xy 313.23724 -302.719238)
			(xy 313.286095 -302.72517) (xy 313.333366 -302.738862) (xy 313.377828 -302.75996) (xy 313.418331 -302.787916)
			(xy 313.453824 -302.822008) (xy 313.483389 -302.861352) (xy 313.50626 -302.904929) (xy 313.521844 -302.95161)
			(xy 313.529739 -303.000187) (xy 313.530234 -303.024794) (xy 313.869082 -303.024794) (xy 313.873042 -302.97574)
			(xy 313.884819 -302.927956) (xy 313.90411 -302.88268) (xy 313.930413 -302.841084) (xy 313.963048 -302.804247)
			(xy 314.001169 -302.773122) (xy 314.04379 -302.748515) (xy 314.089806 -302.731063) (xy 314.138025 -302.721219)
			(xy 314.1872 -302.719238) (xy 314.236055 -302.72517) (xy 314.283326 -302.738862) (xy 314.327788 -302.75996)
			(xy 314.368291 -302.787916) (xy 314.403784 -302.822008) (xy 314.433349 -302.861352) (xy 314.45622 -302.904929)
			(xy 314.471804 -302.95161) (xy 314.479699 -303.000187) (xy 314.480194 -303.024794) (xy 314.803802 -303.024794)
			(xy 314.807762 -302.97574) (xy 314.819539 -302.927956) (xy 314.83883 -302.88268) (xy 314.865133 -302.841084)
			(xy 314.897768 -302.804247) (xy 314.935889 -302.773122) (xy 314.97851 -302.748515) (xy 315.024526 -302.731063)
			(xy 315.072745 -302.721219) (xy 315.12192 -302.719238) (xy 315.170775 -302.72517) (xy 315.218046 -302.738862)
			(xy 315.262508 -302.75996) (xy 315.303011 -302.787916) (xy 315.338504 -302.822008) (xy 315.368069 -302.861352)
			(xy 315.39094 -302.904929) (xy 315.406524 -302.95161) (xy 315.414419 -303.000187) (xy 315.414914 -303.024794)
			(xy 315.414873 -303.026826) (xy 320.819524 -303.026826) (xy 320.823595 -302.971204) (xy 320.835721 -302.916767)
			(xy 320.855644 -302.864676) (xy 320.88294 -302.816041) (xy 320.917026 -302.771898) (xy 320.957175 -302.733189)
			(xy 321.002533 -302.700738) (xy 321.052133 -302.675237) (xy 321.104917 -302.65723) (xy 321.15976 -302.6471)
			(xy 321.215494 -302.645063) (xy 321.270931 -302.651163) (xy 321.324888 -302.665269) (xy 321.376217 -302.687081)
			(xy 321.423823 -302.716135) (xy 321.466691 -302.75181) (xy 321.503908 -302.793347) (xy 321.534681 -302.83986)
			(xy 321.558353 -302.890357) (xy 321.574421 -302.943764) (xy 321.582541 -302.99894) (xy 321.58305 -303.026826)
			(xy 321.835524 -303.026826) (xy 321.839595 -302.971204) (xy 321.851721 -302.916767) (xy 321.871644 -302.864676)
			(xy 321.89894 -302.816041) (xy 321.933026 -302.771898) (xy 321.973175 -302.733189) (xy 322.018533 -302.700738)
			(xy 322.068133 -302.675237) (xy 322.120917 -302.65723) (xy 322.17576 -302.6471) (xy 322.231494 -302.645063)
			(xy 322.286931 -302.651163) (xy 322.340888 -302.665269) (xy 322.392217 -302.687081) (xy 322.439823 -302.716135)
			(xy 322.482691 -302.75181) (xy 322.519908 -302.793347) (xy 322.550681 -302.83986) (xy 322.574353 -302.890357)
			(xy 322.590421 -302.943764) (xy 322.598541 -302.99894) (xy 322.59905 -303.026826) (xy 322.851524 -303.026826)
			(xy 322.855595 -302.971204) (xy 322.867721 -302.916767) (xy 322.887644 -302.864676) (xy 322.91494 -302.816041)
			(xy 322.949026 -302.771898) (xy 322.989175 -302.733189) (xy 323.034533 -302.700738) (xy 323.084133 -302.675237)
			(xy 323.136917 -302.65723) (xy 323.19176 -302.6471) (xy 323.247494 -302.645063) (xy 323.302931 -302.651163)
			(xy 323.356888 -302.665269) (xy 323.408217 -302.687081) (xy 323.455823 -302.716135) (xy 323.498691 -302.75181)
			(xy 323.535908 -302.793347) (xy 323.566681 -302.83986) (xy 323.590353 -302.890357) (xy 323.606421 -302.943764)
			(xy 323.614541 -302.99894) (xy 323.61505 -303.026826) (xy 323.867524 -303.026826) (xy 323.871595 -302.971204)
			(xy 323.883721 -302.916767) (xy 323.903644 -302.864676) (xy 323.93094 -302.816041) (xy 323.965026 -302.771898)
			(xy 324.005175 -302.733189) (xy 324.050533 -302.700738) (xy 324.100133 -302.675237) (xy 324.152917 -302.65723)
			(xy 324.20776 -302.6471) (xy 324.263494 -302.645063) (xy 324.318931 -302.651163) (xy 324.372888 -302.665269)
			(xy 324.424217 -302.687081) (xy 324.471823 -302.716135) (xy 324.514691 -302.75181) (xy 324.551908 -302.793347)
			(xy 324.582681 -302.83986) (xy 324.606353 -302.890357) (xy 324.622421 -302.943764) (xy 324.630541 -302.99894)
			(xy 324.63105 -303.026826) (xy 324.883524 -303.026826) (xy 324.887595 -302.971204) (xy 324.899721 -302.916767)
			(xy 324.919644 -302.864676) (xy 324.94694 -302.816041) (xy 324.981026 -302.771898) (xy 325.021175 -302.733189)
			(xy 325.066533 -302.700738) (xy 325.116133 -302.675237) (xy 325.168917 -302.65723) (xy 325.22376 -302.6471)
			(xy 325.279494 -302.645063) (xy 325.334931 -302.651163) (xy 325.388888 -302.665269) (xy 325.440217 -302.687081)
			(xy 325.487823 -302.716135) (xy 325.530691 -302.75181) (xy 325.567908 -302.793347) (xy 325.598681 -302.83986)
			(xy 325.622353 -302.890357) (xy 325.638421 -302.943764) (xy 325.646541 -302.99894) (xy 325.64705 -303.026826)
			(xy 325.646541 -303.054712) (xy 325.638421 -303.109888) (xy 325.622353 -303.163295) (xy 325.598681 -303.213792)
			(xy 325.567908 -303.260305) (xy 325.530691 -303.301842) (xy 325.487823 -303.337517) (xy 325.440217 -303.366571)
			(xy 325.388888 -303.388383) (xy 325.334931 -303.402489) (xy 325.279494 -303.408589) (xy 325.22376 -303.406552)
			(xy 325.168917 -303.396422) (xy 325.116133 -303.378415) (xy 325.066533 -303.352914) (xy 325.021175 -303.320463)
			(xy 324.981026 -303.281754) (xy 324.94694 -303.237611) (xy 324.919644 -303.188976) (xy 324.899721 -303.136885)
			(xy 324.887595 -303.082448) (xy 324.883524 -303.026826) (xy 324.63105 -303.026826) (xy 324.630541 -303.054712)
			(xy 324.622421 -303.109888) (xy 324.606353 -303.163295) (xy 324.582681 -303.213792) (xy 324.551908 -303.260305)
			(xy 324.514691 -303.301842) (xy 324.471823 -303.337517) (xy 324.424217 -303.366571) (xy 324.372888 -303.388383)
			(xy 324.318931 -303.402489) (xy 324.263494 -303.408589) (xy 324.20776 -303.406552) (xy 324.152917 -303.396422)
			(xy 324.100133 -303.378415) (xy 324.050533 -303.352914) (xy 324.005175 -303.320463) (xy 323.965026 -303.281754)
			(xy 323.93094 -303.237611) (xy 323.903644 -303.188976) (xy 323.883721 -303.136885) (xy 323.871595 -303.082448)
			(xy 323.867524 -303.026826) (xy 323.61505 -303.026826) (xy 323.614541 -303.054712) (xy 323.606421 -303.109888)
			(xy 323.590353 -303.163295) (xy 323.566681 -303.213792) (xy 323.535908 -303.260305) (xy 323.498691 -303.301842)
			(xy 323.455823 -303.337517) (xy 323.408217 -303.366571) (xy 323.356888 -303.388383) (xy 323.302931 -303.402489)
			(xy 323.247494 -303.408589) (xy 323.19176 -303.406552) (xy 323.136917 -303.396422) (xy 323.084133 -303.378415)
			(xy 323.034533 -303.352914) (xy 322.989175 -303.320463) (xy 322.949026 -303.281754) (xy 322.91494 -303.237611)
			(xy 322.887644 -303.188976) (xy 322.867721 -303.136885) (xy 322.855595 -303.082448) (xy 322.851524 -303.026826)
			(xy 322.59905 -303.026826) (xy 322.598541 -303.054712) (xy 322.590421 -303.109888) (xy 322.574353 -303.163295)
			(xy 322.550681 -303.213792) (xy 322.519908 -303.260305) (xy 322.482691 -303.301842) (xy 322.439823 -303.337517)
			(xy 322.392217 -303.366571) (xy 322.340888 -303.388383) (xy 322.286931 -303.402489) (xy 322.231494 -303.408589)
			(xy 322.17576 -303.406552) (xy 322.120917 -303.396422) (xy 322.068133 -303.378415) (xy 322.018533 -303.352914)
			(xy 321.973175 -303.320463) (xy 321.933026 -303.281754) (xy 321.89894 -303.237611) (xy 321.871644 -303.188976)
			(xy 321.851721 -303.136885) (xy 321.839595 -303.082448) (xy 321.835524 -303.026826) (xy 321.58305 -303.026826)
			(xy 321.582541 -303.054712) (xy 321.574421 -303.109888) (xy 321.558353 -303.163295) (xy 321.534681 -303.213792)
			(xy 321.503908 -303.260305) (xy 321.466691 -303.301842) (xy 321.423823 -303.337517) (xy 321.376217 -303.366571)
			(xy 321.324888 -303.388383) (xy 321.270931 -303.402489) (xy 321.215494 -303.408589) (xy 321.15976 -303.406552)
			(xy 321.104917 -303.396422) (xy 321.052133 -303.378415) (xy 321.002533 -303.352914) (xy 320.957175 -303.320463)
			(xy 320.917026 -303.281754) (xy 320.88294 -303.237611) (xy 320.855644 -303.188976) (xy 320.835721 -303.136885)
			(xy 320.823595 -303.082448) (xy 320.819524 -303.026826) (xy 315.414873 -303.026826) (xy 315.414419 -303.049401)
			(xy 315.406524 -303.097978) (xy 315.39094 -303.144659) (xy 315.368069 -303.188236) (xy 315.338504 -303.22758)
			(xy 315.303011 -303.261672) (xy 315.262508 -303.289628) (xy 315.218046 -303.310726) (xy 315.170775 -303.324418)
			(xy 315.12192 -303.33035) (xy 315.072745 -303.328369) (xy 315.024526 -303.318525) (xy 314.97851 -303.301073)
			(xy 314.935889 -303.276466) (xy 314.897768 -303.245341) (xy 314.865133 -303.208504) (xy 314.83883 -303.166908)
			(xy 314.819539 -303.121632) (xy 314.807762 -303.073848) (xy 314.803802 -303.024794) (xy 314.480194 -303.024794)
			(xy 314.479699 -303.049401) (xy 314.471804 -303.097978) (xy 314.45622 -303.144659) (xy 314.433349 -303.188236)
			(xy 314.403784 -303.22758) (xy 314.368291 -303.261672) (xy 314.327788 -303.289628) (xy 314.283326 -303.310726)
			(xy 314.236055 -303.324418) (xy 314.1872 -303.33035) (xy 314.138025 -303.328369) (xy 314.089806 -303.318525)
			(xy 314.04379 -303.301073) (xy 314.001169 -303.276466) (xy 313.963048 -303.245341) (xy 313.930413 -303.208504)
			(xy 313.90411 -303.166908) (xy 313.884819 -303.121632) (xy 313.873042 -303.073848) (xy 313.869082 -303.024794)
			(xy 313.530234 -303.024794) (xy 313.529739 -303.049401) (xy 313.521844 -303.097978) (xy 313.50626 -303.144659)
			(xy 313.483389 -303.188236) (xy 313.453824 -303.22758) (xy 313.418331 -303.261672) (xy 313.377828 -303.289628)
			(xy 313.333366 -303.310726) (xy 313.286095 -303.324418) (xy 313.23724 -303.33035) (xy 313.188065 -303.328369)
			(xy 313.139846 -303.318525) (xy 313.09383 -303.301073) (xy 313.051209 -303.276466) (xy 313.013088 -303.245341)
			(xy 312.980453 -303.208504) (xy 312.95415 -303.166908) (xy 312.934859 -303.121632) (xy 312.923082 -303.073848)
			(xy 312.919122 -303.024794) (xy 312.58002 -303.024794) (xy 312.579525 -303.049401) (xy 312.57163 -303.097978)
			(xy 312.556046 -303.144659) (xy 312.533175 -303.188236) (xy 312.50361 -303.22758) (xy 312.468117 -303.261672)
			(xy 312.427614 -303.289628) (xy 312.383152 -303.310726) (xy 312.335881 -303.324418) (xy 312.287026 -303.33035)
			(xy 312.237851 -303.328369) (xy 312.189632 -303.318525) (xy 312.143616 -303.301073) (xy 312.100995 -303.276466)
			(xy 312.062874 -303.245341) (xy 312.030239 -303.208504) (xy 312.003936 -303.166908) (xy 311.984645 -303.121632)
			(xy 311.972868 -303.073848) (xy 311.968908 -303.024794) (xy 311.630062 -303.024794) (xy 311.630512 -303.033116)
			(xy 311.625139 -303.082466) (xy 311.611853 -303.130298) (xy 311.591003 -303.175349) (xy 311.563139 -303.216434)
			(xy 311.528995 -303.252469) (xy 311.489471 -303.282506) (xy 311.445609 -303.305752) (xy 311.398563 -303.321596)
			(xy 311.349573 -303.32962) (xy 311.324752 -303.330102) (xy 311.310569 -303.329918) (xy 311.282329 -303.327251)
			(xy 311.268364 -303.324768) (xy 311.255918 -303.322482) (xy 311.232296 -303.329848) (xy 311.154826 -303.407318)
			(xy 311.14746 -303.43094) (xy 311.149746 -303.443386) (xy 311.152216 -303.457353) (xy 311.154892 -303.485592)
			(xy 311.15508 -303.499774) (xy 311.154558 -303.525029) (xy 311.152702 -303.536153) (xy 317.895173 -303.536153)
			(xy 317.895173 -303.481647) (xy 317.902931 -303.427697) (xy 317.918287 -303.3754) (xy 317.94093 -303.32582)
			(xy 317.970399 -303.279968) (xy 318.006094 -303.238777) (xy 318.047287 -303.203085) (xy 318.093141 -303.173619)
			(xy 318.142722 -303.150979) (xy 318.19502 -303.135625) (xy 318.248971 -303.127872) (xy 318.276224 -303.12741)
			(xy 318.304673 -303.127942) (xy 318.360943 -303.136369) (xy 318.415337 -303.153063) (xy 318.466646 -303.177652)
			(xy 318.513733 -303.209592) (xy 318.555552 -303.248173) (xy 318.591175 -303.292539) (xy 318.619812 -303.341705)
			(xy 318.630808 -303.367948) (xy 318.63411 -303.376584) (xy 318.646302 -303.390046) (xy 318.723264 -303.429162)
			(xy 318.741044 -303.43094) (xy 318.750442 -303.428654) (xy 318.773729 -303.423072) (xy 318.82124 -303.417089)
			(xy 318.845184 -303.416716) (xy 318.872439 -303.41713) (xy 318.926395 -303.424885) (xy 318.978699 -303.440241)
			(xy 319.028284 -303.462884) (xy 319.074142 -303.492354) (xy 319.115339 -303.528049) (xy 319.151037 -303.569245)
			(xy 319.180508 -303.615102) (xy 319.203153 -303.664686) (xy 319.218511 -303.716989) (xy 319.226269 -303.770945)
			(xy 319.226269 -303.825455) (xy 319.218511 -303.879411) (xy 319.203153 -303.931714) (xy 319.180508 -303.981298)
			(xy 319.151037 -304.027155) (xy 319.115339 -304.068351) (xy 319.074142 -304.104046) (xy 319.028284 -304.133516)
			(xy 318.978699 -304.156159) (xy 318.926395 -304.171515) (xy 318.872439 -304.17927) (xy 318.845184 -304.179732)
			(xy 318.816733 -304.17923) (xy 318.76046 -304.170802) (xy 318.706064 -304.154107) (xy 318.654753 -304.129514)
			(xy 318.607665 -304.097569) (xy 318.565847 -304.058983) (xy 318.530226 -304.014612) (xy 318.501594 -303.96544)
			(xy 318.4906 -303.939194) (xy 318.487298 -303.930558) (xy 318.475106 -303.917096) (xy 318.398144 -303.87798)
			(xy 318.380364 -303.876202) (xy 318.370966 -303.878488) (xy 318.347679 -303.884068) (xy 318.300167 -303.890053)
			(xy 318.276224 -303.890426) (xy 318.248971 -303.889928) (xy 318.19502 -303.882175) (xy 318.142722 -303.866821)
			(xy 318.093141 -303.844181) (xy 318.047287 -303.814715) (xy 318.006094 -303.779023) (xy 317.970399 -303.737832)
			(xy 317.94093 -303.69198) (xy 317.918287 -303.6424) (xy 317.902931 -303.590103) (xy 317.895173 -303.536153)
			(xy 311.152702 -303.536153) (xy 311.146245 -303.574851) (xy 311.129844 -303.622625) (xy 311.105803 -303.667048)
			(xy 311.074779 -303.706908) (xy 311.037617 -303.741118) (xy 310.995331 -303.768744) (xy 310.949075 -303.789034)
			(xy 310.90011 -303.801434) (xy 310.849772 -303.805605) (xy 310.799434 -303.801434) (xy 310.750469 -303.789034)
			(xy 310.704213 -303.768744) (xy 310.661927 -303.741118) (xy 310.624765 -303.706908) (xy 310.593741 -303.667048)
			(xy 310.5697 -303.622625) (xy 310.553299 -303.574851) (xy 310.544986 -303.525029) (xy 310.544464 -303.499774)
			(xy 310.544637 -303.485591) (xy 310.547312 -303.457351) (xy 310.549798 -303.443386) (xy 310.552084 -303.43094)
			(xy 310.544718 -303.407318) (xy 310.467248 -303.329848) (xy 310.443626 -303.322482) (xy 310.43118 -303.324768)
			(xy 310.417214 -303.327243) (xy 310.388974 -303.329916) (xy 310.374792 -303.330102) (xy 310.349972 -303.329614)
			(xy 310.300986 -303.321581) (xy 310.253945 -303.30573) (xy 310.210088 -303.282478) (xy 310.170571 -303.252436)
			(xy 310.136434 -303.216397) (xy 310.108578 -303.17531) (xy 310.087735 -303.130258) (xy 310.074455 -303.082427)
			(xy 310.069089 -303.033078) (xy 309.729973 -303.033078) (xy 309.729645 -303.049401) (xy 309.72175 -303.097978)
			(xy 309.706166 -303.144659) (xy 309.683295 -303.188236) (xy 309.65373 -303.22758) (xy 309.618237 -303.261672)
			(xy 309.577734 -303.289628) (xy 309.533272 -303.310726) (xy 309.486001 -303.324418) (xy 309.437146 -303.33035)
			(xy 309.387971 -303.328369) (xy 309.339752 -303.318525) (xy 309.293736 -303.301073) (xy 309.251115 -303.276466)
			(xy 309.212994 -303.245341) (xy 309.180359 -303.208504) (xy 309.154056 -303.166908) (xy 309.134765 -303.121632)
			(xy 309.122988 -303.073848) (xy 309.119028 -303.024794) (xy 308.780162 -303.024794) (xy 308.780612 -303.033102)
			(xy 308.775242 -303.082452) (xy 308.761958 -303.130284) (xy 308.74111 -303.175335) (xy 308.713249 -303.216421)
			(xy 308.679108 -303.252458) (xy 308.639586 -303.282496) (xy 308.595725 -303.305745) (xy 308.548681 -303.321592)
			(xy 308.499693 -303.329618) (xy 308.474872 -303.330102) (xy 308.460689 -303.329929) (xy 308.432449 -303.327255)
			(xy 308.418484 -303.324768) (xy 308.404519 -303.322605) (xy 308.376389 -303.325188) (xy 308.350043 -303.335379)
			(xy 308.327498 -303.352399) (xy 308.310478 -303.374945) (xy 308.300288 -303.401291) (xy 308.297705 -303.429421)
			(xy 308.299866 -303.443386) (xy 308.302336 -303.457353) (xy 308.305012 -303.485592) (xy 308.3052 -303.499774)
			(xy 308.30475 -303.524597) (xy 308.296722 -303.573591) (xy 308.280874 -303.62064) (xy 308.257622 -303.664505)
			(xy 308.227581 -303.70403) (xy 308.19154 -303.738175) (xy 308.15045 -303.766039) (xy 308.105394 -303.786888)
			(xy 308.057558 -303.800173) (xy 308.008203 -303.805544) (xy 307.958629 -303.80286) (xy 307.910142 -303.79219)
			(xy 307.864021 -303.773817) (xy 307.821479 -303.748224) (xy 307.783638 -303.716086) (xy 307.751496 -303.678249)
			(xy 307.725898 -303.63571) (xy 307.70752 -303.58959) (xy 307.696845 -303.541105) (xy 307.694155 -303.491531)
			(xy 307.355074 -303.491531) (xy 307.35524 -303.499774) (xy 307.354745 -303.524381) (xy 307.34685 -303.572958)
			(xy 307.331266 -303.619639) (xy 307.308395 -303.663216) (xy 307.27883 -303.70256) (xy 307.243337 -303.736652)
			(xy 307.202834 -303.764608) (xy 307.158372 -303.785706) (xy 307.111101 -303.799398) (xy 307.062246 -303.80533)
			(xy 307.013071 -303.803349) (xy 306.964852 -303.793505) (xy 306.918836 -303.776053) (xy 306.876215 -303.751446)
			(xy 306.838094 -303.720321) (xy 306.805459 -303.683484) (xy 306.779156 -303.641888) (xy 306.759865 -303.596612)
			(xy 306.748088 -303.548828) (xy 306.744128 -303.499774) (xy 280.268426 -303.499774) (xy 280.268426 -303.880012)
			(xy 280.268934 -303.886108) (xy 280.270204 -303.897284) (xy 280.270966 -303.900586) (xy 280.270966 -303.901094)
			(xy 280.27522 -303.919212) (xy 280.27981 -303.956146) (xy 280.28011 -303.974754) (xy 280.618958 -303.974754)
			(xy 280.622918 -303.9257) (xy 280.634695 -303.877916) (xy 280.653986 -303.83264) (xy 280.680289 -303.791044)
			(xy 280.712924 -303.754207) (xy 280.751045 -303.723082) (xy 280.793666 -303.698475) (xy 280.839682 -303.681023)
			(xy 280.887901 -303.671179) (xy 280.937076 -303.669198) (xy 280.985931 -303.67513) (xy 281.033202 -303.688822)
			(xy 281.077664 -303.70992) (xy 281.118167 -303.737876) (xy 281.15366 -303.771968) (xy 281.183225 -303.811312)
			(xy 281.206096 -303.854889) (xy 281.22168 -303.90157) (xy 281.229575 -303.950147) (xy 281.23007 -303.974754)
			(xy 281.568918 -303.974754) (xy 281.572878 -303.9257) (xy 281.584655 -303.877916) (xy 281.603946 -303.83264)
			(xy 281.630249 -303.791044) (xy 281.662884 -303.754207) (xy 281.701005 -303.723082) (xy 281.743626 -303.698475)
			(xy 281.789642 -303.681023) (xy 281.837861 -303.671179) (xy 281.887036 -303.669198) (xy 281.935891 -303.67513)
			(xy 281.983162 -303.688822) (xy 282.027624 -303.70992) (xy 282.068127 -303.737876) (xy 282.10362 -303.771968)
			(xy 282.133185 -303.811312) (xy 282.156056 -303.854889) (xy 282.17164 -303.90157) (xy 282.179535 -303.950147)
			(xy 282.18003 -303.974754) (xy 282.519132 -303.974754) (xy 282.523092 -303.9257) (xy 282.534869 -303.877916)
			(xy 282.55416 -303.83264) (xy 282.580463 -303.791044) (xy 282.613098 -303.754207) (xy 282.651219 -303.723082)
			(xy 282.69384 -303.698475) (xy 282.739856 -303.681023) (xy 282.788075 -303.671179) (xy 282.83725 -303.669198)
			(xy 282.886105 -303.67513) (xy 282.933376 -303.688822) (xy 282.977838 -303.70992) (xy 283.018341 -303.737876)
			(xy 283.053834 -303.771968) (xy 283.083399 -303.811312) (xy 283.10627 -303.854889) (xy 283.121854 -303.90157)
			(xy 283.129749 -303.950147) (xy 283.130244 -303.974754) (xy 283.469092 -303.974754) (xy 283.473052 -303.9257)
			(xy 283.484829 -303.877916) (xy 283.50412 -303.83264) (xy 283.530423 -303.791044) (xy 283.563058 -303.754207)
			(xy 283.601179 -303.723082) (xy 283.6438 -303.698475) (xy 283.689816 -303.681023) (xy 283.738035 -303.671179)
			(xy 283.78721 -303.669198) (xy 283.836065 -303.67513) (xy 283.883336 -303.688822) (xy 283.927798 -303.70992)
			(xy 283.968301 -303.737876) (xy 284.003794 -303.771968) (xy 284.033359 -303.811312) (xy 284.05623 -303.854889)
			(xy 284.071814 -303.90157) (xy 284.079709 -303.950147) (xy 284.080204 -303.974754) (xy 284.419052 -303.974754)
			(xy 284.423012 -303.9257) (xy 284.434789 -303.877916) (xy 284.45408 -303.83264) (xy 284.480383 -303.791044)
			(xy 284.513018 -303.754207) (xy 284.551139 -303.723082) (xy 284.59376 -303.698475) (xy 284.639776 -303.681023)
			(xy 284.687995 -303.671179) (xy 284.73717 -303.669198) (xy 284.786025 -303.67513) (xy 284.833296 -303.688822)
			(xy 284.877758 -303.70992) (xy 284.918261 -303.737876) (xy 284.953754 -303.771968) (xy 284.983319 -303.811312)
			(xy 285.00619 -303.854889) (xy 285.021774 -303.90157) (xy 285.029669 -303.950147) (xy 285.030164 -303.974754)
			(xy 285.369012 -303.974754) (xy 285.372972 -303.9257) (xy 285.384749 -303.877916) (xy 285.40404 -303.83264)
			(xy 285.430343 -303.791044) (xy 285.462978 -303.754207) (xy 285.501099 -303.723082) (xy 285.54372 -303.698475)
			(xy 285.589736 -303.681023) (xy 285.637955 -303.671179) (xy 285.68713 -303.669198) (xy 285.735985 -303.67513)
			(xy 285.783256 -303.688822) (xy 285.827718 -303.70992) (xy 285.868221 -303.737876) (xy 285.903714 -303.771968)
			(xy 285.933279 -303.811312) (xy 285.95615 -303.854889) (xy 285.971734 -303.90157) (xy 285.979629 -303.950147)
			(xy 285.980124 -303.974754) (xy 286.318972 -303.974754) (xy 286.322932 -303.9257) (xy 286.334709 -303.877916)
			(xy 286.354 -303.83264) (xy 286.380303 -303.791044) (xy 286.412938 -303.754207) (xy 286.451059 -303.723082)
			(xy 286.49368 -303.698475) (xy 286.539696 -303.681023) (xy 286.587915 -303.671179) (xy 286.63709 -303.669198)
			(xy 286.685945 -303.67513) (xy 286.733216 -303.688822) (xy 286.777678 -303.70992) (xy 286.818181 -303.737876)
			(xy 286.853674 -303.771968) (xy 286.883239 -303.811312) (xy 286.90611 -303.854889) (xy 286.921694 -303.90157)
			(xy 286.929589 -303.950147) (xy 286.930084 -303.974754) (xy 287.268932 -303.974754) (xy 287.272892 -303.9257)
			(xy 287.284669 -303.877916) (xy 287.30396 -303.83264) (xy 287.330263 -303.791044) (xy 287.362898 -303.754207)
			(xy 287.401019 -303.723082) (xy 287.44364 -303.698475) (xy 287.489656 -303.681023) (xy 287.537875 -303.671179)
			(xy 287.58705 -303.669198) (xy 287.635905 -303.67513) (xy 287.683176 -303.688822) (xy 287.727638 -303.70992)
			(xy 287.768141 -303.737876) (xy 287.803634 -303.771968) (xy 287.833199 -303.811312) (xy 287.85607 -303.854889)
			(xy 287.871654 -303.90157) (xy 287.879549 -303.950147) (xy 287.880044 -303.974754) (xy 288.218892 -303.974754)
			(xy 288.222852 -303.9257) (xy 288.234629 -303.877916) (xy 288.25392 -303.83264) (xy 288.280223 -303.791044)
			(xy 288.312858 -303.754207) (xy 288.350979 -303.723082) (xy 288.3936 -303.698475) (xy 288.439616 -303.681023)
			(xy 288.487835 -303.671179) (xy 288.53701 -303.669198) (xy 288.585865 -303.67513) (xy 288.633136 -303.688822)
			(xy 288.677598 -303.70992) (xy 288.718101 -303.737876) (xy 288.753594 -303.771968) (xy 288.783159 -303.811312)
			(xy 288.80603 -303.854889) (xy 288.821614 -303.90157) (xy 288.829509 -303.950147) (xy 288.830004 -303.974754)
			(xy 289.169106 -303.974754) (xy 289.173066 -303.9257) (xy 289.184843 -303.877916) (xy 289.204134 -303.83264)
			(xy 289.230437 -303.791044) (xy 289.263072 -303.754207) (xy 289.301193 -303.723082) (xy 289.343814 -303.698475)
			(xy 289.38983 -303.681023) (xy 289.438049 -303.671179) (xy 289.487224 -303.669198) (xy 289.536079 -303.67513)
			(xy 289.58335 -303.688822) (xy 289.627812 -303.70992) (xy 289.668315 -303.737876) (xy 289.703808 -303.771968)
			(xy 289.733373 -303.811312) (xy 289.756244 -303.854889) (xy 289.771828 -303.90157) (xy 289.779723 -303.950147)
			(xy 289.780218 -303.974754) (xy 290.119066 -303.974754) (xy 290.123026 -303.9257) (xy 290.134803 -303.877916)
			(xy 290.154094 -303.83264) (xy 290.180397 -303.791044) (xy 290.213032 -303.754207) (xy 290.251153 -303.723082)
			(xy 290.293774 -303.698475) (xy 290.33979 -303.681023) (xy 290.388009 -303.671179) (xy 290.437184 -303.669198)
			(xy 290.486039 -303.67513) (xy 290.53331 -303.688822) (xy 290.577772 -303.70992) (xy 290.618275 -303.737876)
			(xy 290.653768 -303.771968) (xy 290.683333 -303.811312) (xy 290.706204 -303.854889) (xy 290.721788 -303.90157)
			(xy 290.729683 -303.950147) (xy 290.730178 -303.974754) (xy 292.018986 -303.974754) (xy 292.022946 -303.9257)
			(xy 292.034723 -303.877916) (xy 292.054014 -303.83264) (xy 292.080317 -303.791044) (xy 292.112952 -303.754207)
			(xy 292.151073 -303.723082) (xy 292.193694 -303.698475) (xy 292.23971 -303.681023) (xy 292.287929 -303.671179)
			(xy 292.337104 -303.669198) (xy 292.385959 -303.67513) (xy 292.43323 -303.688822) (xy 292.477692 -303.70992)
			(xy 292.518195 -303.737876) (xy 292.553688 -303.771968) (xy 292.583253 -303.811312) (xy 292.606124 -303.854889)
			(xy 292.621708 -303.90157) (xy 292.629603 -303.950147) (xy 292.630098 -303.974754) (xy 292.968946 -303.974754)
			(xy 292.972906 -303.9257) (xy 292.984683 -303.877916) (xy 293.003974 -303.83264) (xy 293.030277 -303.791044)
			(xy 293.062912 -303.754207) (xy 293.101033 -303.723082) (xy 293.143654 -303.698475) (xy 293.18967 -303.681023)
			(xy 293.237889 -303.671179) (xy 293.287064 -303.669198) (xy 293.335919 -303.67513) (xy 293.38319 -303.688822)
			(xy 293.427652 -303.70992) (xy 293.468155 -303.737876) (xy 293.503648 -303.771968) (xy 293.533213 -303.811312)
			(xy 293.556084 -303.854889) (xy 293.571668 -303.90157) (xy 293.579563 -303.950147) (xy 293.580058 -303.974754)
			(xy 293.918906 -303.974754) (xy 293.922866 -303.9257) (xy 293.934643 -303.877916) (xy 293.953934 -303.83264)
			(xy 293.980237 -303.791044) (xy 294.012872 -303.754207) (xy 294.050993 -303.723082) (xy 294.093614 -303.698475)
			(xy 294.13963 -303.681023) (xy 294.187849 -303.671179) (xy 294.237024 -303.669198) (xy 294.285879 -303.67513)
			(xy 294.33315 -303.688822) (xy 294.377612 -303.70992) (xy 294.418115 -303.737876) (xy 294.453608 -303.771968)
			(xy 294.483173 -303.811312) (xy 294.506044 -303.854889) (xy 294.521628 -303.90157) (xy 294.529523 -303.950147)
			(xy 294.530018 -303.974754) (xy 294.86912 -303.974754) (xy 294.87308 -303.9257) (xy 294.884857 -303.877916)
			(xy 294.904148 -303.83264) (xy 294.930451 -303.791044) (xy 294.963086 -303.754207) (xy 295.001207 -303.723082)
			(xy 295.043828 -303.698475) (xy 295.089844 -303.681023) (xy 295.138063 -303.671179) (xy 295.187238 -303.669198)
			(xy 295.236093 -303.67513) (xy 295.283364 -303.688822) (xy 295.327826 -303.70992) (xy 295.368329 -303.737876)
			(xy 295.403822 -303.771968) (xy 295.433387 -303.811312) (xy 295.456258 -303.854889) (xy 295.471842 -303.90157)
			(xy 295.479737 -303.950147) (xy 295.480232 -303.974754) (xy 295.81908 -303.974754) (xy 295.82304 -303.9257)
			(xy 295.834817 -303.877916) (xy 295.854108 -303.83264) (xy 295.880411 -303.791044) (xy 295.913046 -303.754207)
			(xy 295.951167 -303.723082) (xy 295.993788 -303.698475) (xy 296.039804 -303.681023) (xy 296.088023 -303.671179)
			(xy 296.137198 -303.669198) (xy 296.186053 -303.67513) (xy 296.233324 -303.688822) (xy 296.277786 -303.70992)
			(xy 296.318289 -303.737876) (xy 296.353782 -303.771968) (xy 296.383347 -303.811312) (xy 296.406218 -303.854889)
			(xy 296.421802 -303.90157) (xy 296.429697 -303.950147) (xy 296.430192 -303.974754) (xy 296.76904 -303.974754)
			(xy 296.773 -303.9257) (xy 296.784777 -303.877916) (xy 296.804068 -303.83264) (xy 296.830371 -303.791044)
			(xy 296.863006 -303.754207) (xy 296.901127 -303.723082) (xy 296.943748 -303.698475) (xy 296.989764 -303.681023)
			(xy 297.037983 -303.671179) (xy 297.087158 -303.669198) (xy 297.136013 -303.67513) (xy 297.183284 -303.688822)
			(xy 297.227746 -303.70992) (xy 297.268249 -303.737876) (xy 297.303742 -303.771968) (xy 297.333307 -303.811312)
			(xy 297.356178 -303.854889) (xy 297.371762 -303.90157) (xy 297.379657 -303.950147) (xy 297.380152 -303.974754)
			(xy 297.719 -303.974754) (xy 297.72296 -303.9257) (xy 297.734737 -303.877916) (xy 297.754028 -303.83264)
			(xy 297.780331 -303.791044) (xy 297.812966 -303.754207) (xy 297.851087 -303.723082) (xy 297.893708 -303.698475)
			(xy 297.939724 -303.681023) (xy 297.987943 -303.671179) (xy 298.037118 -303.669198) (xy 298.085973 -303.67513)
			(xy 298.133244 -303.688822) (xy 298.177706 -303.70992) (xy 298.218209 -303.737876) (xy 298.253702 -303.771968)
			(xy 298.283267 -303.811312) (xy 298.306138 -303.854889) (xy 298.321722 -303.90157) (xy 298.329617 -303.950147)
			(xy 298.330112 -303.974754) (xy 298.66896 -303.974754) (xy 298.67292 -303.9257) (xy 298.684697 -303.877916)
			(xy 298.703988 -303.83264) (xy 298.730291 -303.791044) (xy 298.762926 -303.754207) (xy 298.801047 -303.723082)
			(xy 298.843668 -303.698475) (xy 298.889684 -303.681023) (xy 298.937903 -303.671179) (xy 298.987078 -303.669198)
			(xy 299.035933 -303.67513) (xy 299.083204 -303.688822) (xy 299.127666 -303.70992) (xy 299.168169 -303.737876)
			(xy 299.203662 -303.771968) (xy 299.233227 -303.811312) (xy 299.256098 -303.854889) (xy 299.271682 -303.90157)
			(xy 299.279577 -303.950147) (xy 299.280072 -303.974754) (xy 299.61892 -303.974754) (xy 299.62288 -303.9257)
			(xy 299.634657 -303.877916) (xy 299.653948 -303.83264) (xy 299.680251 -303.791044) (xy 299.712886 -303.754207)
			(xy 299.751007 -303.723082) (xy 299.793628 -303.698475) (xy 299.839644 -303.681023) (xy 299.887863 -303.671179)
			(xy 299.937038 -303.669198) (xy 299.985893 -303.67513) (xy 300.033164 -303.688822) (xy 300.077626 -303.70992)
			(xy 300.118129 -303.737876) (xy 300.153622 -303.771968) (xy 300.183187 -303.811312) (xy 300.206058 -303.854889)
			(xy 300.221642 -303.90157) (xy 300.229537 -303.950147) (xy 300.229935 -303.969928) (xy 300.57396 -303.969928)
			(xy 300.57792 -303.920874) (xy 300.589697 -303.87309) (xy 300.608988 -303.827814) (xy 300.635291 -303.786218)
			(xy 300.667926 -303.749381) (xy 300.706047 -303.718256) (xy 300.748668 -303.693649) (xy 300.794684 -303.676197)
			(xy 300.842903 -303.666353) (xy 300.892078 -303.664372) (xy 300.940933 -303.670304) (xy 300.988204 -303.683996)
			(xy 301.032666 -303.705094) (xy 301.073169 -303.73305) (xy 301.108662 -303.767142) (xy 301.138227 -303.806486)
			(xy 301.161098 -303.850063) (xy 301.176682 -303.896744) (xy 301.184577 -303.945321) (xy 301.185072 -303.969928)
			(xy 301.184975 -303.974754) (xy 301.519094 -303.974754) (xy 301.523054 -303.9257) (xy 301.534831 -303.877916)
			(xy 301.554122 -303.83264) (xy 301.580425 -303.791044) (xy 301.61306 -303.754207) (xy 301.651181 -303.723082)
			(xy 301.693802 -303.698475) (xy 301.739818 -303.681023) (xy 301.788037 -303.671179) (xy 301.837212 -303.669198)
			(xy 301.886067 -303.67513) (xy 301.933338 -303.688822) (xy 301.9778 -303.70992) (xy 302.018303 -303.737876)
			(xy 302.053796 -303.771968) (xy 302.083361 -303.811312) (xy 302.106232 -303.854889) (xy 302.121816 -303.90157)
			(xy 302.129711 -303.950147) (xy 302.130206 -303.974754) (xy 302.469054 -303.974754) (xy 302.473014 -303.9257)
			(xy 302.484791 -303.877916) (xy 302.504082 -303.83264) (xy 302.530385 -303.791044) (xy 302.56302 -303.754207)
			(xy 302.601141 -303.723082) (xy 302.643762 -303.698475) (xy 302.689778 -303.681023) (xy 302.737997 -303.671179)
			(xy 302.787172 -303.669198) (xy 302.836027 -303.67513) (xy 302.883298 -303.688822) (xy 302.92776 -303.70992)
			(xy 302.968263 -303.737876) (xy 303.003756 -303.771968) (xy 303.033321 -303.811312) (xy 303.056192 -303.854889)
			(xy 303.071776 -303.90157) (xy 303.079671 -303.950147) (xy 303.080166 -303.974754) (xy 303.419014 -303.974754)
			(xy 303.422974 -303.9257) (xy 303.434751 -303.877916) (xy 303.454042 -303.83264) (xy 303.480345 -303.791044)
			(xy 303.51298 -303.754207) (xy 303.551101 -303.723082) (xy 303.593722 -303.698475) (xy 303.639738 -303.681023)
			(xy 303.687957 -303.671179) (xy 303.737132 -303.669198) (xy 303.785987 -303.67513) (xy 303.833258 -303.688822)
			(xy 303.87772 -303.70992) (xy 303.918223 -303.737876) (xy 303.953716 -303.771968) (xy 303.983281 -303.811312)
			(xy 304.006152 -303.854889) (xy 304.021736 -303.90157) (xy 304.029631 -303.950147) (xy 304.030126 -303.974754)
			(xy 304.368974 -303.974754) (xy 304.372934 -303.9257) (xy 304.384711 -303.877916) (xy 304.404002 -303.83264)
			(xy 304.430305 -303.791044) (xy 304.46294 -303.754207) (xy 304.501061 -303.723082) (xy 304.543682 -303.698475)
			(xy 304.589698 -303.681023) (xy 304.637917 -303.671179) (xy 304.687092 -303.669198) (xy 304.735947 -303.67513)
			(xy 304.783218 -303.688822) (xy 304.82768 -303.70992) (xy 304.868183 -303.737876) (xy 304.903676 -303.771968)
			(xy 304.933241 -303.811312) (xy 304.956112 -303.854889) (xy 304.971696 -303.90157) (xy 304.979591 -303.950147)
			(xy 304.980086 -303.974754) (xy 304.979591 -303.999361) (xy 304.971696 -304.047938) (xy 304.956112 -304.094619)
			(xy 304.933241 -304.138196) (xy 304.903676 -304.17754) (xy 304.868183 -304.211632) (xy 304.82768 -304.239588)
			(xy 304.783218 -304.260686) (xy 304.735947 -304.274378) (xy 304.687092 -304.28031) (xy 304.637917 -304.278329)
			(xy 304.589698 -304.268485) (xy 304.543682 -304.251033) (xy 304.501061 -304.226426) (xy 304.46294 -304.195301)
			(xy 304.430305 -304.158464) (xy 304.404002 -304.116868) (xy 304.384711 -304.071592) (xy 304.372934 -304.023808)
			(xy 304.368974 -303.974754) (xy 304.030126 -303.974754) (xy 304.029631 -303.999361) (xy 304.021736 -304.047938)
			(xy 304.006152 -304.094619) (xy 303.983281 -304.138196) (xy 303.953716 -304.17754) (xy 303.918223 -304.211632)
			(xy 303.87772 -304.239588) (xy 303.833258 -304.260686) (xy 303.785987 -304.274378) (xy 303.737132 -304.28031)
			(xy 303.687957 -304.278329) (xy 303.639738 -304.268485) (xy 303.593722 -304.251033) (xy 303.551101 -304.226426)
			(xy 303.51298 -304.195301) (xy 303.480345 -304.158464) (xy 303.454042 -304.116868) (xy 303.434751 -304.071592)
			(xy 303.422974 -304.023808) (xy 303.419014 -303.974754) (xy 303.080166 -303.974754) (xy 303.079671 -303.999361)
			(xy 303.071776 -304.047938) (xy 303.056192 -304.094619) (xy 303.033321 -304.138196) (xy 303.003756 -304.17754)
			(xy 302.968263 -304.211632) (xy 302.92776 -304.239588) (xy 302.883298 -304.260686) (xy 302.836027 -304.274378)
			(xy 302.787172 -304.28031) (xy 302.737997 -304.278329) (xy 302.689778 -304.268485) (xy 302.643762 -304.251033)
			(xy 302.601141 -304.226426) (xy 302.56302 -304.195301) (xy 302.530385 -304.158464) (xy 302.504082 -304.116868)
			(xy 302.484791 -304.071592) (xy 302.473014 -304.023808) (xy 302.469054 -303.974754) (xy 302.130206 -303.974754)
			(xy 302.129711 -303.999361) (xy 302.121816 -304.047938) (xy 302.106232 -304.094619) (xy 302.083361 -304.138196)
			(xy 302.053796 -304.17754) (xy 302.018303 -304.211632) (xy 301.9778 -304.239588) (xy 301.933338 -304.260686)
			(xy 301.886067 -304.274378) (xy 301.837212 -304.28031) (xy 301.788037 -304.278329) (xy 301.739818 -304.268485)
			(xy 301.693802 -304.251033) (xy 301.651181 -304.226426) (xy 301.61306 -304.195301) (xy 301.580425 -304.158464)
			(xy 301.554122 -304.116868) (xy 301.534831 -304.071592) (xy 301.523054 -304.023808) (xy 301.519094 -303.974754)
			(xy 301.184975 -303.974754) (xy 301.184577 -303.994535) (xy 301.176682 -304.043112) (xy 301.161098 -304.089793)
			(xy 301.138227 -304.13337) (xy 301.108662 -304.172714) (xy 301.073169 -304.206806) (xy 301.032666 -304.234762)
			(xy 300.988204 -304.25586) (xy 300.940933 -304.269552) (xy 300.892078 -304.275484) (xy 300.842903 -304.273503)
			(xy 300.794684 -304.263659) (xy 300.748668 -304.246207) (xy 300.706047 -304.2216) (xy 300.667926 -304.190475)
			(xy 300.635291 -304.153638) (xy 300.608988 -304.112042) (xy 300.589697 -304.066766) (xy 300.57792 -304.018982)
			(xy 300.57396 -303.969928) (xy 300.229935 -303.969928) (xy 300.230032 -303.974754) (xy 300.229537 -303.999361)
			(xy 300.221642 -304.047938) (xy 300.206058 -304.094619) (xy 300.183187 -304.138196) (xy 300.153622 -304.17754)
			(xy 300.118129 -304.211632) (xy 300.077626 -304.239588) (xy 300.033164 -304.260686) (xy 299.985893 -304.274378)
			(xy 299.937038 -304.28031) (xy 299.887863 -304.278329) (xy 299.839644 -304.268485) (xy 299.793628 -304.251033)
			(xy 299.751007 -304.226426) (xy 299.712886 -304.195301) (xy 299.680251 -304.158464) (xy 299.653948 -304.116868)
			(xy 299.634657 -304.071592) (xy 299.62288 -304.023808) (xy 299.61892 -303.974754) (xy 299.280072 -303.974754)
			(xy 299.279577 -303.999361) (xy 299.271682 -304.047938) (xy 299.256098 -304.094619) (xy 299.233227 -304.138196)
			(xy 299.203662 -304.17754) (xy 299.168169 -304.211632) (xy 299.127666 -304.239588) (xy 299.083204 -304.260686)
			(xy 299.035933 -304.274378) (xy 298.987078 -304.28031) (xy 298.937903 -304.278329) (xy 298.889684 -304.268485)
			(xy 298.843668 -304.251033) (xy 298.801047 -304.226426) (xy 298.762926 -304.195301) (xy 298.730291 -304.158464)
			(xy 298.703988 -304.116868) (xy 298.684697 -304.071592) (xy 298.67292 -304.023808) (xy 298.66896 -303.974754)
			(xy 298.330112 -303.974754) (xy 298.329617 -303.999361) (xy 298.321722 -304.047938) (xy 298.306138 -304.094619)
			(xy 298.283267 -304.138196) (xy 298.253702 -304.17754) (xy 298.218209 -304.211632) (xy 298.177706 -304.239588)
			(xy 298.133244 -304.260686) (xy 298.085973 -304.274378) (xy 298.037118 -304.28031) (xy 297.987943 -304.278329)
			(xy 297.939724 -304.268485) (xy 297.893708 -304.251033) (xy 297.851087 -304.226426) (xy 297.812966 -304.195301)
			(xy 297.780331 -304.158464) (xy 297.754028 -304.116868) (xy 297.734737 -304.071592) (xy 297.72296 -304.023808)
			(xy 297.719 -303.974754) (xy 297.380152 -303.974754) (xy 297.379657 -303.999361) (xy 297.371762 -304.047938)
			(xy 297.356178 -304.094619) (xy 297.333307 -304.138196) (xy 297.303742 -304.17754) (xy 297.268249 -304.211632)
			(xy 297.227746 -304.239588) (xy 297.183284 -304.260686) (xy 297.136013 -304.274378) (xy 297.087158 -304.28031)
			(xy 297.037983 -304.278329) (xy 296.989764 -304.268485) (xy 296.943748 -304.251033) (xy 296.901127 -304.226426)
			(xy 296.863006 -304.195301) (xy 296.830371 -304.158464) (xy 296.804068 -304.116868) (xy 296.784777 -304.071592)
			(xy 296.773 -304.023808) (xy 296.76904 -303.974754) (xy 296.430192 -303.974754) (xy 296.429697 -303.999361)
			(xy 296.421802 -304.047938) (xy 296.406218 -304.094619) (xy 296.383347 -304.138196) (xy 296.353782 -304.17754)
			(xy 296.318289 -304.211632) (xy 296.277786 -304.239588) (xy 296.233324 -304.260686) (xy 296.186053 -304.274378)
			(xy 296.137198 -304.28031) (xy 296.088023 -304.278329) (xy 296.039804 -304.268485) (xy 295.993788 -304.251033)
			(xy 295.951167 -304.226426) (xy 295.913046 -304.195301) (xy 295.880411 -304.158464) (xy 295.854108 -304.116868)
			(xy 295.834817 -304.071592) (xy 295.82304 -304.023808) (xy 295.81908 -303.974754) (xy 295.480232 -303.974754)
			(xy 295.479737 -303.999361) (xy 295.471842 -304.047938) (xy 295.456258 -304.094619) (xy 295.433387 -304.138196)
			(xy 295.403822 -304.17754) (xy 295.368329 -304.211632) (xy 295.327826 -304.239588) (xy 295.283364 -304.260686)
			(xy 295.236093 -304.274378) (xy 295.187238 -304.28031) (xy 295.138063 -304.278329) (xy 295.089844 -304.268485)
			(xy 295.043828 -304.251033) (xy 295.001207 -304.226426) (xy 294.963086 -304.195301) (xy 294.930451 -304.158464)
			(xy 294.904148 -304.116868) (xy 294.884857 -304.071592) (xy 294.87308 -304.023808) (xy 294.86912 -303.974754)
			(xy 294.530018 -303.974754) (xy 294.529523 -303.999361) (xy 294.521628 -304.047938) (xy 294.506044 -304.094619)
			(xy 294.483173 -304.138196) (xy 294.453608 -304.17754) (xy 294.418115 -304.211632) (xy 294.377612 -304.239588)
			(xy 294.33315 -304.260686) (xy 294.285879 -304.274378) (xy 294.237024 -304.28031) (xy 294.187849 -304.278329)
			(xy 294.13963 -304.268485) (xy 294.093614 -304.251033) (xy 294.050993 -304.226426) (xy 294.012872 -304.195301)
			(xy 293.980237 -304.158464) (xy 293.953934 -304.116868) (xy 293.934643 -304.071592) (xy 293.922866 -304.023808)
			(xy 293.918906 -303.974754) (xy 293.580058 -303.974754) (xy 293.579563 -303.999361) (xy 293.571668 -304.047938)
			(xy 293.556084 -304.094619) (xy 293.533213 -304.138196) (xy 293.503648 -304.17754) (xy 293.468155 -304.211632)
			(xy 293.427652 -304.239588) (xy 293.38319 -304.260686) (xy 293.335919 -304.274378) (xy 293.287064 -304.28031)
			(xy 293.237889 -304.278329) (xy 293.18967 -304.268485) (xy 293.143654 -304.251033) (xy 293.101033 -304.226426)
			(xy 293.062912 -304.195301) (xy 293.030277 -304.158464) (xy 293.003974 -304.116868) (xy 292.984683 -304.071592)
			(xy 292.972906 -304.023808) (xy 292.968946 -303.974754) (xy 292.630098 -303.974754) (xy 292.629603 -303.999361)
			(xy 292.621708 -304.047938) (xy 292.606124 -304.094619) (xy 292.583253 -304.138196) (xy 292.553688 -304.17754)
			(xy 292.518195 -304.211632) (xy 292.477692 -304.239588) (xy 292.43323 -304.260686) (xy 292.385959 -304.274378)
			(xy 292.337104 -304.28031) (xy 292.287929 -304.278329) (xy 292.23971 -304.268485) (xy 292.193694 -304.251033)
			(xy 292.151073 -304.226426) (xy 292.112952 -304.195301) (xy 292.080317 -304.158464) (xy 292.054014 -304.116868)
			(xy 292.034723 -304.071592) (xy 292.022946 -304.023808) (xy 292.018986 -303.974754) (xy 290.730178 -303.974754)
			(xy 290.729683 -303.999361) (xy 290.721788 -304.047938) (xy 290.706204 -304.094619) (xy 290.683333 -304.138196)
			(xy 290.653768 -304.17754) (xy 290.618275 -304.211632) (xy 290.577772 -304.239588) (xy 290.53331 -304.260686)
			(xy 290.486039 -304.274378) (xy 290.437184 -304.28031) (xy 290.388009 -304.278329) (xy 290.33979 -304.268485)
			(xy 290.293774 -304.251033) (xy 290.251153 -304.226426) (xy 290.213032 -304.195301) (xy 290.180397 -304.158464)
			(xy 290.154094 -304.116868) (xy 290.134803 -304.071592) (xy 290.123026 -304.023808) (xy 290.119066 -303.974754)
			(xy 289.780218 -303.974754) (xy 289.779723 -303.999361) (xy 289.771828 -304.047938) (xy 289.756244 -304.094619)
			(xy 289.733373 -304.138196) (xy 289.703808 -304.17754) (xy 289.668315 -304.211632) (xy 289.627812 -304.239588)
			(xy 289.58335 -304.260686) (xy 289.536079 -304.274378) (xy 289.487224 -304.28031) (xy 289.438049 -304.278329)
			(xy 289.38983 -304.268485) (xy 289.343814 -304.251033) (xy 289.301193 -304.226426) (xy 289.263072 -304.195301)
			(xy 289.230437 -304.158464) (xy 289.204134 -304.116868) (xy 289.184843 -304.071592) (xy 289.173066 -304.023808)
			(xy 289.169106 -303.974754) (xy 288.830004 -303.974754) (xy 288.829509 -303.999361) (xy 288.821614 -304.047938)
			(xy 288.80603 -304.094619) (xy 288.783159 -304.138196) (xy 288.753594 -304.17754) (xy 288.718101 -304.211632)
			(xy 288.677598 -304.239588) (xy 288.633136 -304.260686) (xy 288.585865 -304.274378) (xy 288.53701 -304.28031)
			(xy 288.487835 -304.278329) (xy 288.439616 -304.268485) (xy 288.3936 -304.251033) (xy 288.350979 -304.226426)
			(xy 288.312858 -304.195301) (xy 288.280223 -304.158464) (xy 288.25392 -304.116868) (xy 288.234629 -304.071592)
			(xy 288.222852 -304.023808) (xy 288.218892 -303.974754) (xy 287.880044 -303.974754) (xy 287.879549 -303.999361)
			(xy 287.871654 -304.047938) (xy 287.85607 -304.094619) (xy 287.833199 -304.138196) (xy 287.803634 -304.17754)
			(xy 287.768141 -304.211632) (xy 287.727638 -304.239588) (xy 287.683176 -304.260686) (xy 287.635905 -304.274378)
			(xy 287.58705 -304.28031) (xy 287.537875 -304.278329) (xy 287.489656 -304.268485) (xy 287.44364 -304.251033)
			(xy 287.401019 -304.226426) (xy 287.362898 -304.195301) (xy 287.330263 -304.158464) (xy 287.30396 -304.116868)
			(xy 287.284669 -304.071592) (xy 287.272892 -304.023808) (xy 287.268932 -303.974754) (xy 286.930084 -303.974754)
			(xy 286.929589 -303.999361) (xy 286.921694 -304.047938) (xy 286.90611 -304.094619) (xy 286.883239 -304.138196)
			(xy 286.853674 -304.17754) (xy 286.818181 -304.211632) (xy 286.777678 -304.239588) (xy 286.733216 -304.260686)
			(xy 286.685945 -304.274378) (xy 286.63709 -304.28031) (xy 286.587915 -304.278329) (xy 286.539696 -304.268485)
			(xy 286.49368 -304.251033) (xy 286.451059 -304.226426) (xy 286.412938 -304.195301) (xy 286.380303 -304.158464)
			(xy 286.354 -304.116868) (xy 286.334709 -304.071592) (xy 286.322932 -304.023808) (xy 286.318972 -303.974754)
			(xy 285.980124 -303.974754) (xy 285.979629 -303.999361) (xy 285.971734 -304.047938) (xy 285.95615 -304.094619)
			(xy 285.933279 -304.138196) (xy 285.903714 -304.17754) (xy 285.868221 -304.211632) (xy 285.827718 -304.239588)
			(xy 285.783256 -304.260686) (xy 285.735985 -304.274378) (xy 285.68713 -304.28031) (xy 285.637955 -304.278329)
			(xy 285.589736 -304.268485) (xy 285.54372 -304.251033) (xy 285.501099 -304.226426) (xy 285.462978 -304.195301)
			(xy 285.430343 -304.158464) (xy 285.40404 -304.116868) (xy 285.384749 -304.071592) (xy 285.372972 -304.023808)
			(xy 285.369012 -303.974754) (xy 285.030164 -303.974754) (xy 285.029669 -303.999361) (xy 285.021774 -304.047938)
			(xy 285.00619 -304.094619) (xy 284.983319 -304.138196) (xy 284.953754 -304.17754) (xy 284.918261 -304.211632)
			(xy 284.877758 -304.239588) (xy 284.833296 -304.260686) (xy 284.786025 -304.274378) (xy 284.73717 -304.28031)
			(xy 284.687995 -304.278329) (xy 284.639776 -304.268485) (xy 284.59376 -304.251033) (xy 284.551139 -304.226426)
			(xy 284.513018 -304.195301) (xy 284.480383 -304.158464) (xy 284.45408 -304.116868) (xy 284.434789 -304.071592)
			(xy 284.423012 -304.023808) (xy 284.419052 -303.974754) (xy 284.080204 -303.974754) (xy 284.079709 -303.999361)
			(xy 284.071814 -304.047938) (xy 284.05623 -304.094619) (xy 284.033359 -304.138196) (xy 284.003794 -304.17754)
			(xy 283.968301 -304.211632) (xy 283.927798 -304.239588) (xy 283.883336 -304.260686) (xy 283.836065 -304.274378)
			(xy 283.78721 -304.28031) (xy 283.738035 -304.278329) (xy 283.689816 -304.268485) (xy 283.6438 -304.251033)
			(xy 283.601179 -304.226426) (xy 283.563058 -304.195301) (xy 283.530423 -304.158464) (xy 283.50412 -304.116868)
			(xy 283.484829 -304.071592) (xy 283.473052 -304.023808) (xy 283.469092 -303.974754) (xy 283.130244 -303.974754)
			(xy 283.129749 -303.999361) (xy 283.121854 -304.047938) (xy 283.10627 -304.094619) (xy 283.083399 -304.138196)
			(xy 283.053834 -304.17754) (xy 283.018341 -304.211632) (xy 282.977838 -304.239588) (xy 282.933376 -304.260686)
			(xy 282.886105 -304.274378) (xy 282.83725 -304.28031) (xy 282.788075 -304.278329) (xy 282.739856 -304.268485)
			(xy 282.69384 -304.251033) (xy 282.651219 -304.226426) (xy 282.613098 -304.195301) (xy 282.580463 -304.158464)
			(xy 282.55416 -304.116868) (xy 282.534869 -304.071592) (xy 282.523092 -304.023808) (xy 282.519132 -303.974754)
			(xy 282.18003 -303.974754) (xy 282.179535 -303.999361) (xy 282.17164 -304.047938) (xy 282.156056 -304.094619)
			(xy 282.133185 -304.138196) (xy 282.10362 -304.17754) (xy 282.068127 -304.211632) (xy 282.027624 -304.239588)
			(xy 281.983162 -304.260686) (xy 281.935891 -304.274378) (xy 281.887036 -304.28031) (xy 281.837861 -304.278329)
			(xy 281.789642 -304.268485) (xy 281.743626 -304.251033) (xy 281.701005 -304.226426) (xy 281.662884 -304.195301)
			(xy 281.630249 -304.158464) (xy 281.603946 -304.116868) (xy 281.584655 -304.071592) (xy 281.572878 -304.023808)
			(xy 281.568918 -303.974754) (xy 281.23007 -303.974754) (xy 281.229575 -303.999361) (xy 281.22168 -304.047938)
			(xy 281.206096 -304.094619) (xy 281.183225 -304.138196) (xy 281.15366 -304.17754) (xy 281.118167 -304.211632)
			(xy 281.077664 -304.239588) (xy 281.033202 -304.260686) (xy 280.985931 -304.274378) (xy 280.937076 -304.28031)
			(xy 280.887901 -304.278329) (xy 280.839682 -304.268485) (xy 280.793666 -304.251033) (xy 280.751045 -304.226426)
			(xy 280.712924 -304.195301) (xy 280.680289 -304.158464) (xy 280.653986 -304.116868) (xy 280.634695 -304.071592)
			(xy 280.622918 -304.023808) (xy 280.618958 -303.974754) (xy 280.28011 -303.974754) (xy 280.28011 -303.991264)
			(xy 280.279602 -303.997106) (xy 280.279602 -303.997614) (xy 280.278332 -304.008536) (xy 280.278332 -304.00879)
			(xy 280.277824 -304.012854) (xy 280.275284 -304.03165) (xy 280.274268 -304.037238) (xy 280.270204 -304.052986)
			(xy 280.268426 -304.065686) (xy 280.268426 -304.449734) (xy 305.793914 -304.449734) (xy 305.797874 -304.40068)
			(xy 305.809651 -304.352896) (xy 305.828942 -304.30762) (xy 305.855245 -304.266024) (xy 305.88788 -304.229187)
			(xy 305.926001 -304.198062) (xy 305.968622 -304.173455) (xy 306.014638 -304.156003) (xy 306.062857 -304.146159)
			(xy 306.112032 -304.144178) (xy 306.160887 -304.15011) (xy 306.208158 -304.163802) (xy 306.25262 -304.1849)
			(xy 306.293123 -304.212856) (xy 306.328616 -304.246948) (xy 306.358181 -304.286292) (xy 306.381052 -304.329869)
			(xy 306.396636 -304.37655) (xy 306.404531 -304.425127) (xy 306.405026 -304.449734) (xy 306.744128 -304.449734)
			(xy 306.748088 -304.40068) (xy 306.759865 -304.352896) (xy 306.779156 -304.30762) (xy 306.805459 -304.266024)
			(xy 306.838094 -304.229187) (xy 306.876215 -304.198062) (xy 306.918836 -304.173455) (xy 306.964852 -304.156003)
			(xy 307.013071 -304.146159) (xy 307.062246 -304.144178) (xy 307.111101 -304.15011) (xy 307.158372 -304.163802)
			(xy 307.202834 -304.1849) (xy 307.243337 -304.212856) (xy 307.27883 -304.246948) (xy 307.308395 -304.286292)
			(xy 307.331266 -304.329869) (xy 307.34685 -304.37655) (xy 307.354745 -304.425127) (xy 307.35524 -304.449734)
			(xy 307.694088 -304.449734) (xy 307.698048 -304.40068) (xy 307.709825 -304.352896) (xy 307.729116 -304.30762)
			(xy 307.755419 -304.266024) (xy 307.788054 -304.229187) (xy 307.826175 -304.198062) (xy 307.868796 -304.173455)
			(xy 307.914812 -304.156003) (xy 307.963031 -304.146159) (xy 308.012206 -304.144178) (xy 308.061061 -304.15011)
			(xy 308.108332 -304.163802) (xy 308.152794 -304.1849) (xy 308.193297 -304.212856) (xy 308.22879 -304.246948)
			(xy 308.258355 -304.286292) (xy 308.281226 -304.329869) (xy 308.29681 -304.37655) (xy 308.304705 -304.425127)
			(xy 308.3052 -304.449734) (xy 308.644048 -304.449734) (xy 308.648008 -304.40068) (xy 308.659785 -304.352896)
			(xy 308.679076 -304.30762) (xy 308.705379 -304.266024) (xy 308.738014 -304.229187) (xy 308.776135 -304.198062)
			(xy 308.818756 -304.173455) (xy 308.864772 -304.156003) (xy 308.912991 -304.146159) (xy 308.962166 -304.144178)
			(xy 309.011021 -304.15011) (xy 309.058292 -304.163802) (xy 309.102754 -304.1849) (xy 309.143257 -304.212856)
			(xy 309.17875 -304.246948) (xy 309.208315 -304.286292) (xy 309.231186 -304.329869) (xy 309.24677 -304.37655)
			(xy 309.254665 -304.425127) (xy 309.25516 -304.449734) (xy 309.594008 -304.449734) (xy 309.597968 -304.40068)
			(xy 309.609745 -304.352896) (xy 309.629036 -304.30762) (xy 309.655339 -304.266024) (xy 309.687974 -304.229187)
			(xy 309.726095 -304.198062) (xy 309.768716 -304.173455) (xy 309.814732 -304.156003) (xy 309.862951 -304.146159)
			(xy 309.912126 -304.144178) (xy 309.960981 -304.15011) (xy 310.008252 -304.163802) (xy 310.052714 -304.1849)
			(xy 310.093217 -304.212856) (xy 310.12871 -304.246948) (xy 310.158275 -304.286292) (xy 310.181146 -304.329869)
			(xy 310.19673 -304.37655) (xy 310.204625 -304.425127) (xy 310.20512 -304.449734) (xy 310.543968 -304.449734)
			(xy 310.547928 -304.40068) (xy 310.559705 -304.352896) (xy 310.578996 -304.30762) (xy 310.605299 -304.266024)
			(xy 310.637934 -304.229187) (xy 310.676055 -304.198062) (xy 310.718676 -304.173455) (xy 310.764692 -304.156003)
			(xy 310.812911 -304.146159) (xy 310.862086 -304.144178) (xy 310.910941 -304.15011) (xy 310.958212 -304.163802)
			(xy 311.002674 -304.1849) (xy 311.043177 -304.212856) (xy 311.07867 -304.246948) (xy 311.108235 -304.286292)
			(xy 311.131106 -304.329869) (xy 311.14669 -304.37655) (xy 311.154585 -304.425127) (xy 311.154912 -304.441387)
			(xy 311.494016 -304.441387) (xy 311.499388 -304.392042) (xy 311.512672 -304.344216) (xy 311.533519 -304.29917)
			(xy 311.561378 -304.25809) (xy 311.595517 -304.222058) (xy 311.635035 -304.192024) (xy 311.678891 -304.168778)
			(xy 311.725931 -304.152934) (xy 311.774914 -304.144909) (xy 311.799732 -304.144426) (xy 311.813915 -304.144598)
			(xy 311.842155 -304.147273) (xy 311.85612 -304.14976) (xy 311.868566 -304.152046) (xy 311.892188 -304.14468)
			(xy 311.969658 -304.06721) (xy 311.977024 -304.043588) (xy 311.974738 -304.031142) (xy 311.972258 -304.017177)
			(xy 311.969588 -303.988937) (xy 311.969404 -303.974754) (xy 311.969926 -303.949499) (xy 311.978239 -303.899677)
			(xy 311.99464 -303.851903) (xy 312.018681 -303.80748) (xy 312.049705 -303.76762) (xy 312.086867 -303.73341)
			(xy 312.129153 -303.705784) (xy 312.175409 -303.685494) (xy 312.224374 -303.673094) (xy 312.274712 -303.668923)
			(xy 312.32505 -303.673094) (xy 312.374015 -303.685494) (xy 312.420271 -303.705784) (xy 312.462557 -303.73341)
			(xy 312.499719 -303.76762) (xy 312.530743 -303.80748) (xy 312.554784 -303.851903) (xy 312.571185 -303.899677)
			(xy 312.579498 -303.949499) (xy 312.58002 -303.974754) (xy 312.579837 -303.988937) (xy 312.577169 -304.017177)
			(xy 312.574686 -304.031142) (xy 312.5724 -304.043588) (xy 312.579766 -304.06721) (xy 312.657236 -304.14468)
			(xy 312.680858 -304.152046) (xy 312.693304 -304.14976) (xy 312.707271 -304.147287) (xy 312.73551 -304.144613)
			(xy 312.749692 -304.144426) (xy 312.763939 -304.144596) (xy 312.792307 -304.147263) (xy 312.806334 -304.14976)
			(xy 312.818526 -304.152046) (xy 312.842656 -304.14468) (xy 312.919872 -304.067464) (xy 312.927238 -304.043588)
			(xy 312.924952 -304.031142) (xy 312.922472 -304.017177) (xy 312.919802 -303.988937) (xy 312.919618 -303.974754)
			(xy 312.92014 -303.949499) (xy 312.928453 -303.899677) (xy 312.944854 -303.851903) (xy 312.968895 -303.80748)
			(xy 312.999919 -303.76762) (xy 313.037081 -303.73341) (xy 313.079367 -303.705784) (xy 313.125623 -303.685494)
			(xy 313.174588 -303.673094) (xy 313.224926 -303.668923) (xy 313.275264 -303.673094) (xy 313.324229 -303.685494)
			(xy 313.370485 -303.705784) (xy 313.412771 -303.73341) (xy 313.449933 -303.76762) (xy 313.480957 -303.80748)
			(xy 313.504998 -303.851903) (xy 313.521399 -303.899677) (xy 313.529712 -303.949499) (xy 313.530234 -303.974754)
			(xy 313.530051 -303.988937) (xy 313.527383 -304.017177) (xy 313.5249 -304.031142) (xy 313.522614 -304.043588)
			(xy 313.52998 -304.06721) (xy 313.60745 -304.14468) (xy 313.631072 -304.152046) (xy 313.643518 -304.14976)
			(xy 313.657484 -304.147286) (xy 313.685724 -304.144612) (xy 313.699906 -304.144426) (xy 313.724726 -304.144884)
			(xy 313.773711 -304.152916) (xy 313.820752 -304.168766) (xy 313.864609 -304.192018) (xy 313.904126 -304.222058)
			(xy 313.938263 -304.258096) (xy 313.96612 -304.299182) (xy 313.986964 -304.344233) (xy 314.000245 -304.392063)
			(xy 314.005613 -304.441411) (xy 314.005162 -304.449734) (xy 314.344062 -304.449734) (xy 314.348022 -304.40068)
			(xy 314.359799 -304.352896) (xy 314.37909 -304.30762) (xy 314.405393 -304.266024) (xy 314.438028 -304.229187)
			(xy 314.476149 -304.198062) (xy 314.51877 -304.173455) (xy 314.564786 -304.156003) (xy 314.613005 -304.146159)
			(xy 314.66218 -304.144178) (xy 314.711035 -304.15011) (xy 314.758306 -304.163802) (xy 314.802768 -304.1849)
			(xy 314.843271 -304.212856) (xy 314.878764 -304.246948) (xy 314.908329 -304.286292) (xy 314.9312 -304.329869)
			(xy 314.946784 -304.37655) (xy 314.954679 -304.425127) (xy 314.955174 -304.449734) (xy 315.294276 -304.449734)
			(xy 315.298236 -304.40068) (xy 315.310013 -304.352896) (xy 315.329304 -304.30762) (xy 315.355607 -304.266024)
			(xy 315.388242 -304.229187) (xy 315.426363 -304.198062) (xy 315.468984 -304.173455) (xy 315.515 -304.156003)
			(xy 315.563219 -304.146159) (xy 315.612394 -304.144178) (xy 315.661249 -304.15011) (xy 315.70852 -304.163802)
			(xy 315.752982 -304.1849) (xy 315.793485 -304.212856) (xy 315.828978 -304.246948) (xy 315.858543 -304.286292)
			(xy 315.881414 -304.329869) (xy 315.896998 -304.37655) (xy 315.904893 -304.425127) (xy 315.905388 -304.449734)
			(xy 315.904893 -304.474341) (xy 315.896998 -304.522918) (xy 315.881414 -304.569599) (xy 315.858543 -304.613176)
			(xy 315.828978 -304.65252) (xy 315.793485 -304.686612) (xy 315.752982 -304.714568) (xy 315.70852 -304.735666)
			(xy 315.661249 -304.749358) (xy 315.612394 -304.75529) (xy 315.563219 -304.753309) (xy 315.515 -304.743465)
			(xy 315.468984 -304.726013) (xy 315.426363 -304.701406) (xy 315.388242 -304.670281) (xy 315.355607 -304.633444)
			(xy 315.329304 -304.591848) (xy 315.310013 -304.546572) (xy 315.298236 -304.498788) (xy 315.294276 -304.449734)
			(xy 314.955174 -304.449734) (xy 314.954679 -304.474341) (xy 314.946784 -304.522918) (xy 314.9312 -304.569599)
			(xy 314.908329 -304.613176) (xy 314.878764 -304.65252) (xy 314.843271 -304.686612) (xy 314.802768 -304.714568)
			(xy 314.758306 -304.735666) (xy 314.711035 -304.749358) (xy 314.66218 -304.75529) (xy 314.613005 -304.753309)
			(xy 314.564786 -304.743465) (xy 314.51877 -304.726013) (xy 314.476149 -304.701406) (xy 314.438028 -304.670281)
			(xy 314.405393 -304.633444) (xy 314.37909 -304.591848) (xy 314.359799 -304.546572) (xy 314.348022 -304.498788)
			(xy 314.344062 -304.449734) (xy 314.005162 -304.449734) (xy 314.002927 -304.490978) (xy 313.992257 -304.539457)
			(xy 313.973885 -304.585572) (xy 313.948295 -304.628106) (xy 313.916161 -304.665941) (xy 313.878329 -304.698079)
			(xy 313.835797 -304.723673) (xy 313.789684 -304.742049) (xy 313.741206 -304.752723) (xy 313.691639 -304.755413)
			(xy 313.642291 -304.75005) (xy 313.59446 -304.736774) (xy 313.549406 -304.715934) (xy 313.508318 -304.688081)
			(xy 313.472277 -304.653947) (xy 313.442233 -304.614432) (xy 313.418977 -304.570577) (xy 313.403123 -304.523538)
			(xy 313.395087 -304.474554) (xy 313.394598 -304.449734) (xy 313.394779 -304.435551) (xy 313.397448 -304.407311)
			(xy 313.399932 -304.393346) (xy 313.402218 -304.3809) (xy 313.394852 -304.357278) (xy 313.317382 -304.279808)
			(xy 313.29376 -304.272442) (xy 313.281314 -304.274728) (xy 313.267347 -304.277199) (xy 313.239108 -304.279874)
			(xy 313.224926 -304.280062) (xy 313.210679 -304.279904) (xy 313.182311 -304.277229) (xy 313.168284 -304.274728)
			(xy 313.156092 -304.272442) (xy 313.131962 -304.279808) (xy 313.054746 -304.357024) (xy 313.04738 -304.3809)
			(xy 313.049666 -304.393346) (xy 313.052145 -304.407312) (xy 313.054815 -304.435551) (xy 313.055 -304.449734)
			(xy 313.054478 -304.474989) (xy 313.046165 -304.524811) (xy 313.029764 -304.572585) (xy 313.005723 -304.617008)
			(xy 312.974699 -304.656868) (xy 312.937537 -304.691078) (xy 312.895251 -304.718704) (xy 312.848995 -304.738994)
			(xy 312.80003 -304.751394) (xy 312.749692 -304.755565) (xy 312.699354 -304.751394) (xy 312.650389 -304.738994)
			(xy 312.604133 -304.718704) (xy 312.561847 -304.691078) (xy 312.524685 -304.656868) (xy 312.493661 -304.617008)
			(xy 312.46962 -304.572585) (xy 312.453219 -304.524811) (xy 312.444906 -304.474989) (xy 312.444384 -304.449734)
			(xy 312.444565 -304.435551) (xy 312.447234 -304.407311) (xy 312.449718 -304.393346) (xy 312.452004 -304.3809)
			(xy 312.444638 -304.357278) (xy 312.367168 -304.279808) (xy 312.343546 -304.272442) (xy 312.3311 -304.274728)
			(xy 312.317134 -304.277201) (xy 312.288894 -304.279875) (xy 312.274712 -304.280062) (xy 312.260529 -304.279884)
			(xy 312.232289 -304.277213) (xy 312.218324 -304.274728) (xy 312.205878 -304.272442) (xy 312.182256 -304.279808)
			(xy 312.104786 -304.357278) (xy 312.09742 -304.3809) (xy 312.099706 -304.393346) (xy 312.102185 -304.407311)
			(xy 312.104855 -304.435551) (xy 312.10504 -304.449734) (xy 312.104485 -304.474552) (xy 312.09645 -304.523533)
			(xy 312.080596 -304.570569) (xy 312.057341 -304.614421) (xy 312.027298 -304.653933) (xy 311.991259 -304.688063)
			(xy 311.950172 -304.715914) (xy 311.905121 -304.736751) (xy 311.857293 -304.750025) (xy 311.807947 -304.755386)
			(xy 311.758384 -304.752693) (xy 311.70991 -304.742018) (xy 311.663801 -304.72364) (xy 311.621273 -304.698046)
			(xy 311.583445 -304.665908) (xy 311.551316 -304.628074) (xy 311.52573 -304.58554) (xy 311.507363 -304.539427)
			(xy 311.496698 -304.49095) (xy 311.494016 -304.441387) (xy 311.154912 -304.441387) (xy 311.15508 -304.449734)
			(xy 311.154585 -304.474341) (xy 311.14669 -304.522918) (xy 311.131106 -304.569599) (xy 311.108235 -304.613176)
			(xy 311.07867 -304.65252) (xy 311.043177 -304.686612) (xy 311.002674 -304.714568) (xy 310.958212 -304.735666)
			(xy 310.910941 -304.749358) (xy 310.862086 -304.75529) (xy 310.812911 -304.753309) (xy 310.764692 -304.743465)
			(xy 310.718676 -304.726013) (xy 310.676055 -304.701406) (xy 310.637934 -304.670281) (xy 310.605299 -304.633444)
			(xy 310.578996 -304.591848) (xy 310.559705 -304.546572) (xy 310.547928 -304.498788) (xy 310.543968 -304.449734)
			(xy 310.20512 -304.449734) (xy 310.204625 -304.474341) (xy 310.19673 -304.522918) (xy 310.181146 -304.569599)
			(xy 310.158275 -304.613176) (xy 310.12871 -304.65252) (xy 310.093217 -304.686612) (xy 310.052714 -304.714568)
			(xy 310.008252 -304.735666) (xy 309.960981 -304.749358) (xy 309.912126 -304.75529) (xy 309.862951 -304.753309)
			(xy 309.814732 -304.743465) (xy 309.768716 -304.726013) (xy 309.726095 -304.701406) (xy 309.687974 -304.670281)
			(xy 309.655339 -304.633444) (xy 309.629036 -304.591848) (xy 309.609745 -304.546572) (xy 309.597968 -304.498788)
			(xy 309.594008 -304.449734) (xy 309.25516 -304.449734) (xy 309.254665 -304.474341) (xy 309.24677 -304.522918)
			(xy 309.231186 -304.569599) (xy 309.208315 -304.613176) (xy 309.17875 -304.65252) (xy 309.143257 -304.686612)
			(xy 309.102754 -304.714568) (xy 309.058292 -304.735666) (xy 309.011021 -304.749358) (xy 308.962166 -304.75529)
			(xy 308.912991 -304.753309) (xy 308.864772 -304.743465) (xy 308.818756 -304.726013) (xy 308.776135 -304.701406)
			(xy 308.738014 -304.670281) (xy 308.705379 -304.633444) (xy 308.679076 -304.591848) (xy 308.659785 -304.546572)
			(xy 308.648008 -304.498788) (xy 308.644048 -304.449734) (xy 308.3052 -304.449734) (xy 308.304705 -304.474341)
			(xy 308.29681 -304.522918) (xy 308.281226 -304.569599) (xy 308.258355 -304.613176) (xy 308.22879 -304.65252)
			(xy 308.193297 -304.686612) (xy 308.152794 -304.714568) (xy 308.108332 -304.735666) (xy 308.061061 -304.749358)
			(xy 308.012206 -304.75529) (xy 307.963031 -304.753309) (xy 307.914812 -304.743465) (xy 307.868796 -304.726013)
			(xy 307.826175 -304.701406) (xy 307.788054 -304.670281) (xy 307.755419 -304.633444) (xy 307.729116 -304.591848)
			(xy 307.709825 -304.546572) (xy 307.698048 -304.498788) (xy 307.694088 -304.449734) (xy 307.35524 -304.449734)
			(xy 307.354745 -304.474341) (xy 307.34685 -304.522918) (xy 307.331266 -304.569599) (xy 307.308395 -304.613176)
			(xy 307.27883 -304.65252) (xy 307.243337 -304.686612) (xy 307.202834 -304.714568) (xy 307.158372 -304.735666)
			(xy 307.111101 -304.749358) (xy 307.062246 -304.75529) (xy 307.013071 -304.753309) (xy 306.964852 -304.743465)
			(xy 306.918836 -304.726013) (xy 306.876215 -304.701406) (xy 306.838094 -304.670281) (xy 306.805459 -304.633444)
			(xy 306.779156 -304.591848) (xy 306.759865 -304.546572) (xy 306.748088 -304.498788) (xy 306.744128 -304.449734)
			(xy 306.405026 -304.449734) (xy 306.404531 -304.474341) (xy 306.396636 -304.522918) (xy 306.381052 -304.569599)
			(xy 306.358181 -304.613176) (xy 306.328616 -304.65252) (xy 306.293123 -304.686612) (xy 306.25262 -304.714568)
			(xy 306.208158 -304.735666) (xy 306.160887 -304.749358) (xy 306.112032 -304.75529) (xy 306.062857 -304.753309)
			(xy 306.014638 -304.743465) (xy 305.968622 -304.726013) (xy 305.926001 -304.701406) (xy 305.88788 -304.670281)
			(xy 305.855245 -304.633444) (xy 305.828942 -304.591848) (xy 305.809651 -304.546572) (xy 305.797874 -304.498788)
			(xy 305.793914 -304.449734) (xy 280.268426 -304.449734) (xy 280.268426 -304.829972) (xy 280.268934 -304.836068)
			(xy 280.270204 -304.847244) (xy 280.270966 -304.850546) (xy 280.270966 -304.851054) (xy 280.275216 -304.869173)
			(xy 280.279799 -304.906106) (xy 280.28011 -304.924714) (xy 280.618958 -304.924714) (xy 280.622918 -304.87566)
			(xy 280.634695 -304.827876) (xy 280.653986 -304.7826) (xy 280.680289 -304.741004) (xy 280.712924 -304.704167)
			(xy 280.751045 -304.673042) (xy 280.793666 -304.648435) (xy 280.839682 -304.630983) (xy 280.887901 -304.621139)
			(xy 280.937076 -304.619158) (xy 280.985931 -304.62509) (xy 281.033202 -304.638782) (xy 281.077664 -304.65988)
			(xy 281.118167 -304.687836) (xy 281.15366 -304.721928) (xy 281.183225 -304.761272) (xy 281.206096 -304.804849)
			(xy 281.22168 -304.85153) (xy 281.229575 -304.900107) (xy 281.23007 -304.924714) (xy 281.568918 -304.924714)
			(xy 281.572878 -304.87566) (xy 281.584655 -304.827876) (xy 281.603946 -304.7826) (xy 281.630249 -304.741004)
			(xy 281.662884 -304.704167) (xy 281.701005 -304.673042) (xy 281.743626 -304.648435) (xy 281.789642 -304.630983)
			(xy 281.837861 -304.621139) (xy 281.887036 -304.619158) (xy 281.935891 -304.62509) (xy 281.983162 -304.638782)
			(xy 282.027624 -304.65988) (xy 282.068127 -304.687836) (xy 282.10362 -304.721928) (xy 282.133185 -304.761272)
			(xy 282.156056 -304.804849) (xy 282.17164 -304.85153) (xy 282.179535 -304.900107) (xy 282.18003 -304.924714)
			(xy 282.519132 -304.924714) (xy 282.523092 -304.87566) (xy 282.534869 -304.827876) (xy 282.55416 -304.7826)
			(xy 282.580463 -304.741004) (xy 282.613098 -304.704167) (xy 282.651219 -304.673042) (xy 282.69384 -304.648435)
			(xy 282.739856 -304.630983) (xy 282.788075 -304.621139) (xy 282.83725 -304.619158) (xy 282.886105 -304.62509)
			(xy 282.933376 -304.638782) (xy 282.977838 -304.65988) (xy 283.018341 -304.687836) (xy 283.053834 -304.721928)
			(xy 283.083399 -304.761272) (xy 283.10627 -304.804849) (xy 283.121854 -304.85153) (xy 283.129749 -304.900107)
			(xy 283.130244 -304.924714) (xy 283.469092 -304.924714) (xy 283.473052 -304.87566) (xy 283.484829 -304.827876)
			(xy 283.50412 -304.7826) (xy 283.530423 -304.741004) (xy 283.563058 -304.704167) (xy 283.601179 -304.673042)
			(xy 283.6438 -304.648435) (xy 283.689816 -304.630983) (xy 283.738035 -304.621139) (xy 283.78721 -304.619158)
			(xy 283.836065 -304.62509) (xy 283.883336 -304.638782) (xy 283.927798 -304.65988) (xy 283.968301 -304.687836)
			(xy 284.003794 -304.721928) (xy 284.033359 -304.761272) (xy 284.05623 -304.804849) (xy 284.071814 -304.85153)
			(xy 284.079709 -304.900107) (xy 284.080204 -304.924714) (xy 284.419052 -304.924714) (xy 284.423012 -304.87566)
			(xy 284.434789 -304.827876) (xy 284.45408 -304.7826) (xy 284.480383 -304.741004) (xy 284.513018 -304.704167)
			(xy 284.551139 -304.673042) (xy 284.59376 -304.648435) (xy 284.639776 -304.630983) (xy 284.687995 -304.621139)
			(xy 284.73717 -304.619158) (xy 284.786025 -304.62509) (xy 284.833296 -304.638782) (xy 284.877758 -304.65988)
			(xy 284.918261 -304.687836) (xy 284.953754 -304.721928) (xy 284.983319 -304.761272) (xy 285.00619 -304.804849)
			(xy 285.021774 -304.85153) (xy 285.029669 -304.900107) (xy 285.030164 -304.924714) (xy 285.369012 -304.924714)
			(xy 285.372972 -304.87566) (xy 285.384749 -304.827876) (xy 285.40404 -304.7826) (xy 285.430343 -304.741004)
			(xy 285.462978 -304.704167) (xy 285.501099 -304.673042) (xy 285.54372 -304.648435) (xy 285.589736 -304.630983)
			(xy 285.637955 -304.621139) (xy 285.68713 -304.619158) (xy 285.735985 -304.62509) (xy 285.783256 -304.638782)
			(xy 285.827718 -304.65988) (xy 285.868221 -304.687836) (xy 285.903714 -304.721928) (xy 285.933279 -304.761272)
			(xy 285.95615 -304.804849) (xy 285.971734 -304.85153) (xy 285.979629 -304.900107) (xy 285.980124 -304.924714)
			(xy 286.318972 -304.924714) (xy 286.322932 -304.87566) (xy 286.334709 -304.827876) (xy 286.354 -304.7826)
			(xy 286.380303 -304.741004) (xy 286.412938 -304.704167) (xy 286.451059 -304.673042) (xy 286.49368 -304.648435)
			(xy 286.539696 -304.630983) (xy 286.587915 -304.621139) (xy 286.63709 -304.619158) (xy 286.685945 -304.62509)
			(xy 286.733216 -304.638782) (xy 286.777678 -304.65988) (xy 286.818181 -304.687836) (xy 286.853674 -304.721928)
			(xy 286.883239 -304.761272) (xy 286.90611 -304.804849) (xy 286.921694 -304.85153) (xy 286.929589 -304.900107)
			(xy 286.930084 -304.924714) (xy 287.268932 -304.924714) (xy 287.272892 -304.87566) (xy 287.284669 -304.827876)
			(xy 287.30396 -304.7826) (xy 287.330263 -304.741004) (xy 287.362898 -304.704167) (xy 287.401019 -304.673042)
			(xy 287.44364 -304.648435) (xy 287.489656 -304.630983) (xy 287.537875 -304.621139) (xy 287.58705 -304.619158)
			(xy 287.635905 -304.62509) (xy 287.683176 -304.638782) (xy 287.727638 -304.65988) (xy 287.768141 -304.687836)
			(xy 287.803634 -304.721928) (xy 287.833199 -304.761272) (xy 287.85607 -304.804849) (xy 287.871654 -304.85153)
			(xy 287.879549 -304.900107) (xy 287.880044 -304.924714) (xy 288.218892 -304.924714) (xy 288.222852 -304.87566)
			(xy 288.234629 -304.827876) (xy 288.25392 -304.7826) (xy 288.280223 -304.741004) (xy 288.312858 -304.704167)
			(xy 288.350979 -304.673042) (xy 288.3936 -304.648435) (xy 288.439616 -304.630983) (xy 288.487835 -304.621139)
			(xy 288.53701 -304.619158) (xy 288.585865 -304.62509) (xy 288.633136 -304.638782) (xy 288.677598 -304.65988)
			(xy 288.718101 -304.687836) (xy 288.753594 -304.721928) (xy 288.783159 -304.761272) (xy 288.80603 -304.804849)
			(xy 288.821614 -304.85153) (xy 288.829509 -304.900107) (xy 288.830004 -304.924714) (xy 289.169106 -304.924714)
			(xy 289.173066 -304.87566) (xy 289.184843 -304.827876) (xy 289.204134 -304.7826) (xy 289.230437 -304.741004)
			(xy 289.263072 -304.704167) (xy 289.301193 -304.673042) (xy 289.343814 -304.648435) (xy 289.38983 -304.630983)
			(xy 289.438049 -304.621139) (xy 289.487224 -304.619158) (xy 289.536079 -304.62509) (xy 289.58335 -304.638782)
			(xy 289.627812 -304.65988) (xy 289.668315 -304.687836) (xy 289.703808 -304.721928) (xy 289.733373 -304.761272)
			(xy 289.756244 -304.804849) (xy 289.771828 -304.85153) (xy 289.779723 -304.900107) (xy 289.780218 -304.924714)
			(xy 290.119066 -304.924714) (xy 290.123026 -304.87566) (xy 290.134803 -304.827876) (xy 290.154094 -304.7826)
			(xy 290.180397 -304.741004) (xy 290.213032 -304.704167) (xy 290.251153 -304.673042) (xy 290.293774 -304.648435)
			(xy 290.33979 -304.630983) (xy 290.388009 -304.621139) (xy 290.437184 -304.619158) (xy 290.486039 -304.62509)
			(xy 290.53331 -304.638782) (xy 290.577772 -304.65988) (xy 290.618275 -304.687836) (xy 290.653768 -304.721928)
			(xy 290.683333 -304.761272) (xy 290.706204 -304.804849) (xy 290.721788 -304.85153) (xy 290.729683 -304.900107)
			(xy 290.730178 -304.924714) (xy 292.018986 -304.924714) (xy 292.022946 -304.87566) (xy 292.034723 -304.827876)
			(xy 292.054014 -304.7826) (xy 292.080317 -304.741004) (xy 292.112952 -304.704167) (xy 292.151073 -304.673042)
			(xy 292.193694 -304.648435) (xy 292.23971 -304.630983) (xy 292.287929 -304.621139) (xy 292.337104 -304.619158)
			(xy 292.385959 -304.62509) (xy 292.43323 -304.638782) (xy 292.477692 -304.65988) (xy 292.518195 -304.687836)
			(xy 292.553688 -304.721928) (xy 292.583253 -304.761272) (xy 292.606124 -304.804849) (xy 292.621708 -304.85153)
			(xy 292.629603 -304.900107) (xy 292.630098 -304.924714) (xy 292.968946 -304.924714) (xy 292.972906 -304.87566)
			(xy 292.984683 -304.827876) (xy 293.003974 -304.7826) (xy 293.030277 -304.741004) (xy 293.062912 -304.704167)
			(xy 293.101033 -304.673042) (xy 293.143654 -304.648435) (xy 293.18967 -304.630983) (xy 293.237889 -304.621139)
			(xy 293.287064 -304.619158) (xy 293.335919 -304.62509) (xy 293.38319 -304.638782) (xy 293.427652 -304.65988)
			(xy 293.468155 -304.687836) (xy 293.503648 -304.721928) (xy 293.533213 -304.761272) (xy 293.556084 -304.804849)
			(xy 293.571668 -304.85153) (xy 293.579563 -304.900107) (xy 293.580058 -304.924714) (xy 293.918906 -304.924714)
			(xy 293.922866 -304.87566) (xy 293.934643 -304.827876) (xy 293.953934 -304.7826) (xy 293.980237 -304.741004)
			(xy 294.012872 -304.704167) (xy 294.050993 -304.673042) (xy 294.093614 -304.648435) (xy 294.13963 -304.630983)
			(xy 294.187849 -304.621139) (xy 294.237024 -304.619158) (xy 294.285879 -304.62509) (xy 294.33315 -304.638782)
			(xy 294.377612 -304.65988) (xy 294.418115 -304.687836) (xy 294.453608 -304.721928) (xy 294.483173 -304.761272)
			(xy 294.506044 -304.804849) (xy 294.521628 -304.85153) (xy 294.529523 -304.900107) (xy 294.530018 -304.924714)
			(xy 294.86912 -304.924714) (xy 294.87308 -304.87566) (xy 294.884857 -304.827876) (xy 294.904148 -304.7826)
			(xy 294.930451 -304.741004) (xy 294.963086 -304.704167) (xy 295.001207 -304.673042) (xy 295.043828 -304.648435)
			(xy 295.089844 -304.630983) (xy 295.138063 -304.621139) (xy 295.187238 -304.619158) (xy 295.236093 -304.62509)
			(xy 295.283364 -304.638782) (xy 295.327826 -304.65988) (xy 295.368329 -304.687836) (xy 295.403822 -304.721928)
			(xy 295.433387 -304.761272) (xy 295.456258 -304.804849) (xy 295.471842 -304.85153) (xy 295.479737 -304.900107)
			(xy 295.480232 -304.924714) (xy 295.81908 -304.924714) (xy 295.82304 -304.87566) (xy 295.834817 -304.827876)
			(xy 295.854108 -304.7826) (xy 295.880411 -304.741004) (xy 295.913046 -304.704167) (xy 295.951167 -304.673042)
			(xy 295.993788 -304.648435) (xy 296.039804 -304.630983) (xy 296.088023 -304.621139) (xy 296.137198 -304.619158)
			(xy 296.186053 -304.62509) (xy 296.233324 -304.638782) (xy 296.277786 -304.65988) (xy 296.318289 -304.687836)
			(xy 296.353782 -304.721928) (xy 296.383347 -304.761272) (xy 296.406218 -304.804849) (xy 296.421802 -304.85153)
			(xy 296.429697 -304.900107) (xy 296.430192 -304.924714) (xy 296.76904 -304.924714) (xy 296.773 -304.87566)
			(xy 296.784777 -304.827876) (xy 296.804068 -304.7826) (xy 296.830371 -304.741004) (xy 296.863006 -304.704167)
			(xy 296.901127 -304.673042) (xy 296.943748 -304.648435) (xy 296.989764 -304.630983) (xy 297.037983 -304.621139)
			(xy 297.087158 -304.619158) (xy 297.136013 -304.62509) (xy 297.183284 -304.638782) (xy 297.227746 -304.65988)
			(xy 297.268249 -304.687836) (xy 297.303742 -304.721928) (xy 297.333307 -304.761272) (xy 297.356178 -304.804849)
			(xy 297.371762 -304.85153) (xy 297.379657 -304.900107) (xy 297.380152 -304.924714) (xy 297.719 -304.924714)
			(xy 297.72296 -304.87566) (xy 297.734737 -304.827876) (xy 297.754028 -304.7826) (xy 297.780331 -304.741004)
			(xy 297.812966 -304.704167) (xy 297.851087 -304.673042) (xy 297.893708 -304.648435) (xy 297.939724 -304.630983)
			(xy 297.987943 -304.621139) (xy 298.037118 -304.619158) (xy 298.085973 -304.62509) (xy 298.133244 -304.638782)
			(xy 298.177706 -304.65988) (xy 298.218209 -304.687836) (xy 298.253702 -304.721928) (xy 298.283267 -304.761272)
			(xy 298.306138 -304.804849) (xy 298.321722 -304.85153) (xy 298.329617 -304.900107) (xy 298.330112 -304.924714)
			(xy 298.66896 -304.924714) (xy 298.67292 -304.87566) (xy 298.684697 -304.827876) (xy 298.703988 -304.7826)
			(xy 298.730291 -304.741004) (xy 298.762926 -304.704167) (xy 298.801047 -304.673042) (xy 298.843668 -304.648435)
			(xy 298.889684 -304.630983) (xy 298.937903 -304.621139) (xy 298.987078 -304.619158) (xy 299.035933 -304.62509)
			(xy 299.083204 -304.638782) (xy 299.127666 -304.65988) (xy 299.168169 -304.687836) (xy 299.203662 -304.721928)
			(xy 299.233227 -304.761272) (xy 299.256098 -304.804849) (xy 299.271682 -304.85153) (xy 299.279577 -304.900107)
			(xy 299.280072 -304.924714) (xy 299.61892 -304.924714) (xy 299.62288 -304.87566) (xy 299.634657 -304.827876)
			(xy 299.653948 -304.7826) (xy 299.680251 -304.741004) (xy 299.712886 -304.704167) (xy 299.751007 -304.673042)
			(xy 299.793628 -304.648435) (xy 299.839644 -304.630983) (xy 299.887863 -304.621139) (xy 299.937038 -304.619158)
			(xy 299.985893 -304.62509) (xy 300.033164 -304.638782) (xy 300.077626 -304.65988) (xy 300.118129 -304.687836)
			(xy 300.153622 -304.721928) (xy 300.183187 -304.761272) (xy 300.206058 -304.804849) (xy 300.221642 -304.85153)
			(xy 300.229537 -304.900107) (xy 300.230032 -304.924714) (xy 300.56888 -304.924714) (xy 300.57284 -304.87566)
			(xy 300.584617 -304.827876) (xy 300.603908 -304.7826) (xy 300.630211 -304.741004) (xy 300.662846 -304.704167)
			(xy 300.700967 -304.673042) (xy 300.743588 -304.648435) (xy 300.789604 -304.630983) (xy 300.837823 -304.621139)
			(xy 300.886998 -304.619158) (xy 300.935853 -304.62509) (xy 300.983124 -304.638782) (xy 301.027586 -304.65988)
			(xy 301.068089 -304.687836) (xy 301.103582 -304.721928) (xy 301.133147 -304.761272) (xy 301.156018 -304.804849)
			(xy 301.171602 -304.85153) (xy 301.179497 -304.900107) (xy 301.179992 -304.924714) (xy 301.519094 -304.924714)
			(xy 301.523054 -304.87566) (xy 301.534831 -304.827876) (xy 301.554122 -304.7826) (xy 301.580425 -304.741004)
			(xy 301.61306 -304.704167) (xy 301.651181 -304.673042) (xy 301.693802 -304.648435) (xy 301.739818 -304.630983)
			(xy 301.788037 -304.621139) (xy 301.837212 -304.619158) (xy 301.886067 -304.62509) (xy 301.933338 -304.638782)
			(xy 301.9778 -304.65988) (xy 302.018303 -304.687836) (xy 302.053796 -304.721928) (xy 302.083361 -304.761272)
			(xy 302.106232 -304.804849) (xy 302.121816 -304.85153) (xy 302.129711 -304.900107) (xy 302.130206 -304.924714)
			(xy 302.469054 -304.924714) (xy 302.473014 -304.87566) (xy 302.484791 -304.827876) (xy 302.504082 -304.7826)
			(xy 302.530385 -304.741004) (xy 302.56302 -304.704167) (xy 302.601141 -304.673042) (xy 302.643762 -304.648435)
			(xy 302.689778 -304.630983) (xy 302.737997 -304.621139) (xy 302.787172 -304.619158) (xy 302.836027 -304.62509)
			(xy 302.883298 -304.638782) (xy 302.92776 -304.65988) (xy 302.968263 -304.687836) (xy 303.003756 -304.721928)
			(xy 303.033321 -304.761272) (xy 303.056192 -304.804849) (xy 303.071776 -304.85153) (xy 303.079671 -304.900107)
			(xy 303.080166 -304.924714) (xy 303.419014 -304.924714) (xy 303.422974 -304.87566) (xy 303.434751 -304.827876)
			(xy 303.454042 -304.7826) (xy 303.480345 -304.741004) (xy 303.51298 -304.704167) (xy 303.551101 -304.673042)
			(xy 303.593722 -304.648435) (xy 303.639738 -304.630983) (xy 303.687957 -304.621139) (xy 303.737132 -304.619158)
			(xy 303.785987 -304.62509) (xy 303.833258 -304.638782) (xy 303.87772 -304.65988) (xy 303.918223 -304.687836)
			(xy 303.953716 -304.721928) (xy 303.983281 -304.761272) (xy 304.006152 -304.804849) (xy 304.021736 -304.85153)
			(xy 304.029631 -304.900107) (xy 304.030126 -304.924714) (xy 304.368974 -304.924714) (xy 304.372934 -304.87566)
			(xy 304.384711 -304.827876) (xy 304.404002 -304.7826) (xy 304.430305 -304.741004) (xy 304.46294 -304.704167)
			(xy 304.501061 -304.673042) (xy 304.543682 -304.648435) (xy 304.589698 -304.630983) (xy 304.637917 -304.621139)
			(xy 304.687092 -304.619158) (xy 304.735947 -304.62509) (xy 304.783218 -304.638782) (xy 304.82768 -304.65988)
			(xy 304.868183 -304.687836) (xy 304.903676 -304.721928) (xy 304.933241 -304.761272) (xy 304.943098 -304.780052)
			(xy 320.049634 -304.780052) (xy 320.049634 -304.725548) (xy 320.05739 -304.671598) (xy 320.072744 -304.619301)
			(xy 320.095385 -304.569721) (xy 320.12485 -304.523868) (xy 320.16054 -304.482674) (xy 320.20173 -304.446979)
			(xy 320.247579 -304.417508) (xy 320.297156 -304.394861) (xy 320.349451 -304.3795) (xy 320.4034 -304.371737)
			(xy 320.430652 -304.371248) (xy 320.457798 -304.371686) (xy 320.511542 -304.379369) (xy 320.563653 -304.394598)
			(xy 320.613075 -304.417068) (xy 320.65881 -304.446323) (xy 320.699931 -304.481771) (xy 320.735606 -304.522694)
			(xy 320.765115 -304.568266) (xy 320.787858 -304.617563) (xy 320.803377 -304.669588) (xy 320.807842 -304.696368)
			(xy 320.810662 -304.711198) (xy 320.823697 -304.738407) (xy 320.844104 -304.760628) (xy 320.870107 -304.775928)
			(xy 320.899443 -304.782974) (xy 320.929558 -304.781155) (xy 320.957832 -304.770627) (xy 320.970148 -304.7619)
			(xy 320.990212 -304.747097) (xy 321.033428 -304.722226) (xy 321.079513 -304.703192) (xy 321.127683 -304.690317)
			(xy 321.177119 -304.683822) (xy 321.20205 -304.683414) (xy 321.229307 -304.683829) (xy 321.283266 -304.691581)
			(xy 321.335573 -304.706934) (xy 321.385163 -304.729575) (xy 321.431025 -304.759043) (xy 321.472226 -304.794739)
			(xy 321.507927 -304.835935) (xy 321.537401 -304.881793) (xy 321.560049 -304.93138) (xy 321.575408 -304.983685)
			(xy 321.583167 -305.037643) (xy 321.583167 -305.064922) (xy 321.835016 -305.064922) (xy 321.839087 -305.0093)
			(xy 321.851213 -304.954863) (xy 321.871136 -304.902772) (xy 321.898432 -304.854137) (xy 321.932518 -304.809994)
			(xy 321.972667 -304.771285) (xy 322.018025 -304.738834) (xy 322.067625 -304.713333) (xy 322.120409 -304.695326)
			(xy 322.175252 -304.685196) (xy 322.230986 -304.683159) (xy 322.286423 -304.689259) (xy 322.34038 -304.703365)
			(xy 322.391709 -304.725177) (xy 322.439315 -304.754231) (xy 322.482183 -304.789906) (xy 322.5194 -304.831443)
			(xy 322.550173 -304.877956) (xy 322.573845 -304.928453) (xy 322.589913 -304.98186) (xy 322.598033 -305.037036)
			(xy 322.598542 -305.064922) (xy 322.843396 -305.064922) (xy 322.847467 -305.0093) (xy 322.859593 -304.954863)
			(xy 322.879516 -304.902772) (xy 322.906812 -304.854137) (xy 322.940898 -304.809994) (xy 322.981047 -304.771285)
			(xy 323.026405 -304.738834) (xy 323.076005 -304.713333) (xy 323.128789 -304.695326) (xy 323.183632 -304.685196)
			(xy 323.239366 -304.683159) (xy 323.294803 -304.689259) (xy 323.34876 -304.703365) (xy 323.400089 -304.725177)
			(xy 323.447695 -304.754231) (xy 323.490563 -304.789906) (xy 323.52778 -304.831443) (xy 323.558553 -304.877956)
			(xy 323.582225 -304.928453) (xy 323.598293 -304.98186) (xy 323.606413 -305.037036) (xy 323.606903 -305.063906)
			(xy 323.868032 -305.063906) (xy 323.872103 -305.008284) (xy 323.884229 -304.953847) (xy 323.904152 -304.901756)
			(xy 323.931448 -304.853121) (xy 323.965534 -304.808978) (xy 324.005683 -304.770269) (xy 324.051041 -304.737818)
			(xy 324.100641 -304.712317) (xy 324.153425 -304.69431) (xy 324.208268 -304.68418) (xy 324.264002 -304.682143)
			(xy 324.319439 -304.688243) (xy 324.373396 -304.702349) (xy 324.424725 -304.724161) (xy 324.472331 -304.753215)
			(xy 324.515199 -304.78889) (xy 324.552416 -304.830427) (xy 324.583189 -304.87694) (xy 324.606861 -304.927437)
			(xy 324.622929 -304.980844) (xy 324.631049 -305.03602) (xy 324.631233 -305.046126) (xy 324.884032 -305.046126)
			(xy 324.888103 -304.990504) (xy 324.900229 -304.936067) (xy 324.920152 -304.883976) (xy 324.947448 -304.835341)
			(xy 324.981534 -304.791198) (xy 325.021683 -304.752489) (xy 325.067041 -304.720038) (xy 325.116641 -304.694537)
			(xy 325.169425 -304.67653) (xy 325.224268 -304.6664) (xy 325.280002 -304.664363) (xy 325.335439 -304.670463)
			(xy 325.389396 -304.684569) (xy 325.440725 -304.706381) (xy 325.488331 -304.735435) (xy 325.531199 -304.77111)
			(xy 325.568416 -304.812647) (xy 325.599189 -304.85916) (xy 325.622861 -304.909657) (xy 325.638929 -304.963064)
			(xy 325.645621 -305.008534) (xy 334.435704 -305.008534) (xy 334.436189 -304.981164) (xy 334.444002 -304.926986)
			(xy 334.459487 -304.874483) (xy 334.482324 -304.824736) (xy 334.512045 -304.778768) (xy 334.529684 -304.757836)
			(xy 334.53578 -304.750724) (xy 334.54213 -304.733706) (xy 334.54213 -304.648362) (xy 334.53578 -304.631344)
			(xy 334.529684 -304.624232) (xy 334.512044 -304.603301) (xy 334.482333 -304.557327) (xy 334.459497 -304.50758)
			(xy 334.444006 -304.455079) (xy 334.436178 -304.400903) (xy 334.435704 -304.373534) (xy 334.43619 -304.346283)
			(xy 334.443946 -304.292335) (xy 334.459301 -304.24004) (xy 334.481943 -304.190463) (xy 334.511409 -304.144613)
			(xy 334.5471 -304.103422) (xy 334.588291 -304.067731) (xy 334.634141 -304.038265) (xy 334.683718 -304.015623)
			(xy 334.736013 -304.000268) (xy 334.789961 -303.992512) (xy 334.844463 -303.992512) (xy 334.898411 -304.000268)
			(xy 334.950706 -304.015623) (xy 335.000283 -304.038265) (xy 335.046133 -304.067731) (xy 335.087324 -304.103422)
			(xy 335.123015 -304.144613) (xy 335.152481 -304.190463) (xy 335.175123 -304.24004) (xy 335.190478 -304.292335)
			(xy 335.198234 -304.346283) (xy 335.19872 -304.373534) (xy 335.198293 -304.400906) (xy 335.190469 -304.455087)
			(xy 335.174972 -304.507592) (xy 335.152121 -304.557338) (xy 335.122386 -304.603302) (xy 335.10474 -304.624232)
			(xy 335.098644 -304.631344) (xy 335.092294 -304.648362) (xy 335.092294 -304.733706) (xy 335.098644 -304.750724)
			(xy 335.10474 -304.757836) (xy 335.122369 -304.778776) (xy 335.152081 -304.824747) (xy 335.174919 -304.874493)
			(xy 335.190412 -304.926991) (xy 335.198244 -304.981165) (xy 335.19872 -305.008534) (xy 337.855814 -305.008534)
			(xy 337.856297 -304.981164) (xy 337.86411 -304.926986) (xy 337.879595 -304.874483) (xy 337.902433 -304.824736)
			(xy 337.932154 -304.778768) (xy 337.949794 -304.757836) (xy 337.95589 -304.750724) (xy 337.96224 -304.733706)
			(xy 337.96224 -304.648362) (xy 337.95589 -304.631344) (xy 337.949794 -304.624232) (xy 337.932156 -304.603299)
			(xy 337.902444 -304.557327) (xy 337.879608 -304.507579) (xy 337.864117 -304.455079) (xy 337.856288 -304.400903)
			(xy 337.855814 -304.373534) (xy 337.8563 -304.346283) (xy 337.864056 -304.292335) (xy 337.879411 -304.24004)
			(xy 337.902053 -304.190463) (xy 337.931519 -304.144613) (xy 337.96721 -304.103422) (xy 338.008401 -304.067731)
			(xy 338.054251 -304.038265) (xy 338.103828 -304.015623) (xy 338.156123 -304.000268) (xy 338.210071 -303.992512)
			(xy 338.264573 -303.992512) (xy 338.318521 -304.000268) (xy 338.370816 -304.015623) (xy 338.420393 -304.038265)
			(xy 338.466243 -304.067731) (xy 338.507434 -304.103422) (xy 338.543125 -304.144613) (xy 338.572591 -304.190463)
			(xy 338.595233 -304.24004) (xy 338.610588 -304.292335) (xy 338.618344 -304.346283) (xy 338.61883 -304.373534)
			(xy 338.618401 -304.400906) (xy 338.610577 -304.455087) (xy 338.59508 -304.507591) (xy 338.57223 -304.557338)
			(xy 338.542496 -304.603302) (xy 338.52485 -304.624232) (xy 338.518754 -304.631344) (xy 338.512404 -304.648362)
			(xy 338.512404 -304.733706) (xy 338.518754 -304.750724) (xy 338.52485 -304.757836) (xy 338.542465 -304.778788)
			(xy 338.572182 -304.824754) (xy 338.595023 -304.874497) (xy 338.61052 -304.926993) (xy 338.618353 -304.981166)
			(xy 338.61883 -305.008534) (xy 339.243924 -305.008534) (xy 339.244404 -304.981164) (xy 339.252218 -304.926985)
			(xy 339.267703 -304.874482) (xy 339.290542 -304.824735) (xy 339.320264 -304.778768) (xy 339.337904 -304.757836)
			(xy 339.344 -304.750724) (xy 339.35035 -304.733706) (xy 339.35035 -304.648362) (xy 339.344 -304.631344)
			(xy 339.337904 -304.624232) (xy 339.320267 -304.603298) (xy 339.290555 -304.557326) (xy 339.267718 -304.507579)
			(xy 339.252227 -304.455079) (xy 339.244398 -304.400903) (xy 339.243924 -304.373534) (xy 339.24441 -304.346283)
			(xy 339.252166 -304.292335) (xy 339.267521 -304.24004) (xy 339.290163 -304.190463) (xy 339.319629 -304.144613)
			(xy 339.35532 -304.103422) (xy 339.396511 -304.067731) (xy 339.442361 -304.038265) (xy 339.491938 -304.015623)
			(xy 339.544233 -304.000268) (xy 339.598181 -303.992512) (xy 339.652683 -303.992512) (xy 339.706631 -304.000268)
			(xy 339.758926 -304.015623) (xy 339.808503 -304.038265) (xy 339.854353 -304.067731) (xy 339.895544 -304.103422)
			(xy 339.931235 -304.144613) (xy 339.960701 -304.190463) (xy 339.983343 -304.24004) (xy 339.998698 -304.292335)
			(xy 340.006454 -304.346283) (xy 340.00694 -304.373534) (xy 340.006508 -304.400906) (xy 339.998685 -304.455087)
			(xy 339.983188 -304.507591) (xy 339.960338 -304.557337) (xy 339.930605 -304.603302) (xy 339.91296 -304.624232)
			(xy 339.906864 -304.631344) (xy 339.900514 -304.648362) (xy 339.900514 -304.733706) (xy 339.906864 -304.750724)
			(xy 339.91296 -304.757836) (xy 339.930576 -304.778787) (xy 339.960293 -304.824754) (xy 339.983134 -304.874496)
			(xy 339.99863 -304.926993) (xy 340.006463 -304.981166) (xy 340.00694 -305.008534) (xy 341.275924 -305.008534)
			(xy 341.276404 -304.981164) (xy 341.284218 -304.926985) (xy 341.299703 -304.874482) (xy 341.322542 -304.824735)
			(xy 341.352264 -304.778768) (xy 341.369904 -304.757836) (xy 341.376 -304.750724) (xy 341.38235 -304.733706)
			(xy 341.38235 -304.648362) (xy 341.376 -304.631344) (xy 341.369904 -304.624232) (xy 341.352267 -304.603298)
			(xy 341.322555 -304.557326) (xy 341.299718 -304.507579) (xy 341.284227 -304.455079) (xy 341.276398 -304.400903)
			(xy 341.275924 -304.373534) (xy 341.27641 -304.346283) (xy 341.284166 -304.292335) (xy 341.299521 -304.24004)
			(xy 341.322163 -304.190463) (xy 341.351629 -304.144613) (xy 341.38732 -304.103422) (xy 341.428511 -304.067731)
			(xy 341.474361 -304.038265) (xy 341.523938 -304.015623) (xy 341.576233 -304.000268) (xy 341.630181 -303.992512)
			(xy 341.684683 -303.992512) (xy 341.738631 -304.000268) (xy 341.790926 -304.015623) (xy 341.840503 -304.038265)
			(xy 341.886353 -304.067731) (xy 341.927544 -304.103422) (xy 341.963235 -304.144613) (xy 341.992701 -304.190463)
			(xy 342.015343 -304.24004) (xy 342.030698 -304.292335) (xy 342.038454 -304.346283) (xy 342.03894 -304.373534)
			(xy 342.038508 -304.400906) (xy 342.030685 -304.455087) (xy 342.015188 -304.507591) (xy 341.992338 -304.557337)
			(xy 341.962605 -304.603302) (xy 341.94496 -304.624232) (xy 341.938864 -304.631344) (xy 341.932514 -304.648362)
			(xy 341.932514 -304.733706) (xy 341.938864 -304.750724) (xy 341.94496 -304.757836) (xy 341.962576 -304.778787)
			(xy 341.992293 -304.824754) (xy 342.015134 -304.874496) (xy 342.03063 -304.926993) (xy 342.038463 -304.981166)
			(xy 342.03894 -305.008534) (xy 346.084144 -305.008534) (xy 346.084619 -304.981164) (xy 346.092433 -304.926985)
			(xy 346.10792 -304.874481) (xy 346.13076 -304.824734) (xy 346.160483 -304.778768) (xy 346.178124 -304.757836)
			(xy 346.18422 -304.750724) (xy 346.19057 -304.733706) (xy 346.19057 -304.648362) (xy 346.18422 -304.631344)
			(xy 346.178124 -304.624232) (xy 346.16049 -304.603296) (xy 346.130777 -304.557324) (xy 346.107939 -304.507578)
			(xy 346.092447 -304.455078) (xy 346.084618 -304.400903) (xy 346.084144 -304.373534) (xy 346.08463 -304.346283)
			(xy 346.092386 -304.292335) (xy 346.107741 -304.24004) (xy 346.130383 -304.190463) (xy 346.159849 -304.144613)
			(xy 346.19554 -304.103422) (xy 346.236731 -304.067731) (xy 346.282581 -304.038265) (xy 346.332158 -304.015623)
			(xy 346.384453 -304.000268) (xy 346.438401 -303.992512) (xy 346.492903 -303.992512) (xy 346.546851 -304.000268)
			(xy 346.599146 -304.015623) (xy 346.648723 -304.038265) (xy 346.694573 -304.067731) (xy 346.735764 -304.103422)
			(xy 346.771455 -304.144613) (xy 346.800921 -304.190463) (xy 346.823563 -304.24004) (xy 346.838918 -304.292335)
			(xy 346.846674 -304.346283) (xy 346.84716 -304.373534) (xy 346.846724 -304.400905) (xy 346.8389 -304.455086)
			(xy 346.823405 -304.50759) (xy 346.800556 -304.557336) (xy 346.770825 -304.603302) (xy 346.75318 -304.624232)
			(xy 346.747084 -304.631344) (xy 346.740734 -304.648362) (xy 346.740734 -304.733706) (xy 346.747084 -304.750724)
			(xy 346.75318 -304.757836) (xy 346.770799 -304.778784) (xy 346.800515 -304.824752) (xy 346.823355 -304.874496)
			(xy 346.838851 -304.926993) (xy 346.846684 -304.981166) (xy 346.84716 -305.008534) (xy 346.846674 -305.035785)
			(xy 346.838918 -305.089733) (xy 346.823563 -305.142028) (xy 346.800921 -305.191605) (xy 346.771455 -305.237455)
			(xy 346.735764 -305.278646) (xy 346.694573 -305.314337) (xy 346.648723 -305.343803) (xy 346.599146 -305.366445)
			(xy 346.546851 -305.3818) (xy 346.492903 -305.389556) (xy 346.438401 -305.389556) (xy 346.384453 -305.3818)
			(xy 346.332158 -305.366445) (xy 346.282581 -305.343803) (xy 346.236731 -305.314337) (xy 346.19554 -305.278646)
			(xy 346.159849 -305.237455) (xy 346.130383 -305.191605) (xy 346.107741 -305.142028) (xy 346.092386 -305.089733)
			(xy 346.08463 -305.035785) (xy 346.084144 -305.008534) (xy 342.03894 -305.008534) (xy 342.038454 -305.035785)
			(xy 342.030698 -305.089733) (xy 342.015343 -305.142028) (xy 341.992701 -305.191605) (xy 341.963235 -305.237455)
			(xy 341.927544 -305.278646) (xy 341.886353 -305.314337) (xy 341.840503 -305.343803) (xy 341.790926 -305.366445)
			(xy 341.738631 -305.3818) (xy 341.684683 -305.389556) (xy 341.630181 -305.389556) (xy 341.576233 -305.3818)
			(xy 341.523938 -305.366445) (xy 341.474361 -305.343803) (xy 341.428511 -305.314337) (xy 341.38732 -305.278646)
			(xy 341.351629 -305.237455) (xy 341.322163 -305.191605) (xy 341.299521 -305.142028) (xy 341.284166 -305.089733)
			(xy 341.27641 -305.035785) (xy 341.275924 -305.008534) (xy 340.00694 -305.008534) (xy 340.006454 -305.035785)
			(xy 339.998698 -305.089733) (xy 339.983343 -305.142028) (xy 339.960701 -305.191605) (xy 339.931235 -305.237455)
			(xy 339.895544 -305.278646) (xy 339.854353 -305.314337) (xy 339.808503 -305.343803) (xy 339.758926 -305.366445)
			(xy 339.706631 -305.3818) (xy 339.652683 -305.389556) (xy 339.598181 -305.389556) (xy 339.544233 -305.3818)
			(xy 339.491938 -305.366445) (xy 339.442361 -305.343803) (xy 339.396511 -305.314337) (xy 339.35532 -305.278646)
			(xy 339.319629 -305.237455) (xy 339.290163 -305.191605) (xy 339.267521 -305.142028) (xy 339.252166 -305.089733)
			(xy 339.24441 -305.035785) (xy 339.243924 -305.008534) (xy 338.61883 -305.008534) (xy 338.618344 -305.035785)
			(xy 338.610588 -305.089733) (xy 338.595233 -305.142028) (xy 338.572591 -305.191605) (xy 338.543125 -305.237455)
			(xy 338.507434 -305.278646) (xy 338.466243 -305.314337) (xy 338.420393 -305.343803) (xy 338.370816 -305.366445)
			(xy 338.318521 -305.3818) (xy 338.264573 -305.389556) (xy 338.210071 -305.389556) (xy 338.156123 -305.3818)
			(xy 338.103828 -305.366445) (xy 338.054251 -305.343803) (xy 338.008401 -305.314337) (xy 337.96721 -305.278646)
			(xy 337.931519 -305.237455) (xy 337.902053 -305.191605) (xy 337.879411 -305.142028) (xy 337.864056 -305.089733)
			(xy 337.8563 -305.035785) (xy 337.855814 -305.008534) (xy 335.19872 -305.008534) (xy 335.198234 -305.035785)
			(xy 335.190478 -305.089733) (xy 335.175123 -305.142028) (xy 335.152481 -305.191605) (xy 335.123015 -305.237455)
			(xy 335.087324 -305.278646) (xy 335.046133 -305.314337) (xy 335.000283 -305.343803) (xy 334.950706 -305.366445)
			(xy 334.898411 -305.3818) (xy 334.844463 -305.389556) (xy 334.789961 -305.389556) (xy 334.736013 -305.3818)
			(xy 334.683718 -305.366445) (xy 334.634141 -305.343803) (xy 334.588291 -305.314337) (xy 334.5471 -305.278646)
			(xy 334.511409 -305.237455) (xy 334.481943 -305.191605) (xy 334.459301 -305.142028) (xy 334.443946 -305.089733)
			(xy 334.43619 -305.035785) (xy 334.435704 -305.008534) (xy 325.645621 -305.008534) (xy 325.647049 -305.01824)
			(xy 325.647558 -305.046126) (xy 325.647049 -305.074012) (xy 325.638929 -305.129188) (xy 325.622861 -305.182595)
			(xy 325.599189 -305.233092) (xy 325.568416 -305.279605) (xy 325.531199 -305.321142) (xy 325.488331 -305.356817)
			(xy 325.440725 -305.385871) (xy 325.389396 -305.407683) (xy 325.335439 -305.421789) (xy 325.280002 -305.427889)
			(xy 325.224268 -305.425852) (xy 325.169425 -305.415722) (xy 325.116641 -305.397715) (xy 325.067041 -305.372214)
			(xy 325.021683 -305.339763) (xy 324.981534 -305.301054) (xy 324.947448 -305.256911) (xy 324.920152 -305.208276)
			(xy 324.900229 -305.156185) (xy 324.888103 -305.101748) (xy 324.884032 -305.046126) (xy 324.631233 -305.046126)
			(xy 324.631558 -305.063906) (xy 324.631049 -305.091792) (xy 324.622929 -305.146968) (xy 324.606861 -305.200375)
			(xy 324.583189 -305.250872) (xy 324.552416 -305.297385) (xy 324.515199 -305.338922) (xy 324.472331 -305.374597)
			(xy 324.424725 -305.403651) (xy 324.373396 -305.425463) (xy 324.319439 -305.439569) (xy 324.264002 -305.445669)
			(xy 324.208268 -305.443632) (xy 324.153425 -305.433502) (xy 324.100641 -305.415495) (xy 324.051041 -305.389994)
			(xy 324.005683 -305.357543) (xy 323.965534 -305.318834) (xy 323.931448 -305.274691) (xy 323.904152 -305.226056)
			(xy 323.884229 -305.173965) (xy 323.872103 -305.119528) (xy 323.868032 -305.063906) (xy 323.606903 -305.063906)
			(xy 323.606922 -305.064922) (xy 323.606413 -305.092808) (xy 323.598293 -305.147984) (xy 323.582225 -305.201391)
			(xy 323.558553 -305.251888) (xy 323.52778 -305.298401) (xy 323.490563 -305.339938) (xy 323.447695 -305.375613)
			(xy 323.400089 -305.404667) (xy 323.34876 -305.426479) (xy 323.294803 -305.440585) (xy 323.239366 -305.446685)
			(xy 323.183632 -305.444648) (xy 323.128789 -305.434518) (xy 323.076005 -305.416511) (xy 323.026405 -305.39101)
			(xy 322.981047 -305.358559) (xy 322.940898 -305.31985) (xy 322.906812 -305.275707) (xy 322.879516 -305.227072)
			(xy 322.859593 -305.174981) (xy 322.847467 -305.120544) (xy 322.843396 -305.064922) (xy 322.598542 -305.064922)
			(xy 322.598033 -305.092808) (xy 322.589913 -305.147984) (xy 322.573845 -305.201391) (xy 322.550173 -305.251888)
			(xy 322.5194 -305.298401) (xy 322.482183 -305.339938) (xy 322.439315 -305.375613) (xy 322.391709 -305.404667)
			(xy 322.34038 -305.426479) (xy 322.286423 -305.440585) (xy 322.230986 -305.446685) (xy 322.175252 -305.444648)
			(xy 322.120409 -305.434518) (xy 322.067625 -305.416511) (xy 322.018025 -305.39101) (xy 321.972667 -305.358559)
			(xy 321.932518 -305.31985) (xy 321.898432 -305.275707) (xy 321.871136 -305.227072) (xy 321.851213 -305.174981)
			(xy 321.839087 -305.120544) (xy 321.835016 -305.064922) (xy 321.583167 -305.064922) (xy 321.583167 -305.092157)
			(xy 321.575408 -305.146115) (xy 321.560049 -305.19842) (xy 321.537401 -305.248007) (xy 321.507927 -305.293865)
			(xy 321.472226 -305.335061) (xy 321.431025 -305.370757) (xy 321.385163 -305.400225) (xy 321.335573 -305.422866)
			(xy 321.283266 -305.438219) (xy 321.229307 -305.445971) (xy 321.20205 -305.44643) (xy 321.174904 -305.446009)
			(xy 321.121158 -305.438326) (xy 321.069045 -305.423095) (xy 321.019622 -305.400624) (xy 320.973886 -305.371368)
			(xy 320.932765 -305.335918) (xy 320.89709 -305.294992) (xy 320.867582 -305.249418) (xy 320.84484 -305.200119)
			(xy 320.829323 -305.148091) (xy 320.82486 -305.12131) (xy 320.822048 -305.106479) (xy 320.809009 -305.079273)
			(xy 320.788599 -305.057054) (xy 320.762596 -305.041756) (xy 320.733261 -305.03471) (xy 320.703146 -305.036528)
			(xy 320.674871 -305.047052) (xy 320.662554 -305.055778) (xy 320.642497 -305.070592) (xy 320.599278 -305.095458)
			(xy 320.553191 -305.114489) (xy 320.50502 -305.127362) (xy 320.455583 -305.133857) (xy 320.430652 -305.134264)
			(xy 320.4034 -305.133863) (xy 320.349451 -305.1261) (xy 320.297156 -305.110739) (xy 320.247579 -305.088092)
			(xy 320.20173 -305.058621) (xy 320.16054 -305.022926) (xy 320.12485 -304.981732) (xy 320.095385 -304.935879)
			(xy 320.072744 -304.886299) (xy 320.05739 -304.834002) (xy 320.049634 -304.780052) (xy 304.943098 -304.780052)
			(xy 304.956112 -304.804849) (xy 304.971696 -304.85153) (xy 304.979591 -304.900107) (xy 304.980086 -304.924714)
			(xy 304.979591 -304.949321) (xy 304.971696 -304.997898) (xy 304.956112 -305.044579) (xy 304.933241 -305.088156)
			(xy 304.903676 -305.1275) (xy 304.868183 -305.161592) (xy 304.82768 -305.189548) (xy 304.783218 -305.210646)
			(xy 304.735947 -305.224338) (xy 304.687092 -305.23027) (xy 304.637917 -305.228289) (xy 304.589698 -305.218445)
			(xy 304.543682 -305.200993) (xy 304.501061 -305.176386) (xy 304.46294 -305.145261) (xy 304.430305 -305.108424)
			(xy 304.404002 -305.066828) (xy 304.384711 -305.021552) (xy 304.372934 -304.973768) (xy 304.368974 -304.924714)
			(xy 304.030126 -304.924714) (xy 304.029631 -304.949321) (xy 304.021736 -304.997898) (xy 304.006152 -305.044579)
			(xy 303.983281 -305.088156) (xy 303.953716 -305.1275) (xy 303.918223 -305.161592) (xy 303.87772 -305.189548)
			(xy 303.833258 -305.210646) (xy 303.785987 -305.224338) (xy 303.737132 -305.23027) (xy 303.687957 -305.228289)
			(xy 303.639738 -305.218445) (xy 303.593722 -305.200993) (xy 303.551101 -305.176386) (xy 303.51298 -305.145261)
			(xy 303.480345 -305.108424) (xy 303.454042 -305.066828) (xy 303.434751 -305.021552) (xy 303.422974 -304.973768)
			(xy 303.419014 -304.924714) (xy 303.080166 -304.924714) (xy 303.079671 -304.949321) (xy 303.071776 -304.997898)
			(xy 303.056192 -305.044579) (xy 303.033321 -305.088156) (xy 303.003756 -305.1275) (xy 302.968263 -305.161592)
			(xy 302.92776 -305.189548) (xy 302.883298 -305.210646) (xy 302.836027 -305.224338) (xy 302.787172 -305.23027)
			(xy 302.737997 -305.228289) (xy 302.689778 -305.218445) (xy 302.643762 -305.200993) (xy 302.601141 -305.176386)
			(xy 302.56302 -305.145261) (xy 302.530385 -305.108424) (xy 302.504082 -305.066828) (xy 302.484791 -305.021552)
			(xy 302.473014 -304.973768) (xy 302.469054 -304.924714) (xy 302.130206 -304.924714) (xy 302.129711 -304.949321)
			(xy 302.121816 -304.997898) (xy 302.106232 -305.044579) (xy 302.083361 -305.088156) (xy 302.053796 -305.1275)
			(xy 302.018303 -305.161592) (xy 301.9778 -305.189548) (xy 301.933338 -305.210646) (xy 301.886067 -305.224338)
			(xy 301.837212 -305.23027) (xy 301.788037 -305.228289) (xy 301.739818 -305.218445) (xy 301.693802 -305.200993)
			(xy 301.651181 -305.176386) (xy 301.61306 -305.145261) (xy 301.580425 -305.108424) (xy 301.554122 -305.066828)
			(xy 301.534831 -305.021552) (xy 301.523054 -304.973768) (xy 301.519094 -304.924714) (xy 301.179992 -304.924714)
			(xy 301.179497 -304.949321) (xy 301.171602 -304.997898) (xy 301.156018 -305.044579) (xy 301.133147 -305.088156)
			(xy 301.103582 -305.1275) (xy 301.068089 -305.161592) (xy 301.027586 -305.189548) (xy 300.983124 -305.210646)
			(xy 300.935853 -305.224338) (xy 300.886998 -305.23027) (xy 300.837823 -305.228289) (xy 300.789604 -305.218445)
			(xy 300.743588 -305.200993) (xy 300.700967 -305.176386) (xy 300.662846 -305.145261) (xy 300.630211 -305.108424)
			(xy 300.603908 -305.066828) (xy 300.584617 -305.021552) (xy 300.57284 -304.973768) (xy 300.56888 -304.924714)
			(xy 300.230032 -304.924714) (xy 300.229537 -304.949321) (xy 300.221642 -304.997898) (xy 300.206058 -305.044579)
			(xy 300.183187 -305.088156) (xy 300.153622 -305.1275) (xy 300.118129 -305.161592) (xy 300.077626 -305.189548)
			(xy 300.033164 -305.210646) (xy 299.985893 -305.224338) (xy 299.937038 -305.23027) (xy 299.887863 -305.228289)
			(xy 299.839644 -305.218445) (xy 299.793628 -305.200993) (xy 299.751007 -305.176386) (xy 299.712886 -305.145261)
			(xy 299.680251 -305.108424) (xy 299.653948 -305.066828) (xy 299.634657 -305.021552) (xy 299.62288 -304.973768)
			(xy 299.61892 -304.924714) (xy 299.280072 -304.924714) (xy 299.279577 -304.949321) (xy 299.271682 -304.997898)
			(xy 299.256098 -305.044579) (xy 299.233227 -305.088156) (xy 299.203662 -305.1275) (xy 299.168169 -305.161592)
			(xy 299.127666 -305.189548) (xy 299.083204 -305.210646) (xy 299.035933 -305.224338) (xy 298.987078 -305.23027)
			(xy 298.937903 -305.228289) (xy 298.889684 -305.218445) (xy 298.843668 -305.200993) (xy 298.801047 -305.176386)
			(xy 298.762926 -305.145261) (xy 298.730291 -305.108424) (xy 298.703988 -305.066828) (xy 298.684697 -305.021552)
			(xy 298.67292 -304.973768) (xy 298.66896 -304.924714) (xy 298.330112 -304.924714) (xy 298.329617 -304.949321)
			(xy 298.321722 -304.997898) (xy 298.306138 -305.044579) (xy 298.283267 -305.088156) (xy 298.253702 -305.1275)
			(xy 298.218209 -305.161592) (xy 298.177706 -305.189548) (xy 298.133244 -305.210646) (xy 298.085973 -305.224338)
			(xy 298.037118 -305.23027) (xy 297.987943 -305.228289) (xy 297.939724 -305.218445) (xy 297.893708 -305.200993)
			(xy 297.851087 -305.176386) (xy 297.812966 -305.145261) (xy 297.780331 -305.108424) (xy 297.754028 -305.066828)
			(xy 297.734737 -305.021552) (xy 297.72296 -304.973768) (xy 297.719 -304.924714) (xy 297.380152 -304.924714)
			(xy 297.379657 -304.949321) (xy 297.371762 -304.997898) (xy 297.356178 -305.044579) (xy 297.333307 -305.088156)
			(xy 297.303742 -305.1275) (xy 297.268249 -305.161592) (xy 297.227746 -305.189548) (xy 297.183284 -305.210646)
			(xy 297.136013 -305.224338) (xy 297.087158 -305.23027) (xy 297.037983 -305.228289) (xy 296.989764 -305.218445)
			(xy 296.943748 -305.200993) (xy 296.901127 -305.176386) (xy 296.863006 -305.145261) (xy 296.830371 -305.108424)
			(xy 296.804068 -305.066828) (xy 296.784777 -305.021552) (xy 296.773 -304.973768) (xy 296.76904 -304.924714)
			(xy 296.430192 -304.924714) (xy 296.429697 -304.949321) (xy 296.421802 -304.997898) (xy 296.406218 -305.044579)
			(xy 296.383347 -305.088156) (xy 296.353782 -305.1275) (xy 296.318289 -305.161592) (xy 296.277786 -305.189548)
			(xy 296.233324 -305.210646) (xy 296.186053 -305.224338) (xy 296.137198 -305.23027) (xy 296.088023 -305.228289)
			(xy 296.039804 -305.218445) (xy 295.993788 -305.200993) (xy 295.951167 -305.176386) (xy 295.913046 -305.145261)
			(xy 295.880411 -305.108424) (xy 295.854108 -305.066828) (xy 295.834817 -305.021552) (xy 295.82304 -304.973768)
			(xy 295.81908 -304.924714) (xy 295.480232 -304.924714) (xy 295.479737 -304.949321) (xy 295.471842 -304.997898)
			(xy 295.456258 -305.044579) (xy 295.433387 -305.088156) (xy 295.403822 -305.1275) (xy 295.368329 -305.161592)
			(xy 295.327826 -305.189548) (xy 295.283364 -305.210646) (xy 295.236093 -305.224338) (xy 295.187238 -305.23027)
			(xy 295.138063 -305.228289) (xy 295.089844 -305.218445) (xy 295.043828 -305.200993) (xy 295.001207 -305.176386)
			(xy 294.963086 -305.145261) (xy 294.930451 -305.108424) (xy 294.904148 -305.066828) (xy 294.884857 -305.021552)
			(xy 294.87308 -304.973768) (xy 294.86912 -304.924714) (xy 294.530018 -304.924714) (xy 294.529523 -304.949321)
			(xy 294.521628 -304.997898) (xy 294.506044 -305.044579) (xy 294.483173 -305.088156) (xy 294.453608 -305.1275)
			(xy 294.418115 -305.161592) (xy 294.377612 -305.189548) (xy 294.33315 -305.210646) (xy 294.285879 -305.224338)
			(xy 294.237024 -305.23027) (xy 294.187849 -305.228289) (xy 294.13963 -305.218445) (xy 294.093614 -305.200993)
			(xy 294.050993 -305.176386) (xy 294.012872 -305.145261) (xy 293.980237 -305.108424) (xy 293.953934 -305.066828)
			(xy 293.934643 -305.021552) (xy 293.922866 -304.973768) (xy 293.918906 -304.924714) (xy 293.580058 -304.924714)
			(xy 293.579563 -304.949321) (xy 293.571668 -304.997898) (xy 293.556084 -305.044579) (xy 293.533213 -305.088156)
			(xy 293.503648 -305.1275) (xy 293.468155 -305.161592) (xy 293.427652 -305.189548) (xy 293.38319 -305.210646)
			(xy 293.335919 -305.224338) (xy 293.287064 -305.23027) (xy 293.237889 -305.228289) (xy 293.18967 -305.218445)
			(xy 293.143654 -305.200993) (xy 293.101033 -305.176386) (xy 293.062912 -305.145261) (xy 293.030277 -305.108424)
			(xy 293.003974 -305.066828) (xy 292.984683 -305.021552) (xy 292.972906 -304.973768) (xy 292.968946 -304.924714)
			(xy 292.630098 -304.924714) (xy 292.629603 -304.949321) (xy 292.621708 -304.997898) (xy 292.606124 -305.044579)
			(xy 292.583253 -305.088156) (xy 292.553688 -305.1275) (xy 292.518195 -305.161592) (xy 292.477692 -305.189548)
			(xy 292.43323 -305.210646) (xy 292.385959 -305.224338) (xy 292.337104 -305.23027) (xy 292.287929 -305.228289)
			(xy 292.23971 -305.218445) (xy 292.193694 -305.200993) (xy 292.151073 -305.176386) (xy 292.112952 -305.145261)
			(xy 292.080317 -305.108424) (xy 292.054014 -305.066828) (xy 292.034723 -305.021552) (xy 292.022946 -304.973768)
			(xy 292.018986 -304.924714) (xy 290.730178 -304.924714) (xy 290.729683 -304.949321) (xy 290.721788 -304.997898)
			(xy 290.706204 -305.044579) (xy 290.683333 -305.088156) (xy 290.653768 -305.1275) (xy 290.618275 -305.161592)
			(xy 290.577772 -305.189548) (xy 290.53331 -305.210646) (xy 290.486039 -305.224338) (xy 290.437184 -305.23027)
			(xy 290.388009 -305.228289) (xy 290.33979 -305.218445) (xy 290.293774 -305.200993) (xy 290.251153 -305.176386)
			(xy 290.213032 -305.145261) (xy 290.180397 -305.108424) (xy 290.154094 -305.066828) (xy 290.134803 -305.021552)
			(xy 290.123026 -304.973768) (xy 290.119066 -304.924714) (xy 289.780218 -304.924714) (xy 289.779723 -304.949321)
			(xy 289.771828 -304.997898) (xy 289.756244 -305.044579) (xy 289.733373 -305.088156) (xy 289.703808 -305.1275)
			(xy 289.668315 -305.161592) (xy 289.627812 -305.189548) (xy 289.58335 -305.210646) (xy 289.536079 -305.224338)
			(xy 289.487224 -305.23027) (xy 289.438049 -305.228289) (xy 289.38983 -305.218445) (xy 289.343814 -305.200993)
			(xy 289.301193 -305.176386) (xy 289.263072 -305.145261) (xy 289.230437 -305.108424) (xy 289.204134 -305.066828)
			(xy 289.184843 -305.021552) (xy 289.173066 -304.973768) (xy 289.169106 -304.924714) (xy 288.830004 -304.924714)
			(xy 288.829509 -304.949321) (xy 288.821614 -304.997898) (xy 288.80603 -305.044579) (xy 288.783159 -305.088156)
			(xy 288.753594 -305.1275) (xy 288.718101 -305.161592) (xy 288.677598 -305.189548) (xy 288.633136 -305.210646)
			(xy 288.585865 -305.224338) (xy 288.53701 -305.23027) (xy 288.487835 -305.228289) (xy 288.439616 -305.218445)
			(xy 288.3936 -305.200993) (xy 288.350979 -305.176386) (xy 288.312858 -305.145261) (xy 288.280223 -305.108424)
			(xy 288.25392 -305.066828) (xy 288.234629 -305.021552) (xy 288.222852 -304.973768) (xy 288.218892 -304.924714)
			(xy 287.880044 -304.924714) (xy 287.879549 -304.949321) (xy 287.871654 -304.997898) (xy 287.85607 -305.044579)
			(xy 287.833199 -305.088156) (xy 287.803634 -305.1275) (xy 287.768141 -305.161592) (xy 287.727638 -305.189548)
			(xy 287.683176 -305.210646) (xy 287.635905 -305.224338) (xy 287.58705 -305.23027) (xy 287.537875 -305.228289)
			(xy 287.489656 -305.218445) (xy 287.44364 -305.200993) (xy 287.401019 -305.176386) (xy 287.362898 -305.145261)
			(xy 287.330263 -305.108424) (xy 287.30396 -305.066828) (xy 287.284669 -305.021552) (xy 287.272892 -304.973768)
			(xy 287.268932 -304.924714) (xy 286.930084 -304.924714) (xy 286.929589 -304.949321) (xy 286.921694 -304.997898)
			(xy 286.90611 -305.044579) (xy 286.883239 -305.088156) (xy 286.853674 -305.1275) (xy 286.818181 -305.161592)
			(xy 286.777678 -305.189548) (xy 286.733216 -305.210646) (xy 286.685945 -305.224338) (xy 286.63709 -305.23027)
			(xy 286.587915 -305.228289) (xy 286.539696 -305.218445) (xy 286.49368 -305.200993) (xy 286.451059 -305.176386)
			(xy 286.412938 -305.145261) (xy 286.380303 -305.108424) (xy 286.354 -305.066828) (xy 286.334709 -305.021552)
			(xy 286.322932 -304.973768) (xy 286.318972 -304.924714) (xy 285.980124 -304.924714) (xy 285.979629 -304.949321)
			(xy 285.971734 -304.997898) (xy 285.95615 -305.044579) (xy 285.933279 -305.088156) (xy 285.903714 -305.1275)
			(xy 285.868221 -305.161592) (xy 285.827718 -305.189548) (xy 285.783256 -305.210646) (xy 285.735985 -305.224338)
			(xy 285.68713 -305.23027) (xy 285.637955 -305.228289) (xy 285.589736 -305.218445) (xy 285.54372 -305.200993)
			(xy 285.501099 -305.176386) (xy 285.462978 -305.145261) (xy 285.430343 -305.108424) (xy 285.40404 -305.066828)
			(xy 285.384749 -305.021552) (xy 285.372972 -304.973768) (xy 285.369012 -304.924714) (xy 285.030164 -304.924714)
			(xy 285.029669 -304.949321) (xy 285.021774 -304.997898) (xy 285.00619 -305.044579) (xy 284.983319 -305.088156)
			(xy 284.953754 -305.1275) (xy 284.918261 -305.161592) (xy 284.877758 -305.189548) (xy 284.833296 -305.210646)
			(xy 284.786025 -305.224338) (xy 284.73717 -305.23027) (xy 284.687995 -305.228289) (xy 284.639776 -305.218445)
			(xy 284.59376 -305.200993) (xy 284.551139 -305.176386) (xy 284.513018 -305.145261) (xy 284.480383 -305.108424)
			(xy 284.45408 -305.066828) (xy 284.434789 -305.021552) (xy 284.423012 -304.973768) (xy 284.419052 -304.924714)
			(xy 284.080204 -304.924714) (xy 284.079709 -304.949321) (xy 284.071814 -304.997898) (xy 284.05623 -305.044579)
			(xy 284.033359 -305.088156) (xy 284.003794 -305.1275) (xy 283.968301 -305.161592) (xy 283.927798 -305.189548)
			(xy 283.883336 -305.210646) (xy 283.836065 -305.224338) (xy 283.78721 -305.23027) (xy 283.738035 -305.228289)
			(xy 283.689816 -305.218445) (xy 283.6438 -305.200993) (xy 283.601179 -305.176386) (xy 283.563058 -305.145261)
			(xy 283.530423 -305.108424) (xy 283.50412 -305.066828) (xy 283.484829 -305.021552) (xy 283.473052 -304.973768)
			(xy 283.469092 -304.924714) (xy 283.130244 -304.924714) (xy 283.129749 -304.949321) (xy 283.121854 -304.997898)
			(xy 283.10627 -305.044579) (xy 283.083399 -305.088156) (xy 283.053834 -305.1275) (xy 283.018341 -305.161592)
			(xy 282.977838 -305.189548) (xy 282.933376 -305.210646) (xy 282.886105 -305.224338) (xy 282.83725 -305.23027)
			(xy 282.788075 -305.228289) (xy 282.739856 -305.218445) (xy 282.69384 -305.200993) (xy 282.651219 -305.176386)
			(xy 282.613098 -305.145261) (xy 282.580463 -305.108424) (xy 282.55416 -305.066828) (xy 282.534869 -305.021552)
			(xy 282.523092 -304.973768) (xy 282.519132 -304.924714) (xy 282.18003 -304.924714) (xy 282.179535 -304.949321)
			(xy 282.17164 -304.997898) (xy 282.156056 -305.044579) (xy 282.133185 -305.088156) (xy 282.10362 -305.1275)
			(xy 282.068127 -305.161592) (xy 282.027624 -305.189548) (xy 281.983162 -305.210646) (xy 281.935891 -305.224338)
			(xy 281.887036 -305.23027) (xy 281.837861 -305.228289) (xy 281.789642 -305.218445) (xy 281.743626 -305.200993)
			(xy 281.701005 -305.176386) (xy 281.662884 -305.145261) (xy 281.630249 -305.108424) (xy 281.603946 -305.066828)
			(xy 281.584655 -305.021552) (xy 281.572878 -304.973768) (xy 281.568918 -304.924714) (xy 281.23007 -304.924714)
			(xy 281.229575 -304.949321) (xy 281.22168 -304.997898) (xy 281.206096 -305.044579) (xy 281.183225 -305.088156)
			(xy 281.15366 -305.1275) (xy 281.118167 -305.161592) (xy 281.077664 -305.189548) (xy 281.033202 -305.210646)
			(xy 280.985931 -305.224338) (xy 280.937076 -305.23027) (xy 280.887901 -305.228289) (xy 280.839682 -305.218445)
			(xy 280.793666 -305.200993) (xy 280.751045 -305.176386) (xy 280.712924 -305.145261) (xy 280.680289 -305.108424)
			(xy 280.653986 -305.066828) (xy 280.634695 -305.021552) (xy 280.622918 -304.973768) (xy 280.618958 -304.924714)
			(xy 280.28011 -304.924714) (xy 280.28011 -304.941224) (xy 280.279602 -304.947066) (xy 280.279602 -304.947574)
			(xy 280.278332 -304.958496) (xy 280.278332 -304.95875) (xy 280.277824 -304.962814) (xy 280.275284 -304.98161)
			(xy 280.274268 -304.987198) (xy 280.270204 -305.002946) (xy 280.268426 -305.015646) (xy 280.268426 -305.399948)
			(xy 305.793914 -305.399948) (xy 305.797874 -305.350894) (xy 305.809651 -305.30311) (xy 305.828942 -305.257834)
			(xy 305.855245 -305.216238) (xy 305.88788 -305.179401) (xy 305.926001 -305.148276) (xy 305.968622 -305.123669)
			(xy 306.014638 -305.106217) (xy 306.062857 -305.096373) (xy 306.112032 -305.094392) (xy 306.160887 -305.100324)
			(xy 306.208158 -305.114016) (xy 306.25262 -305.135114) (xy 306.293123 -305.16307) (xy 306.328616 -305.197162)
			(xy 306.358181 -305.236506) (xy 306.381052 -305.280083) (xy 306.396636 -305.326764) (xy 306.404531 -305.375341)
			(xy 306.405026 -305.399948) (xy 306.744128 -305.399948) (xy 306.748088 -305.350894) (xy 306.759865 -305.30311)
			(xy 306.779156 -305.257834) (xy 306.805459 -305.216238) (xy 306.838094 -305.179401) (xy 306.876215 -305.148276)
			(xy 306.918836 -305.123669) (xy 306.964852 -305.106217) (xy 307.013071 -305.096373) (xy 307.062246 -305.094392)
			(xy 307.111101 -305.100324) (xy 307.158372 -305.114016) (xy 307.202834 -305.135114) (xy 307.243337 -305.16307)
			(xy 307.27883 -305.197162) (xy 307.308395 -305.236506) (xy 307.331266 -305.280083) (xy 307.34685 -305.326764)
			(xy 307.354745 -305.375341) (xy 307.35524 -305.399948) (xy 307.694088 -305.399948) (xy 307.698048 -305.350894)
			(xy 307.709825 -305.30311) (xy 307.729116 -305.257834) (xy 307.755419 -305.216238) (xy 307.788054 -305.179401)
			(xy 307.826175 -305.148276) (xy 307.868796 -305.123669) (xy 307.914812 -305.106217) (xy 307.963031 -305.096373)
			(xy 308.012206 -305.094392) (xy 308.061061 -305.100324) (xy 308.108332 -305.114016) (xy 308.152794 -305.135114)
			(xy 308.193297 -305.16307) (xy 308.22879 -305.197162) (xy 308.258355 -305.236506) (xy 308.281226 -305.280083)
			(xy 308.29681 -305.326764) (xy 308.304705 -305.375341) (xy 308.3052 -305.399948) (xy 308.644048 -305.399948)
			(xy 308.648008 -305.350894) (xy 308.659785 -305.30311) (xy 308.679076 -305.257834) (xy 308.705379 -305.216238)
			(xy 308.738014 -305.179401) (xy 308.776135 -305.148276) (xy 308.818756 -305.123669) (xy 308.864772 -305.106217)
			(xy 308.912991 -305.096373) (xy 308.962166 -305.094392) (xy 309.011021 -305.100324) (xy 309.058292 -305.114016)
			(xy 309.102754 -305.135114) (xy 309.143257 -305.16307) (xy 309.17875 -305.197162) (xy 309.208315 -305.236506)
			(xy 309.231186 -305.280083) (xy 309.24677 -305.326764) (xy 309.254665 -305.375341) (xy 309.25516 -305.399948)
			(xy 309.594008 -305.399948) (xy 309.597968 -305.350894) (xy 309.609745 -305.30311) (xy 309.629036 -305.257834)
			(xy 309.655339 -305.216238) (xy 309.687974 -305.179401) (xy 309.726095 -305.148276) (xy 309.768716 -305.123669)
			(xy 309.814732 -305.106217) (xy 309.862951 -305.096373) (xy 309.912126 -305.094392) (xy 309.960981 -305.100324)
			(xy 310.008252 -305.114016) (xy 310.052714 -305.135114) (xy 310.093217 -305.16307) (xy 310.12871 -305.197162)
			(xy 310.158275 -305.236506) (xy 310.181146 -305.280083) (xy 310.19673 -305.326764) (xy 310.204625 -305.375341)
			(xy 310.20512 -305.399948) (xy 310.543968 -305.399948) (xy 310.547928 -305.350894) (xy 310.559705 -305.30311)
			(xy 310.578996 -305.257834) (xy 310.605299 -305.216238) (xy 310.637934 -305.179401) (xy 310.676055 -305.148276)
			(xy 310.718676 -305.123669) (xy 310.764692 -305.106217) (xy 310.812911 -305.096373) (xy 310.862086 -305.094392)
			(xy 310.910941 -305.100324) (xy 310.958212 -305.114016) (xy 311.002674 -305.135114) (xy 311.043177 -305.16307)
			(xy 311.07867 -305.197162) (xy 311.108235 -305.236506) (xy 311.131106 -305.280083) (xy 311.14669 -305.326764)
			(xy 311.154585 -305.375341) (xy 311.15508 -305.399948) (xy 311.493928 -305.399948) (xy 311.497888 -305.350894)
			(xy 311.509665 -305.30311) (xy 311.528956 -305.257834) (xy 311.555259 -305.216238) (xy 311.587894 -305.179401)
			(xy 311.626015 -305.148276) (xy 311.668636 -305.123669) (xy 311.714652 -305.106217) (xy 311.762871 -305.096373)
			(xy 311.812046 -305.094392) (xy 311.860901 -305.100324) (xy 311.908172 -305.114016) (xy 311.952634 -305.135114)
			(xy 311.993137 -305.16307) (xy 312.02863 -305.197162) (xy 312.058195 -305.236506) (xy 312.081066 -305.280083)
			(xy 312.09665 -305.326764) (xy 312.104545 -305.375341) (xy 312.10504 -305.399948) (xy 312.443888 -305.399948)
			(xy 312.447848 -305.350894) (xy 312.459625 -305.30311) (xy 312.478916 -305.257834) (xy 312.505219 -305.216238)
			(xy 312.537854 -305.179401) (xy 312.575975 -305.148276) (xy 312.618596 -305.123669) (xy 312.664612 -305.106217)
			(xy 312.712831 -305.096373) (xy 312.762006 -305.094392) (xy 312.810861 -305.100324) (xy 312.858132 -305.114016)
			(xy 312.902594 -305.135114) (xy 312.943097 -305.16307) (xy 312.97859 -305.197162) (xy 313.008155 -305.236506)
			(xy 313.031026 -305.280083) (xy 313.04661 -305.326764) (xy 313.054505 -305.375341) (xy 313.055 -305.399948)
			(xy 313.394102 -305.399948) (xy 313.398062 -305.350894) (xy 313.409839 -305.30311) (xy 313.42913 -305.257834)
			(xy 313.455433 -305.216238) (xy 313.488068 -305.179401) (xy 313.526189 -305.148276) (xy 313.56881 -305.123669)
			(xy 313.614826 -305.106217) (xy 313.663045 -305.096373) (xy 313.71222 -305.094392) (xy 313.761075 -305.100324)
			(xy 313.808346 -305.114016) (xy 313.852808 -305.135114) (xy 313.893311 -305.16307) (xy 313.928804 -305.197162)
			(xy 313.958369 -305.236506) (xy 313.98124 -305.280083) (xy 313.996824 -305.326764) (xy 314.004719 -305.375341)
			(xy 314.005214 -305.399948) (xy 314.344062 -305.399948) (xy 314.348022 -305.350894) (xy 314.359799 -305.30311)
			(xy 314.37909 -305.257834) (xy 314.405393 -305.216238) (xy 314.438028 -305.179401) (xy 314.476149 -305.148276)
			(xy 314.51877 -305.123669) (xy 314.564786 -305.106217) (xy 314.613005 -305.096373) (xy 314.66218 -305.094392)
			(xy 314.711035 -305.100324) (xy 314.758306 -305.114016) (xy 314.802768 -305.135114) (xy 314.843271 -305.16307)
			(xy 314.878764 -305.197162) (xy 314.908329 -305.236506) (xy 314.9312 -305.280083) (xy 314.946784 -305.326764)
			(xy 314.954679 -305.375341) (xy 314.955174 -305.399948) (xy 314.954679 -305.424555) (xy 314.946784 -305.473132)
			(xy 314.9312 -305.519813) (xy 314.908329 -305.56339) (xy 314.878764 -305.602734) (xy 314.843271 -305.636826)
			(xy 314.802768 -305.664782) (xy 314.758306 -305.68588) (xy 314.711035 -305.699572) (xy 314.66218 -305.705504)
			(xy 314.613005 -305.703523) (xy 314.564786 -305.693679) (xy 314.51877 -305.676227) (xy 314.476149 -305.65162)
			(xy 314.438028 -305.620495) (xy 314.405393 -305.583658) (xy 314.37909 -305.542062) (xy 314.359799 -305.496786)
			(xy 314.348022 -305.449002) (xy 314.344062 -305.399948) (xy 314.005214 -305.399948) (xy 314.004719 -305.424555)
			(xy 313.996824 -305.473132) (xy 313.98124 -305.519813) (xy 313.958369 -305.56339) (xy 313.928804 -305.602734)
			(xy 313.893311 -305.636826) (xy 313.852808 -305.664782) (xy 313.808346 -305.68588) (xy 313.761075 -305.699572)
			(xy 313.71222 -305.705504) (xy 313.663045 -305.703523) (xy 313.614826 -305.693679) (xy 313.56881 -305.676227)
			(xy 313.526189 -305.65162) (xy 313.488068 -305.620495) (xy 313.455433 -305.583658) (xy 313.42913 -305.542062)
			(xy 313.409839 -305.496786) (xy 313.398062 -305.449002) (xy 313.394102 -305.399948) (xy 313.055 -305.399948)
			(xy 313.054505 -305.424555) (xy 313.04661 -305.473132) (xy 313.031026 -305.519813) (xy 313.008155 -305.56339)
			(xy 312.97859 -305.602734) (xy 312.943097 -305.636826) (xy 312.902594 -305.664782) (xy 312.858132 -305.68588)
			(xy 312.810861 -305.699572) (xy 312.762006 -305.705504) (xy 312.712831 -305.703523) (xy 312.664612 -305.693679)
			(xy 312.618596 -305.676227) (xy 312.575975 -305.65162) (xy 312.537854 -305.620495) (xy 312.505219 -305.583658)
			(xy 312.478916 -305.542062) (xy 312.459625 -305.496786) (xy 312.447848 -305.449002) (xy 312.443888 -305.399948)
			(xy 312.10504 -305.399948) (xy 312.104545 -305.424555) (xy 312.09665 -305.473132) (xy 312.081066 -305.519813)
			(xy 312.058195 -305.56339) (xy 312.02863 -305.602734) (xy 311.993137 -305.636826) (xy 311.952634 -305.664782)
			(xy 311.908172 -305.68588) (xy 311.860901 -305.699572) (xy 311.812046 -305.705504) (xy 311.762871 -305.703523)
			(xy 311.714652 -305.693679) (xy 311.668636 -305.676227) (xy 311.626015 -305.65162) (xy 311.587894 -305.620495)
			(xy 311.555259 -305.583658) (xy 311.528956 -305.542062) (xy 311.509665 -305.496786) (xy 311.497888 -305.449002)
			(xy 311.493928 -305.399948) (xy 311.15508 -305.399948) (xy 311.154585 -305.424555) (xy 311.14669 -305.473132)
			(xy 311.131106 -305.519813) (xy 311.108235 -305.56339) (xy 311.07867 -305.602734) (xy 311.043177 -305.636826)
			(xy 311.002674 -305.664782) (xy 310.958212 -305.68588) (xy 310.910941 -305.699572) (xy 310.862086 -305.705504)
			(xy 310.812911 -305.703523) (xy 310.764692 -305.693679) (xy 310.718676 -305.676227) (xy 310.676055 -305.65162)
			(xy 310.637934 -305.620495) (xy 310.605299 -305.583658) (xy 310.578996 -305.542062) (xy 310.559705 -305.496786)
			(xy 310.547928 -305.449002) (xy 310.543968 -305.399948) (xy 310.20512 -305.399948) (xy 310.204625 -305.424555)
			(xy 310.19673 -305.473132) (xy 310.181146 -305.519813) (xy 310.158275 -305.56339) (xy 310.12871 -305.602734)
			(xy 310.093217 -305.636826) (xy 310.052714 -305.664782) (xy 310.008252 -305.68588) (xy 309.960981 -305.699572)
			(xy 309.912126 -305.705504) (xy 309.862951 -305.703523) (xy 309.814732 -305.693679) (xy 309.768716 -305.676227)
			(xy 309.726095 -305.65162) (xy 309.687974 -305.620495) (xy 309.655339 -305.583658) (xy 309.629036 -305.542062)
			(xy 309.609745 -305.496786) (xy 309.597968 -305.449002) (xy 309.594008 -305.399948) (xy 309.25516 -305.399948)
			(xy 309.254665 -305.424555) (xy 309.24677 -305.473132) (xy 309.231186 -305.519813) (xy 309.208315 -305.56339)
			(xy 309.17875 -305.602734) (xy 309.143257 -305.636826) (xy 309.102754 -305.664782) (xy 309.058292 -305.68588)
			(xy 309.011021 -305.699572) (xy 308.962166 -305.705504) (xy 308.912991 -305.703523) (xy 308.864772 -305.693679)
			(xy 308.818756 -305.676227) (xy 308.776135 -305.65162) (xy 308.738014 -305.620495) (xy 308.705379 -305.583658)
			(xy 308.679076 -305.542062) (xy 308.659785 -305.496786) (xy 308.648008 -305.449002) (xy 308.644048 -305.399948)
			(xy 308.3052 -305.399948) (xy 308.304705 -305.424555) (xy 308.29681 -305.473132) (xy 308.281226 -305.519813)
			(xy 308.258355 -305.56339) (xy 308.22879 -305.602734) (xy 308.193297 -305.636826) (xy 308.152794 -305.664782)
			(xy 308.108332 -305.68588) (xy 308.061061 -305.699572) (xy 308.012206 -305.705504) (xy 307.963031 -305.703523)
			(xy 307.914812 -305.693679) (xy 307.868796 -305.676227) (xy 307.826175 -305.65162) (xy 307.788054 -305.620495)
			(xy 307.755419 -305.583658) (xy 307.729116 -305.542062) (xy 307.709825 -305.496786) (xy 307.698048 -305.449002)
			(xy 307.694088 -305.399948) (xy 307.35524 -305.399948) (xy 307.354745 -305.424555) (xy 307.34685 -305.473132)
			(xy 307.331266 -305.519813) (xy 307.308395 -305.56339) (xy 307.27883 -305.602734) (xy 307.243337 -305.636826)
			(xy 307.202834 -305.664782) (xy 307.158372 -305.68588) (xy 307.111101 -305.699572) (xy 307.062246 -305.705504)
			(xy 307.013071 -305.703523) (xy 306.964852 -305.693679) (xy 306.918836 -305.676227) (xy 306.876215 -305.65162)
			(xy 306.838094 -305.620495) (xy 306.805459 -305.583658) (xy 306.779156 -305.542062) (xy 306.759865 -305.496786)
			(xy 306.748088 -305.449002) (xy 306.744128 -305.399948) (xy 306.405026 -305.399948) (xy 306.404531 -305.424555)
			(xy 306.396636 -305.473132) (xy 306.381052 -305.519813) (xy 306.358181 -305.56339) (xy 306.328616 -305.602734)
			(xy 306.293123 -305.636826) (xy 306.25262 -305.664782) (xy 306.208158 -305.68588) (xy 306.160887 -305.699572)
			(xy 306.112032 -305.705504) (xy 306.062857 -305.703523) (xy 306.014638 -305.693679) (xy 305.968622 -305.676227)
			(xy 305.926001 -305.65162) (xy 305.88788 -305.620495) (xy 305.855245 -305.583658) (xy 305.828942 -305.542062)
			(xy 305.809651 -305.496786) (xy 305.797874 -305.449002) (xy 305.793914 -305.399948) (xy 280.268426 -305.399948)
			(xy 280.268426 -305.780186) (xy 280.268934 -305.786282) (xy 280.270204 -305.797458) (xy 280.270966 -305.80076)
			(xy 280.270966 -305.801268) (xy 280.275216 -305.819387) (xy 280.279797 -305.85632) (xy 280.28011 -305.874928)
			(xy 280.618958 -305.874928) (xy 280.622918 -305.825874) (xy 280.634695 -305.77809) (xy 280.653986 -305.732814)
			(xy 280.680289 -305.691218) (xy 280.712924 -305.654381) (xy 280.751045 -305.623256) (xy 280.793666 -305.598649)
			(xy 280.839682 -305.581197) (xy 280.887901 -305.571353) (xy 280.937076 -305.569372) (xy 280.985931 -305.575304)
			(xy 281.033202 -305.588996) (xy 281.077664 -305.610094) (xy 281.118167 -305.63805) (xy 281.15366 -305.672142)
			(xy 281.183225 -305.711486) (xy 281.206096 -305.755063) (xy 281.22168 -305.801744) (xy 281.229575 -305.850321)
			(xy 281.23007 -305.874928) (xy 281.568918 -305.874928) (xy 281.572878 -305.825874) (xy 281.584655 -305.77809)
			(xy 281.603946 -305.732814) (xy 281.630249 -305.691218) (xy 281.662884 -305.654381) (xy 281.701005 -305.623256)
			(xy 281.743626 -305.598649) (xy 281.789642 -305.581197) (xy 281.837861 -305.571353) (xy 281.887036 -305.569372)
			(xy 281.935891 -305.575304) (xy 281.983162 -305.588996) (xy 282.027624 -305.610094) (xy 282.068127 -305.63805)
			(xy 282.10362 -305.672142) (xy 282.133185 -305.711486) (xy 282.156056 -305.755063) (xy 282.17164 -305.801744)
			(xy 282.179535 -305.850321) (xy 282.18003 -305.874928) (xy 282.519132 -305.874928) (xy 282.523092 -305.825874)
			(xy 282.534869 -305.77809) (xy 282.55416 -305.732814) (xy 282.580463 -305.691218) (xy 282.613098 -305.654381)
			(xy 282.651219 -305.623256) (xy 282.69384 -305.598649) (xy 282.739856 -305.581197) (xy 282.788075 -305.571353)
			(xy 282.83725 -305.569372) (xy 282.886105 -305.575304) (xy 282.933376 -305.588996) (xy 282.977838 -305.610094)
			(xy 283.018341 -305.63805) (xy 283.053834 -305.672142) (xy 283.083399 -305.711486) (xy 283.10627 -305.755063)
			(xy 283.121854 -305.801744) (xy 283.129749 -305.850321) (xy 283.130244 -305.874928) (xy 283.469092 -305.874928)
			(xy 283.473052 -305.825874) (xy 283.484829 -305.77809) (xy 283.50412 -305.732814) (xy 283.530423 -305.691218)
			(xy 283.563058 -305.654381) (xy 283.601179 -305.623256) (xy 283.6438 -305.598649) (xy 283.689816 -305.581197)
			(xy 283.738035 -305.571353) (xy 283.78721 -305.569372) (xy 283.836065 -305.575304) (xy 283.883336 -305.588996)
			(xy 283.927798 -305.610094) (xy 283.968301 -305.63805) (xy 284.003794 -305.672142) (xy 284.033359 -305.711486)
			(xy 284.05623 -305.755063) (xy 284.071814 -305.801744) (xy 284.079709 -305.850321) (xy 284.080204 -305.874928)
			(xy 284.419052 -305.874928) (xy 284.423012 -305.825874) (xy 284.434789 -305.77809) (xy 284.45408 -305.732814)
			(xy 284.480383 -305.691218) (xy 284.513018 -305.654381) (xy 284.551139 -305.623256) (xy 284.59376 -305.598649)
			(xy 284.639776 -305.581197) (xy 284.687995 -305.571353) (xy 284.73717 -305.569372) (xy 284.786025 -305.575304)
			(xy 284.833296 -305.588996) (xy 284.877758 -305.610094) (xy 284.918261 -305.63805) (xy 284.953754 -305.672142)
			(xy 284.983319 -305.711486) (xy 285.00619 -305.755063) (xy 285.021774 -305.801744) (xy 285.029669 -305.850321)
			(xy 285.030164 -305.874928) (xy 285.369012 -305.874928) (xy 285.372972 -305.825874) (xy 285.384749 -305.77809)
			(xy 285.40404 -305.732814) (xy 285.430343 -305.691218) (xy 285.462978 -305.654381) (xy 285.501099 -305.623256)
			(xy 285.54372 -305.598649) (xy 285.589736 -305.581197) (xy 285.637955 -305.571353) (xy 285.68713 -305.569372)
			(xy 285.735985 -305.575304) (xy 285.783256 -305.588996) (xy 285.827718 -305.610094) (xy 285.868221 -305.63805)
			(xy 285.903714 -305.672142) (xy 285.933279 -305.711486) (xy 285.95615 -305.755063) (xy 285.971734 -305.801744)
			(xy 285.979629 -305.850321) (xy 285.980124 -305.874928) (xy 286.318972 -305.874928) (xy 286.322932 -305.825874)
			(xy 286.334709 -305.77809) (xy 286.354 -305.732814) (xy 286.380303 -305.691218) (xy 286.412938 -305.654381)
			(xy 286.451059 -305.623256) (xy 286.49368 -305.598649) (xy 286.539696 -305.581197) (xy 286.587915 -305.571353)
			(xy 286.63709 -305.569372) (xy 286.685945 -305.575304) (xy 286.733216 -305.588996) (xy 286.777678 -305.610094)
			(xy 286.818181 -305.63805) (xy 286.853674 -305.672142) (xy 286.883239 -305.711486) (xy 286.90611 -305.755063)
			(xy 286.921694 -305.801744) (xy 286.929589 -305.850321) (xy 286.930084 -305.874928) (xy 287.268932 -305.874928)
			(xy 287.272892 -305.825874) (xy 287.284669 -305.77809) (xy 287.30396 -305.732814) (xy 287.330263 -305.691218)
			(xy 287.362898 -305.654381) (xy 287.401019 -305.623256) (xy 287.44364 -305.598649) (xy 287.489656 -305.581197)
			(xy 287.537875 -305.571353) (xy 287.58705 -305.569372) (xy 287.635905 -305.575304) (xy 287.683176 -305.588996)
			(xy 287.727638 -305.610094) (xy 287.768141 -305.63805) (xy 287.803634 -305.672142) (xy 287.833199 -305.711486)
			(xy 287.85607 -305.755063) (xy 287.871654 -305.801744) (xy 287.879549 -305.850321) (xy 287.880044 -305.874928)
			(xy 288.218892 -305.874928) (xy 288.222852 -305.825874) (xy 288.234629 -305.77809) (xy 288.25392 -305.732814)
			(xy 288.280223 -305.691218) (xy 288.312858 -305.654381) (xy 288.350979 -305.623256) (xy 288.3936 -305.598649)
			(xy 288.439616 -305.581197) (xy 288.487835 -305.571353) (xy 288.53701 -305.569372) (xy 288.585865 -305.575304)
			(xy 288.633136 -305.588996) (xy 288.677598 -305.610094) (xy 288.718101 -305.63805) (xy 288.753594 -305.672142)
			(xy 288.783159 -305.711486) (xy 288.80603 -305.755063) (xy 288.821614 -305.801744) (xy 288.829509 -305.850321)
			(xy 288.830004 -305.874928) (xy 289.169106 -305.874928) (xy 289.173066 -305.825874) (xy 289.184843 -305.77809)
			(xy 289.204134 -305.732814) (xy 289.230437 -305.691218) (xy 289.263072 -305.654381) (xy 289.301193 -305.623256)
			(xy 289.343814 -305.598649) (xy 289.38983 -305.581197) (xy 289.438049 -305.571353) (xy 289.487224 -305.569372)
			(xy 289.536079 -305.575304) (xy 289.58335 -305.588996) (xy 289.627812 -305.610094) (xy 289.668315 -305.63805)
			(xy 289.703808 -305.672142) (xy 289.733373 -305.711486) (xy 289.756244 -305.755063) (xy 289.771828 -305.801744)
			(xy 289.779723 -305.850321) (xy 289.780218 -305.874928) (xy 290.119066 -305.874928) (xy 290.123026 -305.825874)
			(xy 290.134803 -305.77809) (xy 290.154094 -305.732814) (xy 290.180397 -305.691218) (xy 290.213032 -305.654381)
			(xy 290.251153 -305.623256) (xy 290.293774 -305.598649) (xy 290.33979 -305.581197) (xy 290.388009 -305.571353)
			(xy 290.437184 -305.569372) (xy 290.486039 -305.575304) (xy 290.53331 -305.588996) (xy 290.577772 -305.610094)
			(xy 290.618275 -305.63805) (xy 290.653768 -305.672142) (xy 290.683333 -305.711486) (xy 290.706204 -305.755063)
			(xy 290.721788 -305.801744) (xy 290.729683 -305.850321) (xy 290.730178 -305.874928) (xy 292.018986 -305.874928)
			(xy 292.022946 -305.825874) (xy 292.034723 -305.77809) (xy 292.054014 -305.732814) (xy 292.080317 -305.691218)
			(xy 292.112952 -305.654381) (xy 292.151073 -305.623256) (xy 292.193694 -305.598649) (xy 292.23971 -305.581197)
			(xy 292.287929 -305.571353) (xy 292.337104 -305.569372) (xy 292.385959 -305.575304) (xy 292.43323 -305.588996)
			(xy 292.477692 -305.610094) (xy 292.518195 -305.63805) (xy 292.553688 -305.672142) (xy 292.583253 -305.711486)
			(xy 292.606124 -305.755063) (xy 292.621708 -305.801744) (xy 292.629603 -305.850321) (xy 292.630098 -305.874928)
			(xy 292.968946 -305.874928) (xy 292.972906 -305.825874) (xy 292.984683 -305.77809) (xy 293.003974 -305.732814)
			(xy 293.030277 -305.691218) (xy 293.062912 -305.654381) (xy 293.101033 -305.623256) (xy 293.143654 -305.598649)
			(xy 293.18967 -305.581197) (xy 293.237889 -305.571353) (xy 293.287064 -305.569372) (xy 293.335919 -305.575304)
			(xy 293.38319 -305.588996) (xy 293.427652 -305.610094) (xy 293.468155 -305.63805) (xy 293.503648 -305.672142)
			(xy 293.533213 -305.711486) (xy 293.556084 -305.755063) (xy 293.571668 -305.801744) (xy 293.579563 -305.850321)
			(xy 293.580058 -305.874928) (xy 293.918906 -305.874928) (xy 293.922866 -305.825874) (xy 293.934643 -305.77809)
			(xy 293.953934 -305.732814) (xy 293.980237 -305.691218) (xy 294.012872 -305.654381) (xy 294.050993 -305.623256)
			(xy 294.093614 -305.598649) (xy 294.13963 -305.581197) (xy 294.187849 -305.571353) (xy 294.237024 -305.569372)
			(xy 294.285879 -305.575304) (xy 294.33315 -305.588996) (xy 294.377612 -305.610094) (xy 294.418115 -305.63805)
			(xy 294.453608 -305.672142) (xy 294.483173 -305.711486) (xy 294.506044 -305.755063) (xy 294.521628 -305.801744)
			(xy 294.529523 -305.850321) (xy 294.530018 -305.874928) (xy 294.86912 -305.874928) (xy 294.87308 -305.825874)
			(xy 294.884857 -305.77809) (xy 294.904148 -305.732814) (xy 294.930451 -305.691218) (xy 294.963086 -305.654381)
			(xy 295.001207 -305.623256) (xy 295.043828 -305.598649) (xy 295.089844 -305.581197) (xy 295.138063 -305.571353)
			(xy 295.187238 -305.569372) (xy 295.236093 -305.575304) (xy 295.283364 -305.588996) (xy 295.327826 -305.610094)
			(xy 295.368329 -305.63805) (xy 295.403822 -305.672142) (xy 295.433387 -305.711486) (xy 295.456258 -305.755063)
			(xy 295.471842 -305.801744) (xy 295.479737 -305.850321) (xy 295.480232 -305.874928) (xy 295.81908 -305.874928)
			(xy 295.82304 -305.825874) (xy 295.834817 -305.77809) (xy 295.854108 -305.732814) (xy 295.880411 -305.691218)
			(xy 295.913046 -305.654381) (xy 295.951167 -305.623256) (xy 295.993788 -305.598649) (xy 296.039804 -305.581197)
			(xy 296.088023 -305.571353) (xy 296.137198 -305.569372) (xy 296.186053 -305.575304) (xy 296.233324 -305.588996)
			(xy 296.277786 -305.610094) (xy 296.318289 -305.63805) (xy 296.353782 -305.672142) (xy 296.383347 -305.711486)
			(xy 296.406218 -305.755063) (xy 296.421802 -305.801744) (xy 296.429697 -305.850321) (xy 296.430192 -305.874928)
			(xy 296.76904 -305.874928) (xy 296.773 -305.825874) (xy 296.784777 -305.77809) (xy 296.804068 -305.732814)
			(xy 296.830371 -305.691218) (xy 296.863006 -305.654381) (xy 296.901127 -305.623256) (xy 296.943748 -305.598649)
			(xy 296.989764 -305.581197) (xy 297.037983 -305.571353) (xy 297.087158 -305.569372) (xy 297.136013 -305.575304)
			(xy 297.183284 -305.588996) (xy 297.227746 -305.610094) (xy 297.268249 -305.63805) (xy 297.303742 -305.672142)
			(xy 297.333307 -305.711486) (xy 297.356178 -305.755063) (xy 297.371762 -305.801744) (xy 297.379657 -305.850321)
			(xy 297.380152 -305.874928) (xy 297.719 -305.874928) (xy 297.72296 -305.825874) (xy 297.734737 -305.77809)
			(xy 297.754028 -305.732814) (xy 297.780331 -305.691218) (xy 297.812966 -305.654381) (xy 297.851087 -305.623256)
			(xy 297.893708 -305.598649) (xy 297.939724 -305.581197) (xy 297.987943 -305.571353) (xy 298.037118 -305.569372)
			(xy 298.085973 -305.575304) (xy 298.133244 -305.588996) (xy 298.177706 -305.610094) (xy 298.218209 -305.63805)
			(xy 298.253702 -305.672142) (xy 298.283267 -305.711486) (xy 298.306138 -305.755063) (xy 298.321722 -305.801744)
			(xy 298.329617 -305.850321) (xy 298.330112 -305.874928) (xy 298.66896 -305.874928) (xy 298.67292 -305.825874)
			(xy 298.684697 -305.77809) (xy 298.703988 -305.732814) (xy 298.730291 -305.691218) (xy 298.762926 -305.654381)
			(xy 298.801047 -305.623256) (xy 298.843668 -305.598649) (xy 298.889684 -305.581197) (xy 298.937903 -305.571353)
			(xy 298.987078 -305.569372) (xy 299.035933 -305.575304) (xy 299.083204 -305.588996) (xy 299.127666 -305.610094)
			(xy 299.168169 -305.63805) (xy 299.203662 -305.672142) (xy 299.233227 -305.711486) (xy 299.256098 -305.755063)
			(xy 299.271682 -305.801744) (xy 299.279577 -305.850321) (xy 299.280072 -305.874928) (xy 299.61892 -305.874928)
			(xy 299.62288 -305.825874) (xy 299.634657 -305.77809) (xy 299.653948 -305.732814) (xy 299.680251 -305.691218)
			(xy 299.712886 -305.654381) (xy 299.751007 -305.623256) (xy 299.793628 -305.598649) (xy 299.839644 -305.581197)
			(xy 299.887863 -305.571353) (xy 299.937038 -305.569372) (xy 299.985893 -305.575304) (xy 300.033164 -305.588996)
			(xy 300.077626 -305.610094) (xy 300.118129 -305.63805) (xy 300.153622 -305.672142) (xy 300.183187 -305.711486)
			(xy 300.206058 -305.755063) (xy 300.221642 -305.801744) (xy 300.229537 -305.850321) (xy 300.230032 -305.874928)
			(xy 300.56888 -305.874928) (xy 300.57284 -305.825874) (xy 300.584617 -305.77809) (xy 300.603908 -305.732814)
			(xy 300.630211 -305.691218) (xy 300.662846 -305.654381) (xy 300.700967 -305.623256) (xy 300.743588 -305.598649)
			(xy 300.789604 -305.581197) (xy 300.837823 -305.571353) (xy 300.886998 -305.569372) (xy 300.935853 -305.575304)
			(xy 300.983124 -305.588996) (xy 301.027586 -305.610094) (xy 301.068089 -305.63805) (xy 301.103582 -305.672142)
			(xy 301.133147 -305.711486) (xy 301.156018 -305.755063) (xy 301.171602 -305.801744) (xy 301.179497 -305.850321)
			(xy 301.179992 -305.874928) (xy 301.519094 -305.874928) (xy 301.523054 -305.825874) (xy 301.534831 -305.77809)
			(xy 301.554122 -305.732814) (xy 301.580425 -305.691218) (xy 301.61306 -305.654381) (xy 301.651181 -305.623256)
			(xy 301.693802 -305.598649) (xy 301.739818 -305.581197) (xy 301.788037 -305.571353) (xy 301.837212 -305.569372)
			(xy 301.886067 -305.575304) (xy 301.933338 -305.588996) (xy 301.9778 -305.610094) (xy 302.018303 -305.63805)
			(xy 302.053796 -305.672142) (xy 302.083361 -305.711486) (xy 302.106232 -305.755063) (xy 302.121816 -305.801744)
			(xy 302.129711 -305.850321) (xy 302.130206 -305.874928) (xy 302.469054 -305.874928) (xy 302.473014 -305.825874)
			(xy 302.484791 -305.77809) (xy 302.504082 -305.732814) (xy 302.530385 -305.691218) (xy 302.56302 -305.654381)
			(xy 302.601141 -305.623256) (xy 302.643762 -305.598649) (xy 302.689778 -305.581197) (xy 302.737997 -305.571353)
			(xy 302.787172 -305.569372) (xy 302.836027 -305.575304) (xy 302.883298 -305.588996) (xy 302.92776 -305.610094)
			(xy 302.968263 -305.63805) (xy 303.003756 -305.672142) (xy 303.033321 -305.711486) (xy 303.056192 -305.755063)
			(xy 303.071776 -305.801744) (xy 303.079671 -305.850321) (xy 303.080166 -305.874928) (xy 303.419014 -305.874928)
			(xy 303.422974 -305.825874) (xy 303.434751 -305.77809) (xy 303.454042 -305.732814) (xy 303.480345 -305.691218)
			(xy 303.51298 -305.654381) (xy 303.551101 -305.623256) (xy 303.593722 -305.598649) (xy 303.639738 -305.581197)
			(xy 303.687957 -305.571353) (xy 303.737132 -305.569372) (xy 303.785987 -305.575304) (xy 303.833258 -305.588996)
			(xy 303.87772 -305.610094) (xy 303.918223 -305.63805) (xy 303.953716 -305.672142) (xy 303.983281 -305.711486)
			(xy 304.006152 -305.755063) (xy 304.021736 -305.801744) (xy 304.029631 -305.850321) (xy 304.030126 -305.874928)
			(xy 304.368974 -305.874928) (xy 304.372934 -305.825874) (xy 304.384711 -305.77809) (xy 304.404002 -305.732814)
			(xy 304.430305 -305.691218) (xy 304.46294 -305.654381) (xy 304.501061 -305.623256) (xy 304.543682 -305.598649)
			(xy 304.589698 -305.581197) (xy 304.637917 -305.571353) (xy 304.687092 -305.569372) (xy 304.735947 -305.575304)
			(xy 304.783218 -305.588996) (xy 304.82768 -305.610094) (xy 304.868183 -305.63805) (xy 304.903676 -305.672142)
			(xy 304.933241 -305.711486) (xy 304.956112 -305.755063) (xy 304.971696 -305.801744) (xy 304.979591 -305.850321)
			(xy 304.980086 -305.874928) (xy 304.979591 -305.899535) (xy 304.971696 -305.948112) (xy 304.956112 -305.994793)
			(xy 304.933241 -306.03837) (xy 304.903676 -306.077714) (xy 304.868183 -306.111806) (xy 304.82768 -306.139762)
			(xy 304.783218 -306.16086) (xy 304.735947 -306.174552) (xy 304.687092 -306.180484) (xy 304.637917 -306.178503)
			(xy 304.589698 -306.168659) (xy 304.543682 -306.151207) (xy 304.501061 -306.1266) (xy 304.46294 -306.095475)
			(xy 304.430305 -306.058638) (xy 304.404002 -306.017042) (xy 304.384711 -305.971766) (xy 304.372934 -305.923982)
			(xy 304.368974 -305.874928) (xy 304.030126 -305.874928) (xy 304.029631 -305.899535) (xy 304.021736 -305.948112)
			(xy 304.006152 -305.994793) (xy 303.983281 -306.03837) (xy 303.953716 -306.077714) (xy 303.918223 -306.111806)
			(xy 303.87772 -306.139762) (xy 303.833258 -306.16086) (xy 303.785987 -306.174552) (xy 303.737132 -306.180484)
			(xy 303.687957 -306.178503) (xy 303.639738 -306.168659) (xy 303.593722 -306.151207) (xy 303.551101 -306.1266)
			(xy 303.51298 -306.095475) (xy 303.480345 -306.058638) (xy 303.454042 -306.017042) (xy 303.434751 -305.971766)
			(xy 303.422974 -305.923982) (xy 303.419014 -305.874928) (xy 303.080166 -305.874928) (xy 303.079671 -305.899535)
			(xy 303.071776 -305.948112) (xy 303.056192 -305.994793) (xy 303.033321 -306.03837) (xy 303.003756 -306.077714)
			(xy 302.968263 -306.111806) (xy 302.92776 -306.139762) (xy 302.883298 -306.16086) (xy 302.836027 -306.174552)
			(xy 302.787172 -306.180484) (xy 302.737997 -306.178503) (xy 302.689778 -306.168659) (xy 302.643762 -306.151207)
			(xy 302.601141 -306.1266) (xy 302.56302 -306.095475) (xy 302.530385 -306.058638) (xy 302.504082 -306.017042)
			(xy 302.484791 -305.971766) (xy 302.473014 -305.923982) (xy 302.469054 -305.874928) (xy 302.130206 -305.874928)
			(xy 302.129711 -305.899535) (xy 302.121816 -305.948112) (xy 302.106232 -305.994793) (xy 302.083361 -306.03837)
			(xy 302.053796 -306.077714) (xy 302.018303 -306.111806) (xy 301.9778 -306.139762) (xy 301.933338 -306.16086)
			(xy 301.886067 -306.174552) (xy 301.837212 -306.180484) (xy 301.788037 -306.178503) (xy 301.739818 -306.168659)
			(xy 301.693802 -306.151207) (xy 301.651181 -306.1266) (xy 301.61306 -306.095475) (xy 301.580425 -306.058638)
			(xy 301.554122 -306.017042) (xy 301.534831 -305.971766) (xy 301.523054 -305.923982) (xy 301.519094 -305.874928)
			(xy 301.179992 -305.874928) (xy 301.179497 -305.899535) (xy 301.171602 -305.948112) (xy 301.156018 -305.994793)
			(xy 301.133147 -306.03837) (xy 301.103582 -306.077714) (xy 301.068089 -306.111806) (xy 301.027586 -306.139762)
			(xy 300.983124 -306.16086) (xy 300.935853 -306.174552) (xy 300.886998 -306.180484) (xy 300.837823 -306.178503)
			(xy 300.789604 -306.168659) (xy 300.743588 -306.151207) (xy 300.700967 -306.1266) (xy 300.662846 -306.095475)
			(xy 300.630211 -306.058638) (xy 300.603908 -306.017042) (xy 300.584617 -305.971766) (xy 300.57284 -305.923982)
			(xy 300.56888 -305.874928) (xy 300.230032 -305.874928) (xy 300.229537 -305.899535) (xy 300.221642 -305.948112)
			(xy 300.206058 -305.994793) (xy 300.183187 -306.03837) (xy 300.153622 -306.077714) (xy 300.118129 -306.111806)
			(xy 300.077626 -306.139762) (xy 300.033164 -306.16086) (xy 299.985893 -306.174552) (xy 299.937038 -306.180484)
			(xy 299.887863 -306.178503) (xy 299.839644 -306.168659) (xy 299.793628 -306.151207) (xy 299.751007 -306.1266)
			(xy 299.712886 -306.095475) (xy 299.680251 -306.058638) (xy 299.653948 -306.017042) (xy 299.634657 -305.971766)
			(xy 299.62288 -305.923982) (xy 299.61892 -305.874928) (xy 299.280072 -305.874928) (xy 299.279577 -305.899535)
			(xy 299.271682 -305.948112) (xy 299.256098 -305.994793) (xy 299.233227 -306.03837) (xy 299.203662 -306.077714)
			(xy 299.168169 -306.111806) (xy 299.127666 -306.139762) (xy 299.083204 -306.16086) (xy 299.035933 -306.174552)
			(xy 298.987078 -306.180484) (xy 298.937903 -306.178503) (xy 298.889684 -306.168659) (xy 298.843668 -306.151207)
			(xy 298.801047 -306.1266) (xy 298.762926 -306.095475) (xy 298.730291 -306.058638) (xy 298.703988 -306.017042)
			(xy 298.684697 -305.971766) (xy 298.67292 -305.923982) (xy 298.66896 -305.874928) (xy 298.330112 -305.874928)
			(xy 298.329617 -305.899535) (xy 298.321722 -305.948112) (xy 298.306138 -305.994793) (xy 298.283267 -306.03837)
			(xy 298.253702 -306.077714) (xy 298.218209 -306.111806) (xy 298.177706 -306.139762) (xy 298.133244 -306.16086)
			(xy 298.085973 -306.174552) (xy 298.037118 -306.180484) (xy 297.987943 -306.178503) (xy 297.939724 -306.168659)
			(xy 297.893708 -306.151207) (xy 297.851087 -306.1266) (xy 297.812966 -306.095475) (xy 297.780331 -306.058638)
			(xy 297.754028 -306.017042) (xy 297.734737 -305.971766) (xy 297.72296 -305.923982) (xy 297.719 -305.874928)
			(xy 297.380152 -305.874928) (xy 297.379657 -305.899535) (xy 297.371762 -305.948112) (xy 297.356178 -305.994793)
			(xy 297.333307 -306.03837) (xy 297.303742 -306.077714) (xy 297.268249 -306.111806) (xy 297.227746 -306.139762)
			(xy 297.183284 -306.16086) (xy 297.136013 -306.174552) (xy 297.087158 -306.180484) (xy 297.037983 -306.178503)
			(xy 296.989764 -306.168659) (xy 296.943748 -306.151207) (xy 296.901127 -306.1266) (xy 296.863006 -306.095475)
			(xy 296.830371 -306.058638) (xy 296.804068 -306.017042) (xy 296.784777 -305.971766) (xy 296.773 -305.923982)
			(xy 296.76904 -305.874928) (xy 296.430192 -305.874928) (xy 296.429697 -305.899535) (xy 296.421802 -305.948112)
			(xy 296.406218 -305.994793) (xy 296.383347 -306.03837) (xy 296.353782 -306.077714) (xy 296.318289 -306.111806)
			(xy 296.277786 -306.139762) (xy 296.233324 -306.16086) (xy 296.186053 -306.174552) (xy 296.137198 -306.180484)
			(xy 296.088023 -306.178503) (xy 296.039804 -306.168659) (xy 295.993788 -306.151207) (xy 295.951167 -306.1266)
			(xy 295.913046 -306.095475) (xy 295.880411 -306.058638) (xy 295.854108 -306.017042) (xy 295.834817 -305.971766)
			(xy 295.82304 -305.923982) (xy 295.81908 -305.874928) (xy 295.480232 -305.874928) (xy 295.479737 -305.899535)
			(xy 295.471842 -305.948112) (xy 295.456258 -305.994793) (xy 295.433387 -306.03837) (xy 295.403822 -306.077714)
			(xy 295.368329 -306.111806) (xy 295.327826 -306.139762) (xy 295.283364 -306.16086) (xy 295.236093 -306.174552)
			(xy 295.187238 -306.180484) (xy 295.138063 -306.178503) (xy 295.089844 -306.168659) (xy 295.043828 -306.151207)
			(xy 295.001207 -306.1266) (xy 294.963086 -306.095475) (xy 294.930451 -306.058638) (xy 294.904148 -306.017042)
			(xy 294.884857 -305.971766) (xy 294.87308 -305.923982) (xy 294.86912 -305.874928) (xy 294.530018 -305.874928)
			(xy 294.529523 -305.899535) (xy 294.521628 -305.948112) (xy 294.506044 -305.994793) (xy 294.483173 -306.03837)
			(xy 294.453608 -306.077714) (xy 294.418115 -306.111806) (xy 294.377612 -306.139762) (xy 294.33315 -306.16086)
			(xy 294.285879 -306.174552) (xy 294.237024 -306.180484) (xy 294.187849 -306.178503) (xy 294.13963 -306.168659)
			(xy 294.093614 -306.151207) (xy 294.050993 -306.1266) (xy 294.012872 -306.095475) (xy 293.980237 -306.058638)
			(xy 293.953934 -306.017042) (xy 293.934643 -305.971766) (xy 293.922866 -305.923982) (xy 293.918906 -305.874928)
			(xy 293.580058 -305.874928) (xy 293.579563 -305.899535) (xy 293.571668 -305.948112) (xy 293.556084 -305.994793)
			(xy 293.533213 -306.03837) (xy 293.503648 -306.077714) (xy 293.468155 -306.111806) (xy 293.427652 -306.139762)
			(xy 293.38319 -306.16086) (xy 293.335919 -306.174552) (xy 293.287064 -306.180484) (xy 293.237889 -306.178503)
			(xy 293.18967 -306.168659) (xy 293.143654 -306.151207) (xy 293.101033 -306.1266) (xy 293.062912 -306.095475)
			(xy 293.030277 -306.058638) (xy 293.003974 -306.017042) (xy 292.984683 -305.971766) (xy 292.972906 -305.923982)
			(xy 292.968946 -305.874928) (xy 292.630098 -305.874928) (xy 292.629603 -305.899535) (xy 292.621708 -305.948112)
			(xy 292.606124 -305.994793) (xy 292.583253 -306.03837) (xy 292.553688 -306.077714) (xy 292.518195 -306.111806)
			(xy 292.477692 -306.139762) (xy 292.43323 -306.16086) (xy 292.385959 -306.174552) (xy 292.337104 -306.180484)
			(xy 292.287929 -306.178503) (xy 292.23971 -306.168659) (xy 292.193694 -306.151207) (xy 292.151073 -306.1266)
			(xy 292.112952 -306.095475) (xy 292.080317 -306.058638) (xy 292.054014 -306.017042) (xy 292.034723 -305.971766)
			(xy 292.022946 -305.923982) (xy 292.018986 -305.874928) (xy 290.730178 -305.874928) (xy 290.729683 -305.899535)
			(xy 290.721788 -305.948112) (xy 290.706204 -305.994793) (xy 290.683333 -306.03837) (xy 290.653768 -306.077714)
			(xy 290.618275 -306.111806) (xy 290.577772 -306.139762) (xy 290.53331 -306.16086) (xy 290.486039 -306.174552)
			(xy 290.437184 -306.180484) (xy 290.388009 -306.178503) (xy 290.33979 -306.168659) (xy 290.293774 -306.151207)
			(xy 290.251153 -306.1266) (xy 290.213032 -306.095475) (xy 290.180397 -306.058638) (xy 290.154094 -306.017042)
			(xy 290.134803 -305.971766) (xy 290.123026 -305.923982) (xy 290.119066 -305.874928) (xy 289.780218 -305.874928)
			(xy 289.779723 -305.899535) (xy 289.771828 -305.948112) (xy 289.756244 -305.994793) (xy 289.733373 -306.03837)
			(xy 289.703808 -306.077714) (xy 289.668315 -306.111806) (xy 289.627812 -306.139762) (xy 289.58335 -306.16086)
			(xy 289.536079 -306.174552) (xy 289.487224 -306.180484) (xy 289.438049 -306.178503) (xy 289.38983 -306.168659)
			(xy 289.343814 -306.151207) (xy 289.301193 -306.1266) (xy 289.263072 -306.095475) (xy 289.230437 -306.058638)
			(xy 289.204134 -306.017042) (xy 289.184843 -305.971766) (xy 289.173066 -305.923982) (xy 289.169106 -305.874928)
			(xy 288.830004 -305.874928) (xy 288.829509 -305.899535) (xy 288.821614 -305.948112) (xy 288.80603 -305.994793)
			(xy 288.783159 -306.03837) (xy 288.753594 -306.077714) (xy 288.718101 -306.111806) (xy 288.677598 -306.139762)
			(xy 288.633136 -306.16086) (xy 288.585865 -306.174552) (xy 288.53701 -306.180484) (xy 288.487835 -306.178503)
			(xy 288.439616 -306.168659) (xy 288.3936 -306.151207) (xy 288.350979 -306.1266) (xy 288.312858 -306.095475)
			(xy 288.280223 -306.058638) (xy 288.25392 -306.017042) (xy 288.234629 -305.971766) (xy 288.222852 -305.923982)
			(xy 288.218892 -305.874928) (xy 287.880044 -305.874928) (xy 287.879549 -305.899535) (xy 287.871654 -305.948112)
			(xy 287.85607 -305.994793) (xy 287.833199 -306.03837) (xy 287.803634 -306.077714) (xy 287.768141 -306.111806)
			(xy 287.727638 -306.139762) (xy 287.683176 -306.16086) (xy 287.635905 -306.174552) (xy 287.58705 -306.180484)
			(xy 287.537875 -306.178503) (xy 287.489656 -306.168659) (xy 287.44364 -306.151207) (xy 287.401019 -306.1266)
			(xy 287.362898 -306.095475) (xy 287.330263 -306.058638) (xy 287.30396 -306.017042) (xy 287.284669 -305.971766)
			(xy 287.272892 -305.923982) (xy 287.268932 -305.874928) (xy 286.930084 -305.874928) (xy 286.929589 -305.899535)
			(xy 286.921694 -305.948112) (xy 286.90611 -305.994793) (xy 286.883239 -306.03837) (xy 286.853674 -306.077714)
			(xy 286.818181 -306.111806) (xy 286.777678 -306.139762) (xy 286.733216 -306.16086) (xy 286.685945 -306.174552)
			(xy 286.63709 -306.180484) (xy 286.587915 -306.178503) (xy 286.539696 -306.168659) (xy 286.49368 -306.151207)
			(xy 286.451059 -306.1266) (xy 286.412938 -306.095475) (xy 286.380303 -306.058638) (xy 286.354 -306.017042)
			(xy 286.334709 -305.971766) (xy 286.322932 -305.923982) (xy 286.318972 -305.874928) (xy 285.980124 -305.874928)
			(xy 285.979629 -305.899535) (xy 285.971734 -305.948112) (xy 285.95615 -305.994793) (xy 285.933279 -306.03837)
			(xy 285.903714 -306.077714) (xy 285.868221 -306.111806) (xy 285.827718 -306.139762) (xy 285.783256 -306.16086)
			(xy 285.735985 -306.174552) (xy 285.68713 -306.180484) (xy 285.637955 -306.178503) (xy 285.589736 -306.168659)
			(xy 285.54372 -306.151207) (xy 285.501099 -306.1266) (xy 285.462978 -306.095475) (xy 285.430343 -306.058638)
			(xy 285.40404 -306.017042) (xy 285.384749 -305.971766) (xy 285.372972 -305.923982) (xy 285.369012 -305.874928)
			(xy 285.030164 -305.874928) (xy 285.029669 -305.899535) (xy 285.021774 -305.948112) (xy 285.00619 -305.994793)
			(xy 284.983319 -306.03837) (xy 284.953754 -306.077714) (xy 284.918261 -306.111806) (xy 284.877758 -306.139762)
			(xy 284.833296 -306.16086) (xy 284.786025 -306.174552) (xy 284.73717 -306.180484) (xy 284.687995 -306.178503)
			(xy 284.639776 -306.168659) (xy 284.59376 -306.151207) (xy 284.551139 -306.1266) (xy 284.513018 -306.095475)
			(xy 284.480383 -306.058638) (xy 284.45408 -306.017042) (xy 284.434789 -305.971766) (xy 284.423012 -305.923982)
			(xy 284.419052 -305.874928) (xy 284.080204 -305.874928) (xy 284.079709 -305.899535) (xy 284.071814 -305.948112)
			(xy 284.05623 -305.994793) (xy 284.033359 -306.03837) (xy 284.003794 -306.077714) (xy 283.968301 -306.111806)
			(xy 283.927798 -306.139762) (xy 283.883336 -306.16086) (xy 283.836065 -306.174552) (xy 283.78721 -306.180484)
			(xy 283.738035 -306.178503) (xy 283.689816 -306.168659) (xy 283.6438 -306.151207) (xy 283.601179 -306.1266)
			(xy 283.563058 -306.095475) (xy 283.530423 -306.058638) (xy 283.50412 -306.017042) (xy 283.484829 -305.971766)
			(xy 283.473052 -305.923982) (xy 283.469092 -305.874928) (xy 283.130244 -305.874928) (xy 283.129749 -305.899535)
			(xy 283.121854 -305.948112) (xy 283.10627 -305.994793) (xy 283.083399 -306.03837) (xy 283.053834 -306.077714)
			(xy 283.018341 -306.111806) (xy 282.977838 -306.139762) (xy 282.933376 -306.16086) (xy 282.886105 -306.174552)
			(xy 282.83725 -306.180484) (xy 282.788075 -306.178503) (xy 282.739856 -306.168659) (xy 282.69384 -306.151207)
			(xy 282.651219 -306.1266) (xy 282.613098 -306.095475) (xy 282.580463 -306.058638) (xy 282.55416 -306.017042)
			(xy 282.534869 -305.971766) (xy 282.523092 -305.923982) (xy 282.519132 -305.874928) (xy 282.18003 -305.874928)
			(xy 282.179535 -305.899535) (xy 282.17164 -305.948112) (xy 282.156056 -305.994793) (xy 282.133185 -306.03837)
			(xy 282.10362 -306.077714) (xy 282.068127 -306.111806) (xy 282.027624 -306.139762) (xy 281.983162 -306.16086)
			(xy 281.935891 -306.174552) (xy 281.887036 -306.180484) (xy 281.837861 -306.178503) (xy 281.789642 -306.168659)
			(xy 281.743626 -306.151207) (xy 281.701005 -306.1266) (xy 281.662884 -306.095475) (xy 281.630249 -306.058638)
			(xy 281.603946 -306.017042) (xy 281.584655 -305.971766) (xy 281.572878 -305.923982) (xy 281.568918 -305.874928)
			(xy 281.23007 -305.874928) (xy 281.229575 -305.899535) (xy 281.22168 -305.948112) (xy 281.206096 -305.994793)
			(xy 281.183225 -306.03837) (xy 281.15366 -306.077714) (xy 281.118167 -306.111806) (xy 281.077664 -306.139762)
			(xy 281.033202 -306.16086) (xy 280.985931 -306.174552) (xy 280.937076 -306.180484) (xy 280.887901 -306.178503)
			(xy 280.839682 -306.168659) (xy 280.793666 -306.151207) (xy 280.751045 -306.1266) (xy 280.712924 -306.095475)
			(xy 280.680289 -306.058638) (xy 280.653986 -306.017042) (xy 280.634695 -305.971766) (xy 280.622918 -305.923982)
			(xy 280.618958 -305.874928) (xy 280.28011 -305.874928) (xy 280.28011 -305.891438) (xy 280.279602 -305.89728)
			(xy 280.279602 -305.897788) (xy 280.278332 -305.90871) (xy 280.278332 -305.908964) (xy 280.277824 -305.913028)
			(xy 280.275284 -305.931824) (xy 280.274268 -305.937412) (xy 280.270204 -305.95316) (xy 280.268426 -305.96586)
			(xy 280.268426 -306.349908) (xy 305.793914 -306.349908) (xy 305.797874 -306.300854) (xy 305.809651 -306.25307)
			(xy 305.828942 -306.207794) (xy 305.855245 -306.166198) (xy 305.88788 -306.129361) (xy 305.926001 -306.098236)
			(xy 305.968622 -306.073629) (xy 306.014638 -306.056177) (xy 306.062857 -306.046333) (xy 306.112032 -306.044352)
			(xy 306.160887 -306.050284) (xy 306.208158 -306.063976) (xy 306.25262 -306.085074) (xy 306.293123 -306.11303)
			(xy 306.328616 -306.147122) (xy 306.358181 -306.186466) (xy 306.381052 -306.230043) (xy 306.396636 -306.276724)
			(xy 306.404531 -306.325301) (xy 306.405026 -306.349908) (xy 306.744128 -306.349908) (xy 306.748088 -306.300854)
			(xy 306.759865 -306.25307) (xy 306.779156 -306.207794) (xy 306.805459 -306.166198) (xy 306.838094 -306.129361)
			(xy 306.876215 -306.098236) (xy 306.918836 -306.073629) (xy 306.964852 -306.056177) (xy 307.013071 -306.046333)
			(xy 307.062246 -306.044352) (xy 307.111101 -306.050284) (xy 307.158372 -306.063976) (xy 307.202834 -306.085074)
			(xy 307.243337 -306.11303) (xy 307.27883 -306.147122) (xy 307.308395 -306.186466) (xy 307.331266 -306.230043)
			(xy 307.34685 -306.276724) (xy 307.354745 -306.325301) (xy 307.35524 -306.349908) (xy 307.694088 -306.349908)
			(xy 307.698048 -306.300854) (xy 307.709825 -306.25307) (xy 307.729116 -306.207794) (xy 307.755419 -306.166198)
			(xy 307.788054 -306.129361) (xy 307.826175 -306.098236) (xy 307.868796 -306.073629) (xy 307.914812 -306.056177)
			(xy 307.963031 -306.046333) (xy 308.012206 -306.044352) (xy 308.061061 -306.050284) (xy 308.108332 -306.063976)
			(xy 308.152794 -306.085074) (xy 308.193297 -306.11303) (xy 308.22879 -306.147122) (xy 308.258355 -306.186466)
			(xy 308.281226 -306.230043) (xy 308.29681 -306.276724) (xy 308.304705 -306.325301) (xy 308.3052 -306.349908)
			(xy 308.644048 -306.349908) (xy 308.648008 -306.300854) (xy 308.659785 -306.25307) (xy 308.679076 -306.207794)
			(xy 308.705379 -306.166198) (xy 308.738014 -306.129361) (xy 308.776135 -306.098236) (xy 308.818756 -306.073629)
			(xy 308.864772 -306.056177) (xy 308.912991 -306.046333) (xy 308.962166 -306.044352) (xy 309.011021 -306.050284)
			(xy 309.058292 -306.063976) (xy 309.102754 -306.085074) (xy 309.143257 -306.11303) (xy 309.17875 -306.147122)
			(xy 309.208315 -306.186466) (xy 309.231186 -306.230043) (xy 309.24677 -306.276724) (xy 309.254665 -306.325301)
			(xy 309.25516 -306.349908) (xy 309.594008 -306.349908) (xy 309.597968 -306.300854) (xy 309.609745 -306.25307)
			(xy 309.629036 -306.207794) (xy 309.655339 -306.166198) (xy 309.687974 -306.129361) (xy 309.726095 -306.098236)
			(xy 309.768716 -306.073629) (xy 309.814732 -306.056177) (xy 309.862951 -306.046333) (xy 309.912126 -306.044352)
			(xy 309.960981 -306.050284) (xy 310.008252 -306.063976) (xy 310.052714 -306.085074) (xy 310.093217 -306.11303)
			(xy 310.12871 -306.147122) (xy 310.158275 -306.186466) (xy 310.181146 -306.230043) (xy 310.19673 -306.276724)
			(xy 310.204625 -306.325301) (xy 310.20512 -306.349908) (xy 310.543968 -306.349908) (xy 310.547928 -306.300854)
			(xy 310.559705 -306.25307) (xy 310.578996 -306.207794) (xy 310.605299 -306.166198) (xy 310.637934 -306.129361)
			(xy 310.676055 -306.098236) (xy 310.718676 -306.073629) (xy 310.764692 -306.056177) (xy 310.812911 -306.046333)
			(xy 310.862086 -306.044352) (xy 310.910941 -306.050284) (xy 310.958212 -306.063976) (xy 311.002674 -306.085074)
			(xy 311.043177 -306.11303) (xy 311.07867 -306.147122) (xy 311.108235 -306.186466) (xy 311.131106 -306.230043)
			(xy 311.14669 -306.276724) (xy 311.154585 -306.325301) (xy 311.15508 -306.349908) (xy 311.493928 -306.349908)
			(xy 311.497888 -306.300854) (xy 311.509665 -306.25307) (xy 311.528956 -306.207794) (xy 311.555259 -306.166198)
			(xy 311.587894 -306.129361) (xy 311.626015 -306.098236) (xy 311.668636 -306.073629) (xy 311.714652 -306.056177)
			(xy 311.762871 -306.046333) (xy 311.812046 -306.044352) (xy 311.860901 -306.050284) (xy 311.908172 -306.063976)
			(xy 311.952634 -306.085074) (xy 311.993137 -306.11303) (xy 312.02863 -306.147122) (xy 312.058195 -306.186466)
			(xy 312.081066 -306.230043) (xy 312.09665 -306.276724) (xy 312.104545 -306.325301) (xy 312.10504 -306.349908)
			(xy 312.443888 -306.349908) (xy 312.447848 -306.300854) (xy 312.459625 -306.25307) (xy 312.478916 -306.207794)
			(xy 312.505219 -306.166198) (xy 312.537854 -306.129361) (xy 312.575975 -306.098236) (xy 312.618596 -306.073629)
			(xy 312.664612 -306.056177) (xy 312.712831 -306.046333) (xy 312.762006 -306.044352) (xy 312.810861 -306.050284)
			(xy 312.858132 -306.063976) (xy 312.902594 -306.085074) (xy 312.943097 -306.11303) (xy 312.97859 -306.147122)
			(xy 313.008155 -306.186466) (xy 313.031026 -306.230043) (xy 313.04661 -306.276724) (xy 313.054505 -306.325301)
			(xy 313.055 -306.349908) (xy 313.394102 -306.349908) (xy 313.398062 -306.300854) (xy 313.409839 -306.25307)
			(xy 313.42913 -306.207794) (xy 313.455433 -306.166198) (xy 313.488068 -306.129361) (xy 313.526189 -306.098236)
			(xy 313.56881 -306.073629) (xy 313.614826 -306.056177) (xy 313.663045 -306.046333) (xy 313.71222 -306.044352)
			(xy 313.761075 -306.050284) (xy 313.808346 -306.063976) (xy 313.852808 -306.085074) (xy 313.893311 -306.11303)
			(xy 313.928804 -306.147122) (xy 313.958369 -306.186466) (xy 313.98124 -306.230043) (xy 313.996824 -306.276724)
			(xy 314.004719 -306.325301) (xy 314.005214 -306.349908) (xy 314.344062 -306.349908) (xy 314.348022 -306.300854)
			(xy 314.359799 -306.25307) (xy 314.37909 -306.207794) (xy 314.405393 -306.166198) (xy 314.438028 -306.129361)
			(xy 314.476149 -306.098236) (xy 314.51877 -306.073629) (xy 314.564786 -306.056177) (xy 314.613005 -306.046333)
			(xy 314.66218 -306.044352) (xy 314.711035 -306.050284) (xy 314.758306 -306.063976) (xy 314.802768 -306.085074)
			(xy 314.843271 -306.11303) (xy 314.878764 -306.147122) (xy 314.908329 -306.186466) (xy 314.9312 -306.230043)
			(xy 314.946784 -306.276724) (xy 314.954679 -306.325301) (xy 314.955174 -306.349908) (xy 315.294276 -306.349908)
			(xy 315.298236 -306.300854) (xy 315.310013 -306.25307) (xy 315.329304 -306.207794) (xy 315.355607 -306.166198)
			(xy 315.388242 -306.129361) (xy 315.426363 -306.098236) (xy 315.468984 -306.073629) (xy 315.515 -306.056177)
			(xy 315.563219 -306.046333) (xy 315.612394 -306.044352) (xy 315.661249 -306.050284) (xy 315.70852 -306.063976)
			(xy 315.752982 -306.085074) (xy 315.793485 -306.11303) (xy 315.828978 -306.147122) (xy 315.858543 -306.186466)
			(xy 315.881414 -306.230043) (xy 315.896998 -306.276724) (xy 315.904893 -306.325301) (xy 315.905388 -306.349908)
			(xy 315.904893 -306.374515) (xy 315.896998 -306.423092) (xy 315.881414 -306.469773) (xy 315.858543 -306.51335)
			(xy 315.828978 -306.552694) (xy 315.793485 -306.586786) (xy 315.752982 -306.614742) (xy 315.70852 -306.63584)
			(xy 315.661249 -306.649532) (xy 315.612394 -306.655464) (xy 315.563219 -306.653483) (xy 315.515 -306.643639)
			(xy 315.468984 -306.626187) (xy 315.426363 -306.60158) (xy 315.388242 -306.570455) (xy 315.355607 -306.533618)
			(xy 315.329304 -306.492022) (xy 315.310013 -306.446746) (xy 315.298236 -306.398962) (xy 315.294276 -306.349908)
			(xy 314.955174 -306.349908) (xy 314.954679 -306.374515) (xy 314.946784 -306.423092) (xy 314.9312 -306.469773)
			(xy 314.908329 -306.51335) (xy 314.878764 -306.552694) (xy 314.843271 -306.586786) (xy 314.802768 -306.614742)
			(xy 314.758306 -306.63584) (xy 314.711035 -306.649532) (xy 314.66218 -306.655464) (xy 314.613005 -306.653483)
			(xy 314.564786 -306.643639) (xy 314.51877 -306.626187) (xy 314.476149 -306.60158) (xy 314.438028 -306.570455)
			(xy 314.405393 -306.533618) (xy 314.37909 -306.492022) (xy 314.359799 -306.446746) (xy 314.348022 -306.398962)
			(xy 314.344062 -306.349908) (xy 314.005214 -306.349908) (xy 314.004719 -306.374515) (xy 313.996824 -306.423092)
			(xy 313.98124 -306.469773) (xy 313.958369 -306.51335) (xy 313.928804 -306.552694) (xy 313.893311 -306.586786)
			(xy 313.852808 -306.614742) (xy 313.808346 -306.63584) (xy 313.761075 -306.649532) (xy 313.71222 -306.655464)
			(xy 313.663045 -306.653483) (xy 313.614826 -306.643639) (xy 313.56881 -306.626187) (xy 313.526189 -306.60158)
			(xy 313.488068 -306.570455) (xy 313.455433 -306.533618) (xy 313.42913 -306.492022) (xy 313.409839 -306.446746)
			(xy 313.398062 -306.398962) (xy 313.394102 -306.349908) (xy 313.055 -306.349908) (xy 313.054505 -306.374515)
			(xy 313.04661 -306.423092) (xy 313.031026 -306.469773) (xy 313.008155 -306.51335) (xy 312.97859 -306.552694)
			(xy 312.943097 -306.586786) (xy 312.902594 -306.614742) (xy 312.858132 -306.63584) (xy 312.810861 -306.649532)
			(xy 312.762006 -306.655464) (xy 312.712831 -306.653483) (xy 312.664612 -306.643639) (xy 312.618596 -306.626187)
			(xy 312.575975 -306.60158) (xy 312.537854 -306.570455) (xy 312.505219 -306.533618) (xy 312.478916 -306.492022)
			(xy 312.459625 -306.446746) (xy 312.447848 -306.398962) (xy 312.443888 -306.349908) (xy 312.10504 -306.349908)
			(xy 312.104545 -306.374515) (xy 312.09665 -306.423092) (xy 312.081066 -306.469773) (xy 312.058195 -306.51335)
			(xy 312.02863 -306.552694) (xy 311.993137 -306.586786) (xy 311.952634 -306.614742) (xy 311.908172 -306.63584)
			(xy 311.860901 -306.649532) (xy 311.812046 -306.655464) (xy 311.762871 -306.653483) (xy 311.714652 -306.643639)
			(xy 311.668636 -306.626187) (xy 311.626015 -306.60158) (xy 311.587894 -306.570455) (xy 311.555259 -306.533618)
			(xy 311.528956 -306.492022) (xy 311.509665 -306.446746) (xy 311.497888 -306.398962) (xy 311.493928 -306.349908)
			(xy 311.15508 -306.349908) (xy 311.154585 -306.374515) (xy 311.14669 -306.423092) (xy 311.131106 -306.469773)
			(xy 311.108235 -306.51335) (xy 311.07867 -306.552694) (xy 311.043177 -306.586786) (xy 311.002674 -306.614742)
			(xy 310.958212 -306.63584) (xy 310.910941 -306.649532) (xy 310.862086 -306.655464) (xy 310.812911 -306.653483)
			(xy 310.764692 -306.643639) (xy 310.718676 -306.626187) (xy 310.676055 -306.60158) (xy 310.637934 -306.570455)
			(xy 310.605299 -306.533618) (xy 310.578996 -306.492022) (xy 310.559705 -306.446746) (xy 310.547928 -306.398962)
			(xy 310.543968 -306.349908) (xy 310.20512 -306.349908) (xy 310.204625 -306.374515) (xy 310.19673 -306.423092)
			(xy 310.181146 -306.469773) (xy 310.158275 -306.51335) (xy 310.12871 -306.552694) (xy 310.093217 -306.586786)
			(xy 310.052714 -306.614742) (xy 310.008252 -306.63584) (xy 309.960981 -306.649532) (xy 309.912126 -306.655464)
			(xy 309.862951 -306.653483) (xy 309.814732 -306.643639) (xy 309.768716 -306.626187) (xy 309.726095 -306.60158)
			(xy 309.687974 -306.570455) (xy 309.655339 -306.533618) (xy 309.629036 -306.492022) (xy 309.609745 -306.446746)
			(xy 309.597968 -306.398962) (xy 309.594008 -306.349908) (xy 309.25516 -306.349908) (xy 309.254665 -306.374515)
			(xy 309.24677 -306.423092) (xy 309.231186 -306.469773) (xy 309.208315 -306.51335) (xy 309.17875 -306.552694)
			(xy 309.143257 -306.586786) (xy 309.102754 -306.614742) (xy 309.058292 -306.63584) (xy 309.011021 -306.649532)
			(xy 308.962166 -306.655464) (xy 308.912991 -306.653483) (xy 308.864772 -306.643639) (xy 308.818756 -306.626187)
			(xy 308.776135 -306.60158) (xy 308.738014 -306.570455) (xy 308.705379 -306.533618) (xy 308.679076 -306.492022)
			(xy 308.659785 -306.446746) (xy 308.648008 -306.398962) (xy 308.644048 -306.349908) (xy 308.3052 -306.349908)
			(xy 308.304705 -306.374515) (xy 308.29681 -306.423092) (xy 308.281226 -306.469773) (xy 308.258355 -306.51335)
			(xy 308.22879 -306.552694) (xy 308.193297 -306.586786) (xy 308.152794 -306.614742) (xy 308.108332 -306.63584)
			(xy 308.061061 -306.649532) (xy 308.012206 -306.655464) (xy 307.963031 -306.653483) (xy 307.914812 -306.643639)
			(xy 307.868796 -306.626187) (xy 307.826175 -306.60158) (xy 307.788054 -306.570455) (xy 307.755419 -306.533618)
			(xy 307.729116 -306.492022) (xy 307.709825 -306.446746) (xy 307.698048 -306.398962) (xy 307.694088 -306.349908)
			(xy 307.35524 -306.349908) (xy 307.354745 -306.374515) (xy 307.34685 -306.423092) (xy 307.331266 -306.469773)
			(xy 307.308395 -306.51335) (xy 307.27883 -306.552694) (xy 307.243337 -306.586786) (xy 307.202834 -306.614742)
			(xy 307.158372 -306.63584) (xy 307.111101 -306.649532) (xy 307.062246 -306.655464) (xy 307.013071 -306.653483)
			(xy 306.964852 -306.643639) (xy 306.918836 -306.626187) (xy 306.876215 -306.60158) (xy 306.838094 -306.570455)
			(xy 306.805459 -306.533618) (xy 306.779156 -306.492022) (xy 306.759865 -306.446746) (xy 306.748088 -306.398962)
			(xy 306.744128 -306.349908) (xy 306.405026 -306.349908) (xy 306.404531 -306.374515) (xy 306.396636 -306.423092)
			(xy 306.381052 -306.469773) (xy 306.358181 -306.51335) (xy 306.328616 -306.552694) (xy 306.293123 -306.586786)
			(xy 306.25262 -306.614742) (xy 306.208158 -306.63584) (xy 306.160887 -306.649532) (xy 306.112032 -306.655464)
			(xy 306.062857 -306.653483) (xy 306.014638 -306.643639) (xy 305.968622 -306.626187) (xy 305.926001 -306.60158)
			(xy 305.88788 -306.570455) (xy 305.855245 -306.533618) (xy 305.828942 -306.492022) (xy 305.809651 -306.446746)
			(xy 305.797874 -306.398962) (xy 305.793914 -306.349908) (xy 280.268426 -306.349908) (xy 280.268426 -306.730146)
			(xy 280.268934 -306.736242) (xy 280.270204 -306.747418) (xy 280.270966 -306.75072) (xy 280.270966 -306.751228)
			(xy 280.275218 -306.769346) (xy 280.279804 -306.80628) (xy 280.28011 -306.824888) (xy 280.618958 -306.824888)
			(xy 280.622918 -306.775834) (xy 280.634695 -306.72805) (xy 280.653986 -306.682774) (xy 280.680289 -306.641178)
			(xy 280.712924 -306.604341) (xy 280.751045 -306.573216) (xy 280.793666 -306.548609) (xy 280.839682 -306.531157)
			(xy 280.887901 -306.521313) (xy 280.937076 -306.519332) (xy 280.985931 -306.525264) (xy 281.033202 -306.538956)
			(xy 281.077664 -306.560054) (xy 281.118167 -306.58801) (xy 281.15366 -306.622102) (xy 281.183225 -306.661446)
			(xy 281.206096 -306.705023) (xy 281.22168 -306.751704) (xy 281.229575 -306.800281) (xy 281.23007 -306.824888)
			(xy 281.568918 -306.824888) (xy 281.572878 -306.775834) (xy 281.584655 -306.72805) (xy 281.603946 -306.682774)
			(xy 281.630249 -306.641178) (xy 281.662884 -306.604341) (xy 281.701005 -306.573216) (xy 281.743626 -306.548609)
			(xy 281.789642 -306.531157) (xy 281.837861 -306.521313) (xy 281.887036 -306.519332) (xy 281.935891 -306.525264)
			(xy 281.983162 -306.538956) (xy 282.027624 -306.560054) (xy 282.068127 -306.58801) (xy 282.10362 -306.622102)
			(xy 282.133185 -306.661446) (xy 282.156056 -306.705023) (xy 282.17164 -306.751704) (xy 282.179535 -306.800281)
			(xy 282.18003 -306.824888) (xy 282.519132 -306.824888) (xy 282.523092 -306.775834) (xy 282.534869 -306.72805)
			(xy 282.55416 -306.682774) (xy 282.580463 -306.641178) (xy 282.613098 -306.604341) (xy 282.651219 -306.573216)
			(xy 282.69384 -306.548609) (xy 282.739856 -306.531157) (xy 282.788075 -306.521313) (xy 282.83725 -306.519332)
			(xy 282.886105 -306.525264) (xy 282.933376 -306.538956) (xy 282.977838 -306.560054) (xy 283.018341 -306.58801)
			(xy 283.053834 -306.622102) (xy 283.083399 -306.661446) (xy 283.10627 -306.705023) (xy 283.121854 -306.751704)
			(xy 283.129749 -306.800281) (xy 283.130244 -306.824888) (xy 283.469092 -306.824888) (xy 283.473052 -306.775834)
			(xy 283.484829 -306.72805) (xy 283.50412 -306.682774) (xy 283.530423 -306.641178) (xy 283.563058 -306.604341)
			(xy 283.601179 -306.573216) (xy 283.6438 -306.548609) (xy 283.689816 -306.531157) (xy 283.738035 -306.521313)
			(xy 283.78721 -306.519332) (xy 283.836065 -306.525264) (xy 283.883336 -306.538956) (xy 283.927798 -306.560054)
			(xy 283.968301 -306.58801) (xy 284.003794 -306.622102) (xy 284.033359 -306.661446) (xy 284.05623 -306.705023)
			(xy 284.071814 -306.751704) (xy 284.079709 -306.800281) (xy 284.080204 -306.824888) (xy 284.419052 -306.824888)
			(xy 284.423012 -306.775834) (xy 284.434789 -306.72805) (xy 284.45408 -306.682774) (xy 284.480383 -306.641178)
			(xy 284.513018 -306.604341) (xy 284.551139 -306.573216) (xy 284.59376 -306.548609) (xy 284.639776 -306.531157)
			(xy 284.687995 -306.521313) (xy 284.73717 -306.519332) (xy 284.786025 -306.525264) (xy 284.833296 -306.538956)
			(xy 284.877758 -306.560054) (xy 284.918261 -306.58801) (xy 284.953754 -306.622102) (xy 284.983319 -306.661446)
			(xy 285.00619 -306.705023) (xy 285.021774 -306.751704) (xy 285.029669 -306.800281) (xy 285.030164 -306.824888)
			(xy 285.369012 -306.824888) (xy 285.372972 -306.775834) (xy 285.384749 -306.72805) (xy 285.40404 -306.682774)
			(xy 285.430343 -306.641178) (xy 285.462978 -306.604341) (xy 285.501099 -306.573216) (xy 285.54372 -306.548609)
			(xy 285.589736 -306.531157) (xy 285.637955 -306.521313) (xy 285.68713 -306.519332) (xy 285.735985 -306.525264)
			(xy 285.783256 -306.538956) (xy 285.827718 -306.560054) (xy 285.868221 -306.58801) (xy 285.903714 -306.622102)
			(xy 285.933279 -306.661446) (xy 285.95615 -306.705023) (xy 285.971734 -306.751704) (xy 285.979629 -306.800281)
			(xy 285.980124 -306.824888) (xy 286.318972 -306.824888) (xy 286.322932 -306.775834) (xy 286.334709 -306.72805)
			(xy 286.354 -306.682774) (xy 286.380303 -306.641178) (xy 286.412938 -306.604341) (xy 286.451059 -306.573216)
			(xy 286.49368 -306.548609) (xy 286.539696 -306.531157) (xy 286.587915 -306.521313) (xy 286.63709 -306.519332)
			(xy 286.685945 -306.525264) (xy 286.733216 -306.538956) (xy 286.777678 -306.560054) (xy 286.818181 -306.58801)
			(xy 286.853674 -306.622102) (xy 286.883239 -306.661446) (xy 286.90611 -306.705023) (xy 286.921694 -306.751704)
			(xy 286.929589 -306.800281) (xy 286.930084 -306.824888) (xy 287.268932 -306.824888) (xy 287.272892 -306.775834)
			(xy 287.284669 -306.72805) (xy 287.30396 -306.682774) (xy 287.330263 -306.641178) (xy 287.362898 -306.604341)
			(xy 287.401019 -306.573216) (xy 287.44364 -306.548609) (xy 287.489656 -306.531157) (xy 287.537875 -306.521313)
			(xy 287.58705 -306.519332) (xy 287.635905 -306.525264) (xy 287.683176 -306.538956) (xy 287.727638 -306.560054)
			(xy 287.768141 -306.58801) (xy 287.803634 -306.622102) (xy 287.833199 -306.661446) (xy 287.85607 -306.705023)
			(xy 287.871654 -306.751704) (xy 287.879549 -306.800281) (xy 287.880044 -306.824888) (xy 288.218892 -306.824888)
			(xy 288.222852 -306.775834) (xy 288.234629 -306.72805) (xy 288.25392 -306.682774) (xy 288.280223 -306.641178)
			(xy 288.312858 -306.604341) (xy 288.350979 -306.573216) (xy 288.3936 -306.548609) (xy 288.439616 -306.531157)
			(xy 288.487835 -306.521313) (xy 288.53701 -306.519332) (xy 288.585865 -306.525264) (xy 288.633136 -306.538956)
			(xy 288.677598 -306.560054) (xy 288.718101 -306.58801) (xy 288.753594 -306.622102) (xy 288.783159 -306.661446)
			(xy 288.80603 -306.705023) (xy 288.821614 -306.751704) (xy 288.829509 -306.800281) (xy 288.830004 -306.824888)
			(xy 289.169106 -306.824888) (xy 289.173066 -306.775834) (xy 289.184843 -306.72805) (xy 289.204134 -306.682774)
			(xy 289.230437 -306.641178) (xy 289.263072 -306.604341) (xy 289.301193 -306.573216) (xy 289.343814 -306.548609)
			(xy 289.38983 -306.531157) (xy 289.438049 -306.521313) (xy 289.487224 -306.519332) (xy 289.536079 -306.525264)
			(xy 289.58335 -306.538956) (xy 289.627812 -306.560054) (xy 289.668315 -306.58801) (xy 289.703808 -306.622102)
			(xy 289.733373 -306.661446) (xy 289.756244 -306.705023) (xy 289.771828 -306.751704) (xy 289.779723 -306.800281)
			(xy 289.780218 -306.824888) (xy 290.119066 -306.824888) (xy 290.123026 -306.775834) (xy 290.134803 -306.72805)
			(xy 290.154094 -306.682774) (xy 290.180397 -306.641178) (xy 290.213032 -306.604341) (xy 290.251153 -306.573216)
			(xy 290.293774 -306.548609) (xy 290.33979 -306.531157) (xy 290.388009 -306.521313) (xy 290.437184 -306.519332)
			(xy 290.486039 -306.525264) (xy 290.53331 -306.538956) (xy 290.577772 -306.560054) (xy 290.618275 -306.58801)
			(xy 290.653768 -306.622102) (xy 290.683333 -306.661446) (xy 290.706204 -306.705023) (xy 290.721788 -306.751704)
			(xy 290.729683 -306.800281) (xy 290.730178 -306.824888) (xy 292.018986 -306.824888) (xy 292.022946 -306.775834)
			(xy 292.034723 -306.72805) (xy 292.054014 -306.682774) (xy 292.080317 -306.641178) (xy 292.112952 -306.604341)
			(xy 292.151073 -306.573216) (xy 292.193694 -306.548609) (xy 292.23971 -306.531157) (xy 292.287929 -306.521313)
			(xy 292.337104 -306.519332) (xy 292.385959 -306.525264) (xy 292.43323 -306.538956) (xy 292.477692 -306.560054)
			(xy 292.518195 -306.58801) (xy 292.553688 -306.622102) (xy 292.583253 -306.661446) (xy 292.606124 -306.705023)
			(xy 292.621708 -306.751704) (xy 292.629603 -306.800281) (xy 292.630098 -306.824888) (xy 292.968946 -306.824888)
			(xy 292.972906 -306.775834) (xy 292.984683 -306.72805) (xy 293.003974 -306.682774) (xy 293.030277 -306.641178)
			(xy 293.062912 -306.604341) (xy 293.101033 -306.573216) (xy 293.143654 -306.548609) (xy 293.18967 -306.531157)
			(xy 293.237889 -306.521313) (xy 293.287064 -306.519332) (xy 293.335919 -306.525264) (xy 293.38319 -306.538956)
			(xy 293.427652 -306.560054) (xy 293.468155 -306.58801) (xy 293.503648 -306.622102) (xy 293.533213 -306.661446)
			(xy 293.556084 -306.705023) (xy 293.571668 -306.751704) (xy 293.579563 -306.800281) (xy 293.580058 -306.824888)
			(xy 293.918906 -306.824888) (xy 293.922866 -306.775834) (xy 293.934643 -306.72805) (xy 293.953934 -306.682774)
			(xy 293.980237 -306.641178) (xy 294.012872 -306.604341) (xy 294.050993 -306.573216) (xy 294.093614 -306.548609)
			(xy 294.13963 -306.531157) (xy 294.187849 -306.521313) (xy 294.237024 -306.519332) (xy 294.285879 -306.525264)
			(xy 294.33315 -306.538956) (xy 294.377612 -306.560054) (xy 294.418115 -306.58801) (xy 294.453608 -306.622102)
			(xy 294.483173 -306.661446) (xy 294.506044 -306.705023) (xy 294.521628 -306.751704) (xy 294.529523 -306.800281)
			(xy 294.530018 -306.824888) (xy 294.86912 -306.824888) (xy 294.87308 -306.775834) (xy 294.884857 -306.72805)
			(xy 294.904148 -306.682774) (xy 294.930451 -306.641178) (xy 294.963086 -306.604341) (xy 295.001207 -306.573216)
			(xy 295.043828 -306.548609) (xy 295.089844 -306.531157) (xy 295.138063 -306.521313) (xy 295.187238 -306.519332)
			(xy 295.236093 -306.525264) (xy 295.283364 -306.538956) (xy 295.327826 -306.560054) (xy 295.368329 -306.58801)
			(xy 295.403822 -306.622102) (xy 295.433387 -306.661446) (xy 295.456258 -306.705023) (xy 295.471842 -306.751704)
			(xy 295.479737 -306.800281) (xy 295.480232 -306.824888) (xy 295.81908 -306.824888) (xy 295.82304 -306.775834)
			(xy 295.834817 -306.72805) (xy 295.854108 -306.682774) (xy 295.880411 -306.641178) (xy 295.913046 -306.604341)
			(xy 295.951167 -306.573216) (xy 295.993788 -306.548609) (xy 296.039804 -306.531157) (xy 296.088023 -306.521313)
			(xy 296.137198 -306.519332) (xy 296.186053 -306.525264) (xy 296.233324 -306.538956) (xy 296.277786 -306.560054)
			(xy 296.318289 -306.58801) (xy 296.353782 -306.622102) (xy 296.383347 -306.661446) (xy 296.406218 -306.705023)
			(xy 296.421802 -306.751704) (xy 296.429697 -306.800281) (xy 296.430192 -306.824888) (xy 296.76904 -306.824888)
			(xy 296.773 -306.775834) (xy 296.784777 -306.72805) (xy 296.804068 -306.682774) (xy 296.830371 -306.641178)
			(xy 296.863006 -306.604341) (xy 296.901127 -306.573216) (xy 296.943748 -306.548609) (xy 296.989764 -306.531157)
			(xy 297.037983 -306.521313) (xy 297.087158 -306.519332) (xy 297.136013 -306.525264) (xy 297.183284 -306.538956)
			(xy 297.227746 -306.560054) (xy 297.268249 -306.58801) (xy 297.303742 -306.622102) (xy 297.333307 -306.661446)
			(xy 297.356178 -306.705023) (xy 297.371762 -306.751704) (xy 297.379657 -306.800281) (xy 297.380152 -306.824888)
			(xy 297.719 -306.824888) (xy 297.72296 -306.775834) (xy 297.734737 -306.72805) (xy 297.754028 -306.682774)
			(xy 297.780331 -306.641178) (xy 297.812966 -306.604341) (xy 297.851087 -306.573216) (xy 297.893708 -306.548609)
			(xy 297.939724 -306.531157) (xy 297.987943 -306.521313) (xy 298.037118 -306.519332) (xy 298.085973 -306.525264)
			(xy 298.133244 -306.538956) (xy 298.177706 -306.560054) (xy 298.218209 -306.58801) (xy 298.253702 -306.622102)
			(xy 298.283267 -306.661446) (xy 298.306138 -306.705023) (xy 298.321722 -306.751704) (xy 298.329617 -306.800281)
			(xy 298.330112 -306.824888) (xy 298.66896 -306.824888) (xy 298.67292 -306.775834) (xy 298.684697 -306.72805)
			(xy 298.703988 -306.682774) (xy 298.730291 -306.641178) (xy 298.762926 -306.604341) (xy 298.801047 -306.573216)
			(xy 298.843668 -306.548609) (xy 298.889684 -306.531157) (xy 298.937903 -306.521313) (xy 298.987078 -306.519332)
			(xy 299.035933 -306.525264) (xy 299.083204 -306.538956) (xy 299.127666 -306.560054) (xy 299.168169 -306.58801)
			(xy 299.203662 -306.622102) (xy 299.233227 -306.661446) (xy 299.256098 -306.705023) (xy 299.271682 -306.751704)
			(xy 299.279577 -306.800281) (xy 299.280072 -306.824888) (xy 299.61892 -306.824888) (xy 299.62288 -306.775834)
			(xy 299.634657 -306.72805) (xy 299.653948 -306.682774) (xy 299.680251 -306.641178) (xy 299.712886 -306.604341)
			(xy 299.751007 -306.573216) (xy 299.793628 -306.548609) (xy 299.839644 -306.531157) (xy 299.887863 -306.521313)
			(xy 299.937038 -306.519332) (xy 299.985893 -306.525264) (xy 300.033164 -306.538956) (xy 300.077626 -306.560054)
			(xy 300.118129 -306.58801) (xy 300.153622 -306.622102) (xy 300.183187 -306.661446) (xy 300.206058 -306.705023)
			(xy 300.221642 -306.751704) (xy 300.229537 -306.800281) (xy 300.230032 -306.824888) (xy 300.56888 -306.824888)
			(xy 300.57284 -306.775834) (xy 300.584617 -306.72805) (xy 300.603908 -306.682774) (xy 300.630211 -306.641178)
			(xy 300.662846 -306.604341) (xy 300.700967 -306.573216) (xy 300.743588 -306.548609) (xy 300.789604 -306.531157)
			(xy 300.837823 -306.521313) (xy 300.886998 -306.519332) (xy 300.935853 -306.525264) (xy 300.983124 -306.538956)
			(xy 301.027586 -306.560054) (xy 301.068089 -306.58801) (xy 301.103582 -306.622102) (xy 301.133147 -306.661446)
			(xy 301.156018 -306.705023) (xy 301.171602 -306.751704) (xy 301.179497 -306.800281) (xy 301.179992 -306.824888)
			(xy 301.519094 -306.824888) (xy 301.523054 -306.775834) (xy 301.534831 -306.72805) (xy 301.554122 -306.682774)
			(xy 301.580425 -306.641178) (xy 301.61306 -306.604341) (xy 301.651181 -306.573216) (xy 301.693802 -306.548609)
			(xy 301.739818 -306.531157) (xy 301.788037 -306.521313) (xy 301.837212 -306.519332) (xy 301.886067 -306.525264)
			(xy 301.933338 -306.538956) (xy 301.9778 -306.560054) (xy 302.018303 -306.58801) (xy 302.053796 -306.622102)
			(xy 302.083361 -306.661446) (xy 302.106232 -306.705023) (xy 302.121816 -306.751704) (xy 302.129711 -306.800281)
			(xy 302.130206 -306.824888) (xy 302.469054 -306.824888) (xy 302.473014 -306.775834) (xy 302.484791 -306.72805)
			(xy 302.504082 -306.682774) (xy 302.530385 -306.641178) (xy 302.56302 -306.604341) (xy 302.601141 -306.573216)
			(xy 302.643762 -306.548609) (xy 302.689778 -306.531157) (xy 302.737997 -306.521313) (xy 302.787172 -306.519332)
			(xy 302.836027 -306.525264) (xy 302.883298 -306.538956) (xy 302.92776 -306.560054) (xy 302.968263 -306.58801)
			(xy 303.003756 -306.622102) (xy 303.033321 -306.661446) (xy 303.056192 -306.705023) (xy 303.071776 -306.751704)
			(xy 303.079671 -306.800281) (xy 303.080166 -306.824888) (xy 303.419014 -306.824888) (xy 303.422974 -306.775834)
			(xy 303.434751 -306.72805) (xy 303.454042 -306.682774) (xy 303.480345 -306.641178) (xy 303.51298 -306.604341)
			(xy 303.551101 -306.573216) (xy 303.593722 -306.548609) (xy 303.639738 -306.531157) (xy 303.687957 -306.521313)
			(xy 303.737132 -306.519332) (xy 303.785987 -306.525264) (xy 303.833258 -306.538956) (xy 303.87772 -306.560054)
			(xy 303.918223 -306.58801) (xy 303.953716 -306.622102) (xy 303.983281 -306.661446) (xy 304.006152 -306.705023)
			(xy 304.021736 -306.751704) (xy 304.029631 -306.800281) (xy 304.030126 -306.824888) (xy 304.368974 -306.824888)
			(xy 304.372934 -306.775834) (xy 304.384711 -306.72805) (xy 304.404002 -306.682774) (xy 304.430305 -306.641178)
			(xy 304.46294 -306.604341) (xy 304.501061 -306.573216) (xy 304.543682 -306.548609) (xy 304.589698 -306.531157)
			(xy 304.637917 -306.521313) (xy 304.687092 -306.519332) (xy 304.735947 -306.525264) (xy 304.783218 -306.538956)
			(xy 304.82768 -306.560054) (xy 304.868183 -306.58801) (xy 304.903676 -306.622102) (xy 304.933241 -306.661446)
			(xy 304.956112 -306.705023) (xy 304.971696 -306.751704) (xy 304.979591 -306.800281) (xy 304.980086 -306.824888)
			(xy 304.979591 -306.849495) (xy 304.971696 -306.898072) (xy 304.956112 -306.944753) (xy 304.933241 -306.98833)
			(xy 304.903676 -307.027674) (xy 304.868183 -307.061766) (xy 304.82768 -307.089722) (xy 304.783218 -307.11082)
			(xy 304.735947 -307.124512) (xy 304.687092 -307.130444) (xy 304.637917 -307.128463) (xy 304.589698 -307.118619)
			(xy 304.543682 -307.101167) (xy 304.501061 -307.07656) (xy 304.46294 -307.045435) (xy 304.430305 -307.008598)
			(xy 304.404002 -306.967002) (xy 304.384711 -306.921726) (xy 304.372934 -306.873942) (xy 304.368974 -306.824888)
			(xy 304.030126 -306.824888) (xy 304.029631 -306.849495) (xy 304.021736 -306.898072) (xy 304.006152 -306.944753)
			(xy 303.983281 -306.98833) (xy 303.953716 -307.027674) (xy 303.918223 -307.061766) (xy 303.87772 -307.089722)
			(xy 303.833258 -307.11082) (xy 303.785987 -307.124512) (xy 303.737132 -307.130444) (xy 303.687957 -307.128463)
			(xy 303.639738 -307.118619) (xy 303.593722 -307.101167) (xy 303.551101 -307.07656) (xy 303.51298 -307.045435)
			(xy 303.480345 -307.008598) (xy 303.454042 -306.967002) (xy 303.434751 -306.921726) (xy 303.422974 -306.873942)
			(xy 303.419014 -306.824888) (xy 303.080166 -306.824888) (xy 303.079671 -306.849495) (xy 303.071776 -306.898072)
			(xy 303.056192 -306.944753) (xy 303.033321 -306.98833) (xy 303.003756 -307.027674) (xy 302.968263 -307.061766)
			(xy 302.92776 -307.089722) (xy 302.883298 -307.11082) (xy 302.836027 -307.124512) (xy 302.787172 -307.130444)
			(xy 302.737997 -307.128463) (xy 302.689778 -307.118619) (xy 302.643762 -307.101167) (xy 302.601141 -307.07656)
			(xy 302.56302 -307.045435) (xy 302.530385 -307.008598) (xy 302.504082 -306.967002) (xy 302.484791 -306.921726)
			(xy 302.473014 -306.873942) (xy 302.469054 -306.824888) (xy 302.130206 -306.824888) (xy 302.129711 -306.849495)
			(xy 302.121816 -306.898072) (xy 302.106232 -306.944753) (xy 302.083361 -306.98833) (xy 302.053796 -307.027674)
			(xy 302.018303 -307.061766) (xy 301.9778 -307.089722) (xy 301.933338 -307.11082) (xy 301.886067 -307.124512)
			(xy 301.837212 -307.130444) (xy 301.788037 -307.128463) (xy 301.739818 -307.118619) (xy 301.693802 -307.101167)
			(xy 301.651181 -307.07656) (xy 301.61306 -307.045435) (xy 301.580425 -307.008598) (xy 301.554122 -306.967002)
			(xy 301.534831 -306.921726) (xy 301.523054 -306.873942) (xy 301.519094 -306.824888) (xy 301.179992 -306.824888)
			(xy 301.179497 -306.849495) (xy 301.171602 -306.898072) (xy 301.156018 -306.944753) (xy 301.133147 -306.98833)
			(xy 301.103582 -307.027674) (xy 301.068089 -307.061766) (xy 301.027586 -307.089722) (xy 300.983124 -307.11082)
			(xy 300.935853 -307.124512) (xy 300.886998 -307.130444) (xy 300.837823 -307.128463) (xy 300.789604 -307.118619)
			(xy 300.743588 -307.101167) (xy 300.700967 -307.07656) (xy 300.662846 -307.045435) (xy 300.630211 -307.008598)
			(xy 300.603908 -306.967002) (xy 300.584617 -306.921726) (xy 300.57284 -306.873942) (xy 300.56888 -306.824888)
			(xy 300.230032 -306.824888) (xy 300.229537 -306.849495) (xy 300.221642 -306.898072) (xy 300.206058 -306.944753)
			(xy 300.183187 -306.98833) (xy 300.153622 -307.027674) (xy 300.118129 -307.061766) (xy 300.077626 -307.089722)
			(xy 300.033164 -307.11082) (xy 299.985893 -307.124512) (xy 299.937038 -307.130444) (xy 299.887863 -307.128463)
			(xy 299.839644 -307.118619) (xy 299.793628 -307.101167) (xy 299.751007 -307.07656) (xy 299.712886 -307.045435)
			(xy 299.680251 -307.008598) (xy 299.653948 -306.967002) (xy 299.634657 -306.921726) (xy 299.62288 -306.873942)
			(xy 299.61892 -306.824888) (xy 299.280072 -306.824888) (xy 299.279577 -306.849495) (xy 299.271682 -306.898072)
			(xy 299.256098 -306.944753) (xy 299.233227 -306.98833) (xy 299.203662 -307.027674) (xy 299.168169 -307.061766)
			(xy 299.127666 -307.089722) (xy 299.083204 -307.11082) (xy 299.035933 -307.124512) (xy 298.987078 -307.130444)
			(xy 298.937903 -307.128463) (xy 298.889684 -307.118619) (xy 298.843668 -307.101167) (xy 298.801047 -307.07656)
			(xy 298.762926 -307.045435) (xy 298.730291 -307.008598) (xy 298.703988 -306.967002) (xy 298.684697 -306.921726)
			(xy 298.67292 -306.873942) (xy 298.66896 -306.824888) (xy 298.330112 -306.824888) (xy 298.329617 -306.849495)
			(xy 298.321722 -306.898072) (xy 298.306138 -306.944753) (xy 298.283267 -306.98833) (xy 298.253702 -307.027674)
			(xy 298.218209 -307.061766) (xy 298.177706 -307.089722) (xy 298.133244 -307.11082) (xy 298.085973 -307.124512)
			(xy 298.037118 -307.130444) (xy 297.987943 -307.128463) (xy 297.939724 -307.118619) (xy 297.893708 -307.101167)
			(xy 297.851087 -307.07656) (xy 297.812966 -307.045435) (xy 297.780331 -307.008598) (xy 297.754028 -306.967002)
			(xy 297.734737 -306.921726) (xy 297.72296 -306.873942) (xy 297.719 -306.824888) (xy 297.380152 -306.824888)
			(xy 297.379657 -306.849495) (xy 297.371762 -306.898072) (xy 297.356178 -306.944753) (xy 297.333307 -306.98833)
			(xy 297.303742 -307.027674) (xy 297.268249 -307.061766) (xy 297.227746 -307.089722) (xy 297.183284 -307.11082)
			(xy 297.136013 -307.124512) (xy 297.087158 -307.130444) (xy 297.037983 -307.128463) (xy 296.989764 -307.118619)
			(xy 296.943748 -307.101167) (xy 296.901127 -307.07656) (xy 296.863006 -307.045435) (xy 296.830371 -307.008598)
			(xy 296.804068 -306.967002) (xy 296.784777 -306.921726) (xy 296.773 -306.873942) (xy 296.76904 -306.824888)
			(xy 296.430192 -306.824888) (xy 296.429697 -306.849495) (xy 296.421802 -306.898072) (xy 296.406218 -306.944753)
			(xy 296.383347 -306.98833) (xy 296.353782 -307.027674) (xy 296.318289 -307.061766) (xy 296.277786 -307.089722)
			(xy 296.233324 -307.11082) (xy 296.186053 -307.124512) (xy 296.137198 -307.130444) (xy 296.088023 -307.128463)
			(xy 296.039804 -307.118619) (xy 295.993788 -307.101167) (xy 295.951167 -307.07656) (xy 295.913046 -307.045435)
			(xy 295.880411 -307.008598) (xy 295.854108 -306.967002) (xy 295.834817 -306.921726) (xy 295.82304 -306.873942)
			(xy 295.81908 -306.824888) (xy 295.480232 -306.824888) (xy 295.479737 -306.849495) (xy 295.471842 -306.898072)
			(xy 295.456258 -306.944753) (xy 295.433387 -306.98833) (xy 295.403822 -307.027674) (xy 295.368329 -307.061766)
			(xy 295.327826 -307.089722) (xy 295.283364 -307.11082) (xy 295.236093 -307.124512) (xy 295.187238 -307.130444)
			(xy 295.138063 -307.128463) (xy 295.089844 -307.118619) (xy 295.043828 -307.101167) (xy 295.001207 -307.07656)
			(xy 294.963086 -307.045435) (xy 294.930451 -307.008598) (xy 294.904148 -306.967002) (xy 294.884857 -306.921726)
			(xy 294.87308 -306.873942) (xy 294.86912 -306.824888) (xy 294.530018 -306.824888) (xy 294.529523 -306.849495)
			(xy 294.521628 -306.898072) (xy 294.506044 -306.944753) (xy 294.483173 -306.98833) (xy 294.453608 -307.027674)
			(xy 294.418115 -307.061766) (xy 294.377612 -307.089722) (xy 294.33315 -307.11082) (xy 294.285879 -307.124512)
			(xy 294.237024 -307.130444) (xy 294.187849 -307.128463) (xy 294.13963 -307.118619) (xy 294.093614 -307.101167)
			(xy 294.050993 -307.07656) (xy 294.012872 -307.045435) (xy 293.980237 -307.008598) (xy 293.953934 -306.967002)
			(xy 293.934643 -306.921726) (xy 293.922866 -306.873942) (xy 293.918906 -306.824888) (xy 293.580058 -306.824888)
			(xy 293.579563 -306.849495) (xy 293.571668 -306.898072) (xy 293.556084 -306.944753) (xy 293.533213 -306.98833)
			(xy 293.503648 -307.027674) (xy 293.468155 -307.061766) (xy 293.427652 -307.089722) (xy 293.38319 -307.11082)
			(xy 293.335919 -307.124512) (xy 293.287064 -307.130444) (xy 293.237889 -307.128463) (xy 293.18967 -307.118619)
			(xy 293.143654 -307.101167) (xy 293.101033 -307.07656) (xy 293.062912 -307.045435) (xy 293.030277 -307.008598)
			(xy 293.003974 -306.967002) (xy 292.984683 -306.921726) (xy 292.972906 -306.873942) (xy 292.968946 -306.824888)
			(xy 292.630098 -306.824888) (xy 292.629603 -306.849495) (xy 292.621708 -306.898072) (xy 292.606124 -306.944753)
			(xy 292.583253 -306.98833) (xy 292.553688 -307.027674) (xy 292.518195 -307.061766) (xy 292.477692 -307.089722)
			(xy 292.43323 -307.11082) (xy 292.385959 -307.124512) (xy 292.337104 -307.130444) (xy 292.287929 -307.128463)
			(xy 292.23971 -307.118619) (xy 292.193694 -307.101167) (xy 292.151073 -307.07656) (xy 292.112952 -307.045435)
			(xy 292.080317 -307.008598) (xy 292.054014 -306.967002) (xy 292.034723 -306.921726) (xy 292.022946 -306.873942)
			(xy 292.018986 -306.824888) (xy 290.730178 -306.824888) (xy 290.729683 -306.849495) (xy 290.721788 -306.898072)
			(xy 290.706204 -306.944753) (xy 290.683333 -306.98833) (xy 290.653768 -307.027674) (xy 290.618275 -307.061766)
			(xy 290.577772 -307.089722) (xy 290.53331 -307.11082) (xy 290.486039 -307.124512) (xy 290.437184 -307.130444)
			(xy 290.388009 -307.128463) (xy 290.33979 -307.118619) (xy 290.293774 -307.101167) (xy 290.251153 -307.07656)
			(xy 290.213032 -307.045435) (xy 290.180397 -307.008598) (xy 290.154094 -306.967002) (xy 290.134803 -306.921726)
			(xy 290.123026 -306.873942) (xy 290.119066 -306.824888) (xy 289.780218 -306.824888) (xy 289.779723 -306.849495)
			(xy 289.771828 -306.898072) (xy 289.756244 -306.944753) (xy 289.733373 -306.98833) (xy 289.703808 -307.027674)
			(xy 289.668315 -307.061766) (xy 289.627812 -307.089722) (xy 289.58335 -307.11082) (xy 289.536079 -307.124512)
			(xy 289.487224 -307.130444) (xy 289.438049 -307.128463) (xy 289.38983 -307.118619) (xy 289.343814 -307.101167)
			(xy 289.301193 -307.07656) (xy 289.263072 -307.045435) (xy 289.230437 -307.008598) (xy 289.204134 -306.967002)
			(xy 289.184843 -306.921726) (xy 289.173066 -306.873942) (xy 289.169106 -306.824888) (xy 288.830004 -306.824888)
			(xy 288.829509 -306.849495) (xy 288.821614 -306.898072) (xy 288.80603 -306.944753) (xy 288.783159 -306.98833)
			(xy 288.753594 -307.027674) (xy 288.718101 -307.061766) (xy 288.677598 -307.089722) (xy 288.633136 -307.11082)
			(xy 288.585865 -307.124512) (xy 288.53701 -307.130444) (xy 288.487835 -307.128463) (xy 288.439616 -307.118619)
			(xy 288.3936 -307.101167) (xy 288.350979 -307.07656) (xy 288.312858 -307.045435) (xy 288.280223 -307.008598)
			(xy 288.25392 -306.967002) (xy 288.234629 -306.921726) (xy 288.222852 -306.873942) (xy 288.218892 -306.824888)
			(xy 287.880044 -306.824888) (xy 287.879549 -306.849495) (xy 287.871654 -306.898072) (xy 287.85607 -306.944753)
			(xy 287.833199 -306.98833) (xy 287.803634 -307.027674) (xy 287.768141 -307.061766) (xy 287.727638 -307.089722)
			(xy 287.683176 -307.11082) (xy 287.635905 -307.124512) (xy 287.58705 -307.130444) (xy 287.537875 -307.128463)
			(xy 287.489656 -307.118619) (xy 287.44364 -307.101167) (xy 287.401019 -307.07656) (xy 287.362898 -307.045435)
			(xy 287.330263 -307.008598) (xy 287.30396 -306.967002) (xy 287.284669 -306.921726) (xy 287.272892 -306.873942)
			(xy 287.268932 -306.824888) (xy 286.930084 -306.824888) (xy 286.929589 -306.849495) (xy 286.921694 -306.898072)
			(xy 286.90611 -306.944753) (xy 286.883239 -306.98833) (xy 286.853674 -307.027674) (xy 286.818181 -307.061766)
			(xy 286.777678 -307.089722) (xy 286.733216 -307.11082) (xy 286.685945 -307.124512) (xy 286.63709 -307.130444)
			(xy 286.587915 -307.128463) (xy 286.539696 -307.118619) (xy 286.49368 -307.101167) (xy 286.451059 -307.07656)
			(xy 286.412938 -307.045435) (xy 286.380303 -307.008598) (xy 286.354 -306.967002) (xy 286.334709 -306.921726)
			(xy 286.322932 -306.873942) (xy 286.318972 -306.824888) (xy 285.980124 -306.824888) (xy 285.979629 -306.849495)
			(xy 285.971734 -306.898072) (xy 285.95615 -306.944753) (xy 285.933279 -306.98833) (xy 285.903714 -307.027674)
			(xy 285.868221 -307.061766) (xy 285.827718 -307.089722) (xy 285.783256 -307.11082) (xy 285.735985 -307.124512)
			(xy 285.68713 -307.130444) (xy 285.637955 -307.128463) (xy 285.589736 -307.118619) (xy 285.54372 -307.101167)
			(xy 285.501099 -307.07656) (xy 285.462978 -307.045435) (xy 285.430343 -307.008598) (xy 285.40404 -306.967002)
			(xy 285.384749 -306.921726) (xy 285.372972 -306.873942) (xy 285.369012 -306.824888) (xy 285.030164 -306.824888)
			(xy 285.029669 -306.849495) (xy 285.021774 -306.898072) (xy 285.00619 -306.944753) (xy 284.983319 -306.98833)
			(xy 284.953754 -307.027674) (xy 284.918261 -307.061766) (xy 284.877758 -307.089722) (xy 284.833296 -307.11082)
			(xy 284.786025 -307.124512) (xy 284.73717 -307.130444) (xy 284.687995 -307.128463) (xy 284.639776 -307.118619)
			(xy 284.59376 -307.101167) (xy 284.551139 -307.07656) (xy 284.513018 -307.045435) (xy 284.480383 -307.008598)
			(xy 284.45408 -306.967002) (xy 284.434789 -306.921726) (xy 284.423012 -306.873942) (xy 284.419052 -306.824888)
			(xy 284.080204 -306.824888) (xy 284.079709 -306.849495) (xy 284.071814 -306.898072) (xy 284.05623 -306.944753)
			(xy 284.033359 -306.98833) (xy 284.003794 -307.027674) (xy 283.968301 -307.061766) (xy 283.927798 -307.089722)
			(xy 283.883336 -307.11082) (xy 283.836065 -307.124512) (xy 283.78721 -307.130444) (xy 283.738035 -307.128463)
			(xy 283.689816 -307.118619) (xy 283.6438 -307.101167) (xy 283.601179 -307.07656) (xy 283.563058 -307.045435)
			(xy 283.530423 -307.008598) (xy 283.50412 -306.967002) (xy 283.484829 -306.921726) (xy 283.473052 -306.873942)
			(xy 283.469092 -306.824888) (xy 283.130244 -306.824888) (xy 283.129749 -306.849495) (xy 283.121854 -306.898072)
			(xy 283.10627 -306.944753) (xy 283.083399 -306.98833) (xy 283.053834 -307.027674) (xy 283.018341 -307.061766)
			(xy 282.977838 -307.089722) (xy 282.933376 -307.11082) (xy 282.886105 -307.124512) (xy 282.83725 -307.130444)
			(xy 282.788075 -307.128463) (xy 282.739856 -307.118619) (xy 282.69384 -307.101167) (xy 282.651219 -307.07656)
			(xy 282.613098 -307.045435) (xy 282.580463 -307.008598) (xy 282.55416 -306.967002) (xy 282.534869 -306.921726)
			(xy 282.523092 -306.873942) (xy 282.519132 -306.824888) (xy 282.18003 -306.824888) (xy 282.179535 -306.849495)
			(xy 282.17164 -306.898072) (xy 282.156056 -306.944753) (xy 282.133185 -306.98833) (xy 282.10362 -307.027674)
			(xy 282.068127 -307.061766) (xy 282.027624 -307.089722) (xy 281.983162 -307.11082) (xy 281.935891 -307.124512)
			(xy 281.887036 -307.130444) (xy 281.837861 -307.128463) (xy 281.789642 -307.118619) (xy 281.743626 -307.101167)
			(xy 281.701005 -307.07656) (xy 281.662884 -307.045435) (xy 281.630249 -307.008598) (xy 281.603946 -306.967002)
			(xy 281.584655 -306.921726) (xy 281.572878 -306.873942) (xy 281.568918 -306.824888) (xy 281.23007 -306.824888)
			(xy 281.229575 -306.849495) (xy 281.22168 -306.898072) (xy 281.206096 -306.944753) (xy 281.183225 -306.98833)
			(xy 281.15366 -307.027674) (xy 281.118167 -307.061766) (xy 281.077664 -307.089722) (xy 281.033202 -307.11082)
			(xy 280.985931 -307.124512) (xy 280.937076 -307.130444) (xy 280.887901 -307.128463) (xy 280.839682 -307.118619)
			(xy 280.793666 -307.101167) (xy 280.751045 -307.07656) (xy 280.712924 -307.045435) (xy 280.680289 -307.008598)
			(xy 280.653986 -306.967002) (xy 280.634695 -306.921726) (xy 280.622918 -306.873942) (xy 280.618958 -306.824888)
			(xy 280.28011 -306.824888) (xy 280.28011 -306.841398) (xy 280.279602 -306.84724) (xy 280.279602 -306.847748)
			(xy 280.278332 -306.85867) (xy 280.278332 -306.858924) (xy 280.277824 -306.862988) (xy 280.275284 -306.881784)
			(xy 280.274268 -306.887372) (xy 280.270204 -306.90312) (xy 280.268426 -306.91582) (xy 280.268426 -307.299868)
			(xy 305.793914 -307.299868) (xy 305.797874 -307.250814) (xy 305.809651 -307.20303) (xy 305.828942 -307.157754)
			(xy 305.855245 -307.116158) (xy 305.88788 -307.079321) (xy 305.926001 -307.048196) (xy 305.968622 -307.023589)
			(xy 306.014638 -307.006137) (xy 306.062857 -306.996293) (xy 306.112032 -306.994312) (xy 306.160887 -307.000244)
			(xy 306.208158 -307.013936) (xy 306.25262 -307.035034) (xy 306.293123 -307.06299) (xy 306.328616 -307.097082)
			(xy 306.358181 -307.136426) (xy 306.381052 -307.180003) (xy 306.396636 -307.226684) (xy 306.404531 -307.275261)
			(xy 306.405026 -307.299868) (xy 306.744128 -307.299868) (xy 306.748088 -307.250814) (xy 306.759865 -307.20303)
			(xy 306.779156 -307.157754) (xy 306.805459 -307.116158) (xy 306.838094 -307.079321) (xy 306.876215 -307.048196)
			(xy 306.918836 -307.023589) (xy 306.964852 -307.006137) (xy 307.013071 -306.996293) (xy 307.062246 -306.994312)
			(xy 307.111101 -307.000244) (xy 307.158372 -307.013936) (xy 307.202834 -307.035034) (xy 307.243337 -307.06299)
			(xy 307.27883 -307.097082) (xy 307.308395 -307.136426) (xy 307.331266 -307.180003) (xy 307.34685 -307.226684)
			(xy 307.354745 -307.275261) (xy 307.35524 -307.299868) (xy 307.694088 -307.299868) (xy 307.698048 -307.250814)
			(xy 307.709825 -307.20303) (xy 307.729116 -307.157754) (xy 307.755419 -307.116158) (xy 307.788054 -307.079321)
			(xy 307.826175 -307.048196) (xy 307.868796 -307.023589) (xy 307.914812 -307.006137) (xy 307.963031 -306.996293)
			(xy 308.012206 -306.994312) (xy 308.061061 -307.000244) (xy 308.108332 -307.013936) (xy 308.152794 -307.035034)
			(xy 308.193297 -307.06299) (xy 308.22879 -307.097082) (xy 308.258355 -307.136426) (xy 308.281226 -307.180003)
			(xy 308.29681 -307.226684) (xy 308.304705 -307.275261) (xy 308.3052 -307.299868) (xy 308.644048 -307.299868)
			(xy 308.648008 -307.250814) (xy 308.659785 -307.20303) (xy 308.679076 -307.157754) (xy 308.705379 -307.116158)
			(xy 308.738014 -307.079321) (xy 308.776135 -307.048196) (xy 308.818756 -307.023589) (xy 308.864772 -307.006137)
			(xy 308.912991 -306.996293) (xy 308.962166 -306.994312) (xy 309.011021 -307.000244) (xy 309.058292 -307.013936)
			(xy 309.102754 -307.035034) (xy 309.143257 -307.06299) (xy 309.17875 -307.097082) (xy 309.208315 -307.136426)
			(xy 309.231186 -307.180003) (xy 309.24677 -307.226684) (xy 309.254665 -307.275261) (xy 309.25516 -307.299868)
			(xy 309.594008 -307.299868) (xy 309.597968 -307.250814) (xy 309.609745 -307.20303) (xy 309.629036 -307.157754)
			(xy 309.655339 -307.116158) (xy 309.687974 -307.079321) (xy 309.726095 -307.048196) (xy 309.768716 -307.023589)
			(xy 309.814732 -307.006137) (xy 309.862951 -306.996293) (xy 309.912126 -306.994312) (xy 309.960981 -307.000244)
			(xy 310.008252 -307.013936) (xy 310.052714 -307.035034) (xy 310.093217 -307.06299) (xy 310.12871 -307.097082)
			(xy 310.158275 -307.136426) (xy 310.181146 -307.180003) (xy 310.19673 -307.226684) (xy 310.204625 -307.275261)
			(xy 310.20512 -307.299868) (xy 310.543968 -307.299868) (xy 310.547928 -307.250814) (xy 310.559705 -307.20303)
			(xy 310.578996 -307.157754) (xy 310.605299 -307.116158) (xy 310.637934 -307.079321) (xy 310.676055 -307.048196)
			(xy 310.718676 -307.023589) (xy 310.764692 -307.006137) (xy 310.812911 -306.996293) (xy 310.862086 -306.994312)
			(xy 310.910941 -307.000244) (xy 310.958212 -307.013936) (xy 311.002674 -307.035034) (xy 311.043177 -307.06299)
			(xy 311.07867 -307.097082) (xy 311.108235 -307.136426) (xy 311.131106 -307.180003) (xy 311.14669 -307.226684)
			(xy 311.154585 -307.275261) (xy 311.15508 -307.299868) (xy 311.493928 -307.299868) (xy 311.497888 -307.250814)
			(xy 311.509665 -307.20303) (xy 311.528956 -307.157754) (xy 311.555259 -307.116158) (xy 311.587894 -307.079321)
			(xy 311.626015 -307.048196) (xy 311.668636 -307.023589) (xy 311.714652 -307.006137) (xy 311.762871 -306.996293)
			(xy 311.812046 -306.994312) (xy 311.860901 -307.000244) (xy 311.908172 -307.013936) (xy 311.952634 -307.035034)
			(xy 311.993137 -307.06299) (xy 312.02863 -307.097082) (xy 312.058195 -307.136426) (xy 312.081066 -307.180003)
			(xy 312.09665 -307.226684) (xy 312.104545 -307.275261) (xy 312.10504 -307.299868) (xy 312.443888 -307.299868)
			(xy 312.447848 -307.250814) (xy 312.459625 -307.20303) (xy 312.478916 -307.157754) (xy 312.505219 -307.116158)
			(xy 312.537854 -307.079321) (xy 312.575975 -307.048196) (xy 312.618596 -307.023589) (xy 312.664612 -307.006137)
			(xy 312.712831 -306.996293) (xy 312.762006 -306.994312) (xy 312.810861 -307.000244) (xy 312.858132 -307.013936)
			(xy 312.902594 -307.035034) (xy 312.943097 -307.06299) (xy 312.97859 -307.097082) (xy 313.008155 -307.136426)
			(xy 313.031026 -307.180003) (xy 313.04661 -307.226684) (xy 313.054505 -307.275261) (xy 313.055 -307.299868)
			(xy 313.394102 -307.299868) (xy 313.398062 -307.250814) (xy 313.409839 -307.20303) (xy 313.42913 -307.157754)
			(xy 313.455433 -307.116158) (xy 313.488068 -307.079321) (xy 313.526189 -307.048196) (xy 313.56881 -307.023589)
			(xy 313.614826 -307.006137) (xy 313.663045 -306.996293) (xy 313.71222 -306.994312) (xy 313.761075 -307.000244)
			(xy 313.808346 -307.013936) (xy 313.852808 -307.035034) (xy 313.893311 -307.06299) (xy 313.928804 -307.097082)
			(xy 313.958369 -307.136426) (xy 313.98124 -307.180003) (xy 313.996824 -307.226684) (xy 314.004719 -307.275261)
			(xy 314.005214 -307.299868) (xy 314.344062 -307.299868) (xy 314.348022 -307.250814) (xy 314.359799 -307.20303)
			(xy 314.37909 -307.157754) (xy 314.405393 -307.116158) (xy 314.438028 -307.079321) (xy 314.476149 -307.048196)
			(xy 314.51877 -307.023589) (xy 314.564786 -307.006137) (xy 314.613005 -306.996293) (xy 314.66218 -306.994312)
			(xy 314.711035 -307.000244) (xy 314.758306 -307.013936) (xy 314.802768 -307.035034) (xy 314.843271 -307.06299)
			(xy 314.878764 -307.097082) (xy 314.908329 -307.136426) (xy 314.9312 -307.180003) (xy 314.940667 -307.208361)
			(xy 323.477026 -307.208361) (xy 323.484781 -307.154405) (xy 323.500137 -307.102102) (xy 323.52278 -307.052516)
			(xy 323.552249 -307.006658) (xy 323.587945 -306.96546) (xy 323.62914 -306.929762) (xy 323.674997 -306.90029)
			(xy 323.724581 -306.877644) (xy 323.776883 -306.862286) (xy 323.830839 -306.854527) (xy 323.88535 -306.854527)
			(xy 323.939306 -306.862284) (xy 323.991609 -306.877641) (xy 324.041194 -306.900285) (xy 324.087051 -306.929756)
			(xy 324.128248 -306.965453) (xy 324.163945 -307.006649) (xy 324.193415 -307.052507) (xy 324.207899 -307.084222)
			(xy 324.914258 -307.084222) (xy 324.918329 -307.0286) (xy 324.930455 -306.974163) (xy 324.950378 -306.922072)
			(xy 324.977674 -306.873437) (xy 325.01176 -306.829294) (xy 325.051909 -306.790585) (xy 325.097267 -306.758134)
			(xy 325.146867 -306.732633) (xy 325.199651 -306.714626) (xy 325.254494 -306.704496) (xy 325.310228 -306.702459)
			(xy 325.365665 -306.708559) (xy 325.419622 -306.722665) (xy 325.470951 -306.744477) (xy 325.518557 -306.773531)
			(xy 325.561425 -306.809206) (xy 325.598642 -306.850743) (xy 325.629415 -306.897256) (xy 325.653087 -306.947753)
			(xy 325.669155 -307.00116) (xy 325.677275 -307.056336) (xy 325.677784 -307.084222) (xy 325.677275 -307.112108)
			(xy 325.669155 -307.167284) (xy 325.653087 -307.220691) (xy 325.629415 -307.271188) (xy 325.598642 -307.317701)
			(xy 325.561425 -307.359238) (xy 325.518557 -307.394913) (xy 325.470951 -307.423967) (xy 325.419622 -307.445779)
			(xy 325.365665 -307.459885) (xy 325.310228 -307.465985) (xy 325.254494 -307.463948) (xy 325.199651 -307.453818)
			(xy 325.146867 -307.435811) (xy 325.097267 -307.41031) (xy 325.051909 -307.377859) (xy 325.01176 -307.33915)
			(xy 324.977674 -307.295007) (xy 324.950378 -307.246372) (xy 324.930455 -307.194281) (xy 324.918329 -307.139844)
			(xy 324.914258 -307.084222) (xy 324.207899 -307.084222) (xy 324.21606 -307.102092) (xy 324.231416 -307.154395)
			(xy 324.239173 -307.208351) (xy 324.239636 -307.235606) (xy 324.237858 -307.272182) (xy 324.236842 -307.283612)
			(xy 324.244462 -307.304694) (xy 324.31609 -307.376322) (xy 324.337426 -307.383942) (xy 324.348856 -307.382926)
			(xy 324.385432 -307.381148) (xy 324.412682 -307.381648) (xy 324.466627 -307.389408) (xy 324.518919 -307.404765)
			(xy 324.568493 -307.427406) (xy 324.614341 -307.456872) (xy 324.65553 -307.492562) (xy 324.691221 -307.533749)
			(xy 324.720688 -307.579596) (xy 324.743331 -307.62917) (xy 324.75869 -307.681461) (xy 324.766451 -307.735406)
			(xy 324.76694 -307.762656) (xy 324.766584 -307.785162) (xy 324.761957 -307.82387) (xy 335.023714 -307.82387)
			(xy 335.024159 -307.796499) (xy 335.031981 -307.742319) (xy 335.047475 -307.689815) (xy 335.070322 -307.640069)
			(xy 335.100051 -307.594103) (xy 335.117694 -307.573172) (xy 335.12379 -307.56606) (xy 335.13014 -307.549042)
			(xy 335.13014 -307.463698) (xy 335.12379 -307.44668) (xy 335.117694 -307.439568) (xy 335.100025 -307.418658)
			(xy 335.070304 -307.372686) (xy 335.047463 -307.322936) (xy 335.03197 -307.27043) (xy 335.024145 -307.216249)
			(xy 335.024148 -307.161506) (xy 335.03198 -307.107326) (xy 335.047479 -307.054822) (xy 335.070326 -307.005075)
			(xy 335.100053 -306.959105) (xy 335.117694 -306.938172) (xy 335.12379 -306.93106) (xy 335.13014 -306.914042)
			(xy 335.13014 -306.828698) (xy 335.12379 -306.81168) (xy 335.117694 -306.804568) (xy 335.100025 -306.783658)
			(xy 335.070304 -306.737686) (xy 335.047463 -306.687936) (xy 335.03197 -306.63543) (xy 335.024145 -306.581249)
			(xy 335.024148 -306.526506) (xy 335.03198 -306.472326) (xy 335.047479 -306.419822) (xy 335.070326 -306.370075)
			(xy 335.100053 -306.324105) (xy 335.117694 -306.303172) (xy 335.12379 -306.29606) (xy 335.13014 -306.279042)
			(xy 335.13014 -306.193698) (xy 335.12379 -306.17668) (xy 335.117694 -306.169568) (xy 335.100072 -306.148622)
			(xy 335.070358 -306.102653) (xy 335.047519 -306.052909) (xy 335.032024 -306.000411) (xy 335.024191 -305.946238)
			(xy 335.023714 -305.91887) (xy 335.0242 -305.891619) (xy 335.031956 -305.837671) (xy 335.047311 -305.785376)
			(xy 335.069953 -305.735799) (xy 335.099419 -305.689949) (xy 335.13511 -305.648758) (xy 335.176301 -305.613067)
			(xy 335.222151 -305.583601) (xy 335.271728 -305.560959) (xy 335.324023 -305.545604) (xy 335.377971 -305.537848)
			(xy 335.432473 -305.537848) (xy 335.486421 -305.545604) (xy 335.538716 -305.560959) (xy 335.588293 -305.583601)
			(xy 335.634143 -305.613067) (xy 335.675334 -305.648758) (xy 335.711025 -305.689949) (xy 335.740491 -305.735799)
			(xy 335.763133 -305.785376) (xy 335.778488 -305.837671) (xy 335.786244 -305.891619) (xy 335.78673 -305.91887)
			(xy 335.786263 -305.94624) (xy 335.778448 -306.00042) (xy 335.76296 -306.052924) (xy 335.740118 -306.102671)
			(xy 335.710392 -306.148637) (xy 335.69275 -306.169568) (xy 335.686654 -306.17668) (xy 335.680304 -306.193698)
			(xy 335.680304 -306.279042) (xy 335.686654 -306.29606) (xy 335.69275 -306.303172) (xy 335.710362 -306.324128)
			(xy 335.74009 -306.370091) (xy 335.762939 -306.419834) (xy 335.778438 -306.472332) (xy 335.78627 -306.526508)
			(xy 335.786273 -306.581247) (xy 335.778448 -306.635424) (xy 335.762954 -306.687924) (xy 335.740112 -306.737669)
			(xy 335.71039 -306.783636) (xy 335.69275 -306.804568) (xy 335.686654 -306.81168) (xy 335.680304 -306.828698)
			(xy 335.680304 -306.914042) (xy 335.686654 -306.93106) (xy 335.69275 -306.938172) (xy 335.710362 -306.959128)
			(xy 335.74009 -307.005091) (xy 335.762939 -307.054834) (xy 335.778438 -307.107332) (xy 335.78627 -307.161508)
			(xy 335.786273 -307.216247) (xy 335.778448 -307.270424) (xy 335.762954 -307.322924) (xy 335.740112 -307.372669)
			(xy 335.71039 -307.418636) (xy 335.69275 -307.439568) (xy 335.686654 -307.44668) (xy 335.680304 -307.463698)
			(xy 335.680304 -307.549042) (xy 335.686654 -307.56606) (xy 335.69275 -307.573172) (xy 335.710382 -307.59411)
			(xy 335.740096 -307.640081) (xy 335.762934 -307.689826) (xy 335.778427 -307.742326) (xy 335.786256 -307.796501)
			(xy 335.78673 -307.82387) (xy 335.786244 -307.851121) (xy 335.78242 -307.877718) (xy 338.655914 -307.877718)
			(xy 338.656387 -307.850348) (xy 338.664203 -307.796169) (xy 338.67969 -307.743666) (xy 338.70253 -307.693919)
			(xy 338.732253 -307.647952) (xy 338.749894 -307.62702) (xy 338.75599 -307.619908) (xy 338.76234 -307.60289)
			(xy 338.76234 -307.517546) (xy 338.75599 -307.500528) (xy 338.749894 -307.493416) (xy 338.732272 -307.472468)
			(xy 338.702549 -307.426502) (xy 338.679705 -307.376758) (xy 338.664209 -307.324259) (xy 338.656379 -307.270083)
			(xy 338.656377 -307.215344) (xy 338.664203 -307.161168) (xy 338.679695 -307.108667) (xy 338.702536 -307.058921)
			(xy 338.732256 -307.012953) (xy 338.749894 -306.99202) (xy 338.75599 -306.984908) (xy 338.76234 -306.96789)
			(xy 338.76234 -306.882546) (xy 338.75599 -306.865528) (xy 338.749894 -306.858416) (xy 338.732272 -306.837468)
			(xy 338.702549 -306.791502) (xy 338.679705 -306.741758) (xy 338.664209 -306.689259) (xy 338.656379 -306.635083)
			(xy 338.656377 -306.580344) (xy 338.664203 -306.526168) (xy 338.679695 -306.473667) (xy 338.702536 -306.423921)
			(xy 338.732256 -306.377953) (xy 338.749894 -306.35702) (xy 338.75599 -306.349908) (xy 338.76234 -306.33289)
			(xy 338.76234 -306.247546) (xy 338.75599 -306.230528) (xy 338.749894 -306.223416) (xy 338.732248 -306.20249)
			(xy 338.702537 -306.156515) (xy 338.679703 -306.106766) (xy 338.664213 -306.054264) (xy 338.656387 -306.000088)
			(xy 338.655914 -305.972718) (xy 338.6564 -305.945467) (xy 338.664156 -305.891519) (xy 338.679511 -305.839224)
			(xy 338.702153 -305.789647) (xy 338.731619 -305.743797) (xy 338.76731 -305.702606) (xy 338.808501 -305.666915)
			(xy 338.854351 -305.637449) (xy 338.903928 -305.614807) (xy 338.956223 -305.599452) (xy 339.010171 -305.591696)
			(xy 339.064673 -305.591696) (xy 339.118621 -305.599452) (xy 339.170916 -305.614807) (xy 339.220493 -305.637449)
			(xy 339.266343 -305.666915) (xy 339.307534 -305.702606) (xy 339.343225 -305.743797) (xy 339.372691 -305.789647)
			(xy 339.395333 -305.839224) (xy 339.410688 -305.891519) (xy 339.418444 -305.945467) (xy 339.41893 -305.972718)
			(xy 339.418492 -306.000089) (xy 339.41067 -306.05427) (xy 339.395175 -306.106774) (xy 339.372327 -306.156521)
			(xy 339.342595 -306.202486) (xy 339.32495 -306.223416) (xy 339.318854 -306.230528) (xy 339.312504 -306.247546)
			(xy 339.312504 -306.33289) (xy 339.318854 -306.349908) (xy 339.32495 -306.35702) (xy 339.342609 -306.377938)
			(xy 339.372335 -306.423908) (xy 339.395181 -306.473656) (xy 339.410677 -306.526161) (xy 339.418504 -306.580342)
			(xy 339.418502 -306.635085) (xy 339.410671 -306.689266) (xy 339.395171 -306.741769) (xy 339.372322 -306.791516)
			(xy 339.342593 -306.837484) (xy 339.32495 -306.858416) (xy 339.318854 -306.865528) (xy 339.312504 -306.882546)
			(xy 339.312504 -306.96789) (xy 339.318854 -306.984908) (xy 339.32495 -306.99202) (xy 339.342609 -307.012938)
			(xy 339.372335 -307.058908) (xy 339.395181 -307.108656) (xy 339.410677 -307.161161) (xy 339.418504 -307.215342)
			(xy 339.418502 -307.270085) (xy 339.410671 -307.324266) (xy 339.395171 -307.376769) (xy 339.372322 -307.426516)
			(xy 339.342593 -307.472484) (xy 339.32495 -307.493416) (xy 339.318854 -307.500528) (xy 339.312504 -307.517546)
			(xy 339.312504 -307.60289) (xy 339.318854 -307.619908) (xy 339.32495 -307.62702) (xy 339.342557 -307.647978)
			(xy 339.372276 -307.693943) (xy 339.395118 -307.743684) (xy 339.410617 -307.796179) (xy 339.414622 -307.82387)
			(xy 341.863934 -307.82387) (xy 341.864374 -307.796499) (xy 341.872197 -307.742318) (xy 341.887692 -307.689814)
			(xy 341.910539 -307.640068) (xy 341.94027 -307.594103) (xy 341.957914 -307.573172) (xy 341.96401 -307.56606)
			(xy 341.97036 -307.549042) (xy 341.97036 -307.463698) (xy 341.96401 -307.44668) (xy 341.957914 -307.439568)
			(xy 341.940244 -307.418659) (xy 341.910522 -307.372687) (xy 341.887679 -307.322936) (xy 341.872186 -307.270431)
			(xy 341.86436 -307.216249) (xy 341.864363 -307.161506) (xy 341.872195 -307.107325) (xy 341.887695 -307.054821)
			(xy 341.910544 -307.005074) (xy 341.940272 -306.959105) (xy 341.957914 -306.938172) (xy 341.96401 -306.93106)
			(xy 341.97036 -306.914042) (xy 341.97036 -306.828698) (xy 341.96401 -306.81168) (xy 341.957914 -306.804568)
			(xy 341.940244 -306.783659) (xy 341.910522 -306.737687) (xy 341.887679 -306.687936) (xy 341.872186 -306.635431)
			(xy 341.86436 -306.581249) (xy 341.864363 -306.526506) (xy 341.872195 -306.472325) (xy 341.887695 -306.419821)
			(xy 341.910544 -306.370074) (xy 341.940272 -306.324105) (xy 341.957914 -306.303172) (xy 341.96401 -306.29606)
			(xy 341.97036 -306.279042) (xy 341.97036 -306.193698) (xy 341.96401 -306.17668) (xy 341.957914 -306.169568)
			(xy 341.940296 -306.148619) (xy 341.91058 -306.102651) (xy 341.88774 -306.052908) (xy 341.872244 -306.000411)
			(xy 341.864411 -305.946238) (xy 341.863934 -305.91887) (xy 341.86442 -305.891619) (xy 341.872176 -305.837671)
			(xy 341.887531 -305.785376) (xy 341.910173 -305.735799) (xy 341.939639 -305.689949) (xy 341.97533 -305.648758)
			(xy 342.016521 -305.613067) (xy 342.062371 -305.583601) (xy 342.111948 -305.560959) (xy 342.164243 -305.545604)
			(xy 342.218191 -305.537848) (xy 342.272693 -305.537848) (xy 342.326641 -305.545604) (xy 342.378936 -305.560959)
			(xy 342.428513 -305.583601) (xy 342.474363 -305.613067) (xy 342.515554 -305.648758) (xy 342.551245 -305.689949)
			(xy 342.580711 -305.735799) (xy 342.603353 -305.785376) (xy 342.618708 -305.837671) (xy 342.626464 -305.891619)
			(xy 342.62695 -305.91887) (xy 342.626479 -305.94624) (xy 342.618664 -306.00042) (xy 342.603177 -306.052923)
			(xy 342.580336 -306.10267) (xy 342.550611 -306.148637) (xy 342.53297 -306.169568) (xy 342.526874 -306.17668)
			(xy 342.520524 -306.193698) (xy 342.520524 -306.279042) (xy 342.526874 -306.29606) (xy 342.53297 -306.303172)
			(xy 342.550581 -306.324128) (xy 342.580308 -306.370092) (xy 342.603155 -306.419834) (xy 342.618654 -306.472333)
			(xy 342.626485 -306.526508) (xy 342.626488 -306.581247) (xy 342.618663 -306.635423) (xy 342.603171 -306.687923)
			(xy 342.580329 -306.737668) (xy 342.550609 -306.783635) (xy 342.53297 -306.804568) (xy 342.526874 -306.81168)
			(xy 342.520524 -306.828698) (xy 342.520524 -306.914042) (xy 342.526874 -306.93106) (xy 342.53297 -306.938172)
			(xy 342.550581 -306.959128) (xy 342.580308 -307.005092) (xy 342.603155 -307.054834) (xy 342.618654 -307.107333)
			(xy 342.626485 -307.161508) (xy 342.626488 -307.216247) (xy 342.618663 -307.270423) (xy 342.603171 -307.322923)
			(xy 342.580329 -307.372668) (xy 342.550609 -307.418635) (xy 342.53297 -307.439568) (xy 342.526874 -307.44668)
			(xy 342.520524 -307.463698) (xy 342.520524 -307.549042) (xy 342.526874 -307.56606) (xy 342.53297 -307.573172)
			(xy 342.550605 -307.594108) (xy 342.580318 -307.640079) (xy 342.603156 -307.689826) (xy 342.618648 -307.742326)
			(xy 342.626476 -307.796501) (xy 342.62695 -307.82387) (xy 342.626464 -307.851121) (xy 342.62264 -307.877718)
			(xy 345.496134 -307.877718) (xy 345.496602 -307.850348) (xy 345.504418 -307.796168) (xy 345.519906 -307.743665)
			(xy 345.542748 -307.693918) (xy 345.572473 -307.647951) (xy 345.590114 -307.62702) (xy 345.59621 -307.619908)
			(xy 345.60256 -307.60289) (xy 345.60256 -307.517546) (xy 345.59621 -307.500528) (xy 345.590114 -307.493416)
			(xy 345.572491 -307.472469) (xy 345.542767 -307.426503) (xy 345.519921 -307.376759) (xy 345.504424 -307.324259)
			(xy 345.496594 -307.270083) (xy 345.496592 -307.215344) (xy 345.504418 -307.161167) (xy 345.519912 -307.108666)
			(xy 345.542754 -307.058921) (xy 345.572475 -307.012953) (xy 345.590114 -306.99202) (xy 345.59621 -306.984908)
			(xy 345.60256 -306.96789) (xy 345.60256 -306.882546) (xy 345.59621 -306.865528) (xy 345.590114 -306.858416)
			(xy 345.572491 -306.837469) (xy 345.542767 -306.791503) (xy 345.519921 -306.741759) (xy 345.504424 -306.689259)
			(xy 345.496594 -306.635083) (xy 345.496592 -306.580344) (xy 345.504418 -306.526167) (xy 345.519912 -306.473666)
			(xy 345.542754 -306.423921) (xy 345.572475 -306.377953) (xy 345.590114 -306.35702) (xy 345.59621 -306.349908)
			(xy 345.60256 -306.33289) (xy 345.60256 -306.247546) (xy 345.59621 -306.230528) (xy 345.590114 -306.223416)
			(xy 345.572471 -306.202487) (xy 345.542759 -306.156514) (xy 345.519924 -306.106765) (xy 345.504434 -306.054264)
			(xy 345.496607 -306.000087) (xy 345.496134 -305.972718) (xy 345.49662 -305.945467) (xy 345.504376 -305.891519)
			(xy 345.519731 -305.839224) (xy 345.542373 -305.789647) (xy 345.571839 -305.743797) (xy 345.60753 -305.702606)
			(xy 345.648721 -305.666915) (xy 345.694571 -305.637449) (xy 345.744148 -305.614807) (xy 345.796443 -305.599452)
			(xy 345.850391 -305.591696) (xy 345.904893 -305.591696) (xy 345.958841 -305.599452) (xy 346.011136 -305.614807)
			(xy 346.060713 -305.637449) (xy 346.106563 -305.666915) (xy 346.147754 -305.702606) (xy 346.183445 -305.743797)
			(xy 346.212911 -305.789647) (xy 346.235553 -305.839224) (xy 346.250908 -305.891519) (xy 346.258664 -305.945467)
			(xy 346.25915 -305.972718) (xy 346.258707 -306.000089) (xy 346.250885 -306.05427) (xy 346.235392 -306.106774)
			(xy 346.212544 -306.15652) (xy 346.182814 -306.202486) (xy 346.16517 -306.223416) (xy 346.159074 -306.230528)
			(xy 346.152724 -306.247546) (xy 346.152724 -306.33289) (xy 346.159074 -306.349908) (xy 346.16517 -306.35702)
			(xy 346.182828 -306.377938) (xy 346.212553 -306.423909) (xy 346.235397 -306.473657) (xy 346.250892 -306.526161)
			(xy 346.258719 -306.580342) (xy 346.258717 -306.635085) (xy 346.250886 -306.689265) (xy 346.235388 -306.741768)
			(xy 346.21254 -306.791515) (xy 346.182812 -306.837483) (xy 346.16517 -306.858416) (xy 346.159074 -306.865528)
			(xy 346.152724 -306.882546) (xy 346.152724 -306.96789) (xy 346.159074 -306.984908) (xy 346.16517 -306.99202)
			(xy 346.182828 -307.012938) (xy 346.212553 -307.058909) (xy 346.235397 -307.108657) (xy 346.250892 -307.161161)
			(xy 346.258719 -307.215342) (xy 346.258717 -307.270085) (xy 346.250886 -307.324265) (xy 346.235388 -307.376768)
			(xy 346.21254 -307.426515) (xy 346.182812 -307.472483) (xy 346.16517 -307.493416) (xy 346.159074 -307.500528)
			(xy 346.152724 -307.517546) (xy 346.152724 -307.60289) (xy 346.159074 -307.619908) (xy 346.16517 -307.62702)
			(xy 346.18278 -307.647975) (xy 346.212498 -307.693941) (xy 346.23534 -307.743683) (xy 346.250837 -307.796178)
			(xy 346.258672 -307.85035) (xy 346.25915 -307.877718) (xy 346.258664 -307.904969) (xy 346.250908 -307.958917)
			(xy 346.235553 -308.011212) (xy 346.212911 -308.060789) (xy 346.183445 -308.106639) (xy 346.147754 -308.14783)
			(xy 346.106563 -308.183521) (xy 346.060713 -308.212987) (xy 346.011136 -308.235629) (xy 345.958841 -308.250984)
			(xy 345.904893 -308.25874) (xy 345.850391 -308.25874) (xy 345.796443 -308.250984) (xy 345.744148 -308.235629)
			(xy 345.694571 -308.212987) (xy 345.648721 -308.183521) (xy 345.60753 -308.14783) (xy 345.571839 -308.106639)
			(xy 345.542373 -308.060789) (xy 345.519731 -308.011212) (xy 345.504376 -307.958917) (xy 345.49662 -307.904969)
			(xy 345.496134 -307.877718) (xy 342.62264 -307.877718) (xy 342.618708 -307.905069) (xy 342.603353 -307.957364)
			(xy 342.580711 -308.006941) (xy 342.551245 -308.052791) (xy 342.515554 -308.093982) (xy 342.474363 -308.129673)
			(xy 342.428513 -308.159139) (xy 342.378936 -308.181781) (xy 342.326641 -308.197136) (xy 342.272693 -308.204892)
			(xy 342.218191 -308.204892) (xy 342.164243 -308.197136) (xy 342.111948 -308.181781) (xy 342.062371 -308.159139)
			(xy 342.016521 -308.129673) (xy 341.97533 -308.093982) (xy 341.939639 -308.052791) (xy 341.910173 -308.006941)
			(xy 341.887531 -307.957364) (xy 341.872176 -307.905069) (xy 341.86442 -307.851121) (xy 341.863934 -307.82387)
			(xy 339.414622 -307.82387) (xy 339.418452 -307.85035) (xy 339.41893 -307.877718) (xy 339.418444 -307.904969)
			(xy 339.410688 -307.958917) (xy 339.395333 -308.011212) (xy 339.372691 -308.060789) (xy 339.343225 -308.106639)
			(xy 339.307534 -308.14783) (xy 339.266343 -308.183521) (xy 339.220493 -308.212987) (xy 339.170916 -308.235629)
			(xy 339.118621 -308.250984) (xy 339.064673 -308.25874) (xy 339.010171 -308.25874) (xy 338.956223 -308.250984)
			(xy 338.903928 -308.235629) (xy 338.854351 -308.212987) (xy 338.808501 -308.183521) (xy 338.76731 -308.14783)
			(xy 338.731619 -308.106639) (xy 338.702153 -308.060789) (xy 338.679511 -308.011212) (xy 338.664156 -307.958917)
			(xy 338.6564 -307.904969) (xy 338.655914 -307.877718) (xy 335.78242 -307.877718) (xy 335.778488 -307.905069)
			(xy 335.763133 -307.957364) (xy 335.740491 -308.006941) (xy 335.711025 -308.052791) (xy 335.675334 -308.093982)
			(xy 335.634143 -308.129673) (xy 335.588293 -308.159139) (xy 335.538716 -308.181781) (xy 335.486421 -308.197136)
			(xy 335.432473 -308.204892) (xy 335.377971 -308.204892) (xy 335.324023 -308.197136) (xy 335.271728 -308.181781)
			(xy 335.222151 -308.159139) (xy 335.176301 -308.129673) (xy 335.13511 -308.093982) (xy 335.099419 -308.052791)
			(xy 335.069953 -308.006941) (xy 335.047311 -307.957364) (xy 335.031956 -307.905069) (xy 335.0242 -307.851121)
			(xy 335.023714 -307.82387) (xy 324.761957 -307.82387) (xy 324.761241 -307.829856) (xy 324.756272 -307.85181)
			(xy 324.753224 -307.865018) (xy 324.760336 -307.890164) (xy 324.8406 -307.970428) (xy 324.865746 -307.97754)
			(xy 324.878954 -307.974492) (xy 324.90091 -307.969534) (xy 324.945603 -307.964184) (xy 324.968108 -307.963824)
			(xy 324.995358 -307.964286) (xy 325.049303 -307.972043) (xy 325.101596 -307.987399) (xy 325.15117 -308.010039)
			(xy 325.197019 -308.039505) (xy 325.238207 -308.075195) (xy 325.273897 -308.116384) (xy 325.303362 -308.162232)
			(xy 325.326002 -308.211807) (xy 325.341357 -308.264099) (xy 325.349114 -308.318045) (xy 325.349115 -308.372545)
			(xy 325.341359 -308.42649) (xy 325.326006 -308.478783) (xy 325.303367 -308.528359) (xy 325.273903 -308.574208)
			(xy 325.238214 -308.615397) (xy 325.197027 -308.651089) (xy 325.15118 -308.680555) (xy 325.101606 -308.703198)
			(xy 325.049314 -308.718554) (xy 324.995369 -308.726313) (xy 324.940869 -308.726316) (xy 324.886923 -308.718562)
			(xy 324.834629 -308.703211) (xy 324.785053 -308.680573) (xy 324.739203 -308.651111) (xy 324.698012 -308.615424)
			(xy 324.662319 -308.574238) (xy 324.632851 -308.528392) (xy 324.610207 -308.478818) (xy 324.594849 -308.426527)
			(xy 324.587088 -308.372582) (xy 324.5866 -308.345332) (xy 324.586955 -308.322826) (xy 324.592299 -308.278132)
			(xy 324.597268 -308.256178) (xy 324.600316 -308.24297) (xy 324.593204 -308.217824) (xy 324.51294 -308.13756)
			(xy 324.487794 -308.130448) (xy 324.474586 -308.133496) (xy 324.452633 -308.138464) (xy 324.407938 -308.143807)
			(xy 324.385432 -308.144164) (xy 324.358178 -308.143715) (xy 324.304224 -308.135961) (xy 324.251923 -308.120607)
			(xy 324.20234 -308.097965) (xy 324.156485 -308.068496) (xy 324.115291 -308.032801) (xy 324.079597 -307.991605)
			(xy 324.050129 -307.945749) (xy 324.027489 -307.896165) (xy 324.012136 -307.843864) (xy 324.004384 -307.78991)
			(xy 324.003924 -307.762656) (xy 324.005702 -307.72608) (xy 324.006718 -307.71465) (xy 323.999098 -307.693568)
			(xy 323.92747 -307.62194) (xy 323.906134 -307.61432) (xy 323.894704 -307.615336) (xy 323.858128 -307.617114)
			(xy 323.830873 -307.616675) (xy 323.776916 -307.608921) (xy 323.724612 -307.593567) (xy 323.675026 -307.570926)
			(xy 323.629167 -307.541458) (xy 323.587968 -307.505763) (xy 323.552269 -307.464569) (xy 323.522796 -307.418713)
			(xy 323.500148 -307.36913) (xy 323.484788 -307.316828) (xy 323.477028 -307.262872) (xy 323.477026 -307.208361)
			(xy 314.940667 -307.208361) (xy 314.946784 -307.226684) (xy 314.954679 -307.275261) (xy 314.955174 -307.299868)
			(xy 314.954679 -307.324475) (xy 314.946784 -307.373052) (xy 314.9312 -307.419733) (xy 314.908329 -307.46331)
			(xy 314.878764 -307.502654) (xy 314.843271 -307.536746) (xy 314.802768 -307.564702) (xy 314.758306 -307.5858)
			(xy 314.711035 -307.599492) (xy 314.66218 -307.605424) (xy 314.613005 -307.603443) (xy 314.564786 -307.593599)
			(xy 314.51877 -307.576147) (xy 314.476149 -307.55154) (xy 314.438028 -307.520415) (xy 314.405393 -307.483578)
			(xy 314.37909 -307.441982) (xy 314.359799 -307.396706) (xy 314.348022 -307.348922) (xy 314.344062 -307.299868)
			(xy 314.005214 -307.299868) (xy 314.004719 -307.324475) (xy 313.996824 -307.373052) (xy 313.98124 -307.419733)
			(xy 313.958369 -307.46331) (xy 313.928804 -307.502654) (xy 313.893311 -307.536746) (xy 313.852808 -307.564702)
			(xy 313.808346 -307.5858) (xy 313.761075 -307.599492) (xy 313.71222 -307.605424) (xy 313.663045 -307.603443)
			(xy 313.614826 -307.593599) (xy 313.56881 -307.576147) (xy 313.526189 -307.55154) (xy 313.488068 -307.520415)
			(xy 313.455433 -307.483578) (xy 313.42913 -307.441982) (xy 313.409839 -307.396706) (xy 313.398062 -307.348922)
			(xy 313.394102 -307.299868) (xy 313.055 -307.299868) (xy 313.054505 -307.324475) (xy 313.04661 -307.373052)
			(xy 313.031026 -307.419733) (xy 313.008155 -307.46331) (xy 312.97859 -307.502654) (xy 312.943097 -307.536746)
			(xy 312.902594 -307.564702) (xy 312.858132 -307.5858) (xy 312.810861 -307.599492) (xy 312.762006 -307.605424)
			(xy 312.712831 -307.603443) (xy 312.664612 -307.593599) (xy 312.618596 -307.576147) (xy 312.575975 -307.55154)
			(xy 312.537854 -307.520415) (xy 312.505219 -307.483578) (xy 312.478916 -307.441982) (xy 312.459625 -307.396706)
			(xy 312.447848 -307.348922) (xy 312.443888 -307.299868) (xy 312.10504 -307.299868) (xy 312.104545 -307.324475)
			(xy 312.09665 -307.373052) (xy 312.081066 -307.419733) (xy 312.058195 -307.46331) (xy 312.02863 -307.502654)
			(xy 311.993137 -307.536746) (xy 311.952634 -307.564702) (xy 311.908172 -307.5858) (xy 311.860901 -307.599492)
			(xy 311.812046 -307.605424) (xy 311.762871 -307.603443) (xy 311.714652 -307.593599) (xy 311.668636 -307.576147)
			(xy 311.626015 -307.55154) (xy 311.587894 -307.520415) (xy 311.555259 -307.483578) (xy 311.528956 -307.441982)
			(xy 311.509665 -307.396706) (xy 311.497888 -307.348922) (xy 311.493928 -307.299868) (xy 311.15508 -307.299868)
			(xy 311.154585 -307.324475) (xy 311.14669 -307.373052) (xy 311.131106 -307.419733) (xy 311.108235 -307.46331)
			(xy 311.07867 -307.502654) (xy 311.043177 -307.536746) (xy 311.002674 -307.564702) (xy 310.958212 -307.5858)
			(xy 310.910941 -307.599492) (xy 310.862086 -307.605424) (xy 310.812911 -307.603443) (xy 310.764692 -307.593599)
			(xy 310.718676 -307.576147) (xy 310.676055 -307.55154) (xy 310.637934 -307.520415) (xy 310.605299 -307.483578)
			(xy 310.578996 -307.441982) (xy 310.559705 -307.396706) (xy 310.547928 -307.348922) (xy 310.543968 -307.299868)
			(xy 310.20512 -307.299868) (xy 310.204625 -307.324475) (xy 310.19673 -307.373052) (xy 310.181146 -307.419733)
			(xy 310.158275 -307.46331) (xy 310.12871 -307.502654) (xy 310.093217 -307.536746) (xy 310.052714 -307.564702)
			(xy 310.008252 -307.5858) (xy 309.960981 -307.599492) (xy 309.912126 -307.605424) (xy 309.862951 -307.603443)
			(xy 309.814732 -307.593599) (xy 309.768716 -307.576147) (xy 309.726095 -307.55154) (xy 309.687974 -307.520415)
			(xy 309.655339 -307.483578) (xy 309.629036 -307.441982) (xy 309.609745 -307.396706) (xy 309.597968 -307.348922)
			(xy 309.594008 -307.299868) (xy 309.25516 -307.299868) (xy 309.254665 -307.324475) (xy 309.24677 -307.373052)
			(xy 309.231186 -307.419733) (xy 309.208315 -307.46331) (xy 309.17875 -307.502654) (xy 309.143257 -307.536746)
			(xy 309.102754 -307.564702) (xy 309.058292 -307.5858) (xy 309.011021 -307.599492) (xy 308.962166 -307.605424)
			(xy 308.912991 -307.603443) (xy 308.864772 -307.593599) (xy 308.818756 -307.576147) (xy 308.776135 -307.55154)
			(xy 308.738014 -307.520415) (xy 308.705379 -307.483578) (xy 308.679076 -307.441982) (xy 308.659785 -307.396706)
			(xy 308.648008 -307.348922) (xy 308.644048 -307.299868) (xy 308.3052 -307.299868) (xy 308.304705 -307.324475)
			(xy 308.29681 -307.373052) (xy 308.281226 -307.419733) (xy 308.258355 -307.46331) (xy 308.22879 -307.502654)
			(xy 308.193297 -307.536746) (xy 308.152794 -307.564702) (xy 308.108332 -307.5858) (xy 308.061061 -307.599492)
			(xy 308.012206 -307.605424) (xy 307.963031 -307.603443) (xy 307.914812 -307.593599) (xy 307.868796 -307.576147)
			(xy 307.826175 -307.55154) (xy 307.788054 -307.520415) (xy 307.755419 -307.483578) (xy 307.729116 -307.441982)
			(xy 307.709825 -307.396706) (xy 307.698048 -307.348922) (xy 307.694088 -307.299868) (xy 307.35524 -307.299868)
			(xy 307.354745 -307.324475) (xy 307.34685 -307.373052) (xy 307.331266 -307.419733) (xy 307.308395 -307.46331)
			(xy 307.27883 -307.502654) (xy 307.243337 -307.536746) (xy 307.202834 -307.564702) (xy 307.158372 -307.5858)
			(xy 307.111101 -307.599492) (xy 307.062246 -307.605424) (xy 307.013071 -307.603443) (xy 306.964852 -307.593599)
			(xy 306.918836 -307.576147) (xy 306.876215 -307.55154) (xy 306.838094 -307.520415) (xy 306.805459 -307.483578)
			(xy 306.779156 -307.441982) (xy 306.759865 -307.396706) (xy 306.748088 -307.348922) (xy 306.744128 -307.299868)
			(xy 306.405026 -307.299868) (xy 306.404531 -307.324475) (xy 306.396636 -307.373052) (xy 306.381052 -307.419733)
			(xy 306.358181 -307.46331) (xy 306.328616 -307.502654) (xy 306.293123 -307.536746) (xy 306.25262 -307.564702)
			(xy 306.208158 -307.5858) (xy 306.160887 -307.599492) (xy 306.112032 -307.605424) (xy 306.062857 -307.603443)
			(xy 306.014638 -307.593599) (xy 305.968622 -307.576147) (xy 305.926001 -307.55154) (xy 305.88788 -307.520415)
			(xy 305.855245 -307.483578) (xy 305.828942 -307.441982) (xy 305.809651 -307.396706) (xy 305.797874 -307.348922)
			(xy 305.793914 -307.299868) (xy 280.268426 -307.299868) (xy 280.268426 -307.680106) (xy 280.268934 -307.686202)
			(xy 280.270204 -307.697378) (xy 280.270966 -307.70068) (xy 280.270966 -307.701188) (xy 280.275214 -307.719307)
			(xy 280.279793 -307.75624) (xy 280.28011 -307.774848) (xy 280.618958 -307.774848) (xy 280.622918 -307.725794)
			(xy 280.634695 -307.67801) (xy 280.653986 -307.632734) (xy 280.680289 -307.591138) (xy 280.712924 -307.554301)
			(xy 280.751045 -307.523176) (xy 280.793666 -307.498569) (xy 280.839682 -307.481117) (xy 280.887901 -307.471273)
			(xy 280.937076 -307.469292) (xy 280.985931 -307.475224) (xy 281.033202 -307.488916) (xy 281.077664 -307.510014)
			(xy 281.118167 -307.53797) (xy 281.15366 -307.572062) (xy 281.183225 -307.611406) (xy 281.206096 -307.654983)
			(xy 281.22168 -307.701664) (xy 281.229575 -307.750241) (xy 281.23007 -307.774848) (xy 281.568918 -307.774848)
			(xy 281.572878 -307.725794) (xy 281.584655 -307.67801) (xy 281.603946 -307.632734) (xy 281.630249 -307.591138)
			(xy 281.662884 -307.554301) (xy 281.701005 -307.523176) (xy 281.743626 -307.498569) (xy 281.789642 -307.481117)
			(xy 281.837861 -307.471273) (xy 281.887036 -307.469292) (xy 281.935891 -307.475224) (xy 281.983162 -307.488916)
			(xy 282.027624 -307.510014) (xy 282.068127 -307.53797) (xy 282.10362 -307.572062) (xy 282.133185 -307.611406)
			(xy 282.156056 -307.654983) (xy 282.17164 -307.701664) (xy 282.179535 -307.750241) (xy 282.18003 -307.774848)
			(xy 282.519132 -307.774848) (xy 282.523092 -307.725794) (xy 282.534869 -307.67801) (xy 282.55416 -307.632734)
			(xy 282.580463 -307.591138) (xy 282.613098 -307.554301) (xy 282.651219 -307.523176) (xy 282.69384 -307.498569)
			(xy 282.739856 -307.481117) (xy 282.788075 -307.471273) (xy 282.83725 -307.469292) (xy 282.886105 -307.475224)
			(xy 282.933376 -307.488916) (xy 282.977838 -307.510014) (xy 283.018341 -307.53797) (xy 283.053834 -307.572062)
			(xy 283.083399 -307.611406) (xy 283.10627 -307.654983) (xy 283.121854 -307.701664) (xy 283.129749 -307.750241)
			(xy 283.130244 -307.774848) (xy 283.469092 -307.774848) (xy 283.473052 -307.725794) (xy 283.484829 -307.67801)
			(xy 283.50412 -307.632734) (xy 283.530423 -307.591138) (xy 283.563058 -307.554301) (xy 283.601179 -307.523176)
			(xy 283.6438 -307.498569) (xy 283.689816 -307.481117) (xy 283.738035 -307.471273) (xy 283.78721 -307.469292)
			(xy 283.836065 -307.475224) (xy 283.883336 -307.488916) (xy 283.927798 -307.510014) (xy 283.968301 -307.53797)
			(xy 284.003794 -307.572062) (xy 284.033359 -307.611406) (xy 284.05623 -307.654983) (xy 284.071814 -307.701664)
			(xy 284.079709 -307.750241) (xy 284.080204 -307.774848) (xy 284.419052 -307.774848) (xy 284.423012 -307.725794)
			(xy 284.434789 -307.67801) (xy 284.45408 -307.632734) (xy 284.480383 -307.591138) (xy 284.513018 -307.554301)
			(xy 284.551139 -307.523176) (xy 284.59376 -307.498569) (xy 284.639776 -307.481117) (xy 284.687995 -307.471273)
			(xy 284.73717 -307.469292) (xy 284.786025 -307.475224) (xy 284.833296 -307.488916) (xy 284.877758 -307.510014)
			(xy 284.918261 -307.53797) (xy 284.953754 -307.572062) (xy 284.983319 -307.611406) (xy 285.00619 -307.654983)
			(xy 285.021774 -307.701664) (xy 285.029669 -307.750241) (xy 285.030164 -307.774848) (xy 285.369012 -307.774848)
			(xy 285.372972 -307.725794) (xy 285.384749 -307.67801) (xy 285.40404 -307.632734) (xy 285.430343 -307.591138)
			(xy 285.462978 -307.554301) (xy 285.501099 -307.523176) (xy 285.54372 -307.498569) (xy 285.589736 -307.481117)
			(xy 285.637955 -307.471273) (xy 285.68713 -307.469292) (xy 285.735985 -307.475224) (xy 285.783256 -307.488916)
			(xy 285.827718 -307.510014) (xy 285.868221 -307.53797) (xy 285.903714 -307.572062) (xy 285.933279 -307.611406)
			(xy 285.95615 -307.654983) (xy 285.971734 -307.701664) (xy 285.979629 -307.750241) (xy 285.980124 -307.774848)
			(xy 286.318972 -307.774848) (xy 286.322932 -307.725794) (xy 286.334709 -307.67801) (xy 286.354 -307.632734)
			(xy 286.380303 -307.591138) (xy 286.412938 -307.554301) (xy 286.451059 -307.523176) (xy 286.49368 -307.498569)
			(xy 286.539696 -307.481117) (xy 286.587915 -307.471273) (xy 286.63709 -307.469292) (xy 286.685945 -307.475224)
			(xy 286.733216 -307.488916) (xy 286.777678 -307.510014) (xy 286.818181 -307.53797) (xy 286.853674 -307.572062)
			(xy 286.883239 -307.611406) (xy 286.90611 -307.654983) (xy 286.921694 -307.701664) (xy 286.929589 -307.750241)
			(xy 286.930084 -307.774848) (xy 287.268932 -307.774848) (xy 287.272892 -307.725794) (xy 287.284669 -307.67801)
			(xy 287.30396 -307.632734) (xy 287.330263 -307.591138) (xy 287.362898 -307.554301) (xy 287.401019 -307.523176)
			(xy 287.44364 -307.498569) (xy 287.489656 -307.481117) (xy 287.537875 -307.471273) (xy 287.58705 -307.469292)
			(xy 287.635905 -307.475224) (xy 287.683176 -307.488916) (xy 287.727638 -307.510014) (xy 287.768141 -307.53797)
			(xy 287.803634 -307.572062) (xy 287.833199 -307.611406) (xy 287.85607 -307.654983) (xy 287.871654 -307.701664)
			(xy 287.879549 -307.750241) (xy 287.880044 -307.774848) (xy 288.219146 -307.774848) (xy 288.223106 -307.725794)
			(xy 288.234883 -307.67801) (xy 288.254174 -307.632734) (xy 288.280477 -307.591138) (xy 288.313112 -307.554301)
			(xy 288.351233 -307.523176) (xy 288.393854 -307.498569) (xy 288.43987 -307.481117) (xy 288.488089 -307.471273)
			(xy 288.537264 -307.469292) (xy 288.586119 -307.475224) (xy 288.63339 -307.488916) (xy 288.677852 -307.510014)
			(xy 288.718355 -307.53797) (xy 288.753848 -307.572062) (xy 288.783413 -307.611406) (xy 288.806284 -307.654983)
			(xy 288.821868 -307.701664) (xy 288.829763 -307.750241) (xy 288.830258 -307.774848) (xy 289.169106 -307.774848)
			(xy 289.173066 -307.725794) (xy 289.184843 -307.67801) (xy 289.204134 -307.632734) (xy 289.230437 -307.591138)
			(xy 289.263072 -307.554301) (xy 289.301193 -307.523176) (xy 289.343814 -307.498569) (xy 289.38983 -307.481117)
			(xy 289.438049 -307.471273) (xy 289.487224 -307.469292) (xy 289.536079 -307.475224) (xy 289.58335 -307.488916)
			(xy 289.627812 -307.510014) (xy 289.668315 -307.53797) (xy 289.703808 -307.572062) (xy 289.733373 -307.611406)
			(xy 289.756244 -307.654983) (xy 289.771828 -307.701664) (xy 289.779723 -307.750241) (xy 289.780218 -307.774848)
			(xy 290.119066 -307.774848) (xy 290.123026 -307.725794) (xy 290.134803 -307.67801) (xy 290.154094 -307.632734)
			(xy 290.180397 -307.591138) (xy 290.213032 -307.554301) (xy 290.251153 -307.523176) (xy 290.293774 -307.498569)
			(xy 290.33979 -307.481117) (xy 290.388009 -307.471273) (xy 290.437184 -307.469292) (xy 290.486039 -307.475224)
			(xy 290.53331 -307.488916) (xy 290.577772 -307.510014) (xy 290.618275 -307.53797) (xy 290.653768 -307.572062)
			(xy 290.683333 -307.611406) (xy 290.706204 -307.654983) (xy 290.721788 -307.701664) (xy 290.729683 -307.750241)
			(xy 290.730178 -307.774848) (xy 292.018986 -307.774848) (xy 292.022946 -307.725794) (xy 292.034723 -307.67801)
			(xy 292.054014 -307.632734) (xy 292.080317 -307.591138) (xy 292.112952 -307.554301) (xy 292.151073 -307.523176)
			(xy 292.193694 -307.498569) (xy 292.23971 -307.481117) (xy 292.287929 -307.471273) (xy 292.337104 -307.469292)
			(xy 292.385959 -307.475224) (xy 292.43323 -307.488916) (xy 292.477692 -307.510014) (xy 292.518195 -307.53797)
			(xy 292.553688 -307.572062) (xy 292.583253 -307.611406) (xy 292.606124 -307.654983) (xy 292.621708 -307.701664)
			(xy 292.629603 -307.750241) (xy 292.630098 -307.774848) (xy 292.968946 -307.774848) (xy 292.972906 -307.725794)
			(xy 292.984683 -307.67801) (xy 293.003974 -307.632734) (xy 293.030277 -307.591138) (xy 293.062912 -307.554301)
			(xy 293.101033 -307.523176) (xy 293.143654 -307.498569) (xy 293.18967 -307.481117) (xy 293.237889 -307.471273)
			(xy 293.287064 -307.469292) (xy 293.335919 -307.475224) (xy 293.38319 -307.488916) (xy 293.427652 -307.510014)
			(xy 293.468155 -307.53797) (xy 293.503648 -307.572062) (xy 293.533213 -307.611406) (xy 293.556084 -307.654983)
			(xy 293.571668 -307.701664) (xy 293.579563 -307.750241) (xy 293.580058 -307.774848) (xy 293.918906 -307.774848)
			(xy 293.922866 -307.725794) (xy 293.934643 -307.67801) (xy 293.953934 -307.632734) (xy 293.980237 -307.591138)
			(xy 294.012872 -307.554301) (xy 294.050993 -307.523176) (xy 294.093614 -307.498569) (xy 294.13963 -307.481117)
			(xy 294.187849 -307.471273) (xy 294.237024 -307.469292) (xy 294.285879 -307.475224) (xy 294.33315 -307.488916)
			(xy 294.377612 -307.510014) (xy 294.418115 -307.53797) (xy 294.453608 -307.572062) (xy 294.483173 -307.611406)
			(xy 294.506044 -307.654983) (xy 294.521628 -307.701664) (xy 294.529523 -307.750241) (xy 294.530013 -307.774594)
			(xy 294.868866 -307.774594) (xy 294.872826 -307.72554) (xy 294.884603 -307.677756) (xy 294.903894 -307.63248)
			(xy 294.930197 -307.590884) (xy 294.962832 -307.554047) (xy 295.000953 -307.522922) (xy 295.043574 -307.498315)
			(xy 295.08959 -307.480863) (xy 295.137809 -307.471019) (xy 295.186984 -307.469038) (xy 295.235839 -307.47497)
			(xy 295.28311 -307.488662) (xy 295.327572 -307.50976) (xy 295.368075 -307.537716) (xy 295.403568 -307.571808)
			(xy 295.433133 -307.611152) (xy 295.456004 -307.654729) (xy 295.471588 -307.70141) (xy 295.479483 -307.749987)
			(xy 295.479978 -307.774594) (xy 295.81908 -307.774594) (xy 295.82304 -307.72554) (xy 295.834817 -307.677756)
			(xy 295.854108 -307.63248) (xy 295.880411 -307.590884) (xy 295.913046 -307.554047) (xy 295.951167 -307.522922)
			(xy 295.993788 -307.498315) (xy 296.039804 -307.480863) (xy 296.088023 -307.471019) (xy 296.137198 -307.469038)
			(xy 296.186053 -307.47497) (xy 296.233324 -307.488662) (xy 296.277786 -307.50976) (xy 296.318289 -307.537716)
			(xy 296.353782 -307.571808) (xy 296.383347 -307.611152) (xy 296.406218 -307.654729) (xy 296.421802 -307.70141)
			(xy 296.429697 -307.749987) (xy 296.430192 -307.774594) (xy 296.430187 -307.774848) (xy 296.76904 -307.774848)
			(xy 296.773 -307.725794) (xy 296.784777 -307.67801) (xy 296.804068 -307.632734) (xy 296.830371 -307.591138)
			(xy 296.863006 -307.554301) (xy 296.901127 -307.523176) (xy 296.943748 -307.498569) (xy 296.989764 -307.481117)
			(xy 297.037983 -307.471273) (xy 297.087158 -307.469292) (xy 297.136013 -307.475224) (xy 297.183284 -307.488916)
			(xy 297.227746 -307.510014) (xy 297.268249 -307.53797) (xy 297.303742 -307.572062) (xy 297.333307 -307.611406)
			(xy 297.356178 -307.654983) (xy 297.371762 -307.701664) (xy 297.379657 -307.750241) (xy 297.380152 -307.774848)
			(xy 297.719 -307.774848) (xy 297.72296 -307.725794) (xy 297.734737 -307.67801) (xy 297.754028 -307.632734)
			(xy 297.780331 -307.591138) (xy 297.812966 -307.554301) (xy 297.851087 -307.523176) (xy 297.893708 -307.498569)
			(xy 297.939724 -307.481117) (xy 297.987943 -307.471273) (xy 298.037118 -307.469292) (xy 298.085973 -307.475224)
			(xy 298.133244 -307.488916) (xy 298.177706 -307.510014) (xy 298.218209 -307.53797) (xy 298.253702 -307.572062)
			(xy 298.283267 -307.611406) (xy 298.306138 -307.654983) (xy 298.321722 -307.701664) (xy 298.329617 -307.750241)
			(xy 298.330112 -307.774848) (xy 298.66896 -307.774848) (xy 298.67292 -307.725794) (xy 298.684697 -307.67801)
			(xy 298.703988 -307.632734) (xy 298.730291 -307.591138) (xy 298.762926 -307.554301) (xy 298.801047 -307.523176)
			(xy 298.843668 -307.498569) (xy 298.889684 -307.481117) (xy 298.937903 -307.471273) (xy 298.987078 -307.469292)
			(xy 299.035933 -307.475224) (xy 299.083204 -307.488916) (xy 299.127666 -307.510014) (xy 299.168169 -307.53797)
			(xy 299.203662 -307.572062) (xy 299.233227 -307.611406) (xy 299.256098 -307.654983) (xy 299.271682 -307.701664)
			(xy 299.279577 -307.750241) (xy 299.280072 -307.774848) (xy 299.61892 -307.774848) (xy 299.62288 -307.725794)
			(xy 299.634657 -307.67801) (xy 299.653948 -307.632734) (xy 299.680251 -307.591138) (xy 299.712886 -307.554301)
			(xy 299.751007 -307.523176) (xy 299.793628 -307.498569) (xy 299.839644 -307.481117) (xy 299.887863 -307.471273)
			(xy 299.937038 -307.469292) (xy 299.985893 -307.475224) (xy 300.033164 -307.488916) (xy 300.077626 -307.510014)
			(xy 300.118129 -307.53797) (xy 300.153622 -307.572062) (xy 300.183187 -307.611406) (xy 300.206058 -307.654983)
			(xy 300.221642 -307.701664) (xy 300.229537 -307.750241) (xy 300.230032 -307.774848) (xy 300.56888 -307.774848)
			(xy 300.57284 -307.725794) (xy 300.584617 -307.67801) (xy 300.603908 -307.632734) (xy 300.630211 -307.591138)
			(xy 300.662846 -307.554301) (xy 300.700967 -307.523176) (xy 300.743588 -307.498569) (xy 300.789604 -307.481117)
			(xy 300.837823 -307.471273) (xy 300.886998 -307.469292) (xy 300.935853 -307.475224) (xy 300.983124 -307.488916)
			(xy 301.027586 -307.510014) (xy 301.068089 -307.53797) (xy 301.103582 -307.572062) (xy 301.133147 -307.611406)
			(xy 301.156018 -307.654983) (xy 301.171602 -307.701664) (xy 301.179497 -307.750241) (xy 301.179992 -307.774848)
			(xy 301.519094 -307.774848) (xy 301.523054 -307.725794) (xy 301.534831 -307.67801) (xy 301.554122 -307.632734)
			(xy 301.580425 -307.591138) (xy 301.61306 -307.554301) (xy 301.651181 -307.523176) (xy 301.693802 -307.498569)
			(xy 301.739818 -307.481117) (xy 301.788037 -307.471273) (xy 301.837212 -307.469292) (xy 301.886067 -307.475224)
			(xy 301.933338 -307.488916) (xy 301.9778 -307.510014) (xy 302.018303 -307.53797) (xy 302.053796 -307.572062)
			(xy 302.083361 -307.611406) (xy 302.106232 -307.654983) (xy 302.121816 -307.701664) (xy 302.129711 -307.750241)
			(xy 302.130206 -307.774848) (xy 302.469054 -307.774848) (xy 302.473014 -307.725794) (xy 302.484791 -307.67801)
			(xy 302.504082 -307.632734) (xy 302.530385 -307.591138) (xy 302.56302 -307.554301) (xy 302.601141 -307.523176)
			(xy 302.643762 -307.498569) (xy 302.689778 -307.481117) (xy 302.737997 -307.471273) (xy 302.787172 -307.469292)
			(xy 302.836027 -307.475224) (xy 302.883298 -307.488916) (xy 302.92776 -307.510014) (xy 302.968263 -307.53797)
			(xy 303.003756 -307.572062) (xy 303.033321 -307.611406) (xy 303.056192 -307.654983) (xy 303.071776 -307.701664)
			(xy 303.079671 -307.750241) (xy 303.080166 -307.774848) (xy 303.419014 -307.774848) (xy 303.422974 -307.725794)
			(xy 303.434751 -307.67801) (xy 303.454042 -307.632734) (xy 303.480345 -307.591138) (xy 303.51298 -307.554301)
			(xy 303.551101 -307.523176) (xy 303.593722 -307.498569) (xy 303.639738 -307.481117) (xy 303.687957 -307.471273)
			(xy 303.737132 -307.469292) (xy 303.785987 -307.475224) (xy 303.833258 -307.488916) (xy 303.87772 -307.510014)
			(xy 303.918223 -307.53797) (xy 303.953716 -307.572062) (xy 303.983281 -307.611406) (xy 304.006152 -307.654983)
			(xy 304.021736 -307.701664) (xy 304.029631 -307.750241) (xy 304.030126 -307.774848) (xy 304.368974 -307.774848)
			(xy 304.372934 -307.725794) (xy 304.384711 -307.67801) (xy 304.404002 -307.632734) (xy 304.430305 -307.591138)
			(xy 304.46294 -307.554301) (xy 304.501061 -307.523176) (xy 304.543682 -307.498569) (xy 304.589698 -307.481117)
			(xy 304.637917 -307.471273) (xy 304.687092 -307.469292) (xy 304.735947 -307.475224) (xy 304.783218 -307.488916)
			(xy 304.82768 -307.510014) (xy 304.868183 -307.53797) (xy 304.903676 -307.572062) (xy 304.933241 -307.611406)
			(xy 304.956112 -307.654983) (xy 304.971696 -307.701664) (xy 304.979591 -307.750241) (xy 304.980086 -307.774848)
			(xy 304.979591 -307.799455) (xy 304.971696 -307.848032) (xy 304.956112 -307.894713) (xy 304.933241 -307.93829)
			(xy 304.903676 -307.977634) (xy 304.868183 -308.011726) (xy 304.82768 -308.039682) (xy 304.783218 -308.06078)
			(xy 304.735947 -308.074472) (xy 304.687092 -308.080404) (xy 304.637917 -308.078423) (xy 304.589698 -308.068579)
			(xy 304.543682 -308.051127) (xy 304.501061 -308.02652) (xy 304.46294 -307.995395) (xy 304.430305 -307.958558)
			(xy 304.404002 -307.916962) (xy 304.384711 -307.871686) (xy 304.372934 -307.823902) (xy 304.368974 -307.774848)
			(xy 304.030126 -307.774848) (xy 304.029631 -307.799455) (xy 304.021736 -307.848032) (xy 304.006152 -307.894713)
			(xy 303.983281 -307.93829) (xy 303.953716 -307.977634) (xy 303.918223 -308.011726) (xy 303.87772 -308.039682)
			(xy 303.833258 -308.06078) (xy 303.785987 -308.074472) (xy 303.737132 -308.080404) (xy 303.687957 -308.078423)
			(xy 303.639738 -308.068579) (xy 303.593722 -308.051127) (xy 303.551101 -308.02652) (xy 303.51298 -307.995395)
			(xy 303.480345 -307.958558) (xy 303.454042 -307.916962) (xy 303.434751 -307.871686) (xy 303.422974 -307.823902)
			(xy 303.419014 -307.774848) (xy 303.080166 -307.774848) (xy 303.079671 -307.799455) (xy 303.071776 -307.848032)
			(xy 303.056192 -307.894713) (xy 303.033321 -307.93829) (xy 303.003756 -307.977634) (xy 302.968263 -308.011726)
			(xy 302.92776 -308.039682) (xy 302.883298 -308.06078) (xy 302.836027 -308.074472) (xy 302.787172 -308.080404)
			(xy 302.737997 -308.078423) (xy 302.689778 -308.068579) (xy 302.643762 -308.051127) (xy 302.601141 -308.02652)
			(xy 302.56302 -307.995395) (xy 302.530385 -307.958558) (xy 302.504082 -307.916962) (xy 302.484791 -307.871686)
			(xy 302.473014 -307.823902) (xy 302.469054 -307.774848) (xy 302.130206 -307.774848) (xy 302.129711 -307.799455)
			(xy 302.121816 -307.848032) (xy 302.106232 -307.894713) (xy 302.083361 -307.93829) (xy 302.053796 -307.977634)
			(xy 302.018303 -308.011726) (xy 301.9778 -308.039682) (xy 301.933338 -308.06078) (xy 301.886067 -308.074472)
			(xy 301.837212 -308.080404) (xy 301.788037 -308.078423) (xy 301.739818 -308.068579) (xy 301.693802 -308.051127)
			(xy 301.651181 -308.02652) (xy 301.61306 -307.995395) (xy 301.580425 -307.958558) (xy 301.554122 -307.916962)
			(xy 301.534831 -307.871686) (xy 301.523054 -307.823902) (xy 301.519094 -307.774848) (xy 301.179992 -307.774848)
			(xy 301.179497 -307.799455) (xy 301.171602 -307.848032) (xy 301.156018 -307.894713) (xy 301.133147 -307.93829)
			(xy 301.103582 -307.977634) (xy 301.068089 -308.011726) (xy 301.027586 -308.039682) (xy 300.983124 -308.06078)
			(xy 300.935853 -308.074472) (xy 300.886998 -308.080404) (xy 300.837823 -308.078423) (xy 300.789604 -308.068579)
			(xy 300.743588 -308.051127) (xy 300.700967 -308.02652) (xy 300.662846 -307.995395) (xy 300.630211 -307.958558)
			(xy 300.603908 -307.916962) (xy 300.584617 -307.871686) (xy 300.57284 -307.823902) (xy 300.56888 -307.774848)
			(xy 300.230032 -307.774848) (xy 300.229537 -307.799455) (xy 300.221642 -307.848032) (xy 300.206058 -307.894713)
			(xy 300.183187 -307.93829) (xy 300.153622 -307.977634) (xy 300.118129 -308.011726) (xy 300.077626 -308.039682)
			(xy 300.033164 -308.06078) (xy 299.985893 -308.074472) (xy 299.937038 -308.080404) (xy 299.887863 -308.078423)
			(xy 299.839644 -308.068579) (xy 299.793628 -308.051127) (xy 299.751007 -308.02652) (xy 299.712886 -307.995395)
			(xy 299.680251 -307.958558) (xy 299.653948 -307.916962) (xy 299.634657 -307.871686) (xy 299.62288 -307.823902)
			(xy 299.61892 -307.774848) (xy 299.280072 -307.774848) (xy 299.279577 -307.799455) (xy 299.271682 -307.848032)
			(xy 299.256098 -307.894713) (xy 299.233227 -307.93829) (xy 299.203662 -307.977634) (xy 299.168169 -308.011726)
			(xy 299.127666 -308.039682) (xy 299.083204 -308.06078) (xy 299.035933 -308.074472) (xy 298.987078 -308.080404)
			(xy 298.937903 -308.078423) (xy 298.889684 -308.068579) (xy 298.843668 -308.051127) (xy 298.801047 -308.02652)
			(xy 298.762926 -307.995395) (xy 298.730291 -307.958558) (xy 298.703988 -307.916962) (xy 298.684697 -307.871686)
			(xy 298.67292 -307.823902) (xy 298.66896 -307.774848) (xy 298.330112 -307.774848) (xy 298.329617 -307.799455)
			(xy 298.321722 -307.848032) (xy 298.306138 -307.894713) (xy 298.283267 -307.93829) (xy 298.253702 -307.977634)
			(xy 298.218209 -308.011726) (xy 298.177706 -308.039682) (xy 298.133244 -308.06078) (xy 298.085973 -308.074472)
			(xy 298.037118 -308.080404) (xy 297.987943 -308.078423) (xy 297.939724 -308.068579) (xy 297.893708 -308.051127)
			(xy 297.851087 -308.02652) (xy 297.812966 -307.995395) (xy 297.780331 -307.958558) (xy 297.754028 -307.916962)
			(xy 297.734737 -307.871686) (xy 297.72296 -307.823902) (xy 297.719 -307.774848) (xy 297.380152 -307.774848)
			(xy 297.379657 -307.799455) (xy 297.371762 -307.848032) (xy 297.356178 -307.894713) (xy 297.333307 -307.93829)
			(xy 297.303742 -307.977634) (xy 297.268249 -308.011726) (xy 297.227746 -308.039682) (xy 297.183284 -308.06078)
			(xy 297.136013 -308.074472) (xy 297.087158 -308.080404) (xy 297.037983 -308.078423) (xy 296.989764 -308.068579)
			(xy 296.943748 -308.051127) (xy 296.901127 -308.02652) (xy 296.863006 -307.995395) (xy 296.830371 -307.958558)
			(xy 296.804068 -307.916962) (xy 296.784777 -307.871686) (xy 296.773 -307.823902) (xy 296.76904 -307.774848)
			(xy 296.430187 -307.774848) (xy 296.429697 -307.799201) (xy 296.421802 -307.847778) (xy 296.406218 -307.894459)
			(xy 296.383347 -307.938036) (xy 296.353782 -307.97738) (xy 296.318289 -308.011472) (xy 296.277786 -308.039428)
			(xy 296.233324 -308.060526) (xy 296.186053 -308.074218) (xy 296.137198 -308.08015) (xy 296.088023 -308.078169)
			(xy 296.039804 -308.068325) (xy 295.993788 -308.050873) (xy 295.951167 -308.026266) (xy 295.913046 -307.995141)
			(xy 295.880411 -307.958304) (xy 295.854108 -307.916708) (xy 295.834817 -307.871432) (xy 295.82304 -307.823648)
			(xy 295.81908 -307.774594) (xy 295.479978 -307.774594) (xy 295.479483 -307.799201) (xy 295.471588 -307.847778)
			(xy 295.456004 -307.894459) (xy 295.433133 -307.938036) (xy 295.403568 -307.97738) (xy 295.368075 -308.011472)
			(xy 295.327572 -308.039428) (xy 295.28311 -308.060526) (xy 295.235839 -308.074218) (xy 295.186984 -308.08015)
			(xy 295.137809 -308.078169) (xy 295.08959 -308.068325) (xy 295.043574 -308.050873) (xy 295.000953 -308.026266)
			(xy 294.962832 -307.995141) (xy 294.930197 -307.958304) (xy 294.903894 -307.916708) (xy 294.884603 -307.871432)
			(xy 294.872826 -307.823648) (xy 294.868866 -307.774594) (xy 294.530013 -307.774594) (xy 294.530018 -307.774848)
			(xy 294.529523 -307.799455) (xy 294.521628 -307.848032) (xy 294.506044 -307.894713) (xy 294.483173 -307.93829)
			(xy 294.453608 -307.977634) (xy 294.418115 -308.011726) (xy 294.377612 -308.039682) (xy 294.33315 -308.06078)
			(xy 294.285879 -308.074472) (xy 294.237024 -308.080404) (xy 294.187849 -308.078423) (xy 294.13963 -308.068579)
			(xy 294.093614 -308.051127) (xy 294.050993 -308.02652) (xy 294.012872 -307.995395) (xy 293.980237 -307.958558)
			(xy 293.953934 -307.916962) (xy 293.934643 -307.871686) (xy 293.922866 -307.823902) (xy 293.918906 -307.774848)
			(xy 293.580058 -307.774848) (xy 293.579563 -307.799455) (xy 293.571668 -307.848032) (xy 293.556084 -307.894713)
			(xy 293.533213 -307.93829) (xy 293.503648 -307.977634) (xy 293.468155 -308.011726) (xy 293.427652 -308.039682)
			(xy 293.38319 -308.06078) (xy 293.335919 -308.074472) (xy 293.287064 -308.080404) (xy 293.237889 -308.078423)
			(xy 293.18967 -308.068579) (xy 293.143654 -308.051127) (xy 293.101033 -308.02652) (xy 293.062912 -307.995395)
			(xy 293.030277 -307.958558) (xy 293.003974 -307.916962) (xy 292.984683 -307.871686) (xy 292.972906 -307.823902)
			(xy 292.968946 -307.774848) (xy 292.630098 -307.774848) (xy 292.629603 -307.799455) (xy 292.621708 -307.848032)
			(xy 292.606124 -307.894713) (xy 292.583253 -307.93829) (xy 292.553688 -307.977634) (xy 292.518195 -308.011726)
			(xy 292.477692 -308.039682) (xy 292.43323 -308.06078) (xy 292.385959 -308.074472) (xy 292.337104 -308.080404)
			(xy 292.287929 -308.078423) (xy 292.23971 -308.068579) (xy 292.193694 -308.051127) (xy 292.151073 -308.02652)
			(xy 292.112952 -307.995395) (xy 292.080317 -307.958558) (xy 292.054014 -307.916962) (xy 292.034723 -307.871686)
			(xy 292.022946 -307.823902) (xy 292.018986 -307.774848) (xy 290.730178 -307.774848) (xy 290.729683 -307.799455)
			(xy 290.721788 -307.848032) (xy 290.706204 -307.894713) (xy 290.683333 -307.93829) (xy 290.653768 -307.977634)
			(xy 290.618275 -308.011726) (xy 290.577772 -308.039682) (xy 290.53331 -308.06078) (xy 290.486039 -308.074472)
			(xy 290.437184 -308.080404) (xy 290.388009 -308.078423) (xy 290.33979 -308.068579) (xy 290.293774 -308.051127)
			(xy 290.251153 -308.02652) (xy 290.213032 -307.995395) (xy 290.180397 -307.958558) (xy 290.154094 -307.916962)
			(xy 290.134803 -307.871686) (xy 290.123026 -307.823902) (xy 290.119066 -307.774848) (xy 289.780218 -307.774848)
			(xy 289.779723 -307.799455) (xy 289.771828 -307.848032) (xy 289.756244 -307.894713) (xy 289.733373 -307.93829)
			(xy 289.703808 -307.977634) (xy 289.668315 -308.011726) (xy 289.627812 -308.039682) (xy 289.58335 -308.06078)
			(xy 289.536079 -308.074472) (xy 289.487224 -308.080404) (xy 289.438049 -308.078423) (xy 289.38983 -308.068579)
			(xy 289.343814 -308.051127) (xy 289.301193 -308.02652) (xy 289.263072 -307.995395) (xy 289.230437 -307.958558)
			(xy 289.204134 -307.916962) (xy 289.184843 -307.871686) (xy 289.173066 -307.823902) (xy 289.169106 -307.774848)
			(xy 288.830258 -307.774848) (xy 288.829763 -307.799455) (xy 288.821868 -307.848032) (xy 288.806284 -307.894713)
			(xy 288.783413 -307.93829) (xy 288.753848 -307.977634) (xy 288.718355 -308.011726) (xy 288.677852 -308.039682)
			(xy 288.63339 -308.06078) (xy 288.586119 -308.074472) (xy 288.537264 -308.080404) (xy 288.488089 -308.078423)
			(xy 288.43987 -308.068579) (xy 288.393854 -308.051127) (xy 288.351233 -308.02652) (xy 288.313112 -307.995395)
			(xy 288.280477 -307.958558) (xy 288.254174 -307.916962) (xy 288.234883 -307.871686) (xy 288.223106 -307.823902)
			(xy 288.219146 -307.774848) (xy 287.880044 -307.774848) (xy 287.879549 -307.799455) (xy 287.871654 -307.848032)
			(xy 287.85607 -307.894713) (xy 287.833199 -307.93829) (xy 287.803634 -307.977634) (xy 287.768141 -308.011726)
			(xy 287.727638 -308.039682) (xy 287.683176 -308.06078) (xy 287.635905 -308.074472) (xy 287.58705 -308.080404)
			(xy 287.537875 -308.078423) (xy 287.489656 -308.068579) (xy 287.44364 -308.051127) (xy 287.401019 -308.02652)
			(xy 287.362898 -307.995395) (xy 287.330263 -307.958558) (xy 287.30396 -307.916962) (xy 287.284669 -307.871686)
			(xy 287.272892 -307.823902) (xy 287.268932 -307.774848) (xy 286.930084 -307.774848) (xy 286.929589 -307.799455)
			(xy 286.921694 -307.848032) (xy 286.90611 -307.894713) (xy 286.883239 -307.93829) (xy 286.853674 -307.977634)
			(xy 286.818181 -308.011726) (xy 286.777678 -308.039682) (xy 286.733216 -308.06078) (xy 286.685945 -308.074472)
			(xy 286.63709 -308.080404) (xy 286.587915 -308.078423) (xy 286.539696 -308.068579) (xy 286.49368 -308.051127)
			(xy 286.451059 -308.02652) (xy 286.412938 -307.995395) (xy 286.380303 -307.958558) (xy 286.354 -307.916962)
			(xy 286.334709 -307.871686) (xy 286.322932 -307.823902) (xy 286.318972 -307.774848) (xy 285.980124 -307.774848)
			(xy 285.979629 -307.799455) (xy 285.971734 -307.848032) (xy 285.95615 -307.894713) (xy 285.933279 -307.93829)
			(xy 285.903714 -307.977634) (xy 285.868221 -308.011726) (xy 285.827718 -308.039682) (xy 285.783256 -308.06078)
			(xy 285.735985 -308.074472) (xy 285.68713 -308.080404) (xy 285.637955 -308.078423) (xy 285.589736 -308.068579)
			(xy 285.54372 -308.051127) (xy 285.501099 -308.02652) (xy 285.462978 -307.995395) (xy 285.430343 -307.958558)
			(xy 285.40404 -307.916962) (xy 285.384749 -307.871686) (xy 285.372972 -307.823902) (xy 285.369012 -307.774848)
			(xy 285.030164 -307.774848) (xy 285.029669 -307.799455) (xy 285.021774 -307.848032) (xy 285.00619 -307.894713)
			(xy 284.983319 -307.93829) (xy 284.953754 -307.977634) (xy 284.918261 -308.011726) (xy 284.877758 -308.039682)
			(xy 284.833296 -308.06078) (xy 284.786025 -308.074472) (xy 284.73717 -308.080404) (xy 284.687995 -308.078423)
			(xy 284.639776 -308.068579) (xy 284.59376 -308.051127) (xy 284.551139 -308.02652) (xy 284.513018 -307.995395)
			(xy 284.480383 -307.958558) (xy 284.45408 -307.916962) (xy 284.434789 -307.871686) (xy 284.423012 -307.823902)
			(xy 284.419052 -307.774848) (xy 284.080204 -307.774848) (xy 284.079709 -307.799455) (xy 284.071814 -307.848032)
			(xy 284.05623 -307.894713) (xy 284.033359 -307.93829) (xy 284.003794 -307.977634) (xy 283.968301 -308.011726)
			(xy 283.927798 -308.039682) (xy 283.883336 -308.06078) (xy 283.836065 -308.074472) (xy 283.78721 -308.080404)
			(xy 283.738035 -308.078423) (xy 283.689816 -308.068579) (xy 283.6438 -308.051127) (xy 283.601179 -308.02652)
			(xy 283.563058 -307.995395) (xy 283.530423 -307.958558) (xy 283.50412 -307.916962) (xy 283.484829 -307.871686)
			(xy 283.473052 -307.823902) (xy 283.469092 -307.774848) (xy 283.130244 -307.774848) (xy 283.129749 -307.799455)
			(xy 283.121854 -307.848032) (xy 283.10627 -307.894713) (xy 283.083399 -307.93829) (xy 283.053834 -307.977634)
			(xy 283.018341 -308.011726) (xy 282.977838 -308.039682) (xy 282.933376 -308.06078) (xy 282.886105 -308.074472)
			(xy 282.83725 -308.080404) (xy 282.788075 -308.078423) (xy 282.739856 -308.068579) (xy 282.69384 -308.051127)
			(xy 282.651219 -308.02652) (xy 282.613098 -307.995395) (xy 282.580463 -307.958558) (xy 282.55416 -307.916962)
			(xy 282.534869 -307.871686) (xy 282.523092 -307.823902) (xy 282.519132 -307.774848) (xy 282.18003 -307.774848)
			(xy 282.179535 -307.799455) (xy 282.17164 -307.848032) (xy 282.156056 -307.894713) (xy 282.133185 -307.93829)
			(xy 282.10362 -307.977634) (xy 282.068127 -308.011726) (xy 282.027624 -308.039682) (xy 281.983162 -308.06078)
			(xy 281.935891 -308.074472) (xy 281.887036 -308.080404) (xy 281.837861 -308.078423) (xy 281.789642 -308.068579)
			(xy 281.743626 -308.051127) (xy 281.701005 -308.02652) (xy 281.662884 -307.995395) (xy 281.630249 -307.958558)
			(xy 281.603946 -307.916962) (xy 281.584655 -307.871686) (xy 281.572878 -307.823902) (xy 281.568918 -307.774848)
			(xy 281.23007 -307.774848) (xy 281.229575 -307.799455) (xy 281.22168 -307.848032) (xy 281.206096 -307.894713)
			(xy 281.183225 -307.93829) (xy 281.15366 -307.977634) (xy 281.118167 -308.011726) (xy 281.077664 -308.039682)
			(xy 281.033202 -308.06078) (xy 280.985931 -308.074472) (xy 280.937076 -308.080404) (xy 280.887901 -308.078423)
			(xy 280.839682 -308.068579) (xy 280.793666 -308.051127) (xy 280.751045 -308.02652) (xy 280.712924 -307.995395)
			(xy 280.680289 -307.958558) (xy 280.653986 -307.916962) (xy 280.634695 -307.871686) (xy 280.622918 -307.823902)
			(xy 280.618958 -307.774848) (xy 280.28011 -307.774848) (xy 280.28011 -307.791358) (xy 280.279602 -307.7972)
			(xy 280.279602 -307.797708) (xy 280.278332 -307.80863) (xy 280.278332 -307.808884) (xy 280.277824 -307.812948)
			(xy 280.275284 -307.831744) (xy 280.274268 -307.837332) (xy 280.270204 -307.85308) (xy 280.268426 -307.86578)
			(xy 280.268426 -308.249828) (xy 305.793914 -308.249828) (xy 305.797874 -308.200774) (xy 305.809651 -308.15299)
			(xy 305.828942 -308.107714) (xy 305.855245 -308.066118) (xy 305.88788 -308.029281) (xy 305.926001 -307.998156)
			(xy 305.968622 -307.973549) (xy 306.014638 -307.956097) (xy 306.062857 -307.946253) (xy 306.112032 -307.944272)
			(xy 306.160887 -307.950204) (xy 306.208158 -307.963896) (xy 306.25262 -307.984994) (xy 306.293123 -308.01295)
			(xy 306.328616 -308.047042) (xy 306.358181 -308.086386) (xy 306.381052 -308.129963) (xy 306.396636 -308.176644)
			(xy 306.404531 -308.225221) (xy 306.405026 -308.249828) (xy 306.744128 -308.249828) (xy 306.748088 -308.200774)
			(xy 306.759865 -308.15299) (xy 306.779156 -308.107714) (xy 306.805459 -308.066118) (xy 306.838094 -308.029281)
			(xy 306.876215 -307.998156) (xy 306.918836 -307.973549) (xy 306.964852 -307.956097) (xy 307.013071 -307.946253)
			(xy 307.062246 -307.944272) (xy 307.111101 -307.950204) (xy 307.158372 -307.963896) (xy 307.202834 -307.984994)
			(xy 307.243337 -308.01295) (xy 307.27883 -308.047042) (xy 307.308395 -308.086386) (xy 307.331266 -308.129963)
			(xy 307.34685 -308.176644) (xy 307.354745 -308.225221) (xy 307.35524 -308.249828) (xy 307.694088 -308.249828)
			(xy 307.698048 -308.200774) (xy 307.709825 -308.15299) (xy 307.729116 -308.107714) (xy 307.755419 -308.066118)
			(xy 307.788054 -308.029281) (xy 307.826175 -307.998156) (xy 307.868796 -307.973549) (xy 307.914812 -307.956097)
			(xy 307.963031 -307.946253) (xy 308.012206 -307.944272) (xy 308.061061 -307.950204) (xy 308.108332 -307.963896)
			(xy 308.152794 -307.984994) (xy 308.193297 -308.01295) (xy 308.22879 -308.047042) (xy 308.258355 -308.086386)
			(xy 308.281226 -308.129963) (xy 308.29681 -308.176644) (xy 308.304705 -308.225221) (xy 308.3052 -308.249828)
			(xy 308.644048 -308.249828) (xy 308.648008 -308.200774) (xy 308.659785 -308.15299) (xy 308.679076 -308.107714)
			(xy 308.705379 -308.066118) (xy 308.738014 -308.029281) (xy 308.776135 -307.998156) (xy 308.818756 -307.973549)
			(xy 308.864772 -307.956097) (xy 308.912991 -307.946253) (xy 308.962166 -307.944272) (xy 309.011021 -307.950204)
			(xy 309.058292 -307.963896) (xy 309.102754 -307.984994) (xy 309.143257 -308.01295) (xy 309.17875 -308.047042)
			(xy 309.208315 -308.086386) (xy 309.231186 -308.129963) (xy 309.24677 -308.176644) (xy 309.254665 -308.225221)
			(xy 309.25516 -308.249828) (xy 309.594008 -308.249828) (xy 309.597968 -308.200774) (xy 309.609745 -308.15299)
			(xy 309.629036 -308.107714) (xy 309.655339 -308.066118) (xy 309.687974 -308.029281) (xy 309.726095 -307.998156)
			(xy 309.768716 -307.973549) (xy 309.814732 -307.956097) (xy 309.862951 -307.946253) (xy 309.912126 -307.944272)
			(xy 309.960981 -307.950204) (xy 310.008252 -307.963896) (xy 310.052714 -307.984994) (xy 310.093217 -308.01295)
			(xy 310.12871 -308.047042) (xy 310.158275 -308.086386) (xy 310.181146 -308.129963) (xy 310.19673 -308.176644)
			(xy 310.204625 -308.225221) (xy 310.20512 -308.249828) (xy 310.543968 -308.249828) (xy 310.547928 -308.200774)
			(xy 310.559705 -308.15299) (xy 310.578996 -308.107714) (xy 310.605299 -308.066118) (xy 310.637934 -308.029281)
			(xy 310.676055 -307.998156) (xy 310.718676 -307.973549) (xy 310.764692 -307.956097) (xy 310.812911 -307.946253)
			(xy 310.862086 -307.944272) (xy 310.910941 -307.950204) (xy 310.958212 -307.963896) (xy 311.002674 -307.984994)
			(xy 311.043177 -308.01295) (xy 311.07867 -308.047042) (xy 311.108235 -308.086386) (xy 311.131106 -308.129963)
			(xy 311.14669 -308.176644) (xy 311.154585 -308.225221) (xy 311.15508 -308.249828) (xy 311.493928 -308.249828)
			(xy 311.497888 -308.200774) (xy 311.509665 -308.15299) (xy 311.528956 -308.107714) (xy 311.555259 -308.066118)
			(xy 311.587894 -308.029281) (xy 311.626015 -307.998156) (xy 311.668636 -307.973549) (xy 311.714652 -307.956097)
			(xy 311.762871 -307.946253) (xy 311.812046 -307.944272) (xy 311.860901 -307.950204) (xy 311.908172 -307.963896)
			(xy 311.952634 -307.984994) (xy 311.993137 -308.01295) (xy 312.02863 -308.047042) (xy 312.058195 -308.086386)
			(xy 312.081066 -308.129963) (xy 312.09665 -308.176644) (xy 312.104545 -308.225221) (xy 312.10504 -308.249828)
			(xy 312.443888 -308.249828) (xy 312.447848 -308.200774) (xy 312.459625 -308.15299) (xy 312.478916 -308.107714)
			(xy 312.505219 -308.066118) (xy 312.537854 -308.029281) (xy 312.575975 -307.998156) (xy 312.618596 -307.973549)
			(xy 312.664612 -307.956097) (xy 312.712831 -307.946253) (xy 312.762006 -307.944272) (xy 312.810861 -307.950204)
			(xy 312.858132 -307.963896) (xy 312.902594 -307.984994) (xy 312.943097 -308.01295) (xy 312.97859 -308.047042)
			(xy 313.008155 -308.086386) (xy 313.031026 -308.129963) (xy 313.04661 -308.176644) (xy 313.054505 -308.225221)
			(xy 313.055 -308.249828) (xy 313.394102 -308.249828) (xy 313.398062 -308.200774) (xy 313.409839 -308.15299)
			(xy 313.42913 -308.107714) (xy 313.455433 -308.066118) (xy 313.488068 -308.029281) (xy 313.526189 -307.998156)
			(xy 313.56881 -307.973549) (xy 313.614826 -307.956097) (xy 313.663045 -307.946253) (xy 313.71222 -307.944272)
			(xy 313.761075 -307.950204) (xy 313.808346 -307.963896) (xy 313.852808 -307.984994) (xy 313.893311 -308.01295)
			(xy 313.928804 -308.047042) (xy 313.958369 -308.086386) (xy 313.98124 -308.129963) (xy 313.996824 -308.176644)
			(xy 314.004719 -308.225221) (xy 314.005214 -308.249828) (xy 314.344062 -308.249828) (xy 314.348022 -308.200774)
			(xy 314.359799 -308.15299) (xy 314.37909 -308.107714) (xy 314.405393 -308.066118) (xy 314.438028 -308.029281)
			(xy 314.476149 -307.998156) (xy 314.51877 -307.973549) (xy 314.564786 -307.956097) (xy 314.613005 -307.946253)
			(xy 314.66218 -307.944272) (xy 314.711035 -307.950204) (xy 314.758306 -307.963896) (xy 314.802768 -307.984994)
			(xy 314.843271 -308.01295) (xy 314.878764 -308.047042) (xy 314.908329 -308.086386) (xy 314.9312 -308.129963)
			(xy 314.946784 -308.176644) (xy 314.954679 -308.225221) (xy 314.955174 -308.249828) (xy 315.294276 -308.249828)
			(xy 315.298236 -308.200774) (xy 315.310013 -308.15299) (xy 315.329304 -308.107714) (xy 315.355607 -308.066118)
			(xy 315.388242 -308.029281) (xy 315.426363 -307.998156) (xy 315.468984 -307.973549) (xy 315.515 -307.956097)
			(xy 315.563219 -307.946253) (xy 315.612394 -307.944272) (xy 315.661249 -307.950204) (xy 315.70852 -307.963896)
			(xy 315.752982 -307.984994) (xy 315.793485 -308.01295) (xy 315.828978 -308.047042) (xy 315.858543 -308.086386)
			(xy 315.881414 -308.129963) (xy 315.896998 -308.176644) (xy 315.904893 -308.225221) (xy 315.905388 -308.249828)
			(xy 315.904893 -308.274435) (xy 315.896998 -308.323012) (xy 315.881414 -308.369693) (xy 315.858543 -308.41327)
			(xy 315.828978 -308.452614) (xy 315.793485 -308.486706) (xy 315.752982 -308.514662) (xy 315.70852 -308.53576)
			(xy 315.661249 -308.549452) (xy 315.612394 -308.555384) (xy 315.563219 -308.553403) (xy 315.515 -308.543559)
			(xy 315.468984 -308.526107) (xy 315.426363 -308.5015) (xy 315.388242 -308.470375) (xy 315.355607 -308.433538)
			(xy 315.329304 -308.391942) (xy 315.310013 -308.346666) (xy 315.298236 -308.298882) (xy 315.294276 -308.249828)
			(xy 314.955174 -308.249828) (xy 314.954679 -308.274435) (xy 314.946784 -308.323012) (xy 314.9312 -308.369693)
			(xy 314.908329 -308.41327) (xy 314.878764 -308.452614) (xy 314.843271 -308.486706) (xy 314.802768 -308.514662)
			(xy 314.758306 -308.53576) (xy 314.711035 -308.549452) (xy 314.66218 -308.555384) (xy 314.613005 -308.553403)
			(xy 314.564786 -308.543559) (xy 314.51877 -308.526107) (xy 314.476149 -308.5015) (xy 314.438028 -308.470375)
			(xy 314.405393 -308.433538) (xy 314.37909 -308.391942) (xy 314.359799 -308.346666) (xy 314.348022 -308.298882)
			(xy 314.344062 -308.249828) (xy 314.005214 -308.249828) (xy 314.004719 -308.274435) (xy 313.996824 -308.323012)
			(xy 313.98124 -308.369693) (xy 313.958369 -308.41327) (xy 313.928804 -308.452614) (xy 313.893311 -308.486706)
			(xy 313.852808 -308.514662) (xy 313.808346 -308.53576) (xy 313.761075 -308.549452) (xy 313.71222 -308.555384)
			(xy 313.663045 -308.553403) (xy 313.614826 -308.543559) (xy 313.56881 -308.526107) (xy 313.526189 -308.5015)
			(xy 313.488068 -308.470375) (xy 313.455433 -308.433538) (xy 313.42913 -308.391942) (xy 313.409839 -308.346666)
			(xy 313.398062 -308.298882) (xy 313.394102 -308.249828) (xy 313.055 -308.249828) (xy 313.054505 -308.274435)
			(xy 313.04661 -308.323012) (xy 313.031026 -308.369693) (xy 313.008155 -308.41327) (xy 312.97859 -308.452614)
			(xy 312.943097 -308.486706) (xy 312.902594 -308.514662) (xy 312.858132 -308.53576) (xy 312.810861 -308.549452)
			(xy 312.762006 -308.555384) (xy 312.712831 -308.553403) (xy 312.664612 -308.543559) (xy 312.618596 -308.526107)
			(xy 312.575975 -308.5015) (xy 312.537854 -308.470375) (xy 312.505219 -308.433538) (xy 312.478916 -308.391942)
			(xy 312.459625 -308.346666) (xy 312.447848 -308.298882) (xy 312.443888 -308.249828) (xy 312.10504 -308.249828)
			(xy 312.104545 -308.274435) (xy 312.09665 -308.323012) (xy 312.081066 -308.369693) (xy 312.058195 -308.41327)
			(xy 312.02863 -308.452614) (xy 311.993137 -308.486706) (xy 311.952634 -308.514662) (xy 311.908172 -308.53576)
			(xy 311.860901 -308.549452) (xy 311.812046 -308.555384) (xy 311.762871 -308.553403) (xy 311.714652 -308.543559)
			(xy 311.668636 -308.526107) (xy 311.626015 -308.5015) (xy 311.587894 -308.470375) (xy 311.555259 -308.433538)
			(xy 311.528956 -308.391942) (xy 311.509665 -308.346666) (xy 311.497888 -308.298882) (xy 311.493928 -308.249828)
			(xy 311.15508 -308.249828) (xy 311.154585 -308.274435) (xy 311.14669 -308.323012) (xy 311.131106 -308.369693)
			(xy 311.108235 -308.41327) (xy 311.07867 -308.452614) (xy 311.043177 -308.486706) (xy 311.002674 -308.514662)
			(xy 310.958212 -308.53576) (xy 310.910941 -308.549452) (xy 310.862086 -308.555384) (xy 310.812911 -308.553403)
			(xy 310.764692 -308.543559) (xy 310.718676 -308.526107) (xy 310.676055 -308.5015) (xy 310.637934 -308.470375)
			(xy 310.605299 -308.433538) (xy 310.578996 -308.391942) (xy 310.559705 -308.346666) (xy 310.547928 -308.298882)
			(xy 310.543968 -308.249828) (xy 310.20512 -308.249828) (xy 310.204625 -308.274435) (xy 310.19673 -308.323012)
			(xy 310.181146 -308.369693) (xy 310.158275 -308.41327) (xy 310.12871 -308.452614) (xy 310.093217 -308.486706)
			(xy 310.052714 -308.514662) (xy 310.008252 -308.53576) (xy 309.960981 -308.549452) (xy 309.912126 -308.555384)
			(xy 309.862951 -308.553403) (xy 309.814732 -308.543559) (xy 309.768716 -308.526107) (xy 309.726095 -308.5015)
			(xy 309.687974 -308.470375) (xy 309.655339 -308.433538) (xy 309.629036 -308.391942) (xy 309.609745 -308.346666)
			(xy 309.597968 -308.298882) (xy 309.594008 -308.249828) (xy 309.25516 -308.249828) (xy 309.254665 -308.274435)
			(xy 309.24677 -308.323012) (xy 309.231186 -308.369693) (xy 309.208315 -308.41327) (xy 309.17875 -308.452614)
			(xy 309.143257 -308.486706) (xy 309.102754 -308.514662) (xy 309.058292 -308.53576) (xy 309.011021 -308.549452)
			(xy 308.962166 -308.555384) (xy 308.912991 -308.553403) (xy 308.864772 -308.543559) (xy 308.818756 -308.526107)
			(xy 308.776135 -308.5015) (xy 308.738014 -308.470375) (xy 308.705379 -308.433538) (xy 308.679076 -308.391942)
			(xy 308.659785 -308.346666) (xy 308.648008 -308.298882) (xy 308.644048 -308.249828) (xy 308.3052 -308.249828)
			(xy 308.304705 -308.274435) (xy 308.29681 -308.323012) (xy 308.281226 -308.369693) (xy 308.258355 -308.41327)
			(xy 308.22879 -308.452614) (xy 308.193297 -308.486706) (xy 308.152794 -308.514662) (xy 308.108332 -308.53576)
			(xy 308.061061 -308.549452) (xy 308.012206 -308.555384) (xy 307.963031 -308.553403) (xy 307.914812 -308.543559)
			(xy 307.868796 -308.526107) (xy 307.826175 -308.5015) (xy 307.788054 -308.470375) (xy 307.755419 -308.433538)
			(xy 307.729116 -308.391942) (xy 307.709825 -308.346666) (xy 307.698048 -308.298882) (xy 307.694088 -308.249828)
			(xy 307.35524 -308.249828) (xy 307.354745 -308.274435) (xy 307.34685 -308.323012) (xy 307.331266 -308.369693)
			(xy 307.308395 -308.41327) (xy 307.27883 -308.452614) (xy 307.243337 -308.486706) (xy 307.202834 -308.514662)
			(xy 307.158372 -308.53576) (xy 307.111101 -308.549452) (xy 307.062246 -308.555384) (xy 307.013071 -308.553403)
			(xy 306.964852 -308.543559) (xy 306.918836 -308.526107) (xy 306.876215 -308.5015) (xy 306.838094 -308.470375)
			(xy 306.805459 -308.433538) (xy 306.779156 -308.391942) (xy 306.759865 -308.346666) (xy 306.748088 -308.298882)
			(xy 306.744128 -308.249828) (xy 306.405026 -308.249828) (xy 306.404531 -308.274435) (xy 306.396636 -308.323012)
			(xy 306.381052 -308.369693) (xy 306.358181 -308.41327) (xy 306.328616 -308.452614) (xy 306.293123 -308.486706)
			(xy 306.25262 -308.514662) (xy 306.208158 -308.53576) (xy 306.160887 -308.549452) (xy 306.112032 -308.555384)
			(xy 306.062857 -308.553403) (xy 306.014638 -308.543559) (xy 305.968622 -308.526107) (xy 305.926001 -308.5015)
			(xy 305.88788 -308.470375) (xy 305.855245 -308.433538) (xy 305.828942 -308.391942) (xy 305.809651 -308.346666)
			(xy 305.797874 -308.298882) (xy 305.793914 -308.249828) (xy 280.268426 -308.249828) (xy 280.268426 -308.630066)
			(xy 280.268934 -308.636162) (xy 280.270204 -308.647338) (xy 280.270966 -308.65064) (xy 280.270966 -308.651148)
			(xy 280.275217 -308.669267) (xy 280.2798 -308.7062) (xy 280.28011 -308.724808) (xy 280.618958 -308.724808)
			(xy 280.622918 -308.675754) (xy 280.634695 -308.62797) (xy 280.653986 -308.582694) (xy 280.680289 -308.541098)
			(xy 280.712924 -308.504261) (xy 280.751045 -308.473136) (xy 280.793666 -308.448529) (xy 280.839682 -308.431077)
			(xy 280.887901 -308.421233) (xy 280.937076 -308.419252) (xy 280.985931 -308.425184) (xy 281.033202 -308.438876)
			(xy 281.077664 -308.459974) (xy 281.118167 -308.48793) (xy 281.15366 -308.522022) (xy 281.183225 -308.561366)
			(xy 281.206096 -308.604943) (xy 281.22168 -308.651624) (xy 281.229575 -308.700201) (xy 281.23007 -308.724808)
			(xy 281.229575 -308.749415) (xy 281.22168 -308.797992) (xy 281.206096 -308.844673) (xy 281.183225 -308.88825)
			(xy 281.15366 -308.927594) (xy 281.118167 -308.961686) (xy 281.077664 -308.989642) (xy 281.033202 -309.01074)
			(xy 280.985931 -309.024432) (xy 280.937076 -309.030364) (xy 280.887901 -309.028383) (xy 280.839682 -309.018539)
			(xy 280.793666 -309.001087) (xy 280.751045 -308.97648) (xy 280.712924 -308.945355) (xy 280.680289 -308.908518)
			(xy 280.653986 -308.866922) (xy 280.634695 -308.821646) (xy 280.622918 -308.773862) (xy 280.618958 -308.724808)
			(xy 280.28011 -308.724808) (xy 280.28011 -308.741318) (xy 280.279602 -308.74716) (xy 280.279602 -308.747668)
			(xy 280.278332 -308.75859) (xy 280.278332 -308.758844) (xy 280.277824 -308.762908) (xy 280.275284 -308.781704)
			(xy 280.274268 -308.787292) (xy 280.270204 -308.80304) (xy 280.268426 -308.81574) (xy 280.268426 -309.559452)
			(xy 280.272236 -309.56885) (xy 280.274005 -309.573479) (xy 280.275916 -309.5832) (xy 280.276046 -309.588154)
			(xy 280.276046 -309.624984) (xy 280.276554 -309.628794) (xy 280.276554 -309.629048) (xy 280.279094 -309.651146)
			(xy 280.279094 -309.651654) (xy 280.280264 -309.660535) (xy 280.287809 -309.676767) (xy 280.293826 -309.683404)
			(xy 280.381202 -309.77078) (xy 280.387668 -309.776823) (xy 280.403669 -309.784359) (xy 280.412444 -309.785512)
			(xy 280.414984 -309.785766) (xy 280.517854 -309.785766) (xy 280.528008 -309.785314) (xy 280.546732 -309.777448)
			(xy 280.554176 -309.770526) (xy 280.612342 -309.710836) (xy 280.619708 -309.692294) (xy 280.619454 -309.68188)
			(xy 280.619454 -309.674768) (xy 280.619976 -309.649513) (xy 280.628289 -309.599691) (xy 280.64469 -309.551917)
			(xy 280.668731 -309.507494) (xy 280.699755 -309.467634) (xy 280.736917 -309.433424) (xy 280.779203 -309.405798)
			(xy 280.825459 -309.385508) (xy 280.874424 -309.373108) (xy 280.924762 -309.368937) (xy 280.9751 -309.373108)
			(xy 281.024065 -309.385508) (xy 281.070321 -309.405798) (xy 281.112607 -309.433424) (xy 281.149769 -309.467634)
			(xy 281.180793 -309.507494) (xy 281.204834 -309.551917) (xy 281.221235 -309.599691) (xy 281.229548 -309.649513)
			(xy 281.23007 -309.674768) (xy 281.23007 -309.68188) (xy 281.229816 -309.692294) (xy 281.237182 -309.710836)
			(xy 281.27706 -309.75173) (xy 281.295348 -309.770526) (xy 281.302773 -309.777478) (xy 281.321508 -309.78535)
			(xy 281.33167 -309.785766) (xy 281.467814 -309.785766) (xy 281.477971 -309.785322) (xy 281.496706 -309.777466)
			(xy 281.504136 -309.770526) (xy 281.562302 -309.710836) (xy 281.569668 -309.692294) (xy 281.569414 -309.68188)
			(xy 281.569414 -309.674768) (xy 281.569887 -309.650779) (xy 281.577397 -309.603393) (xy 281.592228 -309.557764)
			(xy 281.614013 -309.515018) (xy 281.642218 -309.476205) (xy 281.676146 -309.442283) (xy 281.714964 -309.414085)
			(xy 281.757714 -309.392307) (xy 281.803345 -309.377485) (xy 281.850733 -309.369983) (xy 281.874722 -309.36946)
			(xy 281.888904 -309.369648) (xy 281.917143 -309.372323) (xy 281.93111 -309.374794) (xy 281.943556 -309.37708)
			(xy 281.967178 -309.369714) (xy 282.044648 -309.292244) (xy 282.052014 -309.268622) (xy 282.049728 -309.256176)
			(xy 282.047243 -309.242211) (xy 282.044572 -309.213971) (xy 282.044394 -309.199788) (xy 282.044581 -309.185606)
			(xy 282.047256 -309.157367) (xy 282.049728 -309.1434) (xy 282.052014 -309.130954) (xy 282.044648 -309.107332)
			(xy 281.967178 -309.029862) (xy 281.943556 -309.022496) (xy 281.93111 -309.024782) (xy 281.917145 -309.027268)
			(xy 281.888905 -309.029942) (xy 281.874722 -309.030116) (xy 281.8499 -309.029632) (xy 281.800909 -309.021604)
			(xy 281.753863 -309.005755) (xy 281.71 -308.982504) (xy 281.670477 -308.952463) (xy 281.636335 -308.916424)
			(xy 281.608474 -308.875336) (xy 281.587626 -308.830281) (xy 281.574343 -308.782447) (xy 281.568973 -308.733094)
			(xy 281.571659 -308.683523) (xy 281.58233 -308.635039) (xy 281.600703 -308.58892) (xy 281.626296 -308.546382)
			(xy 281.658434 -308.508544) (xy 281.69627 -308.476404) (xy 281.738808 -308.45081) (xy 281.784926 -308.432434)
			(xy 281.833409 -308.421761) (xy 281.88298 -308.419073) (xy 281.932333 -308.42444) (xy 281.980168 -308.437722)
			(xy 282.025223 -308.458567) (xy 282.066313 -308.486426) (xy 282.102354 -308.520567) (xy 282.132397 -308.560089)
			(xy 282.15565 -308.60395) (xy 282.1715 -308.650996) (xy 282.179531 -308.699986) (xy 282.18003 -308.724808)
			(xy 282.179843 -308.73899) (xy 282.177169 -308.76723) (xy 282.174696 -308.781196) (xy 282.17241 -308.793642)
			(xy 282.179776 -308.817264) (xy 282.257246 -308.894734) (xy 282.280868 -308.9021) (xy 282.293314 -308.899814)
			(xy 282.307279 -308.897329) (xy 282.335519 -308.894657) (xy 282.349702 -308.89448) (xy 282.373693 -308.894951)
			(xy 282.421086 -308.902457) (xy 282.46672 -308.917284) (xy 282.509473 -308.939068) (xy 282.548293 -308.967271)
			(xy 282.582222 -309.0012) (xy 282.610427 -309.040018) (xy 282.632212 -309.082771) (xy 282.647041 -309.128405)
			(xy 282.654548 -309.175797) (xy 282.65501 -309.199788) (xy 282.654824 -309.21397) (xy 282.652152 -309.24221)
			(xy 282.649676 -309.256176) (xy 282.64739 -309.268622) (xy 282.654756 -309.292498) (xy 282.731972 -309.369714)
			(xy 282.756102 -309.37708) (xy 282.768294 -309.374794) (xy 282.782321 -309.372294) (xy 282.810689 -309.369619)
			(xy 282.824936 -309.36946) (xy 282.839119 -309.369644) (xy 282.867359 -309.372311) (xy 282.881324 -309.374794)
			(xy 282.89377 -309.37708) (xy 282.917392 -309.369714) (xy 282.994862 -309.292244) (xy 283.002228 -309.268622)
			(xy 282.999942 -309.256176) (xy 282.997457 -309.242211) (xy 282.994786 -309.213971) (xy 282.994608 -309.199788)
			(xy 282.995055 -309.175796) (xy 283.002563 -309.128403) (xy 283.017393 -309.082768) (xy 283.039179 -309.040015)
			(xy 283.067386 -309.001196) (xy 283.101317 -308.967267) (xy 283.140138 -308.939065) (xy 283.182894 -308.917283)
			(xy 283.22853 -308.902457) (xy 283.275924 -308.894953) (xy 283.299916 -308.89448) (xy 283.314098 -308.894667)
			(xy 283.342337 -308.897342) (xy 283.356304 -308.899814) (xy 283.36875 -308.9021) (xy 283.392372 -308.894734)
			(xy 283.469842 -308.817264) (xy 283.477208 -308.793642) (xy 283.474922 -308.781196) (xy 283.472436 -308.767231)
			(xy 283.469764 -308.738991) (xy 283.469588 -308.724808) (xy 283.470073 -308.699987) (xy 283.478103 -308.650998)
			(xy 283.493953 -308.603953) (xy 283.517205 -308.560093) (xy 283.547247 -308.520572) (xy 283.583287 -308.486432)
			(xy 283.624375 -308.458572) (xy 283.669429 -308.437727) (xy 283.717262 -308.424445) (xy 283.766614 -308.419077)
			(xy 283.816184 -308.421764) (xy 283.864666 -308.432435) (xy 283.910784 -308.45081) (xy 283.953321 -308.476403)
			(xy 283.991157 -308.508541) (xy 284.023295 -308.546376) (xy 284.048889 -308.588913) (xy 284.067263 -308.63503)
			(xy 284.077935 -308.683512) (xy 284.080174 -308.724808) (xy 284.419052 -308.724808) (xy 284.423012 -308.675754)
			(xy 284.434789 -308.62797) (xy 284.45408 -308.582694) (xy 284.480383 -308.541098) (xy 284.513018 -308.504261)
			(xy 284.551139 -308.473136) (xy 284.59376 -308.448529) (xy 284.639776 -308.431077) (xy 284.687995 -308.421233)
			(xy 284.73717 -308.419252) (xy 284.786025 -308.425184) (xy 284.833296 -308.438876) (xy 284.877758 -308.459974)
			(xy 284.918261 -308.48793) (xy 284.953754 -308.522022) (xy 284.983319 -308.561366) (xy 285.00619 -308.604943)
			(xy 285.021774 -308.651624) (xy 285.029669 -308.700201) (xy 285.030164 -308.724808) (xy 285.369012 -308.724808)
			(xy 285.372972 -308.675754) (xy 285.384749 -308.62797) (xy 285.40404 -308.582694) (xy 285.430343 -308.541098)
			(xy 285.462978 -308.504261) (xy 285.501099 -308.473136) (xy 285.54372 -308.448529) (xy 285.589736 -308.431077)
			(xy 285.637955 -308.421233) (xy 285.68713 -308.419252) (xy 285.735985 -308.425184) (xy 285.783256 -308.438876)
			(xy 285.827718 -308.459974) (xy 285.868221 -308.48793) (xy 285.903714 -308.522022) (xy 285.933279 -308.561366)
			(xy 285.95615 -308.604943) (xy 285.971734 -308.651624) (xy 285.979629 -308.700201) (xy 285.980124 -308.724808)
			(xy 286.318972 -308.724808) (xy 286.322932 -308.675754) (xy 286.334709 -308.62797) (xy 286.354 -308.582694)
			(xy 286.380303 -308.541098) (xy 286.412938 -308.504261) (xy 286.451059 -308.473136) (xy 286.49368 -308.448529)
			(xy 286.539696 -308.431077) (xy 286.587915 -308.421233) (xy 286.63709 -308.419252) (xy 286.685945 -308.425184)
			(xy 286.733216 -308.438876) (xy 286.777678 -308.459974) (xy 286.818181 -308.48793) (xy 286.853674 -308.522022)
			(xy 286.883239 -308.561366) (xy 286.90611 -308.604943) (xy 286.921694 -308.651624) (xy 286.929589 -308.700201)
			(xy 286.930084 -308.724808) (xy 286.929589 -308.749415) (xy 286.921694 -308.797992) (xy 286.90611 -308.844673)
			(xy 286.883239 -308.88825) (xy 286.853674 -308.927594) (xy 286.818181 -308.961686) (xy 286.777678 -308.989642)
			(xy 286.733216 -309.01074) (xy 286.685945 -309.024432) (xy 286.63709 -309.030364) (xy 286.587915 -309.028383)
			(xy 286.539696 -309.018539) (xy 286.49368 -309.001087) (xy 286.451059 -308.97648) (xy 286.412938 -308.945355)
			(xy 286.380303 -308.908518) (xy 286.354 -308.866922) (xy 286.334709 -308.821646) (xy 286.322932 -308.773862)
			(xy 286.318972 -308.724808) (xy 285.980124 -308.724808) (xy 285.979629 -308.749415) (xy 285.971734 -308.797992)
			(xy 285.95615 -308.844673) (xy 285.933279 -308.88825) (xy 285.903714 -308.927594) (xy 285.868221 -308.961686)
			(xy 285.827718 -308.989642) (xy 285.783256 -309.01074) (xy 285.735985 -309.024432) (xy 285.68713 -309.030364)
			(xy 285.637955 -309.028383) (xy 285.589736 -309.018539) (xy 285.54372 -309.001087) (xy 285.501099 -308.97648)
			(xy 285.462978 -308.945355) (xy 285.430343 -308.908518) (xy 285.40404 -308.866922) (xy 285.384749 -308.821646)
			(xy 285.372972 -308.773862) (xy 285.369012 -308.724808) (xy 285.030164 -308.724808) (xy 285.029669 -308.749415)
			(xy 285.021774 -308.797992) (xy 285.00619 -308.844673) (xy 284.983319 -308.88825) (xy 284.953754 -308.927594)
			(xy 284.918261 -308.961686) (xy 284.877758 -308.989642) (xy 284.833296 -309.01074) (xy 284.786025 -309.024432)
			(xy 284.73717 -309.030364) (xy 284.687995 -309.028383) (xy 284.639776 -309.018539) (xy 284.59376 -309.001087)
			(xy 284.551139 -308.97648) (xy 284.513018 -308.945355) (xy 284.480383 -308.908518) (xy 284.45408 -308.866922)
			(xy 284.434789 -308.821646) (xy 284.423012 -308.773862) (xy 284.419052 -308.724808) (xy 284.080174 -308.724808)
			(xy 284.080623 -308.733082) (xy 284.075255 -308.782434) (xy 284.061975 -308.830267) (xy 284.04113 -308.875321)
			(xy 284.013271 -308.91641) (xy 283.979131 -308.95245) (xy 283.939611 -308.982492) (xy 283.895751 -309.005745)
			(xy 283.848706 -309.021596) (xy 283.799717 -309.029626) (xy 283.774896 -309.030116) (xy 283.760714 -309.029929)
			(xy 283.732474 -309.027256) (xy 283.718508 -309.024782) (xy 283.706062 -309.022496) (xy 283.68244 -309.029862)
			(xy 283.60497 -309.107332) (xy 283.597604 -309.130954) (xy 283.59989 -309.1434) (xy 283.602376 -309.157365)
			(xy 283.605049 -309.185605) (xy 283.605224 -309.199788) (xy 283.605038 -309.21397) (xy 283.602366 -309.24221)
			(xy 283.59989 -309.256176) (xy 283.597604 -309.268622) (xy 283.60497 -309.292244) (xy 283.68244 -309.369714)
			(xy 283.706062 -309.37708) (xy 283.718508 -309.374794) (xy 283.732473 -309.372309) (xy 283.760713 -309.369637)
			(xy 283.774896 -309.36946) (xy 283.798888 -309.36993) (xy 283.846282 -309.377436) (xy 283.891919 -309.392262)
			(xy 283.934675 -309.414045) (xy 283.973496 -309.442248) (xy 284.007429 -309.476176) (xy 284.035636 -309.514995)
			(xy 284.057424 -309.557748) (xy 284.072256 -309.603383) (xy 284.079767 -309.650776) (xy 284.080204 -309.674768)
			(xy 284.080204 -309.68188) (xy 284.07995 -309.692294) (xy 284.087316 -309.710836) (xy 284.127194 -309.75173)
			(xy 284.145482 -309.770526) (xy 284.152908 -309.777473) (xy 284.171644 -309.785332) (xy 284.181804 -309.785766)
			(xy 284.317948 -309.785766) (xy 284.328103 -309.785316) (xy 284.346828 -309.777451) (xy 284.35427 -309.770526)
			(xy 284.412436 -309.710836) (xy 284.419802 -309.692294) (xy 284.419548 -309.68188) (xy 284.419548 -309.674768)
			(xy 284.42007 -309.649513) (xy 284.428383 -309.599691) (xy 284.444784 -309.551917) (xy 284.468825 -309.507494)
			(xy 284.499849 -309.467634) (xy 284.537011 -309.433424) (xy 284.579297 -309.405798) (xy 284.625553 -309.385508)
			(xy 284.674518 -309.373108) (xy 284.724856 -309.368937) (xy 284.775194 -309.373108) (xy 284.824159 -309.385508)
			(xy 284.870415 -309.405798) (xy 284.912701 -309.433424) (xy 284.949863 -309.467634) (xy 284.980887 -309.507494)
			(xy 285.004928 -309.551917) (xy 285.021329 -309.599691) (xy 285.029642 -309.649513) (xy 285.030164 -309.674768)
			(xy 285.030164 -309.68188) (xy 285.02991 -309.692294) (xy 285.037276 -309.710836) (xy 285.077154 -309.75173)
			(xy 285.095442 -309.770526) (xy 285.102866 -309.777479) (xy 285.121602 -309.785353) (xy 285.131764 -309.785766)
			(xy 285.267908 -309.785766) (xy 285.278066 -309.785323) (xy 285.296802 -309.777468) (xy 285.30423 -309.770526)
			(xy 285.362396 -309.710836) (xy 285.369762 -309.692294) (xy 285.369508 -309.68188) (xy 285.369508 -309.674768)
			(xy 285.37003 -309.649513) (xy 285.378343 -309.599691) (xy 285.394744 -309.551917) (xy 285.418785 -309.507494)
			(xy 285.449809 -309.467634) (xy 285.486971 -309.433424) (xy 285.529257 -309.405798) (xy 285.575513 -309.385508)
			(xy 285.624478 -309.373108) (xy 285.674816 -309.368937) (xy 285.725154 -309.373108) (xy 285.774119 -309.385508)
			(xy 285.820375 -309.405798) (xy 285.862661 -309.433424) (xy 285.899823 -309.467634) (xy 285.930847 -309.507494)
			(xy 285.954888 -309.551917) (xy 285.971289 -309.599691) (xy 285.979602 -309.649513) (xy 285.980124 -309.674768)
			(xy 285.980124 -309.68188) (xy 285.97987 -309.692294) (xy 285.987236 -309.710836) (xy 286.027114 -309.75173)
			(xy 286.045402 -309.770526) (xy 286.052829 -309.77747) (xy 286.071565 -309.785322) (xy 286.081724 -309.785766)
			(xy 286.217868 -309.785766) (xy 286.228021 -309.785312) (xy 286.246741 -309.777442) (xy 286.25419 -309.770526)
			(xy 286.312356 -309.710836) (xy 286.319722 -309.692294) (xy 286.319468 -309.68188) (xy 286.319468 -309.674768)
			(xy 286.31999 -309.649513) (xy 286.328303 -309.599691) (xy 286.344704 -309.551917) (xy 286.368745 -309.507494)
			(xy 286.399769 -309.467634) (xy 286.436931 -309.433424) (xy 286.479217 -309.405798) (xy 286.525473 -309.385508)
			(xy 286.574438 -309.373108) (xy 286.624776 -309.368937) (xy 286.675114 -309.373108) (xy 286.724079 -309.385508)
			(xy 286.770335 -309.405798) (xy 286.812621 -309.433424) (xy 286.849783 -309.467634) (xy 286.880807 -309.507494)
			(xy 286.904848 -309.551917) (xy 286.921249 -309.599691) (xy 286.929562 -309.649513) (xy 286.930084 -309.674768)
			(xy 286.930084 -309.68188) (xy 286.92983 -309.692294) (xy 286.937196 -309.710836) (xy 286.977074 -309.75173)
			(xy 286.995362 -309.770526) (xy 287.002787 -309.777476) (xy 287.021523 -309.785343) (xy 287.031684 -309.785766)
			(xy 287.167828 -309.785766) (xy 287.177984 -309.785319) (xy 287.196715 -309.777459) (xy 287.20415 -309.770526)
			(xy 287.262316 -309.710836) (xy 287.269682 -309.692294) (xy 287.269428 -309.68188) (xy 287.269428 -309.674768)
			(xy 287.269877 -309.650778) (xy 287.277388 -309.603388) (xy 287.292219 -309.557757) (xy 287.314007 -309.515008)
			(xy 287.342214 -309.476194) (xy 287.376145 -309.44227) (xy 287.414966 -309.414071) (xy 287.45772 -309.392293)
			(xy 287.503354 -309.377472) (xy 287.550745 -309.369971) (xy 287.574736 -309.36946) (xy 287.588919 -309.369644)
			(xy 287.617159 -309.372311) (xy 287.631124 -309.374794) (xy 287.64357 -309.37708) (xy 287.667192 -309.369714)
			(xy 287.744662 -309.292244) (xy 287.752028 -309.268622) (xy 287.749742 -309.256176) (xy 287.747257 -309.242211)
			(xy 287.744586 -309.213971) (xy 287.744408 -309.199788) (xy 287.744595 -309.185606) (xy 287.74727 -309.157367)
			(xy 287.749742 -309.1434) (xy 287.752028 -309.130954) (xy 287.744662 -309.107332) (xy 287.667192 -309.029862)
			(xy 287.64357 -309.022496) (xy 287.631124 -309.024782) (xy 287.617159 -309.027269) (xy 287.588919 -309.029944)
			(xy 287.574736 -309.030116) (xy 287.549914 -309.029633) (xy 287.500922 -309.021607) (xy 287.453875 -309.00576)
			(xy 287.410011 -308.982511) (xy 287.370486 -308.952471) (xy 287.336342 -308.916433) (xy 287.308479 -308.875345)
			(xy 287.28763 -308.830291) (xy 287.274345 -308.782457) (xy 287.268974 -308.733104) (xy 287.271658 -308.683532)
			(xy 287.282327 -308.635047) (xy 287.3007 -308.588927) (xy 287.326292 -308.546388) (xy 287.358429 -308.508549)
			(xy 287.396265 -308.476408) (xy 287.438802 -308.450812) (xy 287.48492 -308.432435) (xy 287.533404 -308.421762)
			(xy 287.582976 -308.419073) (xy 287.632329 -308.42444) (xy 287.680164 -308.43772) (xy 287.725221 -308.458565)
			(xy 287.766311 -308.486425) (xy 287.802353 -308.520565) (xy 287.832396 -308.560087) (xy 287.855649 -308.603949)
			(xy 287.8715 -308.650995) (xy 287.879531 -308.699986) (xy 287.880044 -308.724808) (xy 287.879857 -308.73899)
			(xy 287.877183 -308.76723) (xy 287.87471 -308.781196) (xy 287.872424 -308.793642) (xy 287.87979 -308.817264)
			(xy 287.95726 -308.894734) (xy 287.980882 -308.9021) (xy 287.993328 -308.899814) (xy 288.007293 -308.89733)
			(xy 288.035533 -308.894659) (xy 288.049716 -308.89448) (xy 288.063962 -308.894656) (xy 288.09233 -308.897325)
			(xy 288.106358 -308.899814) (xy 288.11855 -308.9021) (xy 288.14268 -308.894734) (xy 288.219896 -308.817518)
			(xy 288.227262 -308.793642) (xy 288.224976 -308.781196) (xy 288.22249 -308.767231) (xy 288.219817 -308.738991)
			(xy 288.219642 -308.724808) (xy 288.220127 -308.699992) (xy 288.228155 -308.651013) (xy 288.244001 -308.603979)
			(xy 288.267247 -308.560127) (xy 288.297282 -308.520614) (xy 288.333313 -308.48648) (xy 288.374391 -308.458625)
			(xy 288.419435 -308.437782) (xy 288.467257 -308.424501) (xy 288.516598 -308.419132) (xy 288.566157 -308.421815)
			(xy 288.61463 -308.432481) (xy 288.660739 -308.450848) (xy 288.703269 -308.476432) (xy 288.741099 -308.50856)
			(xy 288.773234 -308.546384) (xy 288.798827 -308.588909) (xy 288.817202 -308.635014) (xy 288.827877 -308.683485)
			(xy 288.830122 -308.724808) (xy 290.119066 -308.724808) (xy 290.123026 -308.675754) (xy 290.134803 -308.62797)
			(xy 290.154094 -308.582694) (xy 290.180397 -308.541098) (xy 290.213032 -308.504261) (xy 290.251153 -308.473136)
			(xy 290.293774 -308.448529) (xy 290.33979 -308.431077) (xy 290.388009 -308.421233) (xy 290.437184 -308.419252)
			(xy 290.486039 -308.425184) (xy 290.53331 -308.438876) (xy 290.577772 -308.459974) (xy 290.618275 -308.48793)
			(xy 290.653768 -308.522022) (xy 290.683333 -308.561366) (xy 290.706204 -308.604943) (xy 290.721788 -308.651624)
			(xy 290.729683 -308.700201) (xy 290.730178 -308.724808) (xy 290.729683 -308.749415) (xy 290.721788 -308.797992)
			(xy 290.706204 -308.844673) (xy 290.683333 -308.88825) (xy 290.653768 -308.927594) (xy 290.618275 -308.961686)
			(xy 290.577772 -308.989642) (xy 290.53331 -309.01074) (xy 290.486039 -309.024432) (xy 290.437184 -309.030364)
			(xy 290.388009 -309.028383) (xy 290.33979 -309.018539) (xy 290.293774 -309.001087) (xy 290.251153 -308.97648)
			(xy 290.213032 -308.945355) (xy 290.180397 -308.908518) (xy 290.154094 -308.866922) (xy 290.134803 -308.821646)
			(xy 290.123026 -308.773862) (xy 290.119066 -308.724808) (xy 288.830122 -308.724808) (xy 288.83057 -308.733044)
			(xy 288.82521 -308.782386) (xy 288.811938 -308.830211) (xy 288.791104 -308.875258) (xy 288.763256 -308.916342)
			(xy 288.729129 -308.95238) (xy 288.689622 -308.982421) (xy 288.645775 -309.005676) (xy 288.598743 -309.021531)
			(xy 288.549766 -309.029568) (xy 288.52495 -309.030116) (xy 288.510704 -309.029938) (xy 288.482337 -309.027266)
			(xy 288.468308 -309.024782) (xy 288.456116 -309.022496) (xy 288.431986 -309.029862) (xy 288.35477 -309.107078)
			(xy 288.347404 -309.130954) (xy 288.34969 -309.1434) (xy 288.352176 -309.157365) (xy 288.354849 -309.185605)
			(xy 288.355024 -309.199788) (xy 288.354838 -309.21397) (xy 288.352166 -309.24221) (xy 288.34969 -309.256176)
			(xy 288.347404 -309.268622) (xy 288.35477 -309.292244) (xy 288.43224 -309.369714) (xy 288.455862 -309.37708)
			(xy 288.468308 -309.374794) (xy 288.482273 -309.372309) (xy 288.510513 -309.369637) (xy 288.524696 -309.36946)
			(xy 288.548688 -309.36993) (xy 288.596082 -309.377436) (xy 288.641719 -309.392262) (xy 288.684475 -309.414045)
			(xy 288.723296 -309.442248) (xy 288.757229 -309.476176) (xy 288.785436 -309.514995) (xy 288.807224 -309.557748)
			(xy 288.822056 -309.603383) (xy 288.829567 -309.650776) (xy 288.830004 -309.674768) (xy 288.830004 -309.68188)
			(xy 288.82975 -309.692294) (xy 288.837116 -309.710836) (xy 288.876994 -309.75173) (xy 288.895282 -309.770526)
			(xy 288.902708 -309.777473) (xy 288.921444 -309.785332) (xy 288.931604 -309.785766) (xy 289.068002 -309.785766)
			(xy 289.07816 -309.785324) (xy 289.096898 -309.777471) (xy 289.104324 -309.770526) (xy 289.16249 -309.710836)
			(xy 289.169856 -309.692294) (xy 289.169602 -309.68188) (xy 289.169602 -309.674768) (xy 289.170124 -309.649513)
			(xy 289.178437 -309.599691) (xy 289.194838 -309.551917) (xy 289.218879 -309.507494) (xy 289.249903 -309.467634)
			(xy 289.287065 -309.433424) (xy 289.329351 -309.405798) (xy 289.375607 -309.385508) (xy 289.424572 -309.373108)
			(xy 289.47491 -309.368937) (xy 289.525248 -309.373108) (xy 289.574213 -309.385508) (xy 289.620469 -309.405798)
			(xy 289.662755 -309.433424) (xy 289.699917 -309.467634) (xy 289.730941 -309.507494) (xy 289.754982 -309.551917)
			(xy 289.771383 -309.599691) (xy 289.779696 -309.649513) (xy 289.780218 -309.674768) (xy 289.780218 -309.68188)
			(xy 289.779964 -309.692294) (xy 289.78733 -309.710836) (xy 289.827208 -309.75173) (xy 289.845496 -309.770526)
			(xy 289.852923 -309.777471) (xy 289.871659 -309.785325) (xy 289.881818 -309.785766) (xy 289.935666 -309.785766)
			(xy 289.942024 -309.785599) (xy 289.954358 -309.782508) (xy 289.96005 -309.77967) (xy 289.960304 -309.779416)
			(xy 289.978433 -309.769582) (xy 290.015403 -309.751288) (xy 290.034218 -309.74284) (xy 290.034726 -309.742586)
			(xy 290.040314 -309.740046) (xy 290.043616 -309.738522) (xy 290.04387 -309.738522) (xy 290.05149 -309.73522)
			(xy 290.072572 -309.726584) (xy 290.079684 -309.72379) (xy 290.08705 -309.717948) (xy 290.089775 -309.715652)
			(xy 290.094615 -309.710422) (xy 290.096702 -309.707534) (xy 290.102544 -309.699152) (xy 290.108386 -309.691024)
			(xy 290.112958 -309.6768) (xy 290.113212 -309.668926) (xy 290.114118 -309.644734) (xy 290.122488 -309.597055)
			(xy 290.13813 -309.551244) (xy 290.160667 -309.508402) (xy 290.189558 -309.46956) (xy 290.224107 -309.435653)
			(xy 290.263484 -309.407495) (xy 290.306741 -309.385765) (xy 290.352838 -309.370985) (xy 290.400666 -309.363511)
			(xy 290.42487 -309.36311) (xy 290.449043 -309.36357) (xy 290.496809 -309.371044) (xy 290.542849 -309.385801)
			(xy 290.586059 -309.407488) (xy 290.625404 -309.435584) (xy 290.65994 -309.469417) (xy 290.68884 -309.508176)
			(xy 290.71141 -309.550931) (xy 290.727111 -309.596657) (xy 290.735565 -309.644259) (xy 290.736528 -309.668418)
			(xy 290.736939 -309.675711) (xy 290.741321 -309.689638) (xy 290.745164 -309.69585) (xy 290.753546 -309.708042)
			(xy 290.755961 -309.711421) (xy 290.761706 -309.717419) (xy 290.764976 -309.71998) (xy 290.770818 -309.724552)
			(xy 290.777422 -309.727092) (xy 290.803867 -309.737686) (xy 290.855589 -309.761579) (xy 290.8808 -309.774844)
			(xy 290.881308 -309.775098) (xy 290.885372 -309.77713) (xy 290.8935 -309.780432) (xy 290.900104 -309.782464)
			(xy 290.906962 -309.784242) (xy 290.919408 -309.785766) (xy 291.917882 -309.785766) (xy 291.928034 -309.785309)
			(xy 291.94675 -309.777436) (xy 291.954204 -309.770526) (xy 292.01237 -309.710836) (xy 292.019736 -309.692294)
			(xy 292.019482 -309.68188) (xy 292.019482 -309.674768) (xy 292.019955 -309.650778) (xy 292.027465 -309.60339)
			(xy 292.042295 -309.557759) (xy 292.06408 -309.51501) (xy 292.092284 -309.476195) (xy 292.126212 -309.44227)
			(xy 292.165029 -309.414069) (xy 292.20778 -309.392287) (xy 292.253411 -309.37746) (xy 292.3008 -309.369953)
			(xy 292.32479 -309.36946) (xy 292.338972 -309.369646) (xy 292.367212 -309.372318) (xy 292.381178 -309.374794)
			(xy 292.393624 -309.37708) (xy 292.417246 -309.369714) (xy 292.494716 -309.292244) (xy 292.502082 -309.268622)
			(xy 292.499796 -309.256176) (xy 292.497312 -309.242211) (xy 292.494641 -309.213971) (xy 292.494462 -309.199788)
			(xy 292.494649 -309.185606) (xy 292.497323 -309.157367) (xy 292.499796 -309.1434) (xy 292.502082 -309.130954)
			(xy 292.494716 -309.107332) (xy 292.417246 -309.029862) (xy 292.393624 -309.022496) (xy 292.381178 -309.024782)
			(xy 292.367213 -309.027267) (xy 292.338973 -309.029938) (xy 292.32479 -309.030116) (xy 292.299969 -309.029629)
			(xy 292.25098 -309.021596) (xy 292.203936 -309.005744) (xy 292.160077 -308.982489) (xy 292.120557 -308.952445)
			(xy 292.086419 -308.916404) (xy 292.058561 -308.875314) (xy 292.037718 -308.830259) (xy 292.024439 -308.782425)
			(xy 292.019073 -308.733073) (xy 292.021762 -308.683503) (xy 292.032435 -308.635021) (xy 292.050811 -308.588904)
			(xy 292.076406 -308.546368) (xy 292.108546 -308.508533) (xy 292.146382 -308.476396) (xy 292.18892 -308.450803)
			(xy 292.235038 -308.43243) (xy 292.28352 -308.42176) (xy 292.333091 -308.419073) (xy 292.382442 -308.424442)
			(xy 292.430275 -308.437724) (xy 292.47533 -308.45857) (xy 292.516418 -308.48643) (xy 292.552457 -308.520571)
			(xy 292.582499 -308.560092) (xy 292.605751 -308.603953) (xy 292.621601 -308.650997) (xy 292.629631 -308.699987)
			(xy 292.630098 -308.724808) (xy 292.629911 -308.73899) (xy 292.627237 -308.76723) (xy 292.624764 -308.781196)
			(xy 292.622478 -308.793642) (xy 292.629844 -308.817264) (xy 292.707314 -308.894734) (xy 292.730936 -308.9021)
			(xy 292.743382 -308.899814) (xy 292.757347 -308.897327) (xy 292.785587 -308.894653) (xy 292.79977 -308.89448)
			(xy 292.813953 -308.894665) (xy 292.842192 -308.897336) (xy 292.856158 -308.899814) (xy 292.868604 -308.9021)
			(xy 292.892226 -308.894734) (xy 292.969696 -308.817264) (xy 292.977062 -308.793642) (xy 292.974776 -308.781196)
			(xy 292.97229 -308.767231) (xy 292.969617 -308.738991) (xy 292.969442 -308.724808) (xy 292.969964 -308.699553)
			(xy 292.978277 -308.649731) (xy 292.994678 -308.601957) (xy 293.018719 -308.557534) (xy 293.049743 -308.517674)
			(xy 293.086905 -308.483464) (xy 293.129191 -308.455838) (xy 293.175447 -308.435548) (xy 293.224412 -308.423148)
			(xy 293.27475 -308.418977) (xy 293.325088 -308.423148) (xy 293.374053 -308.435548) (xy 293.420309 -308.455838)
			(xy 293.462595 -308.483464) (xy 293.499757 -308.517674) (xy 293.530781 -308.557534) (xy 293.554822 -308.601957)
			(xy 293.571223 -308.649731) (xy 293.579536 -308.699553) (xy 293.580058 -308.724808) (xy 293.579871 -308.73899)
			(xy 293.577197 -308.76723) (xy 293.574724 -308.781196) (xy 293.572438 -308.793642) (xy 293.579804 -308.817264)
			(xy 293.657274 -308.894734) (xy 293.680896 -308.9021) (xy 293.693342 -308.899814) (xy 293.707307 -308.89733)
			(xy 293.735547 -308.894661) (xy 293.74973 -308.89448) (xy 293.763913 -308.894663) (xy 293.792153 -308.89733)
			(xy 293.806118 -308.899814) (xy 293.818564 -308.9021) (xy 293.842186 -308.894734) (xy 293.919656 -308.817264)
			(xy 293.927022 -308.793642) (xy 293.924736 -308.781196) (xy 293.92225 -308.767231) (xy 293.919577 -308.738991)
			(xy 293.919402 -308.724808) (xy 293.919887 -308.699988) (xy 293.927917 -308.651002) (xy 293.943766 -308.60396)
			(xy 293.967016 -308.560102) (xy 293.997056 -308.520583) (xy 294.033094 -308.486444) (xy 294.074179 -308.458586)
			(xy 294.119231 -308.437741) (xy 294.167061 -308.42446) (xy 294.21641 -308.419091) (xy 294.265977 -308.421777)
			(xy 294.314457 -308.432447) (xy 294.360572 -308.45082) (xy 294.403107 -308.47641) (xy 294.440942 -308.508546)
			(xy 294.473079 -308.546378) (xy 294.498672 -308.588912) (xy 294.517048 -308.635026) (xy 294.52772 -308.683505)
			(xy 294.529947 -308.724554) (xy 294.868866 -308.724554) (xy 294.872826 -308.6755) (xy 294.884603 -308.627716)
			(xy 294.903894 -308.58244) (xy 294.930197 -308.540844) (xy 294.962832 -308.504007) (xy 295.000953 -308.472882)
			(xy 295.043574 -308.448275) (xy 295.08959 -308.430823) (xy 295.137809 -308.420979) (xy 295.186984 -308.418998)
			(xy 295.235839 -308.42493) (xy 295.28311 -308.438622) (xy 295.327572 -308.45972) (xy 295.368075 -308.487676)
			(xy 295.403568 -308.521768) (xy 295.433133 -308.561112) (xy 295.456004 -308.604689) (xy 295.471588 -308.65137)
			(xy 295.479483 -308.699947) (xy 295.479978 -308.724554) (xy 295.479973 -308.724808) (xy 295.81908 -308.724808)
			(xy 295.82304 -308.675754) (xy 295.834817 -308.62797) (xy 295.854108 -308.582694) (xy 295.880411 -308.541098)
			(xy 295.913046 -308.504261) (xy 295.951167 -308.473136) (xy 295.993788 -308.448529) (xy 296.039804 -308.431077)
			(xy 296.088023 -308.421233) (xy 296.137198 -308.419252) (xy 296.186053 -308.425184) (xy 296.233324 -308.438876)
			(xy 296.277786 -308.459974) (xy 296.318289 -308.48793) (xy 296.353782 -308.522022) (xy 296.383347 -308.561366)
			(xy 296.406218 -308.604943) (xy 296.421802 -308.651624) (xy 296.429697 -308.700201) (xy 296.430192 -308.724808)
			(xy 296.76904 -308.724808) (xy 296.773 -308.675754) (xy 296.784777 -308.62797) (xy 296.804068 -308.582694)
			(xy 296.830371 -308.541098) (xy 296.863006 -308.504261) (xy 296.901127 -308.473136) (xy 296.943748 -308.448529)
			(xy 296.989764 -308.431077) (xy 297.037983 -308.421233) (xy 297.087158 -308.419252) (xy 297.136013 -308.425184)
			(xy 297.183284 -308.438876) (xy 297.227746 -308.459974) (xy 297.268249 -308.48793) (xy 297.303742 -308.522022)
			(xy 297.333307 -308.561366) (xy 297.356178 -308.604943) (xy 297.371762 -308.651624) (xy 297.379657 -308.700201)
			(xy 297.380152 -308.724808) (xy 297.719 -308.724808) (xy 297.72296 -308.675754) (xy 297.734737 -308.62797)
			(xy 297.754028 -308.582694) (xy 297.780331 -308.541098) (xy 297.812966 -308.504261) (xy 297.851087 -308.473136)
			(xy 297.893708 -308.448529) (xy 297.939724 -308.431077) (xy 297.987943 -308.421233) (xy 298.037118 -308.419252)
			(xy 298.085973 -308.425184) (xy 298.133244 -308.438876) (xy 298.177706 -308.459974) (xy 298.218209 -308.48793)
			(xy 298.253702 -308.522022) (xy 298.283267 -308.561366) (xy 298.306138 -308.604943) (xy 298.321722 -308.651624)
			(xy 298.329617 -308.700201) (xy 298.330112 -308.724808) (xy 298.66896 -308.724808) (xy 298.67292 -308.675754)
			(xy 298.684697 -308.62797) (xy 298.703988 -308.582694) (xy 298.730291 -308.541098) (xy 298.762926 -308.504261)
			(xy 298.801047 -308.473136) (xy 298.843668 -308.448529) (xy 298.889684 -308.431077) (xy 298.937903 -308.421233)
			(xy 298.987078 -308.419252) (xy 299.035933 -308.425184) (xy 299.083204 -308.438876) (xy 299.127666 -308.459974)
			(xy 299.168169 -308.48793) (xy 299.203662 -308.522022) (xy 299.233227 -308.561366) (xy 299.256098 -308.604943)
			(xy 299.271682 -308.651624) (xy 299.279577 -308.700201) (xy 299.280072 -308.724808) (xy 299.61892 -308.724808)
			(xy 299.62288 -308.675754) (xy 299.634657 -308.62797) (xy 299.653948 -308.582694) (xy 299.680251 -308.541098)
			(xy 299.712886 -308.504261) (xy 299.751007 -308.473136) (xy 299.793628 -308.448529) (xy 299.839644 -308.431077)
			(xy 299.887863 -308.421233) (xy 299.937038 -308.419252) (xy 299.985893 -308.425184) (xy 300.033164 -308.438876)
			(xy 300.077626 -308.459974) (xy 300.118129 -308.48793) (xy 300.153622 -308.522022) (xy 300.183187 -308.561366)
			(xy 300.206058 -308.604943) (xy 300.221642 -308.651624) (xy 300.229537 -308.700201) (xy 300.230032 -308.724808)
			(xy 300.569134 -308.724808) (xy 300.573094 -308.675754) (xy 300.584871 -308.62797) (xy 300.604162 -308.582694)
			(xy 300.630465 -308.541098) (xy 300.6631 -308.504261) (xy 300.701221 -308.473136) (xy 300.743842 -308.448529)
			(xy 300.789858 -308.431077) (xy 300.838077 -308.421233) (xy 300.887252 -308.419252) (xy 300.936107 -308.425184)
			(xy 300.983378 -308.438876) (xy 301.02784 -308.459974) (xy 301.068343 -308.48793) (xy 301.103836 -308.522022)
			(xy 301.133401 -308.561366) (xy 301.156272 -308.604943) (xy 301.171856 -308.651624) (xy 301.179751 -308.700201)
			(xy 301.180246 -308.724808) (xy 301.519094 -308.724808) (xy 301.523054 -308.675754) (xy 301.534831 -308.62797)
			(xy 301.554122 -308.582694) (xy 301.580425 -308.541098) (xy 301.61306 -308.504261) (xy 301.651181 -308.473136)
			(xy 301.693802 -308.448529) (xy 301.739818 -308.431077) (xy 301.788037 -308.421233) (xy 301.837212 -308.419252)
			(xy 301.886067 -308.425184) (xy 301.933338 -308.438876) (xy 301.9778 -308.459974) (xy 302.018303 -308.48793)
			(xy 302.053796 -308.522022) (xy 302.083361 -308.561366) (xy 302.106232 -308.604943) (xy 302.121816 -308.651624)
			(xy 302.129711 -308.700201) (xy 302.130206 -308.724808) (xy 302.469054 -308.724808) (xy 302.473014 -308.675754)
			(xy 302.484791 -308.62797) (xy 302.504082 -308.582694) (xy 302.530385 -308.541098) (xy 302.56302 -308.504261)
			(xy 302.601141 -308.473136) (xy 302.643762 -308.448529) (xy 302.689778 -308.431077) (xy 302.737997 -308.421233)
			(xy 302.787172 -308.419252) (xy 302.836027 -308.425184) (xy 302.883298 -308.438876) (xy 302.92776 -308.459974)
			(xy 302.968263 -308.48793) (xy 303.003756 -308.522022) (xy 303.033321 -308.561366) (xy 303.056192 -308.604943)
			(xy 303.071776 -308.651624) (xy 303.079671 -308.700201) (xy 303.080166 -308.724808) (xy 303.419014 -308.724808)
			(xy 303.422974 -308.675754) (xy 303.434751 -308.62797) (xy 303.454042 -308.582694) (xy 303.480345 -308.541098)
			(xy 303.51298 -308.504261) (xy 303.551101 -308.473136) (xy 303.593722 -308.448529) (xy 303.639738 -308.431077)
			(xy 303.687957 -308.421233) (xy 303.737132 -308.419252) (xy 303.785987 -308.425184) (xy 303.833258 -308.438876)
			(xy 303.87772 -308.459974) (xy 303.918223 -308.48793) (xy 303.953716 -308.522022) (xy 303.983281 -308.561366)
			(xy 304.006152 -308.604943) (xy 304.021736 -308.651624) (xy 304.029631 -308.700201) (xy 304.030126 -308.724808)
			(xy 304.368974 -308.724808) (xy 304.372934 -308.675754) (xy 304.384711 -308.62797) (xy 304.404002 -308.582694)
			(xy 304.430305 -308.541098) (xy 304.46294 -308.504261) (xy 304.501061 -308.473136) (xy 304.543682 -308.448529)
			(xy 304.589698 -308.431077) (xy 304.637917 -308.421233) (xy 304.687092 -308.419252) (xy 304.735947 -308.425184)
			(xy 304.783218 -308.438876) (xy 304.82768 -308.459974) (xy 304.868183 -308.48793) (xy 304.903676 -308.522022)
			(xy 304.933241 -308.561366) (xy 304.956112 -308.604943) (xy 304.971696 -308.651624) (xy 304.979591 -308.700201)
			(xy 304.980086 -308.724808) (xy 304.979591 -308.749415) (xy 304.971696 -308.797992) (xy 304.956112 -308.844673)
			(xy 304.933241 -308.88825) (xy 304.903676 -308.927594) (xy 304.868183 -308.961686) (xy 304.82768 -308.989642)
			(xy 304.783218 -309.01074) (xy 304.735947 -309.024432) (xy 304.687092 -309.030364) (xy 304.637917 -309.028383)
			(xy 304.589698 -309.018539) (xy 304.543682 -309.001087) (xy 304.501061 -308.97648) (xy 304.46294 -308.945355)
			(xy 304.430305 -308.908518) (xy 304.404002 -308.866922) (xy 304.384711 -308.821646) (xy 304.372934 -308.773862)
			(xy 304.368974 -308.724808) (xy 304.030126 -308.724808) (xy 304.029631 -308.749415) (xy 304.021736 -308.797992)
			(xy 304.006152 -308.844673) (xy 303.983281 -308.88825) (xy 303.953716 -308.927594) (xy 303.918223 -308.961686)
			(xy 303.87772 -308.989642) (xy 303.833258 -309.01074) (xy 303.785987 -309.024432) (xy 303.737132 -309.030364)
			(xy 303.687957 -309.028383) (xy 303.639738 -309.018539) (xy 303.593722 -309.001087) (xy 303.551101 -308.97648)
			(xy 303.51298 -308.945355) (xy 303.480345 -308.908518) (xy 303.454042 -308.866922) (xy 303.434751 -308.821646)
			(xy 303.422974 -308.773862) (xy 303.419014 -308.724808) (xy 303.080166 -308.724808) (xy 303.079671 -308.749415)
			(xy 303.071776 -308.797992) (xy 303.056192 -308.844673) (xy 303.033321 -308.88825) (xy 303.003756 -308.927594)
			(xy 302.968263 -308.961686) (xy 302.92776 -308.989642) (xy 302.883298 -309.01074) (xy 302.836027 -309.024432)
			(xy 302.787172 -309.030364) (xy 302.737997 -309.028383) (xy 302.689778 -309.018539) (xy 302.643762 -309.001087)
			(xy 302.601141 -308.97648) (xy 302.56302 -308.945355) (xy 302.530385 -308.908518) (xy 302.504082 -308.866922)
			(xy 302.484791 -308.821646) (xy 302.473014 -308.773862) (xy 302.469054 -308.724808) (xy 302.130206 -308.724808)
			(xy 302.129711 -308.749415) (xy 302.121816 -308.797992) (xy 302.106232 -308.844673) (xy 302.083361 -308.88825)
			(xy 302.053796 -308.927594) (xy 302.018303 -308.961686) (xy 301.9778 -308.989642) (xy 301.933338 -309.01074)
			(xy 301.886067 -309.024432) (xy 301.837212 -309.030364) (xy 301.788037 -309.028383) (xy 301.739818 -309.018539)
			(xy 301.693802 -309.001087) (xy 301.651181 -308.97648) (xy 301.61306 -308.945355) (xy 301.580425 -308.908518)
			(xy 301.554122 -308.866922) (xy 301.534831 -308.821646) (xy 301.523054 -308.773862) (xy 301.519094 -308.724808)
			(xy 301.180246 -308.724808) (xy 301.179751 -308.749415) (xy 301.171856 -308.797992) (xy 301.156272 -308.844673)
			(xy 301.133401 -308.88825) (xy 301.103836 -308.927594) (xy 301.068343 -308.961686) (xy 301.02784 -308.989642)
			(xy 300.983378 -309.01074) (xy 300.936107 -309.024432) (xy 300.887252 -309.030364) (xy 300.838077 -309.028383)
			(xy 300.789858 -309.018539) (xy 300.743842 -309.001087) (xy 300.701221 -308.97648) (xy 300.6631 -308.945355)
			(xy 300.630465 -308.908518) (xy 300.604162 -308.866922) (xy 300.584871 -308.821646) (xy 300.573094 -308.773862)
			(xy 300.569134 -308.724808) (xy 300.230032 -308.724808) (xy 300.229537 -308.749415) (xy 300.221642 -308.797992)
			(xy 300.206058 -308.844673) (xy 300.183187 -308.88825) (xy 300.153622 -308.927594) (xy 300.118129 -308.961686)
			(xy 300.077626 -308.989642) (xy 300.033164 -309.01074) (xy 299.985893 -309.024432) (xy 299.937038 -309.030364)
			(xy 299.887863 -309.028383) (xy 299.839644 -309.018539) (xy 299.793628 -309.001087) (xy 299.751007 -308.97648)
			(xy 299.712886 -308.945355) (xy 299.680251 -308.908518) (xy 299.653948 -308.866922) (xy 299.634657 -308.821646)
			(xy 299.62288 -308.773862) (xy 299.61892 -308.724808) (xy 299.280072 -308.724808) (xy 299.279577 -308.749415)
			(xy 299.271682 -308.797992) (xy 299.256098 -308.844673) (xy 299.233227 -308.88825) (xy 299.203662 -308.927594)
			(xy 299.168169 -308.961686) (xy 299.127666 -308.989642) (xy 299.083204 -309.01074) (xy 299.035933 -309.024432)
			(xy 298.987078 -309.030364) (xy 298.937903 -309.028383) (xy 298.889684 -309.018539) (xy 298.843668 -309.001087)
			(xy 298.801047 -308.97648) (xy 298.762926 -308.945355) (xy 298.730291 -308.908518) (xy 298.703988 -308.866922)
			(xy 298.684697 -308.821646) (xy 298.67292 -308.773862) (xy 298.66896 -308.724808) (xy 298.330112 -308.724808)
			(xy 298.329617 -308.749415) (xy 298.321722 -308.797992) (xy 298.306138 -308.844673) (xy 298.283267 -308.88825)
			(xy 298.253702 -308.927594) (xy 298.218209 -308.961686) (xy 298.177706 -308.989642) (xy 298.133244 -309.01074)
			(xy 298.085973 -309.024432) (xy 298.037118 -309.030364) (xy 297.987943 -309.028383) (xy 297.939724 -309.018539)
			(xy 297.893708 -309.001087) (xy 297.851087 -308.97648) (xy 297.812966 -308.945355) (xy 297.780331 -308.908518)
			(xy 297.754028 -308.866922) (xy 297.734737 -308.821646) (xy 297.72296 -308.773862) (xy 297.719 -308.724808)
			(xy 297.380152 -308.724808) (xy 297.379657 -308.749415) (xy 297.371762 -308.797992) (xy 297.356178 -308.844673)
			(xy 297.333307 -308.88825) (xy 297.303742 -308.927594) (xy 297.268249 -308.961686) (xy 297.227746 -308.989642)
			(xy 297.183284 -309.01074) (xy 297.136013 -309.024432) (xy 297.087158 -309.030364) (xy 297.037983 -309.028383)
			(xy 296.989764 -309.018539) (xy 296.943748 -309.001087) (xy 296.901127 -308.97648) (xy 296.863006 -308.945355)
			(xy 296.830371 -308.908518) (xy 296.804068 -308.866922) (xy 296.784777 -308.821646) (xy 296.773 -308.773862)
			(xy 296.76904 -308.724808) (xy 296.430192 -308.724808) (xy 296.429697 -308.749415) (xy 296.421802 -308.797992)
			(xy 296.406218 -308.844673) (xy 296.383347 -308.88825) (xy 296.353782 -308.927594) (xy 296.318289 -308.961686)
			(xy 296.277786 -308.989642) (xy 296.233324 -309.01074) (xy 296.186053 -309.024432) (xy 296.137198 -309.030364)
			(xy 296.088023 -309.028383) (xy 296.039804 -309.018539) (xy 295.993788 -309.001087) (xy 295.951167 -308.97648)
			(xy 295.913046 -308.945355) (xy 295.880411 -308.908518) (xy 295.854108 -308.866922) (xy 295.834817 -308.821646)
			(xy 295.82304 -308.773862) (xy 295.81908 -308.724808) (xy 295.479973 -308.724808) (xy 295.479483 -308.749161)
			(xy 295.471588 -308.797738) (xy 295.456004 -308.844419) (xy 295.433133 -308.887996) (xy 295.403568 -308.92734)
			(xy 295.368075 -308.961432) (xy 295.327572 -308.989388) (xy 295.28311 -309.010486) (xy 295.235839 -309.024178)
			(xy 295.186984 -309.03011) (xy 295.137809 -309.028129) (xy 295.08959 -309.018285) (xy 295.043574 -309.000833)
			(xy 295.000953 -308.976226) (xy 294.962832 -308.945101) (xy 294.930197 -308.908264) (xy 294.903894 -308.866668)
			(xy 294.884603 -308.821392) (xy 294.872826 -308.773608) (xy 294.868866 -308.724554) (xy 294.529947 -308.724554)
			(xy 294.530409 -308.733072) (xy 294.525044 -308.782421) (xy 294.511765 -308.830252) (xy 294.490923 -308.875305)
			(xy 294.463067 -308.916392) (xy 294.428931 -308.952432) (xy 294.389414 -308.982474) (xy 294.345557 -309.005727)
			(xy 294.298516 -309.021579) (xy 294.24953 -309.029611) (xy 294.22471 -309.030116) (xy 294.210528 -309.02993)
			(xy 294.182288 -309.027257) (xy 294.168322 -309.024782) (xy 294.155876 -309.022496) (xy 294.132254 -309.029862)
			(xy 294.054784 -309.107332) (xy 294.047418 -309.130954) (xy 294.049704 -309.1434) (xy 294.05219 -309.157365)
			(xy 294.054863 -309.185605) (xy 294.055038 -309.199788) (xy 294.054852 -309.213971) (xy 294.05218 -309.24221)
			(xy 294.049704 -309.256176) (xy 294.047418 -309.268622) (xy 294.054784 -309.292244) (xy 294.132254 -309.369714)
			(xy 294.155876 -309.37708) (xy 294.168322 -309.374794) (xy 294.182287 -309.372309) (xy 294.210527 -309.369639)
			(xy 294.22471 -309.36946) (xy 294.248702 -309.369931) (xy 294.296094 -309.377438) (xy 294.341729 -309.392266)
			(xy 294.384482 -309.41405) (xy 294.423302 -309.442253) (xy 294.457233 -309.476181) (xy 294.485439 -309.514999)
			(xy 294.507225 -309.557751) (xy 294.522056 -309.603385) (xy 294.529567 -309.650776) (xy 294.530018 -309.674768)
			(xy 294.530018 -309.68188) (xy 294.529764 -309.692294) (xy 294.53713 -309.710836) (xy 294.577008 -309.75173)
			(xy 294.595296 -309.770526) (xy 294.602723 -309.777471) (xy 294.621459 -309.785325) (xy 294.631618 -309.785766)
			(xy 294.685466 -309.785766) (xy 294.697912 -309.784242) (xy 294.705024 -309.782464) (xy 294.710866 -309.779162)
			(xy 294.738051 -309.764525) (xy 294.793975 -309.738345) (xy 294.822626 -309.726838) (xy 294.829738 -309.724044)
			(xy 294.841168 -309.7149) (xy 294.860472 -309.687214) (xy 294.866822 -309.674768) (xy 294.869362 -309.667656)
			(xy 294.869616 -309.660544) (xy 294.871259 -309.636105) (xy 294.881356 -309.588177) (xy 294.898971 -309.542475)
			(xy 294.923655 -309.50017) (xy 294.954773 -309.462347) (xy 294.991529 -309.429974) (xy 295.032981 -309.403883)
			(xy 295.078065 -309.38474) (xy 295.125626 -309.373038) (xy 295.174444 -309.369077) (xy 295.22327 -309.372957)
			(xy 295.27085 -309.384579) (xy 295.315966 -309.403646) (xy 295.357461 -309.429669) (xy 295.394271 -309.46198)
			(xy 295.425453 -309.499751) (xy 295.450207 -309.542015) (xy 295.467899 -309.587687) (xy 295.478075 -309.635598)
			(xy 295.479724 -309.660036) (xy 295.479978 -309.667402) (xy 295.482264 -309.67426) (xy 295.48455 -309.681372)
			(xy 295.505124 -309.71109) (xy 295.510458 -309.715916) (xy 295.510966 -309.716424) (xy 295.514618 -309.719716)
			(xy 295.522933 -309.724959) (xy 295.527476 -309.726838) (xy 295.555868 -309.738299) (xy 295.611282 -309.764354)
			(xy 295.63822 -309.778908) (xy 295.645078 -309.782464) (xy 295.65092 -309.783988) (xy 295.664128 -309.785766)
			(xy 295.717976 -309.785766) (xy 295.728128 -309.78531) (xy 295.746846 -309.777438) (xy 295.754298 -309.770526)
			(xy 295.812464 -309.710836) (xy 295.81983 -309.692294) (xy 295.819576 -309.68188) (xy 295.819576 -309.674768)
			(xy 295.820098 -309.649513) (xy 295.828411 -309.599691) (xy 295.844812 -309.551917) (xy 295.868853 -309.507494)
			(xy 295.899877 -309.467634) (xy 295.937039 -309.433424) (xy 295.979325 -309.405798) (xy 296.025581 -309.385508)
			(xy 296.074546 -309.373108) (xy 296.124884 -309.368937) (xy 296.175222 -309.373108) (xy 296.224187 -309.385508)
			(xy 296.270443 -309.405798) (xy 296.312729 -309.433424) (xy 296.349891 -309.467634) (xy 296.380915 -309.507494)
			(xy 296.404956 -309.551917) (xy 296.421357 -309.599691) (xy 296.42967 -309.649513) (xy 296.430192 -309.674768)
			(xy 296.430192 -309.68188) (xy 296.429938 -309.692294) (xy 296.437304 -309.710836) (xy 296.477182 -309.75173)
			(xy 296.49547 -309.770526) (xy 296.502896 -309.777475) (xy 296.521632 -309.785339) (xy 296.531792 -309.785766)
			(xy 296.585894 -309.785766) (xy 296.592251 -309.785595) (xy 296.604581 -309.782499) (xy 296.610278 -309.77967)
			(xy 296.610532 -309.779416) (xy 296.631347 -309.768151) (xy 296.673912 -309.74744) (xy 296.695622 -309.738014)
			(xy 296.699686 -309.73649) (xy 296.703496 -309.734712) (xy 296.704004 -309.734458) (xy 296.707052 -309.733188)
			(xy 296.708576 -309.73268) (xy 296.710354 -309.731918) (xy 296.71137 -309.731918) (xy 296.721784 -309.727346)
			(xy 296.724324 -309.72633) (xy 296.727372 -309.724806) (xy 296.730986 -309.722852) (xy 296.737616 -309.718)
			(xy 296.74058 -309.715154) (xy 296.745406 -309.710328) (xy 296.759376 -309.689246) (xy 296.769028 -309.674768)
			(xy 296.76979 -309.660544) (xy 296.771418 -309.636081) (xy 296.781496 -309.588105) (xy 296.799108 -309.542354)
			(xy 296.823803 -309.500004) (xy 296.854947 -309.462144) (xy 296.891739 -309.429745) (xy 296.933234 -309.40364)
			(xy 296.978367 -309.384499) (xy 297.025978 -309.372815) (xy 297.074844 -309.368886) (xy 297.12371 -309.372815)
			(xy 297.171321 -309.384499) (xy 297.216454 -309.40364) (xy 297.257949 -309.429745) (xy 297.294741 -309.462144)
			(xy 297.325885 -309.500004) (xy 297.35058 -309.542354) (xy 297.368192 -309.588105) (xy 297.37827 -309.636081)
			(xy 297.379898 -309.660544) (xy 297.38066 -309.674768) (xy 297.401742 -309.706518) (xy 297.408092 -309.714138)
			(xy 297.416474 -309.72252) (xy 297.426126 -309.726584) (xy 297.427396 -309.727092) (xy 297.429428 -309.728108)
			(xy 297.443652 -309.733696) (xy 297.468128 -309.743967) (xy 297.516034 -309.76684) (xy 297.53941 -309.779416)
			(xy 297.539664 -309.77967) (xy 297.545352 -309.78252) (xy 297.557688 -309.785608) (xy 297.564048 -309.785766)
			(xy 297.617896 -309.785766) (xy 297.628055 -309.785325) (xy 297.646794 -309.777474) (xy 297.654218 -309.770526)
			(xy 297.712384 -309.710836) (xy 297.71975 -309.692294) (xy 297.719496 -309.68188) (xy 297.719496 -309.674768)
			(xy 297.720018 -309.649513) (xy 297.728331 -309.599691) (xy 297.744732 -309.551917) (xy 297.768773 -309.507494)
			(xy 297.799797 -309.467634) (xy 297.836959 -309.433424) (xy 297.879245 -309.405798) (xy 297.925501 -309.385508)
			(xy 297.974466 -309.373108) (xy 298.024804 -309.368937) (xy 298.075142 -309.373108) (xy 298.124107 -309.385508)
			(xy 298.170363 -309.405798) (xy 298.212649 -309.433424) (xy 298.249811 -309.467634) (xy 298.280835 -309.507494)
			(xy 298.304876 -309.551917) (xy 298.321277 -309.599691) (xy 298.32959 -309.649513) (xy 298.330112 -309.674768)
			(xy 298.330112 -309.68188) (xy 298.329858 -309.692294) (xy 298.337224 -309.710836) (xy 298.377102 -309.75173)
			(xy 298.39539 -309.770526) (xy 298.402817 -309.777472) (xy 298.421553 -309.785328) (xy 298.431712 -309.785766)
			(xy 298.485814 -309.785766) (xy 298.492174 -309.785605) (xy 298.504513 -309.782526) (xy 298.510198 -309.77967)
			(xy 298.510452 -309.779416) (xy 298.531267 -309.768151) (xy 298.573832 -309.747441) (xy 298.595542 -309.738014)
			(xy 298.599606 -309.73649) (xy 298.603416 -309.734712) (xy 298.603924 -309.734458) (xy 298.606972 -309.733188)
			(xy 298.608496 -309.73268) (xy 298.610274 -309.731918) (xy 298.61129 -309.731918) (xy 298.621704 -309.727346)
			(xy 298.624244 -309.72633) (xy 298.627292 -309.724806) (xy 298.630906 -309.722851) (xy 298.637533 -309.717997)
			(xy 298.6405 -309.715154) (xy 298.645326 -309.710328) (xy 298.659296 -309.689246) (xy 298.668948 -309.674768)
			(xy 298.66971 -309.660544) (xy 298.671338 -309.636081) (xy 298.681416 -309.588105) (xy 298.699028 -309.542354)
			(xy 298.723723 -309.500004) (xy 298.754867 -309.462144) (xy 298.791659 -309.429745) (xy 298.833154 -309.40364)
			(xy 298.878287 -309.384499) (xy 298.925898 -309.372815) (xy 298.974764 -309.368886) (xy 299.02363 -309.372815)
			(xy 299.071241 -309.384499) (xy 299.116374 -309.40364) (xy 299.157869 -309.429745) (xy 299.194661 -309.462144)
			(xy 299.225805 -309.500004) (xy 299.2505 -309.542354) (xy 299.268112 -309.588105) (xy 299.27819 -309.636081)
			(xy 299.279818 -309.660544) (xy 299.28058 -309.674768) (xy 299.301662 -309.706518) (xy 299.308012 -309.714138)
			(xy 299.316394 -309.72252) (xy 299.326046 -309.726584) (xy 299.327316 -309.727092) (xy 299.329348 -309.728108)
			(xy 299.343572 -309.733696) (xy 299.368049 -309.743965) (xy 299.415957 -309.766835) (xy 299.43933 -309.779416)
			(xy 299.439584 -309.77967) (xy 299.445272 -309.782517) (xy 299.457609 -309.7856) (xy 299.463968 -309.785766)
			(xy 299.517816 -309.785766) (xy 299.527973 -309.785321) (xy 299.546707 -309.777465) (xy 299.554138 -309.770526)
			(xy 299.612304 -309.710836) (xy 299.61967 -309.692294) (xy 299.619416 -309.68188) (xy 299.619416 -309.674768)
			(xy 299.619938 -309.649513) (xy 299.628251 -309.599691) (xy 299.644652 -309.551917) (xy 299.668693 -309.507494)
			(xy 299.699717 -309.467634) (xy 299.736879 -309.433424) (xy 299.779165 -309.405798) (xy 299.825421 -309.385508)
			(xy 299.874386 -309.373108) (xy 299.924724 -309.368937) (xy 299.975062 -309.373108) (xy 300.024027 -309.385508)
			(xy 300.070283 -309.405798) (xy 300.112569 -309.433424) (xy 300.149731 -309.467634) (xy 300.180755 -309.507494)
			(xy 300.204796 -309.551917) (xy 300.221197 -309.599691) (xy 300.22951 -309.649513) (xy 300.230032 -309.674768)
			(xy 300.230032 -309.68188) (xy 300.229778 -309.692294) (xy 300.237144 -309.710836) (xy 300.277022 -309.75173)
			(xy 300.29531 -309.770526) (xy 300.302738 -309.777468) (xy 300.321474 -309.785317) (xy 300.331632 -309.785766)
			(xy 300.385734 -309.785766) (xy 300.392093 -309.785603) (xy 300.40443 -309.782519) (xy 300.410118 -309.77967)
			(xy 300.410372 -309.779416) (xy 300.428502 -309.769583) (xy 300.465473 -309.751291) (xy 300.484286 -309.74284)
			(xy 300.484794 -309.742586) (xy 300.490382 -309.740046) (xy 300.493684 -309.738522) (xy 300.493938 -309.738522)
			(xy 300.501558 -309.73522) (xy 300.52264 -309.726584) (xy 300.529752 -309.72379) (xy 300.537118 -309.717948)
			(xy 300.539844 -309.715653) (xy 300.544687 -309.710425) (xy 300.54677 -309.707534) (xy 300.552612 -309.699152)
			(xy 300.558454 -309.691024) (xy 300.563026 -309.6768) (xy 300.56328 -309.668926) (xy 300.564187 -309.644736)
			(xy 300.572557 -309.597061) (xy 300.5882 -309.551254) (xy 300.610739 -309.508418) (xy 300.63963 -309.469581)
			(xy 300.674181 -309.435681) (xy 300.713558 -309.407531) (xy 300.756815 -309.385809) (xy 300.80291 -309.371039)
			(xy 300.850736 -309.363574) (xy 300.874938 -309.36311) (xy 300.8991 -309.363567) (xy 300.946845 -309.371029)
			(xy 300.992868 -309.385768) (xy 301.036065 -309.407431) (xy 301.075402 -309.435499) (xy 301.109938 -309.469301)
			(xy 301.138845 -309.508026) (xy 301.161431 -309.550748) (xy 301.177155 -309.596443) (xy 301.185641 -309.644017)
			(xy 301.186596 -309.668164) (xy 301.18685 -309.675784) (xy 301.191168 -309.689754) (xy 301.20844 -309.7149)
			(xy 301.220378 -309.724298) (xy 301.22749 -309.727092) (xy 301.260002 -309.740554) (xy 301.28039 -309.749524)
			(xy 301.320411 -309.76909) (xy 301.340012 -309.77967) (xy 301.345854 -309.782718) (xy 301.357792 -309.785766)
			(xy 301.41799 -309.785766) (xy 301.428141 -309.785308) (xy 301.446855 -309.777432) (xy 301.454312 -309.770526)
			(xy 301.512478 -309.710836) (xy 301.519844 -309.692294) (xy 301.51959 -309.68188) (xy 301.51959 -309.674768)
			(xy 301.520112 -309.649513) (xy 301.528425 -309.599691) (xy 301.544826 -309.551917) (xy 301.568867 -309.507494)
			(xy 301.599891 -309.467634) (xy 301.637053 -309.433424) (xy 301.679339 -309.405798) (xy 301.725595 -309.385508)
			(xy 301.77456 -309.373108) (xy 301.824898 -309.368937) (xy 301.875236 -309.373108) (xy 301.924201 -309.385508)
			(xy 301.970457 -309.405798) (xy 302.012743 -309.433424) (xy 302.049905 -309.467634) (xy 302.080929 -309.507494)
			(xy 302.10497 -309.551917) (xy 302.121371 -309.599691) (xy 302.129684 -309.649513) (xy 302.130206 -309.674768)
			(xy 302.130206 -309.68188) (xy 302.129952 -309.692294) (xy 302.137318 -309.710836) (xy 302.177196 -309.75173)
			(xy 302.195484 -309.770526) (xy 302.20291 -309.777472) (xy 302.221646 -309.785331) (xy 302.231806 -309.785766)
			(xy 302.285908 -309.785766) (xy 302.292268 -309.785606) (xy 302.304608 -309.782528) (xy 302.310292 -309.77967)
			(xy 302.310546 -309.779416) (xy 302.331361 -309.768151) (xy 302.373926 -309.747441) (xy 302.395636 -309.738014)
			(xy 302.3997 -309.73649) (xy 302.40351 -309.734712) (xy 302.404018 -309.734458) (xy 302.407066 -309.733188)
			(xy 302.40859 -309.73268) (xy 302.410368 -309.731918) (xy 302.411384 -309.731918) (xy 302.421798 -309.727346)
			(xy 302.424338 -309.72633) (xy 302.427386 -309.724806) (xy 302.431 -309.722852) (xy 302.437628 -309.717998)
			(xy 302.440594 -309.715154) (xy 302.44542 -309.710328) (xy 302.45939 -309.689246) (xy 302.469042 -309.674768)
			(xy 302.469804 -309.660544) (xy 302.471432 -309.636081) (xy 302.48151 -309.588105) (xy 302.499122 -309.542354)
			(xy 302.523817 -309.500004) (xy 302.554961 -309.462144) (xy 302.591753 -309.429745) (xy 302.633248 -309.40364)
			(xy 302.678381 -309.384499) (xy 302.725992 -309.372815) (xy 302.774858 -309.368886) (xy 302.823724 -309.372815)
			(xy 302.871335 -309.384499) (xy 302.916468 -309.40364) (xy 302.957963 -309.429745) (xy 302.994755 -309.462144)
			(xy 303.025899 -309.500004) (xy 303.050594 -309.542354) (xy 303.068206 -309.588105) (xy 303.078284 -309.636081)
			(xy 303.079912 -309.660544) (xy 303.080674 -309.674768) (xy 303.101756 -309.706518) (xy 303.108106 -309.714138)
			(xy 303.116488 -309.72252) (xy 303.12614 -309.726584) (xy 303.12741 -309.727092) (xy 303.129442 -309.728108)
			(xy 303.143666 -309.733696) (xy 303.168143 -309.743965) (xy 303.216051 -309.766835) (xy 303.239424 -309.779416)
			(xy 303.239678 -309.77967) (xy 303.245366 -309.782518) (xy 303.257703 -309.785602) (xy 303.264062 -309.785766)
			(xy 303.31791 -309.785766) (xy 303.328068 -309.785323) (xy 303.346803 -309.777467) (xy 303.354232 -309.770526)
			(xy 303.412398 -309.710836) (xy 303.419764 -309.692294) (xy 303.41951 -309.68188) (xy 303.41951 -309.674768)
			(xy 303.420032 -309.649513) (xy 303.428345 -309.599691) (xy 303.444746 -309.551917) (xy 303.468787 -309.507494)
			(xy 303.499811 -309.467634) (xy 303.536973 -309.433424) (xy 303.579259 -309.405798) (xy 303.625515 -309.385508)
			(xy 303.67448 -309.373108) (xy 303.724818 -309.368937) (xy 303.775156 -309.373108) (xy 303.824121 -309.385508)
			(xy 303.870377 -309.405798) (xy 303.912663 -309.433424) (xy 303.949825 -309.467634) (xy 303.980849 -309.507494)
			(xy 304.00489 -309.551917) (xy 304.021291 -309.599691) (xy 304.029604 -309.649513) (xy 304.030126 -309.674768)
			(xy 304.030126 -309.68188) (xy 304.029872 -309.692294) (xy 304.037238 -309.710836) (xy 304.077116 -309.75173)
			(xy 304.095404 -309.770526) (xy 304.102832 -309.777469) (xy 304.121568 -309.785321) (xy 304.131726 -309.785766)
			(xy 304.185828 -309.785766) (xy 304.192187 -309.785603) (xy 304.204525 -309.782521) (xy 304.210212 -309.77967)
			(xy 304.210466 -309.779416) (xy 304.231282 -309.768151) (xy 304.273847 -309.747442) (xy 304.295556 -309.738014)
			(xy 304.29962 -309.73649) (xy 304.30343 -309.734712) (xy 304.303938 -309.734458) (xy 304.306986 -309.733188)
			(xy 304.30851 -309.73268) (xy 304.310288 -309.731918) (xy 304.311304 -309.731918) (xy 304.321718 -309.727346)
			(xy 304.324258 -309.72633) (xy 304.327306 -309.724806) (xy 304.330923 -309.722856) (xy 304.337558 -309.718009)
			(xy 304.340514 -309.715154) (xy 304.34534 -309.710328) (xy 304.35931 -309.689246) (xy 304.368962 -309.674768)
			(xy 304.369724 -309.660544) (xy 304.371352 -309.636081) (xy 304.38143 -309.588105) (xy 304.399042 -309.542354)
			(xy 304.423737 -309.500004) (xy 304.454881 -309.462144) (xy 304.491673 -309.429745) (xy 304.533168 -309.40364)
			(xy 304.578301 -309.384499) (xy 304.625912 -309.372815) (xy 304.674778 -309.368886) (xy 304.723644 -309.372815)
			(xy 304.771255 -309.384499) (xy 304.816388 -309.40364) (xy 304.857883 -309.429745) (xy 304.894675 -309.462144)
			(xy 304.925819 -309.500004) (xy 304.950514 -309.542354) (xy 304.968126 -309.588105) (xy 304.978204 -309.636081)
			(xy 304.979832 -309.660544) (xy 304.980594 -309.674768) (xy 305.001676 -309.706518) (xy 305.008026 -309.714138)
			(xy 305.016408 -309.72252) (xy 305.02606 -309.726584) (xy 305.02733 -309.727092) (xy 305.029362 -309.728108)
			(xy 305.043586 -309.733696) (xy 305.067997 -309.743973) (xy 305.115776 -309.766847) (xy 305.13909 -309.779416)
			(xy 305.150774 -309.785766) (xy 305.16449 -309.785766) (xy 305.173634 -309.789576) (xy 305.178198 -309.791584)
			(xy 305.186512 -309.797083) (xy 305.190144 -309.800498) (xy 305.21148 -309.821834) (xy 305.21529 -309.825136)
			(xy 305.218338 -309.827676) (xy 305.22222 -309.830752) (xy 305.230918 -309.835487) (xy 305.23561 -309.837074)
			(xy 305.241198 -309.838852) (xy 305.249797 -309.841098) (xy 305.267536 -309.840234) (xy 305.283926 -309.833397)
			(xy 305.290728 -309.827676) (xy 305.300634 -309.818532) (xy 305.308762 -309.792878) (xy 305.304698 -309.77459)
			(xy 305.30419 -309.772812) (xy 305.297323 -309.748884) (xy 305.289921 -309.699658) (xy 305.289458 -309.674768)
			(xy 305.28995 -309.648422) (xy 305.298198 -309.59638) (xy 305.314486 -309.546269) (xy 305.338412 -309.499322)
			(xy 305.369388 -309.456697) (xy 305.40665 -309.419442) (xy 305.449282 -309.388475) (xy 305.496233 -309.364559)
			(xy 305.546348 -309.348282) (xy 305.598392 -309.340045) (xy 305.624738 -309.339488) (xy 305.638324 -309.339602)
			(xy 305.665408 -309.341763) (xy 305.67884 -309.343806) (xy 305.690524 -309.345838) (xy 305.71313 -309.338726)
			(xy 305.78933 -309.266844) (xy 305.797458 -309.244492) (xy 305.796188 -309.232554) (xy 305.79441 -309.199788)
			(xy 305.794897 -309.174969) (xy 305.802929 -309.125986) (xy 305.81878 -309.078947) (xy 305.842032 -309.035092)
			(xy 305.872072 -308.995576) (xy 305.90811 -308.961441) (xy 305.949195 -308.933586) (xy 305.994246 -308.912744)
			(xy 306.042074 -308.899465) (xy 306.091421 -308.894099) (xy 306.140986 -308.896787) (xy 306.189463 -308.907457)
			(xy 306.235575 -308.92583) (xy 306.278108 -308.951421) (xy 306.31594 -308.983555) (xy 306.348076 -309.021387)
			(xy 306.373667 -309.063919) (xy 306.392041 -309.110031) (xy 306.402712 -309.158508) (xy 306.404952 -309.199788)
			(xy 306.744128 -309.199788) (xy 306.748088 -309.150734) (xy 306.759865 -309.10295) (xy 306.779156 -309.057674)
			(xy 306.805459 -309.016078) (xy 306.838094 -308.979241) (xy 306.876215 -308.948116) (xy 306.918836 -308.923509)
			(xy 306.964852 -308.906057) (xy 307.013071 -308.896213) (xy 307.062246 -308.894232) (xy 307.111101 -308.900164)
			(xy 307.158372 -308.913856) (xy 307.202834 -308.934954) (xy 307.243337 -308.96291) (xy 307.27883 -308.997002)
			(xy 307.308395 -309.036346) (xy 307.331266 -309.079923) (xy 307.34685 -309.126604) (xy 307.354745 -309.175181)
			(xy 307.35524 -309.199788) (xy 307.694088 -309.199788) (xy 307.698048 -309.150734) (xy 307.709825 -309.10295)
			(xy 307.729116 -309.057674) (xy 307.755419 -309.016078) (xy 307.788054 -308.979241) (xy 307.826175 -308.948116)
			(xy 307.868796 -308.923509) (xy 307.914812 -308.906057) (xy 307.963031 -308.896213) (xy 308.012206 -308.894232)
			(xy 308.061061 -308.900164) (xy 308.108332 -308.913856) (xy 308.152794 -308.934954) (xy 308.193297 -308.96291)
			(xy 308.22879 -308.997002) (xy 308.258355 -309.036346) (xy 308.281226 -309.079923) (xy 308.29681 -309.126604)
			(xy 308.304705 -309.175181) (xy 308.3052 -309.199788) (xy 308.644048 -309.199788) (xy 308.648008 -309.150734)
			(xy 308.659785 -309.10295) (xy 308.679076 -309.057674) (xy 308.705379 -309.016078) (xy 308.738014 -308.979241)
			(xy 308.776135 -308.948116) (xy 308.818756 -308.923509) (xy 308.864772 -308.906057) (xy 308.912991 -308.896213)
			(xy 308.962166 -308.894232) (xy 309.011021 -308.900164) (xy 309.058292 -308.913856) (xy 309.102754 -308.934954)
			(xy 309.143257 -308.96291) (xy 309.17875 -308.997002) (xy 309.208315 -309.036346) (xy 309.231186 -309.079923)
			(xy 309.24677 -309.126604) (xy 309.254665 -309.175181) (xy 309.25516 -309.199788) (xy 309.594008 -309.199788)
			(xy 309.597968 -309.150734) (xy 309.609745 -309.10295) (xy 309.629036 -309.057674) (xy 309.655339 -309.016078)
			(xy 309.687974 -308.979241) (xy 309.726095 -308.948116) (xy 309.768716 -308.923509) (xy 309.814732 -308.906057)
			(xy 309.862951 -308.896213) (xy 309.912126 -308.894232) (xy 309.960981 -308.900164) (xy 310.008252 -308.913856)
			(xy 310.052714 -308.934954) (xy 310.093217 -308.96291) (xy 310.12871 -308.997002) (xy 310.158275 -309.036346)
			(xy 310.181146 -309.079923) (xy 310.19673 -309.126604) (xy 310.204625 -309.175181) (xy 310.20512 -309.199788)
			(xy 310.543968 -309.199788) (xy 310.547928 -309.150734) (xy 310.559705 -309.10295) (xy 310.578996 -309.057674)
			(xy 310.605299 -309.016078) (xy 310.637934 -308.979241) (xy 310.676055 -308.948116) (xy 310.718676 -308.923509)
			(xy 310.764692 -308.906057) (xy 310.812911 -308.896213) (xy 310.862086 -308.894232) (xy 310.910941 -308.900164)
			(xy 310.958212 -308.913856) (xy 311.002674 -308.934954) (xy 311.043177 -308.96291) (xy 311.07867 -308.997002)
			(xy 311.108235 -309.036346) (xy 311.131106 -309.079923) (xy 311.14669 -309.126604) (xy 311.154585 -309.175181)
			(xy 311.15508 -309.199788) (xy 311.493928 -309.199788) (xy 311.497888 -309.150734) (xy 311.509665 -309.10295)
			(xy 311.528956 -309.057674) (xy 311.555259 -309.016078) (xy 311.587894 -308.979241) (xy 311.626015 -308.948116)
			(xy 311.668636 -308.923509) (xy 311.714652 -308.906057) (xy 311.762871 -308.896213) (xy 311.812046 -308.894232)
			(xy 311.860901 -308.900164) (xy 311.908172 -308.913856) (xy 311.952634 -308.934954) (xy 311.993137 -308.96291)
			(xy 312.02863 -308.997002) (xy 312.058195 -309.036346) (xy 312.081066 -309.079923) (xy 312.09665 -309.126604)
			(xy 312.104545 -309.175181) (xy 312.10504 -309.199788) (xy 312.443888 -309.199788) (xy 312.447848 -309.150734)
			(xy 312.459625 -309.10295) (xy 312.478916 -309.057674) (xy 312.505219 -309.016078) (xy 312.537854 -308.979241)
			(xy 312.575975 -308.948116) (xy 312.618596 -308.923509) (xy 312.664612 -308.906057) (xy 312.712831 -308.896213)
			(xy 312.762006 -308.894232) (xy 312.810861 -308.900164) (xy 312.858132 -308.913856) (xy 312.902594 -308.934954)
			(xy 312.943097 -308.96291) (xy 312.97859 -308.997002) (xy 313.008155 -309.036346) (xy 313.031026 -309.079923)
			(xy 313.04661 -309.126604) (xy 313.054505 -309.175181) (xy 313.055 -309.199788) (xy 313.394102 -309.199788)
			(xy 313.398062 -309.150734) (xy 313.409839 -309.10295) (xy 313.42913 -309.057674) (xy 313.455433 -309.016078)
			(xy 313.488068 -308.979241) (xy 313.526189 -308.948116) (xy 313.56881 -308.923509) (xy 313.614826 -308.906057)
			(xy 313.663045 -308.896213) (xy 313.71222 -308.894232) (xy 313.761075 -308.900164) (xy 313.808346 -308.913856)
			(xy 313.852808 -308.934954) (xy 313.893311 -308.96291) (xy 313.928804 -308.997002) (xy 313.958369 -309.036346)
			(xy 313.98124 -309.079923) (xy 313.996824 -309.126604) (xy 314.004719 -309.175181) (xy 314.005214 -309.199788)
			(xy 314.344062 -309.199788) (xy 314.348022 -309.150734) (xy 314.359799 -309.10295) (xy 314.37909 -309.057674)
			(xy 314.405393 -309.016078) (xy 314.438028 -308.979241) (xy 314.476149 -308.948116) (xy 314.51877 -308.923509)
			(xy 314.564786 -308.906057) (xy 314.613005 -308.896213) (xy 314.66218 -308.894232) (xy 314.711035 -308.900164)
			(xy 314.758306 -308.913856) (xy 314.802768 -308.934954) (xy 314.843271 -308.96291) (xy 314.878764 -308.997002)
			(xy 314.908329 -309.036346) (xy 314.9312 -309.079923) (xy 314.946784 -309.126604) (xy 314.954679 -309.175181)
			(xy 314.954694 -309.175912) (xy 320.534028 -309.175912) (xy 320.538099 -309.12029) (xy 320.550225 -309.065853)
			(xy 320.570148 -309.013762) (xy 320.597444 -308.965127) (xy 320.63153 -308.920984) (xy 320.671679 -308.882275)
			(xy 320.717037 -308.849824) (xy 320.766637 -308.824323) (xy 320.819421 -308.806316) (xy 320.874264 -308.796186)
			(xy 320.929998 -308.794149) (xy 320.985435 -308.800249) (xy 321.039392 -308.814355) (xy 321.090721 -308.836167)
			(xy 321.138327 -308.865221) (xy 321.181195 -308.900896) (xy 321.218412 -308.942433) (xy 321.249185 -308.988946)
			(xy 321.272857 -309.039443) (xy 321.288925 -309.09285) (xy 321.297045 -309.148026) (xy 321.297554 -309.175912)
			(xy 321.297045 -309.203798) (xy 321.288925 -309.258974) (xy 321.272857 -309.312381) (xy 321.249185 -309.362878)
			(xy 321.218412 -309.409391) (xy 321.181195 -309.450928) (xy 321.138327 -309.486603) (xy 321.090721 -309.515657)
			(xy 321.039392 -309.537469) (xy 320.985435 -309.551575) (xy 320.929998 -309.557675) (xy 320.874264 -309.555638)
			(xy 320.819421 -309.545508) (xy 320.766637 -309.527501) (xy 320.717037 -309.502) (xy 320.671679 -309.469549)
			(xy 320.63153 -309.43084) (xy 320.597444 -309.386697) (xy 320.570148 -309.338062) (xy 320.550225 -309.285971)
			(xy 320.538099 -309.231534) (xy 320.534028 -309.175912) (xy 314.954694 -309.175912) (xy 314.955174 -309.199788)
			(xy 314.954679 -309.224395) (xy 314.946784 -309.272972) (xy 314.9312 -309.319653) (xy 314.908329 -309.36323)
			(xy 314.878764 -309.402574) (xy 314.843271 -309.436666) (xy 314.802768 -309.464622) (xy 314.758306 -309.48572)
			(xy 314.711035 -309.499412) (xy 314.66218 -309.505344) (xy 314.613005 -309.503363) (xy 314.564786 -309.493519)
			(xy 314.51877 -309.476067) (xy 314.476149 -309.45146) (xy 314.438028 -309.420335) (xy 314.405393 -309.383498)
			(xy 314.37909 -309.341902) (xy 314.359799 -309.296626) (xy 314.348022 -309.248842) (xy 314.344062 -309.199788)
			(xy 314.005214 -309.199788) (xy 314.004719 -309.224395) (xy 313.996824 -309.272972) (xy 313.98124 -309.319653)
			(xy 313.958369 -309.36323) (xy 313.928804 -309.402574) (xy 313.893311 -309.436666) (xy 313.852808 -309.464622)
			(xy 313.808346 -309.48572) (xy 313.761075 -309.499412) (xy 313.71222 -309.505344) (xy 313.663045 -309.503363)
			(xy 313.614826 -309.493519) (xy 313.56881 -309.476067) (xy 313.526189 -309.45146) (xy 313.488068 -309.420335)
			(xy 313.455433 -309.383498) (xy 313.42913 -309.341902) (xy 313.409839 -309.296626) (xy 313.398062 -309.248842)
			(xy 313.394102 -309.199788) (xy 313.055 -309.199788) (xy 313.054505 -309.224395) (xy 313.04661 -309.272972)
			(xy 313.031026 -309.319653) (xy 313.008155 -309.36323) (xy 312.97859 -309.402574) (xy 312.943097 -309.436666)
			(xy 312.902594 -309.464622) (xy 312.858132 -309.48572) (xy 312.810861 -309.499412) (xy 312.762006 -309.505344)
			(xy 312.712831 -309.503363) (xy 312.664612 -309.493519) (xy 312.618596 -309.476067) (xy 312.575975 -309.45146)
			(xy 312.537854 -309.420335) (xy 312.505219 -309.383498) (xy 312.478916 -309.341902) (xy 312.459625 -309.296626)
			(xy 312.447848 -309.248842) (xy 312.443888 -309.199788) (xy 312.10504 -309.199788) (xy 312.104545 -309.224395)
			(xy 312.09665 -309.272972) (xy 312.081066 -309.319653) (xy 312.058195 -309.36323) (xy 312.02863 -309.402574)
			(xy 311.993137 -309.436666) (xy 311.952634 -309.464622) (xy 311.908172 -309.48572) (xy 311.860901 -309.499412)
			(xy 311.812046 -309.505344) (xy 311.762871 -309.503363) (xy 311.714652 -309.493519) (xy 311.668636 -309.476067)
			(xy 311.626015 -309.45146) (xy 311.587894 -309.420335) (xy 311.555259 -309.383498) (xy 311.528956 -309.341902)
			(xy 311.509665 -309.296626) (xy 311.497888 -309.248842) (xy 311.493928 -309.199788) (xy 311.15508 -309.199788)
			(xy 311.154585 -309.224395) (xy 311.14669 -309.272972) (xy 311.131106 -309.319653) (xy 311.108235 -309.36323)
			(xy 311.07867 -309.402574) (xy 311.043177 -309.436666) (xy 311.002674 -309.464622) (xy 310.958212 -309.48572)
			(xy 310.910941 -309.499412) (xy 310.862086 -309.505344) (xy 310.812911 -309.503363) (xy 310.764692 -309.493519)
			(xy 310.718676 -309.476067) (xy 310.676055 -309.45146) (xy 310.637934 -309.420335) (xy 310.605299 -309.383498)
			(xy 310.578996 -309.341902) (xy 310.559705 -309.296626) (xy 310.547928 -309.248842) (xy 310.543968 -309.199788)
			(xy 310.20512 -309.199788) (xy 310.204625 -309.224395) (xy 310.19673 -309.272972) (xy 310.181146 -309.319653)
			(xy 310.158275 -309.36323) (xy 310.12871 -309.402574) (xy 310.093217 -309.436666) (xy 310.052714 -309.464622)
			(xy 310.008252 -309.48572) (xy 309.960981 -309.499412) (xy 309.912126 -309.505344) (xy 309.862951 -309.503363)
			(xy 309.814732 -309.493519) (xy 309.768716 -309.476067) (xy 309.726095 -309.45146) (xy 309.687974 -309.420335)
			(xy 309.655339 -309.383498) (xy 309.629036 -309.341902) (xy 309.609745 -309.296626) (xy 309.597968 -309.248842)
			(xy 309.594008 -309.199788) (xy 309.25516 -309.199788) (xy 309.254665 -309.224395) (xy 309.24677 -309.272972)
			(xy 309.231186 -309.319653) (xy 309.208315 -309.36323) (xy 309.17875 -309.402574) (xy 309.143257 -309.436666)
			(xy 309.102754 -309.464622) (xy 309.058292 -309.48572) (xy 309.011021 -309.499412) (xy 308.962166 -309.505344)
			(xy 308.912991 -309.503363) (xy 308.864772 -309.493519) (xy 308.818756 -309.476067) (xy 308.776135 -309.45146)
			(xy 308.738014 -309.420335) (xy 308.705379 -309.383498) (xy 308.679076 -309.341902) (xy 308.659785 -309.296626)
			(xy 308.648008 -309.248842) (xy 308.644048 -309.199788) (xy 308.3052 -309.199788) (xy 308.304705 -309.224395)
			(xy 308.29681 -309.272972) (xy 308.281226 -309.319653) (xy 308.258355 -309.36323) (xy 308.22879 -309.402574)
			(xy 308.193297 -309.436666) (xy 308.152794 -309.464622) (xy 308.108332 -309.48572) (xy 308.061061 -309.499412)
			(xy 308.012206 -309.505344) (xy 307.963031 -309.503363) (xy 307.914812 -309.493519) (xy 307.868796 -309.476067)
			(xy 307.826175 -309.45146) (xy 307.788054 -309.420335) (xy 307.755419 -309.383498) (xy 307.729116 -309.341902)
			(xy 307.709825 -309.296626) (xy 307.698048 -309.248842) (xy 307.694088 -309.199788) (xy 307.35524 -309.199788)
			(xy 307.354745 -309.224395) (xy 307.34685 -309.272972) (xy 307.331266 -309.319653) (xy 307.308395 -309.36323)
			(xy 307.27883 -309.402574) (xy 307.243337 -309.436666) (xy 307.202834 -309.464622) (xy 307.158372 -309.48572)
			(xy 307.111101 -309.499412) (xy 307.062246 -309.505344) (xy 307.013071 -309.503363) (xy 306.964852 -309.493519)
			(xy 306.918836 -309.476067) (xy 306.876215 -309.45146) (xy 306.838094 -309.420335) (xy 306.805459 -309.383498)
			(xy 306.779156 -309.341902) (xy 306.759865 -309.296626) (xy 306.748088 -309.248842) (xy 306.744128 -309.199788)
			(xy 306.404952 -309.199788) (xy 306.405401 -309.208073) (xy 306.400036 -309.25742) (xy 306.386758 -309.305249)
			(xy 306.365917 -309.3503) (xy 306.338062 -309.391385) (xy 306.303928 -309.427424) (xy 306.264413 -309.457465)
			(xy 306.220559 -309.480718) (xy 306.17352 -309.49657) (xy 306.124537 -309.504603) (xy 306.099718 -309.505096)
			(xy 306.066952 -309.503318) (xy 306.055014 -309.502048) (xy 306.032662 -309.510176) (xy 305.96078 -309.586376)
			(xy 305.953668 -309.608982) (xy 305.9557 -309.620666) (xy 305.957738 -309.634098) (xy 305.959901 -309.661183)
			(xy 305.960018 -309.674768) (xy 305.959903 -309.688354) (xy 305.95774 -309.715438) (xy 305.9557 -309.72887)
			(xy 305.953668 -309.740554) (xy 305.96078 -309.76316) (xy 306.032662 -309.83936) (xy 306.055014 -309.847488)
			(xy 306.066952 -309.846218) (xy 306.099718 -309.84444) (xy 306.123709 -309.844888) (xy 306.171099 -309.852397)
			(xy 306.216732 -309.867228) (xy 306.259482 -309.889015) (xy 306.298297 -309.917221) (xy 306.332222 -309.951153)
			(xy 306.36042 -309.989975) (xy 306.382198 -310.03273) (xy 306.397019 -310.078365) (xy 306.404518 -310.125757)
			(xy 306.405026 -310.149748) (xy 306.404932 -310.158916) (xy 306.403786 -310.177216) (xy 306.40274 -310.186324)
			(xy 306.40147 -310.198262) (xy 306.409344 -310.220614) (xy 306.485798 -310.293512) (xy 306.508404 -310.300624)
			(xy 306.520342 -310.298592) (xy 306.533893 -310.296454) (xy 306.561234 -310.294167) (xy 306.574952 -310.29402)
			(xy 306.588606 -310.294181) (xy 306.615819 -310.29647) (xy 306.629308 -310.298592) (xy 306.641246 -310.300624)
			(xy 306.663852 -310.293512) (xy 306.740306 -310.220614) (xy 306.74818 -310.198262) (xy 306.74691 -310.18607)
			(xy 306.74586 -310.177026) (xy 306.744713 -310.158852) (xy 306.744624 -310.149748) (xy 306.745106 -310.124929)
			(xy 306.753129 -310.075945) (xy 306.768971 -310.028904) (xy 306.792214 -309.985045) (xy 306.822248 -309.945525)
			(xy 306.858279 -309.911384) (xy 306.899359 -309.883523) (xy 306.944405 -309.862674) (xy 306.992231 -309.849388)
			(xy 307.041576 -309.844014) (xy 307.091141 -309.846695) (xy 307.139619 -309.857359) (xy 307.185733 -309.875725)
			(xy 307.228268 -309.90131) (xy 307.266104 -309.933439) (xy 307.298243 -309.971266) (xy 307.32384 -310.013795)
			(xy 307.342218 -310.059904) (xy 307.352894 -310.10838) (xy 307.355143 -310.149748) (xy 307.694088 -310.149748)
			(xy 307.698048 -310.100694) (xy 307.709825 -310.05291) (xy 307.729116 -310.007634) (xy 307.755419 -309.966038)
			(xy 307.788054 -309.929201) (xy 307.826175 -309.898076) (xy 307.868796 -309.873469) (xy 307.914812 -309.856017)
			(xy 307.963031 -309.846173) (xy 308.012206 -309.844192) (xy 308.061061 -309.850124) (xy 308.108332 -309.863816)
			(xy 308.152794 -309.884914) (xy 308.193297 -309.91287) (xy 308.22879 -309.946962) (xy 308.258355 -309.986306)
			(xy 308.281226 -310.029883) (xy 308.29681 -310.076564) (xy 308.304705 -310.125141) (xy 308.3052 -310.149748)
			(xy 308.644048 -310.149748) (xy 308.648008 -310.100694) (xy 308.659785 -310.05291) (xy 308.679076 -310.007634)
			(xy 308.705379 -309.966038) (xy 308.738014 -309.929201) (xy 308.776135 -309.898076) (xy 308.818756 -309.873469)
			(xy 308.864772 -309.856017) (xy 308.912991 -309.846173) (xy 308.962166 -309.844192) (xy 309.011021 -309.850124)
			(xy 309.058292 -309.863816) (xy 309.102754 -309.884914) (xy 309.143257 -309.91287) (xy 309.17875 -309.946962)
			(xy 309.208315 -309.986306) (xy 309.231186 -310.029883) (xy 309.24677 -310.076564) (xy 309.254665 -310.125141)
			(xy 309.25516 -310.149748) (xy 309.594008 -310.149748) (xy 309.597968 -310.100694) (xy 309.609745 -310.05291)
			(xy 309.629036 -310.007634) (xy 309.655339 -309.966038) (xy 309.687974 -309.929201) (xy 309.726095 -309.898076)
			(xy 309.768716 -309.873469) (xy 309.814732 -309.856017) (xy 309.862951 -309.846173) (xy 309.912126 -309.844192)
			(xy 309.960981 -309.850124) (xy 310.008252 -309.863816) (xy 310.052714 -309.884914) (xy 310.093217 -309.91287)
			(xy 310.12871 -309.946962) (xy 310.158275 -309.986306) (xy 310.181146 -310.029883) (xy 310.19673 -310.076564)
			(xy 310.204625 -310.125141) (xy 310.20512 -310.149748) (xy 310.204625 -310.174355) (xy 310.19673 -310.222932)
			(xy 310.181146 -310.269613) (xy 310.158275 -310.31319) (xy 310.12871 -310.352534) (xy 310.093217 -310.386626)
			(xy 310.052714 -310.414582) (xy 310.008252 -310.43568) (xy 309.960981 -310.449372) (xy 309.912126 -310.455304)
			(xy 309.862951 -310.453323) (xy 309.814732 -310.443479) (xy 309.768716 -310.426027) (xy 309.726095 -310.40142)
			(xy 309.687974 -310.370295) (xy 309.655339 -310.333458) (xy 309.629036 -310.291862) (xy 309.609745 -310.246586)
			(xy 309.597968 -310.198802) (xy 309.594008 -310.149748) (xy 309.25516 -310.149748) (xy 309.254665 -310.174355)
			(xy 309.24677 -310.222932) (xy 309.231186 -310.269613) (xy 309.208315 -310.31319) (xy 309.17875 -310.352534)
			(xy 309.143257 -310.386626) (xy 309.102754 -310.414582) (xy 309.058292 -310.43568) (xy 309.011021 -310.449372)
			(xy 308.962166 -310.455304) (xy 308.912991 -310.453323) (xy 308.864772 -310.443479) (xy 308.818756 -310.426027)
			(xy 308.776135 -310.40142) (xy 308.738014 -310.370295) (xy 308.705379 -310.333458) (xy 308.679076 -310.291862)
			(xy 308.659785 -310.246586) (xy 308.648008 -310.198802) (xy 308.644048 -310.149748) (xy 308.3052 -310.149748)
			(xy 308.304705 -310.174355) (xy 308.29681 -310.222932) (xy 308.281226 -310.269613) (xy 308.258355 -310.31319)
			(xy 308.22879 -310.352534) (xy 308.193297 -310.386626) (xy 308.152794 -310.414582) (xy 308.108332 -310.43568)
			(xy 308.061061 -310.449372) (xy 308.012206 -310.455304) (xy 307.963031 -310.453323) (xy 307.914812 -310.443479)
			(xy 307.868796 -310.426027) (xy 307.826175 -310.40142) (xy 307.788054 -310.370295) (xy 307.755419 -310.333458)
			(xy 307.729116 -310.291862) (xy 307.709825 -310.246586) (xy 307.698048 -310.198802) (xy 307.694088 -310.149748)
			(xy 307.355143 -310.149748) (xy 307.355588 -310.157944) (xy 307.350227 -310.20729) (xy 307.336954 -310.25512)
			(xy 307.316117 -310.300172) (xy 307.288266 -310.341259) (xy 307.254135 -310.377299) (xy 307.214622 -310.407342)
			(xy 307.17077 -310.430598) (xy 307.123733 -310.446452) (xy 307.07475 -310.454488) (xy 307.049932 -310.455056)
			(xy 307.040828 -310.454957) (xy 307.022655 -310.453812) (xy 307.01361 -310.45277) (xy 307.001418 -310.4515)
			(xy 306.979066 -310.459374) (xy 306.906168 -310.535828) (xy 306.899056 -310.558434) (xy 306.901088 -310.570372)
			(xy 306.903217 -310.58386) (xy 306.905503 -310.611074) (xy 306.90566 -310.624728) (xy 306.90566 -310.69534)
			(xy 306.906228 -310.706029) (xy 306.914898 -310.725572) (xy 306.922424 -310.733186) (xy 306.986686 -310.790844)
			(xy 307.007006 -310.797448) (xy 307.017928 -310.796432) (xy 307.049932 -310.794654) (xy 307.075189 -310.795178)
			(xy 307.125013 -310.803497) (xy 307.172788 -310.819903) (xy 307.217211 -310.843948) (xy 307.257072 -310.874976)
			(xy 307.291282 -310.912142) (xy 307.318909 -310.954431) (xy 307.339198 -311.000691) (xy 307.351598 -311.049659)
			(xy 307.355766 -311.099962) (xy 307.694088 -311.099962) (xy 307.698048 -311.050908) (xy 307.709825 -311.003124)
			(xy 307.729116 -310.957848) (xy 307.755419 -310.916252) (xy 307.788054 -310.879415) (xy 307.826175 -310.84829)
			(xy 307.868796 -310.823683) (xy 307.914812 -310.806231) (xy 307.963031 -310.796387) (xy 308.012206 -310.794406)
			(xy 308.061061 -310.800338) (xy 308.108332 -310.81403) (xy 308.152794 -310.835128) (xy 308.193297 -310.863084)
			(xy 308.22879 -310.897176) (xy 308.258355 -310.93652) (xy 308.281226 -310.980097) (xy 308.29681 -311.026778)
			(xy 308.304705 -311.075355) (xy 308.3052 -311.099962) (xy 308.644048 -311.099962) (xy 308.648008 -311.050908)
			(xy 308.659785 -311.003124) (xy 308.679076 -310.957848) (xy 308.705379 -310.916252) (xy 308.738014 -310.879415)
			(xy 308.776135 -310.84829) (xy 308.818756 -310.823683) (xy 308.864772 -310.806231) (xy 308.912991 -310.796387)
			(xy 308.962166 -310.794406) (xy 309.011021 -310.800338) (xy 309.058292 -310.81403) (xy 309.102754 -310.835128)
			(xy 309.143257 -310.863084) (xy 309.17875 -310.897176) (xy 309.208315 -310.93652) (xy 309.231186 -310.980097)
			(xy 309.24677 -311.026778) (xy 309.254665 -311.075355) (xy 309.25516 -311.099962) (xy 309.594008 -311.099962)
			(xy 309.597968 -311.050908) (xy 309.609745 -311.003124) (xy 309.629036 -310.957848) (xy 309.655339 -310.916252)
			(xy 309.687974 -310.879415) (xy 309.726095 -310.84829) (xy 309.768716 -310.823683) (xy 309.814732 -310.806231)
			(xy 309.862951 -310.796387) (xy 309.912126 -310.794406) (xy 309.960981 -310.800338) (xy 310.008252 -310.81403)
			(xy 310.052714 -310.835128) (xy 310.093217 -310.863084) (xy 310.12871 -310.897176) (xy 310.158275 -310.93652)
			(xy 310.181146 -310.980097) (xy 310.19673 -311.026778) (xy 310.204625 -311.075355) (xy 310.204955 -311.091749)
			(xy 310.544042 -311.091749) (xy 310.549405 -311.042391) (xy 310.562683 -310.994551) (xy 310.583525 -310.949489)
			(xy 310.611383 -310.908393) (xy 310.645522 -310.872346) (xy 310.685044 -310.842296) (xy 310.728907 -310.819036)
			(xy 310.775954 -310.803179) (xy 310.824948 -310.795142) (xy 310.849772 -310.794654) (xy 310.863955 -310.794835)
			(xy 310.892195 -310.797504) (xy 310.90616 -310.799988) (xy 310.918606 -310.802274) (xy 310.942482 -310.794908)
			(xy 311.019698 -310.717692) (xy 311.027064 -310.693562) (xy 311.024778 -310.68137) (xy 311.022292 -310.667341)
			(xy 311.019621 -310.638974) (xy 311.019444 -310.624728) (xy 311.019624 -310.610545) (xy 311.022294 -310.582305)
			(xy 311.024778 -310.56834) (xy 311.027064 -310.555894) (xy 311.019698 -310.532272) (xy 310.942228 -310.454802)
			(xy 310.918606 -310.447436) (xy 310.90616 -310.449722) (xy 310.892194 -310.4522) (xy 310.863955 -310.454871)
			(xy 310.849772 -310.455056) (xy 310.824953 -310.454492) (xy 310.77597 -310.446457) (xy 310.728932 -310.430603)
			(xy 310.685079 -310.407348) (xy 310.645565 -310.377304) (xy 310.611433 -310.341264) (xy 310.583581 -310.300176)
			(xy 310.562744 -310.255124) (xy 310.549469 -310.207294) (xy 310.544108 -310.157946) (xy 310.546801 -310.108382)
			(xy 310.557478 -310.059906) (xy 310.575856 -310.013795) (xy 310.601452 -309.971266) (xy 310.633592 -309.933438)
			(xy 310.671428 -309.901308) (xy 310.713963 -309.875722) (xy 310.760078 -309.857355) (xy 310.808557 -309.846691)
			(xy 310.858122 -309.84401) (xy 310.907469 -309.849384) (xy 310.955295 -309.86267) (xy 311.000342 -309.883519)
			(xy 311.041423 -309.911381) (xy 311.077455 -309.945522) (xy 311.107489 -309.985043) (xy 311.130733 -310.028902)
			(xy 311.146575 -310.075944) (xy 311.154598 -310.124929) (xy 311.15508 -310.149748) (xy 311.154897 -310.163931)
			(xy 311.152229 -310.192171) (xy 311.149746 -310.206136) (xy 311.14746 -310.218582) (xy 311.154826 -310.242204)
			(xy 311.232296 -310.319674) (xy 311.255918 -310.32704) (xy 311.268364 -310.324754) (xy 311.282329 -310.322273)
			(xy 311.310569 -310.319604) (xy 311.324752 -310.31942) (xy 311.338935 -310.319603) (xy 311.367175 -310.322271)
			(xy 311.38114 -310.324754) (xy 311.393586 -310.32704) (xy 311.417208 -310.319674) (xy 311.494678 -310.242204)
			(xy 311.502044 -310.218582) (xy 311.499758 -310.206136) (xy 311.497277 -310.192171) (xy 311.494608 -310.163931)
			(xy 311.494424 -310.149748) (xy 311.494826 -310.124923) (xy 311.502851 -310.075926) (xy 311.518697 -310.028872)
			(xy 311.541947 -309.985002) (xy 311.571988 -309.945471) (xy 311.608028 -309.911322) (xy 311.649119 -309.883453)
			(xy 311.694177 -309.862599) (xy 311.742016 -309.849309) (xy 311.791374 -309.843934) (xy 311.840952 -309.846615)
			(xy 311.889443 -309.857282) (xy 311.935569 -309.875653) (xy 311.978115 -309.901244) (xy 312.015961 -309.933382)
			(xy 312.048109 -309.971219) (xy 312.073712 -310.013759) (xy 312.092095 -310.059881) (xy 312.102774 -310.108369)
			(xy 312.105023 -310.149748) (xy 312.443888 -310.149748) (xy 312.447848 -310.100694) (xy 312.459625 -310.05291)
			(xy 312.478916 -310.007634) (xy 312.505219 -309.966038) (xy 312.537854 -309.929201) (xy 312.575975 -309.898076)
			(xy 312.618596 -309.873469) (xy 312.664612 -309.856017) (xy 312.712831 -309.846173) (xy 312.762006 -309.844192)
			(xy 312.810861 -309.850124) (xy 312.858132 -309.863816) (xy 312.902594 -309.884914) (xy 312.943097 -309.91287)
			(xy 312.97859 -309.946962) (xy 313.008155 -309.986306) (xy 313.031026 -310.029883) (xy 313.04661 -310.076564)
			(xy 313.054505 -310.125141) (xy 313.055 -310.149748) (xy 313.394102 -310.149748) (xy 313.398062 -310.100694)
			(xy 313.409839 -310.05291) (xy 313.42913 -310.007634) (xy 313.455433 -309.966038) (xy 313.488068 -309.929201)
			(xy 313.526189 -309.898076) (xy 313.56881 -309.873469) (xy 313.614826 -309.856017) (xy 313.663045 -309.846173)
			(xy 313.71222 -309.844192) (xy 313.761075 -309.850124) (xy 313.808346 -309.863816) (xy 313.852808 -309.884914)
			(xy 313.893311 -309.91287) (xy 313.928804 -309.946962) (xy 313.958369 -309.986306) (xy 313.98124 -310.029883)
			(xy 313.996824 -310.076564) (xy 314.004719 -310.125141) (xy 314.005214 -310.149748) (xy 314.344062 -310.149748)
			(xy 314.348022 -310.100694) (xy 314.359799 -310.05291) (xy 314.37909 -310.007634) (xy 314.405393 -309.966038)
			(xy 314.438028 -309.929201) (xy 314.476149 -309.898076) (xy 314.51877 -309.873469) (xy 314.564786 -309.856017)
			(xy 314.613005 -309.846173) (xy 314.66218 -309.844192) (xy 314.711035 -309.850124) (xy 314.758306 -309.863816)
			(xy 314.802768 -309.884914) (xy 314.843271 -309.91287) (xy 314.878764 -309.946962) (xy 314.908329 -309.986306)
			(xy 314.9312 -310.029883) (xy 314.946784 -310.076564) (xy 314.954679 -310.125141) (xy 314.955174 -310.149748)
			(xy 315.294276 -310.149748) (xy 315.298236 -310.100694) (xy 315.310013 -310.05291) (xy 315.329304 -310.007634)
			(xy 315.355607 -309.966038) (xy 315.388242 -309.929201) (xy 315.426363 -309.898076) (xy 315.468984 -309.873469)
			(xy 315.515 -309.856017) (xy 315.563219 -309.846173) (xy 315.612394 -309.844192) (xy 315.661249 -309.850124)
			(xy 315.672318 -309.85333) (xy 321.210684 -309.85333) (xy 321.214755 -309.797708) (xy 321.226881 -309.743271)
			(xy 321.246804 -309.69118) (xy 321.2741 -309.642545) (xy 321.308186 -309.598402) (xy 321.348335 -309.559693)
			(xy 321.393693 -309.527242) (xy 321.443293 -309.501741) (xy 321.496077 -309.483734) (xy 321.55092 -309.473604)
			(xy 321.606654 -309.471567) (xy 321.662091 -309.477667) (xy 321.716048 -309.491773) (xy 321.767377 -309.513585)
			(xy 321.814983 -309.542639) (xy 321.840069 -309.563516) (xy 325.804274 -309.563516) (xy 325.808345 -309.507894)
			(xy 325.820471 -309.453457) (xy 325.840394 -309.401366) (xy 325.86769 -309.352731) (xy 325.901776 -309.308588)
			(xy 325.941925 -309.269879) (xy 325.987283 -309.237428) (xy 326.036883 -309.211927) (xy 326.089667 -309.19392)
			(xy 326.14451 -309.18379) (xy 326.200244 -309.181753) (xy 326.255681 -309.187853) (xy 326.309638 -309.201959)
			(xy 326.360967 -309.223771) (xy 326.408573 -309.252825) (xy 326.451441 -309.2885) (xy 326.488658 -309.330037)
			(xy 326.519431 -309.37655) (xy 326.543103 -309.427047) (xy 326.559171 -309.480454) (xy 326.567291 -309.53563)
			(xy 326.5678 -309.563516) (xy 326.567291 -309.591402) (xy 326.559171 -309.646578) (xy 326.543103 -309.699985)
			(xy 326.519431 -309.750482) (xy 326.488658 -309.796995) (xy 326.451441 -309.838532) (xy 326.408573 -309.874207)
			(xy 326.360967 -309.903261) (xy 326.309638 -309.925073) (xy 326.255681 -309.939179) (xy 326.200244 -309.945279)
			(xy 326.14451 -309.943242) (xy 326.089667 -309.933112) (xy 326.036883 -309.915105) (xy 325.987283 -309.889604)
			(xy 325.941925 -309.857153) (xy 325.901776 -309.818444) (xy 325.86769 -309.774301) (xy 325.840394 -309.725666)
			(xy 325.820471 -309.673575) (xy 325.808345 -309.619138) (xy 325.804274 -309.563516) (xy 321.840069 -309.563516)
			(xy 321.857851 -309.578314) (xy 321.895068 -309.619851) (xy 321.925841 -309.666364) (xy 321.949513 -309.716861)
			(xy 321.965581 -309.770268) (xy 321.973701 -309.825444) (xy 321.97421 -309.85333) (xy 321.973701 -309.881216)
			(xy 321.965581 -309.936392) (xy 321.949513 -309.989799) (xy 321.925841 -310.040296) (xy 321.895068 -310.086809)
			(xy 321.857851 -310.128346) (xy 321.814983 -310.164021) (xy 321.767377 -310.193075) (xy 321.716048 -310.214887)
			(xy 321.662091 -310.228993) (xy 321.606654 -310.235093) (xy 321.55092 -310.233056) (xy 321.496077 -310.222926)
			(xy 321.443293 -310.204919) (xy 321.393693 -310.179418) (xy 321.348335 -310.146967) (xy 321.308186 -310.108258)
			(xy 321.2741 -310.064115) (xy 321.246804 -310.01548) (xy 321.226881 -309.963389) (xy 321.214755 -309.908952)
			(xy 321.210684 -309.85333) (xy 315.672318 -309.85333) (xy 315.70852 -309.863816) (xy 315.752982 -309.884914)
			(xy 315.793485 -309.91287) (xy 315.828978 -309.946962) (xy 315.858543 -309.986306) (xy 315.881414 -310.029883)
			(xy 315.896998 -310.076564) (xy 315.904893 -310.125141) (xy 315.905388 -310.149748) (xy 315.904893 -310.174355)
			(xy 315.896998 -310.222932) (xy 315.881414 -310.269613) (xy 315.858543 -310.31319) (xy 315.828978 -310.352534)
			(xy 315.793485 -310.386626) (xy 315.752982 -310.414582) (xy 315.70852 -310.43568) (xy 315.661249 -310.449372)
			(xy 315.612394 -310.455304) (xy 315.563219 -310.453323) (xy 315.515 -310.443479) (xy 315.468984 -310.426027)
			(xy 315.426363 -310.40142) (xy 315.388242 -310.370295) (xy 315.355607 -310.333458) (xy 315.329304 -310.291862)
			(xy 315.310013 -310.246586) (xy 315.298236 -310.198802) (xy 315.294276 -310.149748) (xy 314.955174 -310.149748)
			(xy 314.954679 -310.174355) (xy 314.946784 -310.222932) (xy 314.9312 -310.269613) (xy 314.908329 -310.31319)
			(xy 314.878764 -310.352534) (xy 314.843271 -310.386626) (xy 314.802768 -310.414582) (xy 314.758306 -310.43568)
			(xy 314.711035 -310.449372) (xy 314.66218 -310.455304) (xy 314.613005 -310.453323) (xy 314.564786 -310.443479)
			(xy 314.51877 -310.426027) (xy 314.476149 -310.40142) (xy 314.438028 -310.370295) (xy 314.405393 -310.333458)
			(xy 314.37909 -310.291862) (xy 314.359799 -310.246586) (xy 314.348022 -310.198802) (xy 314.344062 -310.149748)
			(xy 314.005214 -310.149748) (xy 314.004719 -310.174355) (xy 313.996824 -310.222932) (xy 313.98124 -310.269613)
			(xy 313.958369 -310.31319) (xy 313.928804 -310.352534) (xy 313.893311 -310.386626) (xy 313.852808 -310.414582)
			(xy 313.808346 -310.43568) (xy 313.761075 -310.449372) (xy 313.71222 -310.455304) (xy 313.663045 -310.453323)
			(xy 313.614826 -310.443479) (xy 313.56881 -310.426027) (xy 313.526189 -310.40142) (xy 313.488068 -310.370295)
			(xy 313.455433 -310.333458) (xy 313.42913 -310.291862) (xy 313.409839 -310.246586) (xy 313.398062 -310.198802)
			(xy 313.394102 -310.149748) (xy 313.055 -310.149748) (xy 313.054505 -310.174355) (xy 313.04661 -310.222932)
			(xy 313.031026 -310.269613) (xy 313.008155 -310.31319) (xy 312.97859 -310.352534) (xy 312.943097 -310.386626)
			(xy 312.902594 -310.414582) (xy 312.858132 -310.43568) (xy 312.810861 -310.449372) (xy 312.762006 -310.455304)
			(xy 312.712831 -310.453323) (xy 312.664612 -310.443479) (xy 312.618596 -310.426027) (xy 312.575975 -310.40142)
			(xy 312.537854 -310.370295) (xy 312.505219 -310.333458) (xy 312.478916 -310.291862) (xy 312.459625 -310.246586)
			(xy 312.447848 -310.198802) (xy 312.443888 -310.149748) (xy 312.105023 -310.149748) (xy 312.105468 -310.157946)
			(xy 312.100106 -310.207305) (xy 312.086829 -310.255147) (xy 312.065987 -310.300211) (xy 312.038129 -310.341309)
			(xy 312.003988 -310.377359) (xy 311.964466 -310.40741) (xy 311.920602 -310.430672) (xy 311.873552 -310.44653)
			(xy 311.824557 -310.454568) (xy 311.799732 -310.455056) (xy 311.785549 -310.454876) (xy 311.757309 -310.452206)
			(xy 311.743344 -310.449722) (xy 311.730898 -310.447436) (xy 311.707276 -310.454802) (xy 311.629806 -310.532272)
			(xy 311.62244 -310.555894) (xy 311.624726 -310.56834) (xy 311.627204 -310.582306) (xy 311.629875 -310.610545)
			(xy 311.63006 -310.624728) (xy 311.629896 -310.638975) (xy 311.627225 -310.667343) (xy 311.624726 -310.68137)
			(xy 311.624012 -310.68518) (xy 322.042534 -310.68518) (xy 322.046605 -310.629558) (xy 322.058731 -310.575121)
			(xy 322.078654 -310.52303) (xy 322.10595 -310.474395) (xy 322.140036 -310.430252) (xy 322.180185 -310.391543)
			(xy 322.225543 -310.359092) (xy 322.275143 -310.333591) (xy 322.327927 -310.315584) (xy 322.38277 -310.305454)
			(xy 322.438504 -310.303417) (xy 322.493941 -310.309517) (xy 322.547898 -310.323623) (xy 322.599227 -310.345435)
			(xy 322.646833 -310.374489) (xy 322.689701 -310.410164) (xy 322.726918 -310.451701) (xy 322.757691 -310.498214)
			(xy 322.781363 -310.548711) (xy 322.797431 -310.602118) (xy 322.805551 -310.657294) (xy 322.80606 -310.68518)
			(xy 322.805551 -310.713066) (xy 322.797431 -310.768242) (xy 322.781363 -310.821649) (xy 322.757691 -310.872146)
			(xy 322.726918 -310.918659) (xy 322.689701 -310.960196) (xy 322.646833 -310.995871) (xy 322.599227 -311.024925)
			(xy 322.547898 -311.046737) (xy 322.493941 -311.060843) (xy 322.438504 -311.066943) (xy 322.38277 -311.064906)
			(xy 322.327927 -311.054776) (xy 322.275143 -311.036769) (xy 322.225543 -311.011268) (xy 322.180185 -310.978817)
			(xy 322.140036 -310.940108) (xy 322.10595 -310.895965) (xy 322.078654 -310.84733) (xy 322.058731 -310.795239)
			(xy 322.046605 -310.740802) (xy 322.042534 -310.68518) (xy 311.624012 -310.68518) (xy 311.62244 -310.693562)
			(xy 311.629806 -310.717692) (xy 311.707022 -310.794908) (xy 311.730898 -310.802274) (xy 311.743344 -310.799988)
			(xy 311.75731 -310.797509) (xy 311.785549 -310.794839) (xy 311.799732 -310.794654) (xy 311.82455 -310.795212)
			(xy 311.873532 -310.803248) (xy 311.920569 -310.819102) (xy 311.964421 -310.842357) (xy 312.003933 -310.8724)
			(xy 312.038065 -310.90844) (xy 312.065916 -310.949527) (xy 312.086753 -310.994578) (xy 312.100027 -311.042407)
			(xy 312.105388 -311.091753) (xy 312.104942 -311.099962) (xy 312.443888 -311.099962) (xy 312.447848 -311.050908)
			(xy 312.459625 -311.003124) (xy 312.478916 -310.957848) (xy 312.505219 -310.916252) (xy 312.537854 -310.879415)
			(xy 312.575975 -310.84829) (xy 312.618596 -310.823683) (xy 312.664612 -310.806231) (xy 312.712831 -310.796387)
			(xy 312.762006 -310.794406) (xy 312.810861 -310.800338) (xy 312.858132 -310.81403) (xy 312.902594 -310.835128)
			(xy 312.943097 -310.863084) (xy 312.97859 -310.897176) (xy 313.008155 -310.93652) (xy 313.031026 -310.980097)
			(xy 313.04661 -311.026778) (xy 313.054505 -311.075355) (xy 313.055 -311.099962) (xy 313.394102 -311.099962)
			(xy 313.398062 -311.050908) (xy 313.409839 -311.003124) (xy 313.42913 -310.957848) (xy 313.455433 -310.916252)
			(xy 313.488068 -310.879415) (xy 313.526189 -310.84829) (xy 313.56881 -310.823683) (xy 313.614826 -310.806231)
			(xy 313.663045 -310.796387) (xy 313.71222 -310.794406) (xy 313.761075 -310.800338) (xy 313.808346 -310.81403)
			(xy 313.852808 -310.835128) (xy 313.893311 -310.863084) (xy 313.928804 -310.897176) (xy 313.958369 -310.93652)
			(xy 313.98124 -310.980097) (xy 313.996824 -311.026778) (xy 314.004719 -311.075355) (xy 314.005214 -311.099962)
			(xy 314.344062 -311.099962) (xy 314.348022 -311.050908) (xy 314.359799 -311.003124) (xy 314.37909 -310.957848)
			(xy 314.405393 -310.916252) (xy 314.438028 -310.879415) (xy 314.476149 -310.84829) (xy 314.51877 -310.823683)
			(xy 314.564786 -310.806231) (xy 314.613005 -310.796387) (xy 314.66218 -310.794406) (xy 314.711035 -310.800338)
			(xy 314.758306 -310.81403) (xy 314.802768 -310.835128) (xy 314.843271 -310.863084) (xy 314.878764 -310.897176)
			(xy 314.908329 -310.93652) (xy 314.9312 -310.980097) (xy 314.946784 -311.026778) (xy 314.954679 -311.075355)
			(xy 314.955174 -311.099962) (xy 314.954679 -311.124569) (xy 314.946784 -311.173146) (xy 314.9312 -311.219827)
			(xy 314.908329 -311.263404) (xy 314.878764 -311.302748) (xy 314.843271 -311.33684) (xy 314.802768 -311.364796)
			(xy 314.768923 -311.380856) (xy 322.766688 -311.380856) (xy 322.774443 -311.326911) (xy 322.789796 -311.274618)
			(xy 322.812435 -311.225043) (xy 322.841898 -311.179194) (xy 322.877587 -311.138005) (xy 322.918773 -311.102314)
			(xy 322.96462 -311.072847) (xy 323.014194 -311.050205) (xy 323.066485 -311.034849) (xy 323.12043 -311.02709)
			(xy 323.174929 -311.027087) (xy 323.228874 -311.03484) (xy 323.281167 -311.050191) (xy 323.330743 -311.072828)
			(xy 323.376593 -311.102289) (xy 323.417784 -311.137976) (xy 323.453477 -311.179161) (xy 323.482945 -311.225007)
			(xy 323.505589 -311.274579) (xy 323.520948 -311.32687) (xy 323.528709 -311.380814) (xy 323.529198 -311.408064)
			(xy 323.529002 -311.425112) (xy 323.525947 -311.459072) (xy 323.523102 -311.475882) (xy 323.521061 -311.489765)
			(xy 323.523783 -311.517684) (xy 323.53399 -311.543811) (xy 323.550916 -311.566181) (xy 323.573284 -311.583107)
			(xy 323.599411 -311.593316) (xy 323.62733 -311.596039) (xy 323.641212 -311.593992) (xy 323.658083 -311.591119)
			(xy 323.692171 -311.588068) (xy 323.709284 -311.587896) (xy 323.736538 -311.588338) (xy 323.790492 -311.596093)
			(xy 323.842793 -311.611448) (xy 323.892377 -311.634089) (xy 323.938233 -311.663557) (xy 323.979429 -311.699251)
			(xy 324.015126 -311.740444) (xy 324.044597 -311.786299) (xy 324.067243 -311.835881) (xy 324.082601 -311.88818)
			(xy 324.09036 -311.942134) (xy 324.090362 -311.996642) (xy 324.082606 -312.050596) (xy 324.067251 -312.102897)
			(xy 324.044609 -312.15248) (xy 324.015141 -312.198336) (xy 323.979446 -312.239532) (xy 323.938252 -312.275229)
			(xy 323.892398 -312.304699) (xy 323.842816 -312.327344) (xy 323.790516 -312.342702) (xy 323.736562 -312.350461)
			(xy 323.682054 -312.350462) (xy 323.6281 -312.342705) (xy 323.575799 -312.32735) (xy 323.526216 -312.304707)
			(xy 323.48036 -312.275238) (xy 323.439165 -312.239543) (xy 323.403469 -312.198349) (xy 323.373999 -312.152494)
			(xy 323.351355 -312.102912) (xy 323.335997 -312.050612) (xy 323.328239 -311.996658) (xy 323.327776 -311.969404)
			(xy 323.327981 -311.952356) (xy 323.33103 -311.918397) (xy 323.333872 -311.901586) (xy 323.335976 -311.88771)
			(xy 323.333247 -311.859783) (xy 323.323029 -311.833649) (xy 323.306093 -311.811277) (xy 323.283714 -311.79435)
			(xy 323.257576 -311.784144) (xy 323.229648 -311.781425) (xy 323.215762 -311.783476) (xy 323.19889 -311.78634)
			(xy 323.164802 -311.789396) (xy 323.14769 -311.789572) (xy 323.12044 -311.789111) (xy 323.066496 -311.781354)
			(xy 323.014204 -311.765998) (xy 322.96463 -311.743358) (xy 322.918782 -311.713893) (xy 322.877594 -311.678203)
			(xy 322.841905 -311.637014) (xy 322.81244 -311.591166) (xy 322.7898 -311.541592) (xy 322.774445 -311.4893)
			(xy 322.766689 -311.435355) (xy 322.766688 -311.380856) (xy 314.768923 -311.380856) (xy 314.758306 -311.385894)
			(xy 314.711035 -311.399586) (xy 314.66218 -311.405518) (xy 314.613005 -311.403537) (xy 314.564786 -311.393693)
			(xy 314.51877 -311.376241) (xy 314.476149 -311.351634) (xy 314.438028 -311.320509) (xy 314.405393 -311.283672)
			(xy 314.37909 -311.242076) (xy 314.359799 -311.1968) (xy 314.348022 -311.149016) (xy 314.344062 -311.099962)
			(xy 314.005214 -311.099962) (xy 314.004719 -311.124569) (xy 313.996824 -311.173146) (xy 313.98124 -311.219827)
			(xy 313.958369 -311.263404) (xy 313.928804 -311.302748) (xy 313.893311 -311.33684) (xy 313.852808 -311.364796)
			(xy 313.808346 -311.385894) (xy 313.761075 -311.399586) (xy 313.71222 -311.405518) (xy 313.663045 -311.403537)
			(xy 313.614826 -311.393693) (xy 313.56881 -311.376241) (xy 313.526189 -311.351634) (xy 313.488068 -311.320509)
			(xy 313.455433 -311.283672) (xy 313.42913 -311.242076) (xy 313.409839 -311.1968) (xy 313.398062 -311.149016)
			(xy 313.394102 -311.099962) (xy 313.055 -311.099962) (xy 313.054505 -311.124569) (xy 313.04661 -311.173146)
			(xy 313.031026 -311.219827) (xy 313.008155 -311.263404) (xy 312.97859 -311.302748) (xy 312.943097 -311.33684)
			(xy 312.902594 -311.364796) (xy 312.858132 -311.385894) (xy 312.810861 -311.399586) (xy 312.762006 -311.405518)
			(xy 312.712831 -311.403537) (xy 312.664612 -311.393693) (xy 312.618596 -311.376241) (xy 312.575975 -311.351634)
			(xy 312.537854 -311.320509) (xy 312.505219 -311.283672) (xy 312.478916 -311.242076) (xy 312.459625 -311.1968)
			(xy 312.447848 -311.149016) (xy 312.443888 -311.099962) (xy 312.104942 -311.099962) (xy 312.102695 -311.141317)
			(xy 312.092019 -311.189792) (xy 312.073641 -311.235901) (xy 312.048046 -311.27843) (xy 312.015908 -311.316257)
			(xy 311.978073 -311.348387) (xy 311.935538 -311.373973) (xy 311.889425 -311.39234) (xy 311.840947 -311.403004)
			(xy 311.791383 -311.405686) (xy 311.742038 -311.400313) (xy 311.694212 -311.387028) (xy 311.649166 -311.366181)
			(xy 311.608085 -311.338321) (xy 311.572053 -311.304181) (xy 311.542019 -311.264662) (xy 311.518774 -311.220805)
			(xy 311.502931 -311.173764) (xy 311.494907 -311.12478) (xy 311.494424 -311.099962) (xy 311.494587 -311.085715)
			(xy 311.497259 -311.057347) (xy 311.499758 -311.04332) (xy 311.502044 -311.031128) (xy 311.494678 -311.006998)
			(xy 311.417462 -310.929782) (xy 311.393586 -310.922416) (xy 311.38114 -310.924702) (xy 311.367175 -310.927183)
			(xy 311.338935 -310.929852) (xy 311.324752 -310.930036) (xy 311.310569 -310.929852) (xy 311.282329 -310.927185)
			(xy 311.268364 -310.924702) (xy 311.255918 -310.922416) (xy 311.232042 -310.929782) (xy 311.154826 -311.006998)
			(xy 311.14746 -311.031128) (xy 311.149746 -311.04332) (xy 311.152231 -311.057349) (xy 311.154903 -311.085716)
			(xy 311.15508 -311.099962) (xy 311.154663 -311.124786) (xy 311.146637 -311.173781) (xy 311.13079 -311.220833)
			(xy 311.10754 -311.2647) (xy 311.077499 -311.304228) (xy 311.041458 -311.338376) (xy 311.000368 -311.366243)
			(xy 310.955311 -311.387095) (xy 310.907474 -311.400382) (xy 310.858118 -311.405756) (xy 310.808542 -311.403074)
			(xy 310.760053 -311.392406) (xy 310.713929 -311.374035) (xy 310.671385 -311.348443) (xy 310.633541 -311.316305)
			(xy 310.601396 -311.278469) (xy 310.575795 -311.23593) (xy 310.557413 -311.18981) (xy 310.546735 -311.141324)
			(xy 310.544042 -311.091749) (xy 310.204955 -311.091749) (xy 310.20512 -311.099962) (xy 310.204625 -311.124569)
			(xy 310.19673 -311.173146) (xy 310.181146 -311.219827) (xy 310.158275 -311.263404) (xy 310.12871 -311.302748)
			(xy 310.093217 -311.33684) (xy 310.052714 -311.364796) (xy 310.008252 -311.385894) (xy 309.960981 -311.399586)
			(xy 309.912126 -311.405518) (xy 309.862951 -311.403537) (xy 309.814732 -311.393693) (xy 309.768716 -311.376241)
			(xy 309.726095 -311.351634) (xy 309.687974 -311.320509) (xy 309.655339 -311.283672) (xy 309.629036 -311.242076)
			(xy 309.609745 -311.1968) (xy 309.597968 -311.149016) (xy 309.594008 -311.099962) (xy 309.25516 -311.099962)
			(xy 309.254665 -311.124569) (xy 309.24677 -311.173146) (xy 309.231186 -311.219827) (xy 309.208315 -311.263404)
			(xy 309.17875 -311.302748) (xy 309.143257 -311.33684) (xy 309.102754 -311.364796) (xy 309.058292 -311.385894)
			(xy 309.011021 -311.399586) (xy 308.962166 -311.405518) (xy 308.912991 -311.403537) (xy 308.864772 -311.393693)
			(xy 308.818756 -311.376241) (xy 308.776135 -311.351634) (xy 308.738014 -311.320509) (xy 308.705379 -311.283672)
			(xy 308.679076 -311.242076) (xy 308.659785 -311.1968) (xy 308.648008 -311.149016) (xy 308.644048 -311.099962)
			(xy 308.3052 -311.099962) (xy 308.304705 -311.124569) (xy 308.29681 -311.173146) (xy 308.281226 -311.219827)
			(xy 308.258355 -311.263404) (xy 308.22879 -311.302748) (xy 308.193297 -311.33684) (xy 308.152794 -311.364796)
			(xy 308.108332 -311.385894) (xy 308.061061 -311.399586) (xy 308.012206 -311.405518) (xy 307.963031 -311.403537)
			(xy 307.914812 -311.393693) (xy 307.868796 -311.376241) (xy 307.826175 -311.351634) (xy 307.788054 -311.320509)
			(xy 307.755419 -311.283672) (xy 307.729116 -311.242076) (xy 307.709825 -311.1968) (xy 307.698048 -311.149016)
			(xy 307.694088 -311.099962) (xy 307.355766 -311.099962) (xy 307.355769 -311.1) (xy 307.351598 -311.150341)
			(xy 307.339198 -311.199309) (xy 307.318909 -311.245569) (xy 307.291282 -311.287858) (xy 307.257072 -311.325024)
			(xy 307.217211 -311.356052) (xy 307.172788 -311.380097) (xy 307.125013 -311.396503) (xy 307.075189 -311.404822)
			(xy 307.049932 -311.40527) (xy 307.017928 -311.403492) (xy 307.007006 -311.402476) (xy 306.986686 -311.40908)
			(xy 306.922424 -311.466738) (xy 306.914772 -311.474258) (xy 306.906106 -311.493863) (xy 306.90566 -311.504584)
			(xy 306.90566 -311.574688) (xy 306.905507 -311.588406) (xy 306.903221 -311.615746) (xy 306.901088 -311.629298)
			(xy 306.899056 -311.641236) (xy 306.906168 -311.663842) (xy 306.979066 -311.740296) (xy 307.001418 -311.74817)
			(xy 307.013356 -311.7469) (xy 307.022463 -311.745844) (xy 307.040764 -311.744698) (xy 307.049932 -311.744614)
			(xy 307.075184 -311.745138) (xy 307.124998 -311.753455) (xy 307.172764 -311.769858) (xy 307.217179 -311.793898)
			(xy 307.257031 -311.82492) (xy 307.291235 -311.862079) (xy 307.318856 -311.90436) (xy 307.339142 -311.95061)
			(xy 307.351539 -311.999569) (xy 307.355709 -312.0499) (xy 307.355707 -312.049922) (xy 307.694088 -312.049922)
			(xy 307.698048 -312.000868) (xy 307.709825 -311.953084) (xy 307.729116 -311.907808) (xy 307.755419 -311.866212)
			(xy 307.788054 -311.829375) (xy 307.826175 -311.79825) (xy 307.868796 -311.773643) (xy 307.914812 -311.756191)
			(xy 307.963031 -311.746347) (xy 308.012206 -311.744366) (xy 308.061061 -311.750298) (xy 308.108332 -311.76399)
			(xy 308.152794 -311.785088) (xy 308.193297 -311.813044) (xy 308.22879 -311.847136) (xy 308.258355 -311.88648)
			(xy 308.281226 -311.930057) (xy 308.29681 -311.976738) (xy 308.304705 -312.025315) (xy 308.3052 -312.049922)
			(xy 308.644048 -312.049922) (xy 308.648008 -312.000868) (xy 308.659785 -311.953084) (xy 308.679076 -311.907808)
			(xy 308.705379 -311.866212) (xy 308.738014 -311.829375) (xy 308.776135 -311.79825) (xy 308.818756 -311.773643)
			(xy 308.864772 -311.756191) (xy 308.912991 -311.746347) (xy 308.962166 -311.744366) (xy 309.011021 -311.750298)
			(xy 309.058292 -311.76399) (xy 309.102754 -311.785088) (xy 309.143257 -311.813044) (xy 309.17875 -311.847136)
			(xy 309.208315 -311.88648) (xy 309.231186 -311.930057) (xy 309.24677 -311.976738) (xy 309.254665 -312.025315)
			(xy 309.25516 -312.049922) (xy 309.594008 -312.049922) (xy 309.597968 -312.000868) (xy 309.609745 -311.953084)
			(xy 309.629036 -311.907808) (xy 309.655339 -311.866212) (xy 309.687974 -311.829375) (xy 309.726095 -311.79825)
			(xy 309.768716 -311.773643) (xy 309.814732 -311.756191) (xy 309.862951 -311.746347) (xy 309.912126 -311.744366)
			(xy 309.960981 -311.750298) (xy 310.008252 -311.76399) (xy 310.052714 -311.785088) (xy 310.093217 -311.813044)
			(xy 310.12871 -311.847136) (xy 310.158275 -311.88648) (xy 310.181146 -311.930057) (xy 310.19673 -311.976738)
			(xy 310.204625 -312.025315) (xy 310.20512 -312.049922) (xy 310.543968 -312.049922) (xy 310.547928 -312.000868)
			(xy 310.559705 -311.953084) (xy 310.578996 -311.907808) (xy 310.605299 -311.866212) (xy 310.637934 -311.829375)
			(xy 310.676055 -311.79825) (xy 310.718676 -311.773643) (xy 310.764692 -311.756191) (xy 310.812911 -311.746347)
			(xy 310.862086 -311.744366) (xy 310.910941 -311.750298) (xy 310.958212 -311.76399) (xy 311.002674 -311.785088)
			(xy 311.043177 -311.813044) (xy 311.07867 -311.847136) (xy 311.108235 -311.88648) (xy 311.131106 -311.930057)
			(xy 311.14669 -311.976738) (xy 311.154585 -312.025315) (xy 311.15508 -312.049922) (xy 311.493928 -312.049922)
			(xy 311.497888 -312.000868) (xy 311.509665 -311.953084) (xy 311.528956 -311.907808) (xy 311.555259 -311.866212)
			(xy 311.587894 -311.829375) (xy 311.626015 -311.79825) (xy 311.668636 -311.773643) (xy 311.714652 -311.756191)
			(xy 311.762871 -311.746347) (xy 311.812046 -311.744366) (xy 311.860901 -311.750298) (xy 311.908172 -311.76399)
			(xy 311.952634 -311.785088) (xy 311.993137 -311.813044) (xy 312.02863 -311.847136) (xy 312.058195 -311.88648)
			(xy 312.081066 -311.930057) (xy 312.09665 -311.976738) (xy 312.104545 -312.025315) (xy 312.10504 -312.049922)
			(xy 312.443888 -312.049922) (xy 312.447848 -312.000868) (xy 312.459625 -311.953084) (xy 312.478916 -311.907808)
			(xy 312.505219 -311.866212) (xy 312.537854 -311.829375) (xy 312.575975 -311.79825) (xy 312.618596 -311.773643)
			(xy 312.664612 -311.756191) (xy 312.712831 -311.746347) (xy 312.762006 -311.744366) (xy 312.810861 -311.750298)
			(xy 312.858132 -311.76399) (xy 312.902594 -311.785088) (xy 312.943097 -311.813044) (xy 312.97859 -311.847136)
			(xy 313.008155 -311.88648) (xy 313.031026 -311.930057) (xy 313.04661 -311.976738) (xy 313.054505 -312.025315)
			(xy 313.055 -312.049922) (xy 313.394102 -312.049922) (xy 313.398062 -312.000868) (xy 313.409839 -311.953084)
			(xy 313.42913 -311.907808) (xy 313.455433 -311.866212) (xy 313.488068 -311.829375) (xy 313.526189 -311.79825)
			(xy 313.56881 -311.773643) (xy 313.614826 -311.756191) (xy 313.663045 -311.746347) (xy 313.71222 -311.744366)
			(xy 313.761075 -311.750298) (xy 313.808346 -311.76399) (xy 313.852808 -311.785088) (xy 313.893311 -311.813044)
			(xy 313.928804 -311.847136) (xy 313.958369 -311.88648) (xy 313.98124 -311.930057) (xy 313.996824 -311.976738)
			(xy 314.004719 -312.025315) (xy 314.005214 -312.049922) (xy 314.344062 -312.049922) (xy 314.348022 -312.000868)
			(xy 314.359799 -311.953084) (xy 314.37909 -311.907808) (xy 314.405393 -311.866212) (xy 314.438028 -311.829375)
			(xy 314.476149 -311.79825) (xy 314.51877 -311.773643) (xy 314.564786 -311.756191) (xy 314.613005 -311.746347)
			(xy 314.66218 -311.744366) (xy 314.711035 -311.750298) (xy 314.758306 -311.76399) (xy 314.802768 -311.785088)
			(xy 314.843271 -311.813044) (xy 314.878764 -311.847136) (xy 314.908329 -311.88648) (xy 314.9312 -311.930057)
			(xy 314.946784 -311.976738) (xy 314.954679 -312.025315) (xy 314.955174 -312.049922) (xy 315.294276 -312.049922)
			(xy 315.298236 -312.000868) (xy 315.310013 -311.953084) (xy 315.329304 -311.907808) (xy 315.355607 -311.866212)
			(xy 315.388242 -311.829375) (xy 315.426363 -311.79825) (xy 315.468984 -311.773643) (xy 315.515 -311.756191)
			(xy 315.563219 -311.746347) (xy 315.612394 -311.744366) (xy 315.661249 -311.750298) (xy 315.70852 -311.76399)
			(xy 315.752982 -311.785088) (xy 315.793485 -311.813044) (xy 315.828978 -311.847136) (xy 315.858543 -311.88648)
			(xy 315.881414 -311.930057) (xy 315.896998 -311.976738) (xy 315.904893 -312.025315) (xy 315.905388 -312.049922)
			(xy 315.904893 -312.074529) (xy 315.896998 -312.123106) (xy 315.881414 -312.169787) (xy 315.858543 -312.213364)
			(xy 315.828978 -312.252708) (xy 315.793485 -312.2868) (xy 315.752982 -312.314756) (xy 315.70852 -312.335854)
			(xy 315.661249 -312.349546) (xy 315.612394 -312.355478) (xy 315.563219 -312.353497) (xy 315.515 -312.343653)
			(xy 315.468984 -312.326201) (xy 315.426363 -312.301594) (xy 315.388242 -312.270469) (xy 315.355607 -312.233632)
			(xy 315.329304 -312.192036) (xy 315.310013 -312.14676) (xy 315.298236 -312.098976) (xy 315.294276 -312.049922)
			(xy 314.955174 -312.049922) (xy 314.954679 -312.074529) (xy 314.946784 -312.123106) (xy 314.9312 -312.169787)
			(xy 314.908329 -312.213364) (xy 314.878764 -312.252708) (xy 314.843271 -312.2868) (xy 314.802768 -312.314756)
			(xy 314.758306 -312.335854) (xy 314.711035 -312.349546) (xy 314.66218 -312.355478) (xy 314.613005 -312.353497)
			(xy 314.564786 -312.343653) (xy 314.51877 -312.326201) (xy 314.476149 -312.301594) (xy 314.438028 -312.270469)
			(xy 314.405393 -312.233632) (xy 314.37909 -312.192036) (xy 314.359799 -312.14676) (xy 314.348022 -312.098976)
			(xy 314.344062 -312.049922) (xy 314.005214 -312.049922) (xy 314.004719 -312.074529) (xy 313.996824 -312.123106)
			(xy 313.98124 -312.169787) (xy 313.958369 -312.213364) (xy 313.928804 -312.252708) (xy 313.893311 -312.2868)
			(xy 313.852808 -312.314756) (xy 313.808346 -312.335854) (xy 313.761075 -312.349546) (xy 313.71222 -312.355478)
			(xy 313.663045 -312.353497) (xy 313.614826 -312.343653) (xy 313.56881 -312.326201) (xy 313.526189 -312.301594)
			(xy 313.488068 -312.270469) (xy 313.455433 -312.233632) (xy 313.42913 -312.192036) (xy 313.409839 -312.14676)
			(xy 313.398062 -312.098976) (xy 313.394102 -312.049922) (xy 313.055 -312.049922) (xy 313.054505 -312.074529)
			(xy 313.04661 -312.123106) (xy 313.031026 -312.169787) (xy 313.008155 -312.213364) (xy 312.97859 -312.252708)
			(xy 312.943097 -312.2868) (xy 312.902594 -312.314756) (xy 312.858132 -312.335854) (xy 312.810861 -312.349546)
			(xy 312.762006 -312.355478) (xy 312.712831 -312.353497) (xy 312.664612 -312.343653) (xy 312.618596 -312.326201)
			(xy 312.575975 -312.301594) (xy 312.537854 -312.270469) (xy 312.505219 -312.233632) (xy 312.478916 -312.192036)
			(xy 312.459625 -312.14676) (xy 312.447848 -312.098976) (xy 312.443888 -312.049922) (xy 312.10504 -312.049922)
			(xy 312.104545 -312.074529) (xy 312.09665 -312.123106) (xy 312.081066 -312.169787) (xy 312.058195 -312.213364)
			(xy 312.02863 -312.252708) (xy 311.993137 -312.2868) (xy 311.952634 -312.314756) (xy 311.908172 -312.335854)
			(xy 311.860901 -312.349546) (xy 311.812046 -312.355478) (xy 311.762871 -312.353497) (xy 311.714652 -312.343653)
			(xy 311.668636 -312.326201) (xy 311.626015 -312.301594) (xy 311.587894 -312.270469) (xy 311.555259 -312.233632)
			(xy 311.528956 -312.192036) (xy 311.509665 -312.14676) (xy 311.497888 -312.098976) (xy 311.493928 -312.049922)
			(xy 311.15508 -312.049922) (xy 311.154585 -312.074529) (xy 311.14669 -312.123106) (xy 311.131106 -312.169787)
			(xy 311.108235 -312.213364) (xy 311.07867 -312.252708) (xy 311.043177 -312.2868) (xy 311.002674 -312.314756)
			(xy 310.958212 -312.335854) (xy 310.910941 -312.349546) (xy 310.862086 -312.355478) (xy 310.812911 -312.353497)
			(xy 310.764692 -312.343653) (xy 310.718676 -312.326201) (xy 310.676055 -312.301594) (xy 310.637934 -312.270469)
			(xy 310.605299 -312.233632) (xy 310.578996 -312.192036) (xy 310.559705 -312.14676) (xy 310.547928 -312.098976)
			(xy 310.543968 -312.049922) (xy 310.20512 -312.049922) (xy 310.204625 -312.074529) (xy 310.19673 -312.123106)
			(xy 310.181146 -312.169787) (xy 310.158275 -312.213364) (xy 310.12871 -312.252708) (xy 310.093217 -312.2868)
			(xy 310.052714 -312.314756) (xy 310.008252 -312.335854) (xy 309.960981 -312.349546) (xy 309.912126 -312.355478)
			(xy 309.862951 -312.353497) (xy 309.814732 -312.343653) (xy 309.768716 -312.326201) (xy 309.726095 -312.301594)
			(xy 309.687974 -312.270469) (xy 309.655339 -312.233632) (xy 309.629036 -312.192036) (xy 309.609745 -312.14676)
			(xy 309.597968 -312.098976) (xy 309.594008 -312.049922) (xy 309.25516 -312.049922) (xy 309.254665 -312.074529)
			(xy 309.24677 -312.123106) (xy 309.231186 -312.169787) (xy 309.208315 -312.213364) (xy 309.17875 -312.252708)
			(xy 309.143257 -312.2868) (xy 309.102754 -312.314756) (xy 309.058292 -312.335854) (xy 309.011021 -312.349546)
			(xy 308.962166 -312.355478) (xy 308.912991 -312.353497) (xy 308.864772 -312.343653) (xy 308.818756 -312.326201)
			(xy 308.776135 -312.301594) (xy 308.738014 -312.270469) (xy 308.705379 -312.233632) (xy 308.679076 -312.192036)
			(xy 308.659785 -312.14676) (xy 308.648008 -312.098976) (xy 308.644048 -312.049922) (xy 308.3052 -312.049922)
			(xy 308.304705 -312.074529) (xy 308.29681 -312.123106) (xy 308.281226 -312.169787) (xy 308.258355 -312.213364)
			(xy 308.22879 -312.252708) (xy 308.193297 -312.2868) (xy 308.152794 -312.314756) (xy 308.108332 -312.335854)
			(xy 308.061061 -312.349546) (xy 308.012206 -312.355478) (xy 307.963031 -312.353497) (xy 307.914812 -312.343653)
			(xy 307.868796 -312.326201) (xy 307.826175 -312.301594) (xy 307.788054 -312.270469) (xy 307.755419 -312.233632)
			(xy 307.729116 -312.192036) (xy 307.709825 -312.14676) (xy 307.698048 -312.098976) (xy 307.694088 -312.049922)
			(xy 307.355707 -312.049922) (xy 307.351539 -312.100231) (xy 307.339142 -312.14919) (xy 307.318856 -312.19544)
			(xy 307.291235 -312.237721) (xy 307.257031 -312.27488) (xy 307.217179 -312.305902) (xy 307.172764 -312.329942)
			(xy 307.124998 -312.346345) (xy 307.075184 -312.354662) (xy 307.049932 -312.35523) (xy 307.035686 -312.355051)
			(xy 307.00732 -312.352377) (xy 306.99329 -312.349896) (xy 306.981098 -312.34761) (xy 306.956968 -312.354976)
			(xy 306.879752 -312.432192) (xy 306.872386 -312.456068) (xy 306.874672 -312.468514) (xy 306.877157 -312.482479)
			(xy 306.879829 -312.510719) (xy 306.880006 -312.524902) (xy 306.879819 -312.539084) (xy 306.877146 -312.567324)
			(xy 306.874672 -312.58129) (xy 306.872386 -312.593736) (xy 306.879752 -312.617612) (xy 306.956968 -312.694828)
			(xy 306.981098 -312.702194) (xy 306.99329 -312.699908) (xy 307.007317 -312.697407) (xy 307.035685 -312.694732)
			(xy 307.049932 -312.694574) (xy 307.075187 -312.695098) (xy 307.125008 -312.703417) (xy 307.17278 -312.719821)
			(xy 307.2172 -312.743865) (xy 307.257058 -312.774891) (xy 307.291266 -312.812054) (xy 307.318891 -312.854341)
			(xy 307.339179 -312.900597) (xy 307.351578 -312.949562) (xy 307.355748 -312.999882) (xy 307.694088 -312.999882)
			(xy 307.698048 -312.950828) (xy 307.709825 -312.903044) (xy 307.729116 -312.857768) (xy 307.755419 -312.816172)
			(xy 307.788054 -312.779335) (xy 307.826175 -312.74821) (xy 307.868796 -312.723603) (xy 307.914812 -312.706151)
			(xy 307.963031 -312.696307) (xy 308.012206 -312.694326) (xy 308.061061 -312.700258) (xy 308.108332 -312.71395)
			(xy 308.152794 -312.735048) (xy 308.193297 -312.763004) (xy 308.22879 -312.797096) (xy 308.258355 -312.83644)
			(xy 308.281226 -312.880017) (xy 308.29681 -312.926698) (xy 308.304705 -312.975275) (xy 308.3052 -312.999882)
			(xy 308.644048 -312.999882) (xy 308.648008 -312.950828) (xy 308.659785 -312.903044) (xy 308.679076 -312.857768)
			(xy 308.705379 -312.816172) (xy 308.738014 -312.779335) (xy 308.776135 -312.74821) (xy 308.818756 -312.723603)
			(xy 308.864772 -312.706151) (xy 308.912991 -312.696307) (xy 308.962166 -312.694326) (xy 309.011021 -312.700258)
			(xy 309.058292 -312.71395) (xy 309.102754 -312.735048) (xy 309.143257 -312.763004) (xy 309.17875 -312.797096)
			(xy 309.208315 -312.83644) (xy 309.231186 -312.880017) (xy 309.24677 -312.926698) (xy 309.254665 -312.975275)
			(xy 309.25516 -312.999882) (xy 309.594008 -312.999882) (xy 309.597968 -312.950828) (xy 309.609745 -312.903044)
			(xy 309.629036 -312.857768) (xy 309.655339 -312.816172) (xy 309.687974 -312.779335) (xy 309.726095 -312.74821)
			(xy 309.768716 -312.723603) (xy 309.814732 -312.706151) (xy 309.862951 -312.696307) (xy 309.912126 -312.694326)
			(xy 309.960981 -312.700258) (xy 310.008252 -312.71395) (xy 310.052714 -312.735048) (xy 310.093217 -312.763004)
			(xy 310.12871 -312.797096) (xy 310.158275 -312.83644) (xy 310.181146 -312.880017) (xy 310.19673 -312.926698)
			(xy 310.204625 -312.975275) (xy 310.20512 -312.999882) (xy 310.543968 -312.999882) (xy 310.547928 -312.950828)
			(xy 310.559705 -312.903044) (xy 310.578996 -312.857768) (xy 310.605299 -312.816172) (xy 310.637934 -312.779335)
			(xy 310.676055 -312.74821) (xy 310.718676 -312.723603) (xy 310.764692 -312.706151) (xy 310.812911 -312.696307)
			(xy 310.862086 -312.694326) (xy 310.910941 -312.700258) (xy 310.958212 -312.71395) (xy 311.002674 -312.735048)
			(xy 311.043177 -312.763004) (xy 311.07867 -312.797096) (xy 311.108235 -312.83644) (xy 311.131106 -312.880017)
			(xy 311.14669 -312.926698) (xy 311.154585 -312.975275) (xy 311.15508 -312.999882) (xy 311.493928 -312.999882)
			(xy 311.497888 -312.950828) (xy 311.509665 -312.903044) (xy 311.528956 -312.857768) (xy 311.555259 -312.816172)
			(xy 311.587894 -312.779335) (xy 311.626015 -312.74821) (xy 311.668636 -312.723603) (xy 311.714652 -312.706151)
			(xy 311.762871 -312.696307) (xy 311.812046 -312.694326) (xy 311.860901 -312.700258) (xy 311.908172 -312.71395)
			(xy 311.952634 -312.735048) (xy 311.993137 -312.763004) (xy 312.02863 -312.797096) (xy 312.058195 -312.83644)
			(xy 312.081066 -312.880017) (xy 312.09665 -312.926698) (xy 312.104545 -312.975275) (xy 312.10504 -312.999882)
			(xy 312.443888 -312.999882) (xy 312.447848 -312.950828) (xy 312.459625 -312.903044) (xy 312.478916 -312.857768)
			(xy 312.505219 -312.816172) (xy 312.537854 -312.779335) (xy 312.575975 -312.74821) (xy 312.618596 -312.723603)
			(xy 312.664612 -312.706151) (xy 312.712831 -312.696307) (xy 312.762006 -312.694326) (xy 312.810861 -312.700258)
			(xy 312.858132 -312.71395) (xy 312.902594 -312.735048) (xy 312.943097 -312.763004) (xy 312.97859 -312.797096)
			(xy 313.008155 -312.83644) (xy 313.031026 -312.880017) (xy 313.04661 -312.926698) (xy 313.054505 -312.975275)
			(xy 313.055 -312.999882) (xy 313.394102 -312.999882) (xy 313.398062 -312.950828) (xy 313.409839 -312.903044)
			(xy 313.42913 -312.857768) (xy 313.455433 -312.816172) (xy 313.488068 -312.779335) (xy 313.526189 -312.74821)
			(xy 313.56881 -312.723603) (xy 313.614826 -312.706151) (xy 313.663045 -312.696307) (xy 313.71222 -312.694326)
			(xy 313.761075 -312.700258) (xy 313.808346 -312.71395) (xy 313.852808 -312.735048) (xy 313.893311 -312.763004)
			(xy 313.928804 -312.797096) (xy 313.958369 -312.83644) (xy 313.98124 -312.880017) (xy 313.996824 -312.926698)
			(xy 314.004719 -312.975275) (xy 314.005214 -312.999882) (xy 314.344062 -312.999882) (xy 314.348022 -312.950828)
			(xy 314.359799 -312.903044) (xy 314.37909 -312.857768) (xy 314.405393 -312.816172) (xy 314.438028 -312.779335)
			(xy 314.476149 -312.74821) (xy 314.51877 -312.723603) (xy 314.564786 -312.706151) (xy 314.613005 -312.696307)
			(xy 314.66218 -312.694326) (xy 314.711035 -312.700258) (xy 314.758306 -312.71395) (xy 314.802768 -312.735048)
			(xy 314.843271 -312.763004) (xy 314.878764 -312.797096) (xy 314.908329 -312.83644) (xy 314.9312 -312.880017)
			(xy 314.946784 -312.926698) (xy 314.954679 -312.975275) (xy 314.955174 -312.999882) (xy 314.954679 -313.024489)
			(xy 314.946784 -313.073066) (xy 314.9312 -313.119747) (xy 314.908329 -313.163324) (xy 314.878764 -313.202668)
			(xy 314.843271 -313.23676) (xy 314.802768 -313.264716) (xy 314.758306 -313.285814) (xy 314.711035 -313.299506)
			(xy 314.66218 -313.305438) (xy 314.613005 -313.303457) (xy 314.564786 -313.293613) (xy 314.51877 -313.276161)
			(xy 314.476149 -313.251554) (xy 314.438028 -313.220429) (xy 314.405393 -313.183592) (xy 314.37909 -313.141996)
			(xy 314.359799 -313.09672) (xy 314.348022 -313.048936) (xy 314.344062 -312.999882) (xy 314.005214 -312.999882)
			(xy 314.004719 -313.024489) (xy 313.996824 -313.073066) (xy 313.98124 -313.119747) (xy 313.958369 -313.163324)
			(xy 313.928804 -313.202668) (xy 313.893311 -313.23676) (xy 313.852808 -313.264716) (xy 313.808346 -313.285814)
			(xy 313.761075 -313.299506) (xy 313.71222 -313.305438) (xy 313.663045 -313.303457) (xy 313.614826 -313.293613)
			(xy 313.56881 -313.276161) (xy 313.526189 -313.251554) (xy 313.488068 -313.220429) (xy 313.455433 -313.183592)
			(xy 313.42913 -313.141996) (xy 313.409839 -313.09672) (xy 313.398062 -313.048936) (xy 313.394102 -312.999882)
			(xy 313.055 -312.999882) (xy 313.054505 -313.024489) (xy 313.04661 -313.073066) (xy 313.031026 -313.119747)
			(xy 313.008155 -313.163324) (xy 312.97859 -313.202668) (xy 312.943097 -313.23676) (xy 312.902594 -313.264716)
			(xy 312.858132 -313.285814) (xy 312.810861 -313.299506) (xy 312.762006 -313.305438) (xy 312.712831 -313.303457)
			(xy 312.664612 -313.293613) (xy 312.618596 -313.276161) (xy 312.575975 -313.251554) (xy 312.537854 -313.220429)
			(xy 312.505219 -313.183592) (xy 312.478916 -313.141996) (xy 312.459625 -313.09672) (xy 312.447848 -313.048936)
			(xy 312.443888 -312.999882) (xy 312.10504 -312.999882) (xy 312.104545 -313.024489) (xy 312.09665 -313.073066)
			(xy 312.081066 -313.119747) (xy 312.058195 -313.163324) (xy 312.02863 -313.202668) (xy 311.993137 -313.23676)
			(xy 311.952634 -313.264716) (xy 311.908172 -313.285814) (xy 311.860901 -313.299506) (xy 311.812046 -313.305438)
			(xy 311.762871 -313.303457) (xy 311.714652 -313.293613) (xy 311.668636 -313.276161) (xy 311.626015 -313.251554)
			(xy 311.587894 -313.220429) (xy 311.555259 -313.183592) (xy 311.528956 -313.141996) (xy 311.509665 -313.09672)
			(xy 311.497888 -313.048936) (xy 311.493928 -312.999882) (xy 311.15508 -312.999882) (xy 311.154585 -313.024489)
			(xy 311.14669 -313.073066) (xy 311.131106 -313.119747) (xy 311.108235 -313.163324) (xy 311.07867 -313.202668)
			(xy 311.043177 -313.23676) (xy 311.002674 -313.264716) (xy 310.958212 -313.285814) (xy 310.910941 -313.299506)
			(xy 310.862086 -313.305438) (xy 310.812911 -313.303457) (xy 310.764692 -313.293613) (xy 310.718676 -313.276161)
			(xy 310.676055 -313.251554) (xy 310.637934 -313.220429) (xy 310.605299 -313.183592) (xy 310.578996 -313.141996)
			(xy 310.559705 -313.09672) (xy 310.547928 -313.048936) (xy 310.543968 -312.999882) (xy 310.20512 -312.999882)
			(xy 310.204625 -313.024489) (xy 310.19673 -313.073066) (xy 310.181146 -313.119747) (xy 310.158275 -313.163324)
			(xy 310.12871 -313.202668) (xy 310.093217 -313.23676) (xy 310.052714 -313.264716) (xy 310.008252 -313.285814)
			(xy 309.960981 -313.299506) (xy 309.912126 -313.305438) (xy 309.862951 -313.303457) (xy 309.814732 -313.293613)
			(xy 309.768716 -313.276161) (xy 309.726095 -313.251554) (xy 309.687974 -313.220429) (xy 309.655339 -313.183592)
			(xy 309.629036 -313.141996) (xy 309.609745 -313.09672) (xy 309.597968 -313.048936) (xy 309.594008 -312.999882)
			(xy 309.25516 -312.999882) (xy 309.254665 -313.024489) (xy 309.24677 -313.073066) (xy 309.231186 -313.119747)
			(xy 309.208315 -313.163324) (xy 309.17875 -313.202668) (xy 309.143257 -313.23676) (xy 309.102754 -313.264716)
			(xy 309.058292 -313.285814) (xy 309.011021 -313.299506) (xy 308.962166 -313.305438) (xy 308.912991 -313.303457)
			(xy 308.864772 -313.293613) (xy 308.818756 -313.276161) (xy 308.776135 -313.251554) (xy 308.738014 -313.220429)
			(xy 308.705379 -313.183592) (xy 308.679076 -313.141996) (xy 308.659785 -313.09672) (xy 308.648008 -313.048936)
			(xy 308.644048 -312.999882) (xy 308.3052 -312.999882) (xy 308.304705 -313.024489) (xy 308.29681 -313.073066)
			(xy 308.281226 -313.119747) (xy 308.258355 -313.163324) (xy 308.22879 -313.202668) (xy 308.193297 -313.23676)
			(xy 308.152794 -313.264716) (xy 308.108332 -313.285814) (xy 308.061061 -313.299506) (xy 308.012206 -313.305438)
			(xy 307.963031 -313.303457) (xy 307.914812 -313.293613) (xy 307.868796 -313.276161) (xy 307.826175 -313.251554)
			(xy 307.788054 -313.220429) (xy 307.755419 -313.183592) (xy 307.729116 -313.141996) (xy 307.709825 -313.09672)
			(xy 307.698048 -313.048936) (xy 307.694088 -312.999882) (xy 307.355748 -312.999882) (xy 307.355749 -312.9999)
			(xy 307.351578 -313.050238) (xy 307.339179 -313.099203) (xy 307.318891 -313.145459) (xy 307.291266 -313.187746)
			(xy 307.257058 -313.224909) (xy 307.2172 -313.255935) (xy 307.17278 -313.279979) (xy 307.125008 -313.296383)
			(xy 307.075187 -313.304702) (xy 307.049932 -313.30519) (xy 307.035686 -313.305011) (xy 307.007319 -313.302337)
			(xy 306.99329 -313.299856) (xy 306.981098 -313.29757) (xy 306.956968 -313.304936) (xy 306.879752 -313.382152)
			(xy 306.872386 -313.406028) (xy 306.874672 -313.418474) (xy 306.877159 -313.432439) (xy 306.879835 -313.460679)
			(xy 306.880006 -313.474862) (xy 306.87982 -313.489045) (xy 306.877149 -313.517284) (xy 306.874672 -313.53125)
			(xy 306.872386 -313.543696) (xy 306.879752 -313.567572) (xy 306.956968 -313.644788) (xy 306.981098 -313.652154)
			(xy 306.99329 -313.649868) (xy 307.007317 -313.647368) (xy 307.035685 -313.644693) (xy 307.049932 -313.644534)
			(xy 307.075182 -313.645058) (xy 307.124993 -313.653375) (xy 307.172756 -313.669776) (xy 307.217168 -313.693815)
			(xy 307.257018 -313.724835) (xy 307.291219 -313.761991) (xy 307.318838 -313.804269) (xy 307.339123 -313.850517)
			(xy 307.351519 -313.899472) (xy 307.355689 -313.9498) (xy 307.355686 -313.949842) (xy 307.694088 -313.949842)
			(xy 307.698048 -313.900788) (xy 307.709825 -313.853004) (xy 307.729116 -313.807728) (xy 307.755419 -313.766132)
			(xy 307.788054 -313.729295) (xy 307.826175 -313.69817) (xy 307.868796 -313.673563) (xy 307.914812 -313.656111)
			(xy 307.963031 -313.646267) (xy 308.012206 -313.644286) (xy 308.061061 -313.650218) (xy 308.108332 -313.66391)
			(xy 308.152794 -313.685008) (xy 308.193297 -313.712964) (xy 308.22879 -313.747056) (xy 308.258355 -313.7864)
			(xy 308.281226 -313.829977) (xy 308.29681 -313.876658) (xy 308.304705 -313.925235) (xy 308.3052 -313.949842)
			(xy 308.644048 -313.949842) (xy 308.648008 -313.900788) (xy 308.659785 -313.853004) (xy 308.679076 -313.807728)
			(xy 308.705379 -313.766132) (xy 308.738014 -313.729295) (xy 308.776135 -313.69817) (xy 308.818756 -313.673563)
			(xy 308.864772 -313.656111) (xy 308.912991 -313.646267) (xy 308.962166 -313.644286) (xy 309.011021 -313.650218)
			(xy 309.058292 -313.66391) (xy 309.102754 -313.685008) (xy 309.143257 -313.712964) (xy 309.17875 -313.747056)
			(xy 309.208315 -313.7864) (xy 309.231186 -313.829977) (xy 309.24677 -313.876658) (xy 309.254665 -313.925235)
			(xy 309.25516 -313.949842) (xy 309.594008 -313.949842) (xy 309.597968 -313.900788) (xy 309.609745 -313.853004)
			(xy 309.629036 -313.807728) (xy 309.655339 -313.766132) (xy 309.687974 -313.729295) (xy 309.726095 -313.69817)
			(xy 309.768716 -313.673563) (xy 309.814732 -313.656111) (xy 309.862951 -313.646267) (xy 309.912126 -313.644286)
			(xy 309.960981 -313.650218) (xy 310.008252 -313.66391) (xy 310.052714 -313.685008) (xy 310.093217 -313.712964)
			(xy 310.12871 -313.747056) (xy 310.158275 -313.7864) (xy 310.181146 -313.829977) (xy 310.19673 -313.876658)
			(xy 310.204625 -313.925235) (xy 310.20512 -313.949842) (xy 310.543968 -313.949842) (xy 310.547928 -313.900788)
			(xy 310.559705 -313.853004) (xy 310.578996 -313.807728) (xy 310.605299 -313.766132) (xy 310.637934 -313.729295)
			(xy 310.676055 -313.69817) (xy 310.718676 -313.673563) (xy 310.764692 -313.656111) (xy 310.812911 -313.646267)
			(xy 310.862086 -313.644286) (xy 310.910941 -313.650218) (xy 310.958212 -313.66391) (xy 311.002674 -313.685008)
			(xy 311.043177 -313.712964) (xy 311.07867 -313.747056) (xy 311.108235 -313.7864) (xy 311.131106 -313.829977)
			(xy 311.14669 -313.876658) (xy 311.154585 -313.925235) (xy 311.15508 -313.949842) (xy 311.493928 -313.949842)
			(xy 311.497888 -313.900788) (xy 311.509665 -313.853004) (xy 311.528956 -313.807728) (xy 311.555259 -313.766132)
			(xy 311.587894 -313.729295) (xy 311.626015 -313.69817) (xy 311.668636 -313.673563) (xy 311.714652 -313.656111)
			(xy 311.762871 -313.646267) (xy 311.812046 -313.644286) (xy 311.860901 -313.650218) (xy 311.908172 -313.66391)
			(xy 311.952634 -313.685008) (xy 311.993137 -313.712964) (xy 312.02863 -313.747056) (xy 312.058195 -313.7864)
			(xy 312.081066 -313.829977) (xy 312.09665 -313.876658) (xy 312.104545 -313.925235) (xy 312.10504 -313.949842)
			(xy 312.443888 -313.949842) (xy 312.447848 -313.900788) (xy 312.459625 -313.853004) (xy 312.478916 -313.807728)
			(xy 312.505219 -313.766132) (xy 312.537854 -313.729295) (xy 312.575975 -313.69817) (xy 312.618596 -313.673563)
			(xy 312.664612 -313.656111) (xy 312.712831 -313.646267) (xy 312.762006 -313.644286) (xy 312.810861 -313.650218)
			(xy 312.858132 -313.66391) (xy 312.902594 -313.685008) (xy 312.943097 -313.712964) (xy 312.97859 -313.747056)
			(xy 313.008155 -313.7864) (xy 313.031026 -313.829977) (xy 313.04661 -313.876658) (xy 313.054505 -313.925235)
			(xy 313.055 -313.949842) (xy 313.394102 -313.949842) (xy 313.398062 -313.900788) (xy 313.409839 -313.853004)
			(xy 313.42913 -313.807728) (xy 313.455433 -313.766132) (xy 313.488068 -313.729295) (xy 313.526189 -313.69817)
			(xy 313.56881 -313.673563) (xy 313.614826 -313.656111) (xy 313.663045 -313.646267) (xy 313.71222 -313.644286)
			(xy 313.761075 -313.650218) (xy 313.808346 -313.66391) (xy 313.852808 -313.685008) (xy 313.893311 -313.712964)
			(xy 313.928804 -313.747056) (xy 313.958369 -313.7864) (xy 313.98124 -313.829977) (xy 313.996824 -313.876658)
			(xy 314.004719 -313.925235) (xy 314.005214 -313.949842) (xy 314.344062 -313.949842) (xy 314.348022 -313.900788)
			(xy 314.359799 -313.853004) (xy 314.37909 -313.807728) (xy 314.405393 -313.766132) (xy 314.438028 -313.729295)
			(xy 314.476149 -313.69817) (xy 314.51877 -313.673563) (xy 314.564786 -313.656111) (xy 314.613005 -313.646267)
			(xy 314.66218 -313.644286) (xy 314.711035 -313.650218) (xy 314.758306 -313.66391) (xy 314.802768 -313.685008)
			(xy 314.843271 -313.712964) (xy 314.878764 -313.747056) (xy 314.908329 -313.7864) (xy 314.9312 -313.829977)
			(xy 314.946784 -313.876658) (xy 314.954679 -313.925235) (xy 314.955174 -313.949842) (xy 314.954679 -313.974449)
			(xy 314.946784 -314.023026) (xy 314.9312 -314.069707) (xy 314.908329 -314.113284) (xy 314.878764 -314.152628)
			(xy 314.843271 -314.18672) (xy 314.802768 -314.214676) (xy 314.758306 -314.235774) (xy 314.711035 -314.249466)
			(xy 314.66218 -314.255398) (xy 314.613005 -314.253417) (xy 314.564786 -314.243573) (xy 314.51877 -314.226121)
			(xy 314.476149 -314.201514) (xy 314.438028 -314.170389) (xy 314.405393 -314.133552) (xy 314.37909 -314.091956)
			(xy 314.359799 -314.04668) (xy 314.348022 -313.998896) (xy 314.344062 -313.949842) (xy 314.005214 -313.949842)
			(xy 314.004719 -313.974449) (xy 313.996824 -314.023026) (xy 313.98124 -314.069707) (xy 313.958369 -314.113284)
			(xy 313.928804 -314.152628) (xy 313.893311 -314.18672) (xy 313.852808 -314.214676) (xy 313.808346 -314.235774)
			(xy 313.761075 -314.249466) (xy 313.71222 -314.255398) (xy 313.663045 -314.253417) (xy 313.614826 -314.243573)
			(xy 313.56881 -314.226121) (xy 313.526189 -314.201514) (xy 313.488068 -314.170389) (xy 313.455433 -314.133552)
			(xy 313.42913 -314.091956) (xy 313.409839 -314.04668) (xy 313.398062 -313.998896) (xy 313.394102 -313.949842)
			(xy 313.055 -313.949842) (xy 313.054505 -313.974449) (xy 313.04661 -314.023026) (xy 313.031026 -314.069707)
			(xy 313.008155 -314.113284) (xy 312.97859 -314.152628) (xy 312.943097 -314.18672) (xy 312.902594 -314.214676)
			(xy 312.858132 -314.235774) (xy 312.810861 -314.249466) (xy 312.762006 -314.255398) (xy 312.712831 -314.253417)
			(xy 312.664612 -314.243573) (xy 312.618596 -314.226121) (xy 312.575975 -314.201514) (xy 312.537854 -314.170389)
			(xy 312.505219 -314.133552) (xy 312.478916 -314.091956) (xy 312.459625 -314.04668) (xy 312.447848 -313.998896)
			(xy 312.443888 -313.949842) (xy 312.10504 -313.949842) (xy 312.104545 -313.974449) (xy 312.09665 -314.023026)
			(xy 312.081066 -314.069707) (xy 312.058195 -314.113284) (xy 312.02863 -314.152628) (xy 311.993137 -314.18672)
			(xy 311.952634 -314.214676) (xy 311.908172 -314.235774) (xy 311.860901 -314.249466) (xy 311.812046 -314.255398)
			(xy 311.762871 -314.253417) (xy 311.714652 -314.243573) (xy 311.668636 -314.226121) (xy 311.626015 -314.201514)
			(xy 311.587894 -314.170389) (xy 311.555259 -314.133552) (xy 311.528956 -314.091956) (xy 311.509665 -314.04668)
			(xy 311.497888 -313.998896) (xy 311.493928 -313.949842) (xy 311.15508 -313.949842) (xy 311.154585 -313.974449)
			(xy 311.14669 -314.023026) (xy 311.131106 -314.069707) (xy 311.108235 -314.113284) (xy 311.07867 -314.152628)
			(xy 311.043177 -314.18672) (xy 311.002674 -314.214676) (xy 310.958212 -314.235774) (xy 310.910941 -314.249466)
			(xy 310.862086 -314.255398) (xy 310.812911 -314.253417) (xy 310.764692 -314.243573) (xy 310.718676 -314.226121)
			(xy 310.676055 -314.201514) (xy 310.637934 -314.170389) (xy 310.605299 -314.133552) (xy 310.578996 -314.091956)
			(xy 310.559705 -314.04668) (xy 310.547928 -313.998896) (xy 310.543968 -313.949842) (xy 310.20512 -313.949842)
			(xy 310.204625 -313.974449) (xy 310.19673 -314.023026) (xy 310.181146 -314.069707) (xy 310.158275 -314.113284)
			(xy 310.12871 -314.152628) (xy 310.093217 -314.18672) (xy 310.052714 -314.214676) (xy 310.008252 -314.235774)
			(xy 309.960981 -314.249466) (xy 309.912126 -314.255398) (xy 309.862951 -314.253417) (xy 309.814732 -314.243573)
			(xy 309.768716 -314.226121) (xy 309.726095 -314.201514) (xy 309.687974 -314.170389) (xy 309.655339 -314.133552)
			(xy 309.629036 -314.091956) (xy 309.609745 -314.04668) (xy 309.597968 -313.998896) (xy 309.594008 -313.949842)
			(xy 309.25516 -313.949842) (xy 309.254665 -313.974449) (xy 309.24677 -314.023026) (xy 309.231186 -314.069707)
			(xy 309.208315 -314.113284) (xy 309.17875 -314.152628) (xy 309.143257 -314.18672) (xy 309.102754 -314.214676)
			(xy 309.058292 -314.235774) (xy 309.011021 -314.249466) (xy 308.962166 -314.255398) (xy 308.912991 -314.253417)
			(xy 308.864772 -314.243573) (xy 308.818756 -314.226121) (xy 308.776135 -314.201514) (xy 308.738014 -314.170389)
			(xy 308.705379 -314.133552) (xy 308.679076 -314.091956) (xy 308.659785 -314.04668) (xy 308.648008 -313.998896)
			(xy 308.644048 -313.949842) (xy 308.3052 -313.949842) (xy 308.304705 -313.974449) (xy 308.29681 -314.023026)
			(xy 308.281226 -314.069707) (xy 308.258355 -314.113284) (xy 308.22879 -314.152628) (xy 308.193297 -314.18672)
			(xy 308.152794 -314.214676) (xy 308.108332 -314.235774) (xy 308.061061 -314.249466) (xy 308.012206 -314.255398)
			(xy 307.963031 -314.253417) (xy 307.914812 -314.243573) (xy 307.868796 -314.226121) (xy 307.826175 -314.201514)
			(xy 307.788054 -314.170389) (xy 307.755419 -314.133552) (xy 307.729116 -314.091956) (xy 307.709825 -314.04668)
			(xy 307.698048 -313.998896) (xy 307.694088 -313.949842) (xy 307.355686 -313.949842) (xy 307.351519 -314.000128)
			(xy 307.339123 -314.049083) (xy 307.318838 -314.095331) (xy 307.291219 -314.137609) (xy 307.257018 -314.174765)
			(xy 307.217168 -314.205785) (xy 307.172756 -314.229824) (xy 307.124993 -314.246225) (xy 307.075182 -314.254542)
			(xy 307.049932 -314.25515) (xy 307.035686 -314.254971) (xy 307.00732 -314.252297) (xy 306.99329 -314.249816)
			(xy 306.981098 -314.24753) (xy 306.956968 -314.254896) (xy 306.879752 -314.332112) (xy 306.872386 -314.355988)
			(xy 306.874672 -314.368434) (xy 306.877158 -314.382399) (xy 306.879827 -314.410639) (xy 306.880006 -314.424822)
			(xy 306.880006 -314.426854) (xy 306.879831 -314.438012) (xy 306.878048 -314.460259) (xy 306.87645 -314.471304)
			(xy 306.87645 -314.471558) (xy 306.876196 -314.473336) (xy 306.87518 -314.47867) (xy 306.874926 -314.481718)
			(xy 306.87264 -314.493656) (xy 306.880006 -314.517278) (xy 306.957476 -314.594748) (xy 306.981098 -314.602114)
			(xy 306.993544 -314.599828) (xy 307.007509 -314.597344) (xy 307.035749 -314.594675) (xy 307.049932 -314.594494)
			(xy 307.075185 -314.595018) (xy 307.125003 -314.603336) (xy 307.172772 -314.619739) (xy 307.21719 -314.643781)
			(xy 307.257045 -314.674806) (xy 307.29125 -314.711967) (xy 307.318873 -314.75425) (xy 307.339161 -314.800504)
			(xy 307.351558 -314.849466) (xy 307.355729 -314.8998) (xy 307.355729 -314.899802) (xy 307.694088 -314.899802)
			(xy 307.698048 -314.850748) (xy 307.709825 -314.802964) (xy 307.729116 -314.757688) (xy 307.755419 -314.716092)
			(xy 307.788054 -314.679255) (xy 307.826175 -314.64813) (xy 307.868796 -314.623523) (xy 307.914812 -314.606071)
			(xy 307.963031 -314.596227) (xy 308.012206 -314.594246) (xy 308.061061 -314.600178) (xy 308.108332 -314.61387)
			(xy 308.152794 -314.634968) (xy 308.193297 -314.662924) (xy 308.22879 -314.697016) (xy 308.258355 -314.73636)
			(xy 308.281226 -314.779937) (xy 308.29681 -314.826618) (xy 308.304705 -314.875195) (xy 308.3052 -314.899802)
			(xy 308.644048 -314.899802) (xy 308.648008 -314.850748) (xy 308.659785 -314.802964) (xy 308.679076 -314.757688)
			(xy 308.705379 -314.716092) (xy 308.738014 -314.679255) (xy 308.776135 -314.64813) (xy 308.818756 -314.623523)
			(xy 308.864772 -314.606071) (xy 308.912991 -314.596227) (xy 308.962166 -314.594246) (xy 309.011021 -314.600178)
			(xy 309.058292 -314.61387) (xy 309.102754 -314.634968) (xy 309.143257 -314.662924) (xy 309.17875 -314.697016)
			(xy 309.208315 -314.73636) (xy 309.231186 -314.779937) (xy 309.24677 -314.826618) (xy 309.254665 -314.875195)
			(xy 309.25516 -314.899802) (xy 309.594008 -314.899802) (xy 309.597968 -314.850748) (xy 309.609745 -314.802964)
			(xy 309.629036 -314.757688) (xy 309.655339 -314.716092) (xy 309.687974 -314.679255) (xy 309.726095 -314.64813)
			(xy 309.768716 -314.623523) (xy 309.814732 -314.606071) (xy 309.862951 -314.596227) (xy 309.912126 -314.594246)
			(xy 309.960981 -314.600178) (xy 310.008252 -314.61387) (xy 310.052714 -314.634968) (xy 310.093217 -314.662924)
			(xy 310.12871 -314.697016) (xy 310.158275 -314.73636) (xy 310.181146 -314.779937) (xy 310.19673 -314.826618)
			(xy 310.204625 -314.875195) (xy 310.20512 -314.899802) (xy 310.543968 -314.899802) (xy 310.547928 -314.850748)
			(xy 310.559705 -314.802964) (xy 310.578996 -314.757688) (xy 310.605299 -314.716092) (xy 310.637934 -314.679255)
			(xy 310.676055 -314.64813) (xy 310.718676 -314.623523) (xy 310.764692 -314.606071) (xy 310.812911 -314.596227)
			(xy 310.862086 -314.594246) (xy 310.910941 -314.600178) (xy 310.958212 -314.61387) (xy 311.002674 -314.634968)
			(xy 311.043177 -314.662924) (xy 311.07867 -314.697016) (xy 311.108235 -314.73636) (xy 311.131106 -314.779937)
			(xy 311.14669 -314.826618) (xy 311.154585 -314.875195) (xy 311.15508 -314.899802) (xy 311.493928 -314.899802)
			(xy 311.497888 -314.850748) (xy 311.509665 -314.802964) (xy 311.528956 -314.757688) (xy 311.555259 -314.716092)
			(xy 311.587894 -314.679255) (xy 311.626015 -314.64813) (xy 311.668636 -314.623523) (xy 311.714652 -314.606071)
			(xy 311.762871 -314.596227) (xy 311.812046 -314.594246) (xy 311.860901 -314.600178) (xy 311.908172 -314.61387)
			(xy 311.952634 -314.634968) (xy 311.993137 -314.662924) (xy 312.02863 -314.697016) (xy 312.058195 -314.73636)
			(xy 312.081066 -314.779937) (xy 312.09665 -314.826618) (xy 312.104545 -314.875195) (xy 312.10504 -314.899802)
			(xy 312.443888 -314.899802) (xy 312.447848 -314.850748) (xy 312.459625 -314.802964) (xy 312.478916 -314.757688)
			(xy 312.505219 -314.716092) (xy 312.537854 -314.679255) (xy 312.575975 -314.64813) (xy 312.618596 -314.623523)
			(xy 312.664612 -314.606071) (xy 312.712831 -314.596227) (xy 312.762006 -314.594246) (xy 312.810861 -314.600178)
			(xy 312.858132 -314.61387) (xy 312.902594 -314.634968) (xy 312.943097 -314.662924) (xy 312.97859 -314.697016)
			(xy 313.008155 -314.73636) (xy 313.031026 -314.779937) (xy 313.04661 -314.826618) (xy 313.054505 -314.875195)
			(xy 313.055 -314.899802) (xy 313.394102 -314.899802) (xy 313.398062 -314.850748) (xy 313.409839 -314.802964)
			(xy 313.42913 -314.757688) (xy 313.455433 -314.716092) (xy 313.488068 -314.679255) (xy 313.526189 -314.64813)
			(xy 313.56881 -314.623523) (xy 313.614826 -314.606071) (xy 313.663045 -314.596227) (xy 313.71222 -314.594246)
			(xy 313.761075 -314.600178) (xy 313.808346 -314.61387) (xy 313.852808 -314.634968) (xy 313.893311 -314.662924)
			(xy 313.928804 -314.697016) (xy 313.958369 -314.73636) (xy 313.98124 -314.779937) (xy 313.996824 -314.826618)
			(xy 314.004719 -314.875195) (xy 314.005214 -314.899802) (xy 314.344062 -314.899802) (xy 314.348022 -314.850748)
			(xy 314.359799 -314.802964) (xy 314.37909 -314.757688) (xy 314.405393 -314.716092) (xy 314.438028 -314.679255)
			(xy 314.476149 -314.64813) (xy 314.51877 -314.623523) (xy 314.564786 -314.606071) (xy 314.613005 -314.596227)
			(xy 314.66218 -314.594246) (xy 314.711035 -314.600178) (xy 314.758306 -314.61387) (xy 314.802768 -314.634968)
			(xy 314.843271 -314.662924) (xy 314.878764 -314.697016) (xy 314.908329 -314.73636) (xy 314.9312 -314.779937)
			(xy 314.946784 -314.826618) (xy 314.954679 -314.875195) (xy 314.955169 -314.899548) (xy 315.294276 -314.899548)
			(xy 315.298236 -314.850494) (xy 315.310013 -314.80271) (xy 315.329304 -314.757434) (xy 315.355607 -314.715838)
			(xy 315.388242 -314.679001) (xy 315.426363 -314.647876) (xy 315.468984 -314.623269) (xy 315.515 -314.605817)
			(xy 315.563219 -314.595973) (xy 315.612394 -314.593992) (xy 315.661249 -314.599924) (xy 315.70852 -314.613616)
			(xy 315.752982 -314.634714) (xy 315.793485 -314.66267) (xy 315.828978 -314.696762) (xy 315.858543 -314.736106)
			(xy 315.881414 -314.779683) (xy 315.896998 -314.826364) (xy 315.904893 -314.874941) (xy 315.905388 -314.899548)
			(xy 315.904893 -314.924155) (xy 315.896998 -314.972732) (xy 315.881414 -315.019413) (xy 315.858543 -315.06299)
			(xy 315.828978 -315.102334) (xy 315.793485 -315.136426) (xy 315.752982 -315.164382) (xy 315.70852 -315.18548)
			(xy 315.661249 -315.199172) (xy 315.612394 -315.205104) (xy 315.563219 -315.203123) (xy 315.515 -315.193279)
			(xy 315.468984 -315.175827) (xy 315.426363 -315.15122) (xy 315.388242 -315.120095) (xy 315.355607 -315.083258)
			(xy 315.329304 -315.041662) (xy 315.310013 -314.996386) (xy 315.298236 -314.948602) (xy 315.294276 -314.899548)
			(xy 314.955169 -314.899548) (xy 314.955174 -314.899802) (xy 314.954679 -314.924409) (xy 314.946784 -314.972986)
			(xy 314.9312 -315.019667) (xy 314.908329 -315.063244) (xy 314.878764 -315.102588) (xy 314.843271 -315.13668)
			(xy 314.802768 -315.164636) (xy 314.758306 -315.185734) (xy 314.711035 -315.199426) (xy 314.66218 -315.205358)
			(xy 314.613005 -315.203377) (xy 314.564786 -315.193533) (xy 314.51877 -315.176081) (xy 314.476149 -315.151474)
			(xy 314.438028 -315.120349) (xy 314.405393 -315.083512) (xy 314.37909 -315.041916) (xy 314.359799 -314.99664)
			(xy 314.348022 -314.948856) (xy 314.344062 -314.899802) (xy 314.005214 -314.899802) (xy 314.004719 -314.924409)
			(xy 313.996824 -314.972986) (xy 313.98124 -315.019667) (xy 313.958369 -315.063244) (xy 313.928804 -315.102588)
			(xy 313.893311 -315.13668) (xy 313.852808 -315.164636) (xy 313.808346 -315.185734) (xy 313.761075 -315.199426)
			(xy 313.71222 -315.205358) (xy 313.663045 -315.203377) (xy 313.614826 -315.193533) (xy 313.56881 -315.176081)
			(xy 313.526189 -315.151474) (xy 313.488068 -315.120349) (xy 313.455433 -315.083512) (xy 313.42913 -315.041916)
			(xy 313.409839 -314.99664) (xy 313.398062 -314.948856) (xy 313.394102 -314.899802) (xy 313.055 -314.899802)
			(xy 313.054505 -314.924409) (xy 313.04661 -314.972986) (xy 313.031026 -315.019667) (xy 313.008155 -315.063244)
			(xy 312.97859 -315.102588) (xy 312.943097 -315.13668) (xy 312.902594 -315.164636) (xy 312.858132 -315.185734)
			(xy 312.810861 -315.199426) (xy 312.762006 -315.205358) (xy 312.712831 -315.203377) (xy 312.664612 -315.193533)
			(xy 312.618596 -315.176081) (xy 312.575975 -315.151474) (xy 312.537854 -315.120349) (xy 312.505219 -315.083512)
			(xy 312.478916 -315.041916) (xy 312.459625 -314.99664) (xy 312.447848 -314.948856) (xy 312.443888 -314.899802)
			(xy 312.10504 -314.899802) (xy 312.104545 -314.924409) (xy 312.09665 -314.972986) (xy 312.081066 -315.019667)
			(xy 312.058195 -315.063244) (xy 312.02863 -315.102588) (xy 311.993137 -315.13668) (xy 311.952634 -315.164636)
			(xy 311.908172 -315.185734) (xy 311.860901 -315.199426) (xy 311.812046 -315.205358) (xy 311.762871 -315.203377)
			(xy 311.714652 -315.193533) (xy 311.668636 -315.176081) (xy 311.626015 -315.151474) (xy 311.587894 -315.120349)
			(xy 311.555259 -315.083512) (xy 311.528956 -315.041916) (xy 311.509665 -314.99664) (xy 311.497888 -314.948856)
			(xy 311.493928 -314.899802) (xy 311.15508 -314.899802) (xy 311.154585 -314.924409) (xy 311.14669 -314.972986)
			(xy 311.131106 -315.019667) (xy 311.108235 -315.063244) (xy 311.07867 -315.102588) (xy 311.043177 -315.13668)
			(xy 311.002674 -315.164636) (xy 310.958212 -315.185734) (xy 310.910941 -315.199426) (xy 310.862086 -315.205358)
			(xy 310.812911 -315.203377) (xy 310.764692 -315.193533) (xy 310.718676 -315.176081) (xy 310.676055 -315.151474)
			(xy 310.637934 -315.120349) (xy 310.605299 -315.083512) (xy 310.578996 -315.041916) (xy 310.559705 -314.99664)
			(xy 310.547928 -314.948856) (xy 310.543968 -314.899802) (xy 310.20512 -314.899802) (xy 310.204625 -314.924409)
			(xy 310.19673 -314.972986) (xy 310.181146 -315.019667) (xy 310.158275 -315.063244) (xy 310.12871 -315.102588)
			(xy 310.093217 -315.13668) (xy 310.052714 -315.164636) (xy 310.008252 -315.185734) (xy 309.960981 -315.199426)
			(xy 309.912126 -315.205358) (xy 309.862951 -315.203377) (xy 309.814732 -315.193533) (xy 309.768716 -315.176081)
			(xy 309.726095 -315.151474) (xy 309.687974 -315.120349) (xy 309.655339 -315.083512) (xy 309.629036 -315.041916)
			(xy 309.609745 -314.99664) (xy 309.597968 -314.948856) (xy 309.594008 -314.899802) (xy 309.25516 -314.899802)
			(xy 309.254665 -314.924409) (xy 309.24677 -314.972986) (xy 309.231186 -315.019667) (xy 309.208315 -315.063244)
			(xy 309.17875 -315.102588) (xy 309.143257 -315.13668) (xy 309.102754 -315.164636) (xy 309.058292 -315.185734)
			(xy 309.011021 -315.199426) (xy 308.962166 -315.205358) (xy 308.912991 -315.203377) (xy 308.864772 -315.193533)
			(xy 308.818756 -315.176081) (xy 308.776135 -315.151474) (xy 308.738014 -315.120349) (xy 308.705379 -315.083512)
			(xy 308.679076 -315.041916) (xy 308.659785 -314.99664) (xy 308.648008 -314.948856) (xy 308.644048 -314.899802)
			(xy 308.3052 -314.899802) (xy 308.304705 -314.924409) (xy 308.29681 -314.972986) (xy 308.281226 -315.019667)
			(xy 308.258355 -315.063244) (xy 308.22879 -315.102588) (xy 308.193297 -315.13668) (xy 308.152794 -315.164636)
			(xy 308.108332 -315.185734) (xy 308.061061 -315.199426) (xy 308.012206 -315.205358) (xy 307.963031 -315.203377)
			(xy 307.914812 -315.193533) (xy 307.868796 -315.176081) (xy 307.826175 -315.151474) (xy 307.788054 -315.120349)
			(xy 307.755419 -315.083512) (xy 307.729116 -315.041916) (xy 307.709825 -314.99664) (xy 307.698048 -314.948856)
			(xy 307.694088 -314.899802) (xy 307.355729 -314.899802) (xy 307.351558 -314.950134) (xy 307.339161 -314.999096)
			(xy 307.318873 -315.04535) (xy 307.29125 -315.087633) (xy 307.257045 -315.124794) (xy 307.21719 -315.155819)
			(xy 307.172772 -315.179861) (xy 307.125003 -315.196264) (xy 307.075185 -315.204582) (xy 307.049932 -315.20511)
			(xy 307.036205 -315.20498) (xy 307.008858 -315.202567) (xy 306.995322 -315.200284) (xy 306.982876 -315.197998)
			(xy 306.959254 -315.205364) (xy 306.882292 -315.28258) (xy 306.874926 -315.306202) (xy 306.877212 -315.318648)
			(xy 306.878854 -315.327915) (xy 306.881141 -315.346597) (xy 306.881784 -315.355986) (xy 306.882593 -315.374732)
			(xy 306.880177 -315.412177) (xy 306.876958 -315.430662) (xy 306.874672 -315.443362) (xy 306.882038 -315.466984)
			(xy 306.959 -315.5442) (xy 306.982622 -315.55182) (xy 306.995068 -315.549534) (xy 307.008664 -315.547189)
			(xy 307.036137 -315.544647) (xy 307.049932 -315.544454) (xy 307.075189 -315.544978) (xy 307.125013 -315.553297)
			(xy 307.172788 -315.569703) (xy 307.217211 -315.593748) (xy 307.257072 -315.624776) (xy 307.291282 -315.661942)
			(xy 307.318909 -315.704231) (xy 307.339198 -315.750491) (xy 307.351598 -315.799459) (xy 307.355766 -315.849762)
			(xy 307.694088 -315.849762) (xy 307.698048 -315.800708) (xy 307.709825 -315.752924) (xy 307.729116 -315.707648)
			(xy 307.755419 -315.666052) (xy 307.788054 -315.629215) (xy 307.826175 -315.59809) (xy 307.868796 -315.573483)
			(xy 307.914812 -315.556031) (xy 307.963031 -315.546187) (xy 308.012206 -315.544206) (xy 308.061061 -315.550138)
			(xy 308.108332 -315.56383) (xy 308.152794 -315.584928) (xy 308.193297 -315.612884) (xy 308.22879 -315.646976)
			(xy 308.258355 -315.68632) (xy 308.281226 -315.729897) (xy 308.29681 -315.776578) (xy 308.304705 -315.825155)
			(xy 308.3052 -315.849762) (xy 308.644048 -315.849762) (xy 308.648008 -315.800708) (xy 308.659785 -315.752924)
			(xy 308.679076 -315.707648) (xy 308.705379 -315.666052) (xy 308.738014 -315.629215) (xy 308.776135 -315.59809)
			(xy 308.818756 -315.573483) (xy 308.864772 -315.556031) (xy 308.912991 -315.546187) (xy 308.962166 -315.544206)
			(xy 309.011021 -315.550138) (xy 309.058292 -315.56383) (xy 309.102754 -315.584928) (xy 309.143257 -315.612884)
			(xy 309.17875 -315.646976) (xy 309.208315 -315.68632) (xy 309.231186 -315.729897) (xy 309.24677 -315.776578)
			(xy 309.254665 -315.825155) (xy 309.25516 -315.849762) (xy 309.594008 -315.849762) (xy 309.597968 -315.800708)
			(xy 309.609745 -315.752924) (xy 309.629036 -315.707648) (xy 309.655339 -315.666052) (xy 309.687974 -315.629215)
			(xy 309.726095 -315.59809) (xy 309.768716 -315.573483) (xy 309.814732 -315.556031) (xy 309.862951 -315.546187)
			(xy 309.912126 -315.544206) (xy 309.960981 -315.550138) (xy 310.008252 -315.56383) (xy 310.052714 -315.584928)
			(xy 310.093217 -315.612884) (xy 310.12871 -315.646976) (xy 310.158275 -315.68632) (xy 310.181146 -315.729897)
			(xy 310.19673 -315.776578) (xy 310.204625 -315.825155) (xy 310.20512 -315.849762) (xy 310.543968 -315.849762)
			(xy 310.547928 -315.800708) (xy 310.559705 -315.752924) (xy 310.578996 -315.707648) (xy 310.605299 -315.666052)
			(xy 310.637934 -315.629215) (xy 310.676055 -315.59809) (xy 310.718676 -315.573483) (xy 310.764692 -315.556031)
			(xy 310.812911 -315.546187) (xy 310.862086 -315.544206) (xy 310.910941 -315.550138) (xy 310.958212 -315.56383)
			(xy 311.002674 -315.584928) (xy 311.043177 -315.612884) (xy 311.07867 -315.646976) (xy 311.108235 -315.68632)
			(xy 311.131106 -315.729897) (xy 311.14669 -315.776578) (xy 311.154585 -315.825155) (xy 311.15508 -315.849762)
			(xy 311.493928 -315.849762) (xy 311.497888 -315.800708) (xy 311.509665 -315.752924) (xy 311.528956 -315.707648)
			(xy 311.555259 -315.666052) (xy 311.587894 -315.629215) (xy 311.626015 -315.59809) (xy 311.668636 -315.573483)
			(xy 311.714652 -315.556031) (xy 311.762871 -315.546187) (xy 311.812046 -315.544206) (xy 311.860901 -315.550138)
			(xy 311.908172 -315.56383) (xy 311.952634 -315.584928) (xy 311.993137 -315.612884) (xy 312.02863 -315.646976)
			(xy 312.058195 -315.68632) (xy 312.081066 -315.729897) (xy 312.09665 -315.776578) (xy 312.104545 -315.825155)
			(xy 312.10504 -315.849762) (xy 312.443888 -315.849762) (xy 312.447848 -315.800708) (xy 312.459625 -315.752924)
			(xy 312.478916 -315.707648) (xy 312.505219 -315.666052) (xy 312.537854 -315.629215) (xy 312.575975 -315.59809)
			(xy 312.618596 -315.573483) (xy 312.664612 -315.556031) (xy 312.712831 -315.546187) (xy 312.762006 -315.544206)
			(xy 312.810861 -315.550138) (xy 312.858132 -315.56383) (xy 312.902594 -315.584928) (xy 312.943097 -315.612884)
			(xy 312.97859 -315.646976) (xy 313.008155 -315.68632) (xy 313.031026 -315.729897) (xy 313.04661 -315.776578)
			(xy 313.054505 -315.825155) (xy 313.055 -315.849762) (xy 313.394102 -315.849762) (xy 313.398062 -315.800708)
			(xy 313.409839 -315.752924) (xy 313.42913 -315.707648) (xy 313.455433 -315.666052) (xy 313.488068 -315.629215)
			(xy 313.526189 -315.59809) (xy 313.56881 -315.573483) (xy 313.614826 -315.556031) (xy 313.663045 -315.546187)
			(xy 313.71222 -315.544206) (xy 313.761075 -315.550138) (xy 313.808346 -315.56383) (xy 313.852808 -315.584928)
			(xy 313.893311 -315.612884) (xy 313.928804 -315.646976) (xy 313.958369 -315.68632) (xy 313.98124 -315.729897)
			(xy 313.996824 -315.776578) (xy 314.004719 -315.825155) (xy 314.005214 -315.849762) (xy 314.344062 -315.849762)
			(xy 314.348022 -315.800708) (xy 314.359799 -315.752924) (xy 314.37909 -315.707648) (xy 314.405393 -315.666052)
			(xy 314.438028 -315.629215) (xy 314.476149 -315.59809) (xy 314.51877 -315.573483) (xy 314.564786 -315.556031)
			(xy 314.613005 -315.546187) (xy 314.66218 -315.544206) (xy 314.711035 -315.550138) (xy 314.758306 -315.56383)
			(xy 314.802768 -315.584928) (xy 314.843271 -315.612884) (xy 314.878764 -315.646976) (xy 314.908329 -315.68632)
			(xy 314.9312 -315.729897) (xy 314.946784 -315.776578) (xy 314.954679 -315.825155) (xy 314.955174 -315.849762)
			(xy 314.954679 -315.874369) (xy 314.946784 -315.922946) (xy 314.9312 -315.969627) (xy 314.908329 -316.013204)
			(xy 314.878764 -316.052548) (xy 314.843271 -316.08664) (xy 314.802768 -316.114596) (xy 314.758306 -316.135694)
			(xy 314.711035 -316.149386) (xy 314.66218 -316.155318) (xy 314.613005 -316.153337) (xy 314.564786 -316.143493)
			(xy 314.51877 -316.126041) (xy 314.476149 -316.101434) (xy 314.438028 -316.070309) (xy 314.405393 -316.033472)
			(xy 314.37909 -315.991876) (xy 314.359799 -315.9466) (xy 314.348022 -315.898816) (xy 314.344062 -315.849762)
			(xy 314.005214 -315.849762) (xy 314.004719 -315.874369) (xy 313.996824 -315.922946) (xy 313.98124 -315.969627)
			(xy 313.958369 -316.013204) (xy 313.928804 -316.052548) (xy 313.893311 -316.08664) (xy 313.852808 -316.114596)
			(xy 313.808346 -316.135694) (xy 313.761075 -316.149386) (xy 313.71222 -316.155318) (xy 313.663045 -316.153337)
			(xy 313.614826 -316.143493) (xy 313.56881 -316.126041) (xy 313.526189 -316.101434) (xy 313.488068 -316.070309)
			(xy 313.455433 -316.033472) (xy 313.42913 -315.991876) (xy 313.409839 -315.9466) (xy 313.398062 -315.898816)
			(xy 313.394102 -315.849762) (xy 313.055 -315.849762) (xy 313.054505 -315.874369) (xy 313.04661 -315.922946)
			(xy 313.031026 -315.969627) (xy 313.008155 -316.013204) (xy 312.97859 -316.052548) (xy 312.943097 -316.08664)
			(xy 312.902594 -316.114596) (xy 312.858132 -316.135694) (xy 312.810861 -316.149386) (xy 312.762006 -316.155318)
			(xy 312.712831 -316.153337) (xy 312.664612 -316.143493) (xy 312.618596 -316.126041) (xy 312.575975 -316.101434)
			(xy 312.537854 -316.070309) (xy 312.505219 -316.033472) (xy 312.478916 -315.991876) (xy 312.459625 -315.9466)
			(xy 312.447848 -315.898816) (xy 312.443888 -315.849762) (xy 312.10504 -315.849762) (xy 312.104545 -315.874369)
			(xy 312.09665 -315.922946) (xy 312.081066 -315.969627) (xy 312.058195 -316.013204) (xy 312.02863 -316.052548)
			(xy 311.993137 -316.08664) (xy 311.952634 -316.114596) (xy 311.908172 -316.135694) (xy 311.860901 -316.149386)
			(xy 311.812046 -316.155318) (xy 311.762871 -316.153337) (xy 311.714652 -316.143493) (xy 311.668636 -316.126041)
			(xy 311.626015 -316.101434) (xy 311.587894 -316.070309) (xy 311.555259 -316.033472) (xy 311.528956 -315.991876)
			(xy 311.509665 -315.9466) (xy 311.497888 -315.898816) (xy 311.493928 -315.849762) (xy 311.15508 -315.849762)
			(xy 311.154585 -315.874369) (xy 311.14669 -315.922946) (xy 311.131106 -315.969627) (xy 311.108235 -316.013204)
			(xy 311.07867 -316.052548) (xy 311.043177 -316.08664) (xy 311.002674 -316.114596) (xy 310.958212 -316.135694)
			(xy 310.910941 -316.149386) (xy 310.862086 -316.155318) (xy 310.812911 -316.153337) (xy 310.764692 -316.143493)
			(xy 310.718676 -316.126041) (xy 310.676055 -316.101434) (xy 310.637934 -316.070309) (xy 310.605299 -316.033472)
			(xy 310.578996 -315.991876) (xy 310.559705 -315.9466) (xy 310.547928 -315.898816) (xy 310.543968 -315.849762)
			(xy 310.20512 -315.849762) (xy 310.204625 -315.874369) (xy 310.19673 -315.922946) (xy 310.181146 -315.969627)
			(xy 310.158275 -316.013204) (xy 310.12871 -316.052548) (xy 310.093217 -316.08664) (xy 310.052714 -316.114596)
			(xy 310.008252 -316.135694) (xy 309.960981 -316.149386) (xy 309.912126 -316.155318) (xy 309.862951 -316.153337)
			(xy 309.814732 -316.143493) (xy 309.768716 -316.126041) (xy 309.726095 -316.101434) (xy 309.687974 -316.070309)
			(xy 309.655339 -316.033472) (xy 309.629036 -315.991876) (xy 309.609745 -315.9466) (xy 309.597968 -315.898816)
			(xy 309.594008 -315.849762) (xy 309.25516 -315.849762) (xy 309.254665 -315.874369) (xy 309.24677 -315.922946)
			(xy 309.231186 -315.969627) (xy 309.208315 -316.013204) (xy 309.17875 -316.052548) (xy 309.143257 -316.08664)
			(xy 309.102754 -316.114596) (xy 309.058292 -316.135694) (xy 309.011021 -316.149386) (xy 308.962166 -316.155318)
			(xy 308.912991 -316.153337) (xy 308.864772 -316.143493) (xy 308.818756 -316.126041) (xy 308.776135 -316.101434)
			(xy 308.738014 -316.070309) (xy 308.705379 -316.033472) (xy 308.679076 -315.991876) (xy 308.659785 -315.9466)
			(xy 308.648008 -315.898816) (xy 308.644048 -315.849762) (xy 308.3052 -315.849762) (xy 308.304705 -315.874369)
			(xy 308.29681 -315.922946) (xy 308.281226 -315.969627) (xy 308.258355 -316.013204) (xy 308.22879 -316.052548)
			(xy 308.193297 -316.08664) (xy 308.152794 -316.114596) (xy 308.108332 -316.135694) (xy 308.061061 -316.149386)
			(xy 308.012206 -316.155318) (xy 307.963031 -316.153337) (xy 307.914812 -316.143493) (xy 307.868796 -316.126041)
			(xy 307.826175 -316.101434) (xy 307.788054 -316.070309) (xy 307.755419 -316.033472) (xy 307.729116 -315.991876)
			(xy 307.709825 -315.9466) (xy 307.698048 -315.898816) (xy 307.694088 -315.849762) (xy 307.355766 -315.849762)
			(xy 307.355769 -315.8498) (xy 307.351598 -315.900141) (xy 307.339198 -315.949109) (xy 307.318909 -315.995369)
			(xy 307.291282 -316.037658) (xy 307.257072 -316.074824) (xy 307.217211 -316.105852) (xy 307.172788 -316.129897)
			(xy 307.125013 -316.146303) (xy 307.075189 -316.154622) (xy 307.049932 -316.15507) (xy 307.040828 -316.154971)
			(xy 307.022655 -316.153826) (xy 307.01361 -316.152784) (xy 307.001418 -316.151514) (xy 306.979066 -316.159388)
			(xy 306.906168 -316.235842) (xy 306.89931 -316.258448) (xy 306.901088 -316.270386) (xy 306.9032 -316.283749)
			(xy 306.90549 -316.310707) (xy 306.90566 -316.324234) (xy 306.90566 -316.3951) (xy 306.906221 -316.405792)
			(xy 306.914881 -316.425348) (xy 306.922424 -316.432946) (xy 306.986686 -316.490604) (xy 307.007006 -316.497208)
			(xy 307.017928 -316.496192) (xy 307.049932 -316.494414) (xy 307.075184 -316.494938) (xy 307.124998 -316.503255)
			(xy 307.172764 -316.519658) (xy 307.217179 -316.543698) (xy 307.257031 -316.57472) (xy 307.291235 -316.611879)
			(xy 307.318856 -316.65416) (xy 307.339142 -316.70041) (xy 307.351539 -316.749369) (xy 307.355709 -316.7997)
			(xy 307.355707 -316.799722) (xy 307.694088 -316.799722) (xy 307.698048 -316.750668) (xy 307.709825 -316.702884)
			(xy 307.729116 -316.657608) (xy 307.755419 -316.616012) (xy 307.788054 -316.579175) (xy 307.826175 -316.54805)
			(xy 307.868796 -316.523443) (xy 307.914812 -316.505991) (xy 307.963031 -316.496147) (xy 308.012206 -316.494166)
			(xy 308.061061 -316.500098) (xy 308.108332 -316.51379) (xy 308.152794 -316.534888) (xy 308.193297 -316.562844)
			(xy 308.22879 -316.596936) (xy 308.258355 -316.63628) (xy 308.281226 -316.679857) (xy 308.29681 -316.726538)
			(xy 308.304705 -316.775115) (xy 308.3052 -316.799722) (xy 308.644048 -316.799722) (xy 308.648008 -316.750668)
			(xy 308.659785 -316.702884) (xy 308.679076 -316.657608) (xy 308.705379 -316.616012) (xy 308.738014 -316.579175)
			(xy 308.776135 -316.54805) (xy 308.818756 -316.523443) (xy 308.864772 -316.505991) (xy 308.912991 -316.496147)
			(xy 308.962166 -316.494166) (xy 309.011021 -316.500098) (xy 309.058292 -316.51379) (xy 309.102754 -316.534888)
			(xy 309.143257 -316.562844) (xy 309.17875 -316.596936) (xy 309.208315 -316.63628) (xy 309.231186 -316.679857)
			(xy 309.24677 -316.726538) (xy 309.254665 -316.775115) (xy 309.25516 -316.799722) (xy 309.594008 -316.799722)
			(xy 309.597968 -316.750668) (xy 309.609745 -316.702884) (xy 309.629036 -316.657608) (xy 309.655339 -316.616012)
			(xy 309.687974 -316.579175) (xy 309.726095 -316.54805) (xy 309.768716 -316.523443) (xy 309.814732 -316.505991)
			(xy 309.862951 -316.496147) (xy 309.912126 -316.494166) (xy 309.960981 -316.500098) (xy 310.008252 -316.51379)
			(xy 310.052714 -316.534888) (xy 310.093217 -316.562844) (xy 310.12871 -316.596936) (xy 310.158275 -316.63628)
			(xy 310.181146 -316.679857) (xy 310.19673 -316.726538) (xy 310.204625 -316.775115) (xy 310.20512 -316.799722)
			(xy 310.543968 -316.799722) (xy 310.547928 -316.750668) (xy 310.559705 -316.702884) (xy 310.578996 -316.657608)
			(xy 310.605299 -316.616012) (xy 310.637934 -316.579175) (xy 310.676055 -316.54805) (xy 310.718676 -316.523443)
			(xy 310.764692 -316.505991) (xy 310.812911 -316.496147) (xy 310.862086 -316.494166) (xy 310.910941 -316.500098)
			(xy 310.958212 -316.51379) (xy 311.002674 -316.534888) (xy 311.043177 -316.562844) (xy 311.07867 -316.596936)
			(xy 311.108235 -316.63628) (xy 311.131106 -316.679857) (xy 311.14669 -316.726538) (xy 311.154585 -316.775115)
			(xy 311.15508 -316.799722) (xy 311.493928 -316.799722) (xy 311.497888 -316.750668) (xy 311.509665 -316.702884)
			(xy 311.528956 -316.657608) (xy 311.555259 -316.616012) (xy 311.587894 -316.579175) (xy 311.626015 -316.54805)
			(xy 311.668636 -316.523443) (xy 311.714652 -316.505991) (xy 311.762871 -316.496147) (xy 311.812046 -316.494166)
			(xy 311.860901 -316.500098) (xy 311.908172 -316.51379) (xy 311.952634 -316.534888) (xy 311.993137 -316.562844)
			(xy 312.02863 -316.596936) (xy 312.058195 -316.63628) (xy 312.081066 -316.679857) (xy 312.09665 -316.726538)
			(xy 312.104545 -316.775115) (xy 312.10504 -316.799722) (xy 312.443888 -316.799722) (xy 312.447848 -316.750668)
			(xy 312.459625 -316.702884) (xy 312.478916 -316.657608) (xy 312.505219 -316.616012) (xy 312.537854 -316.579175)
			(xy 312.575975 -316.54805) (xy 312.618596 -316.523443) (xy 312.664612 -316.505991) (xy 312.712831 -316.496147)
			(xy 312.762006 -316.494166) (xy 312.810861 -316.500098) (xy 312.858132 -316.51379) (xy 312.902594 -316.534888)
			(xy 312.943097 -316.562844) (xy 312.97859 -316.596936) (xy 313.008155 -316.63628) (xy 313.031026 -316.679857)
			(xy 313.04661 -316.726538) (xy 313.054505 -316.775115) (xy 313.055 -316.799722) (xy 313.394102 -316.799722)
			(xy 313.398062 -316.750668) (xy 313.409839 -316.702884) (xy 313.42913 -316.657608) (xy 313.455433 -316.616012)
			(xy 313.488068 -316.579175) (xy 313.526189 -316.54805) (xy 313.56881 -316.523443) (xy 313.614826 -316.505991)
			(xy 313.663045 -316.496147) (xy 313.71222 -316.494166) (xy 313.761075 -316.500098) (xy 313.808346 -316.51379)
			(xy 313.852808 -316.534888) (xy 313.893311 -316.562844) (xy 313.928804 -316.596936) (xy 313.958369 -316.63628)
			(xy 313.98124 -316.679857) (xy 313.996824 -316.726538) (xy 314.004719 -316.775115) (xy 314.005214 -316.799722)
			(xy 314.344062 -316.799722) (xy 314.348022 -316.750668) (xy 314.359799 -316.702884) (xy 314.37909 -316.657608)
			(xy 314.405393 -316.616012) (xy 314.438028 -316.579175) (xy 314.476149 -316.54805) (xy 314.51877 -316.523443)
			(xy 314.564786 -316.505991) (xy 314.613005 -316.496147) (xy 314.66218 -316.494166) (xy 314.711035 -316.500098)
			(xy 314.758306 -316.51379) (xy 314.802768 -316.534888) (xy 314.843271 -316.562844) (xy 314.878764 -316.596936)
			(xy 314.908329 -316.63628) (xy 314.9312 -316.679857) (xy 314.946784 -316.726538) (xy 314.954679 -316.775115)
			(xy 314.955174 -316.799722) (xy 315.294276 -316.799722) (xy 315.298236 -316.750668) (xy 315.310013 -316.702884)
			(xy 315.329304 -316.657608) (xy 315.355607 -316.616012) (xy 315.388242 -316.579175) (xy 315.426363 -316.54805)
			(xy 315.468984 -316.523443) (xy 315.515 -316.505991) (xy 315.563219 -316.496147) (xy 315.612394 -316.494166)
			(xy 315.661249 -316.500098) (xy 315.70852 -316.51379) (xy 315.752982 -316.534888) (xy 315.793485 -316.562844)
			(xy 315.828978 -316.596936) (xy 315.858543 -316.63628) (xy 315.881414 -316.679857) (xy 315.896998 -316.726538)
			(xy 315.904893 -316.775115) (xy 315.905388 -316.799722) (xy 315.904893 -316.824329) (xy 315.896998 -316.872906)
			(xy 315.881414 -316.919587) (xy 315.858543 -316.963164) (xy 315.828978 -317.002508) (xy 315.793485 -317.0366)
			(xy 315.752982 -317.064556) (xy 315.70852 -317.085654) (xy 315.661249 -317.099346) (xy 315.612394 -317.105278)
			(xy 315.563219 -317.103297) (xy 315.515 -317.093453) (xy 315.468984 -317.076001) (xy 315.426363 -317.051394)
			(xy 315.388242 -317.020269) (xy 315.355607 -316.983432) (xy 315.329304 -316.941836) (xy 315.310013 -316.89656)
			(xy 315.298236 -316.848776) (xy 315.294276 -316.799722) (xy 314.955174 -316.799722) (xy 314.954679 -316.824329)
			(xy 314.946784 -316.872906) (xy 314.9312 -316.919587) (xy 314.908329 -316.963164) (xy 314.878764 -317.002508)
			(xy 314.843271 -317.0366) (xy 314.802768 -317.064556) (xy 314.758306 -317.085654) (xy 314.711035 -317.099346)
			(xy 314.66218 -317.105278) (xy 314.613005 -317.103297) (xy 314.564786 -317.093453) (xy 314.51877 -317.076001)
			(xy 314.476149 -317.051394) (xy 314.438028 -317.020269) (xy 314.405393 -316.983432) (xy 314.37909 -316.941836)
			(xy 314.359799 -316.89656) (xy 314.348022 -316.848776) (xy 314.344062 -316.799722) (xy 314.005214 -316.799722)
			(xy 314.004719 -316.824329) (xy 313.996824 -316.872906) (xy 313.98124 -316.919587) (xy 313.958369 -316.963164)
			(xy 313.928804 -317.002508) (xy 313.893311 -317.0366) (xy 313.852808 -317.064556) (xy 313.808346 -317.085654)
			(xy 313.761075 -317.099346) (xy 313.71222 -317.105278) (xy 313.663045 -317.103297) (xy 313.614826 -317.093453)
			(xy 313.56881 -317.076001) (xy 313.526189 -317.051394) (xy 313.488068 -317.020269) (xy 313.455433 -316.983432)
			(xy 313.42913 -316.941836) (xy 313.409839 -316.89656) (xy 313.398062 -316.848776) (xy 313.394102 -316.799722)
			(xy 313.055 -316.799722) (xy 313.054505 -316.824329) (xy 313.04661 -316.872906) (xy 313.031026 -316.919587)
			(xy 313.008155 -316.963164) (xy 312.97859 -317.002508) (xy 312.943097 -317.0366) (xy 312.902594 -317.064556)
			(xy 312.858132 -317.085654) (xy 312.810861 -317.099346) (xy 312.762006 -317.105278) (xy 312.712831 -317.103297)
			(xy 312.664612 -317.093453) (xy 312.618596 -317.076001) (xy 312.575975 -317.051394) (xy 312.537854 -317.020269)
			(xy 312.505219 -316.983432) (xy 312.478916 -316.941836) (xy 312.459625 -316.89656) (xy 312.447848 -316.848776)
			(xy 312.443888 -316.799722) (xy 312.10504 -316.799722) (xy 312.104545 -316.824329) (xy 312.09665 -316.872906)
			(xy 312.081066 -316.919587) (xy 312.058195 -316.963164) (xy 312.02863 -317.002508) (xy 311.993137 -317.0366)
			(xy 311.952634 -317.064556) (xy 311.908172 -317.085654) (xy 311.860901 -317.099346) (xy 311.812046 -317.105278)
			(xy 311.762871 -317.103297) (xy 311.714652 -317.093453) (xy 311.668636 -317.076001) (xy 311.626015 -317.051394)
			(xy 311.587894 -317.020269) (xy 311.555259 -316.983432) (xy 311.528956 -316.941836) (xy 311.509665 -316.89656)
			(xy 311.497888 -316.848776) (xy 311.493928 -316.799722) (xy 311.15508 -316.799722) (xy 311.154585 -316.824329)
			(xy 311.14669 -316.872906) (xy 311.131106 -316.919587) (xy 311.108235 -316.963164) (xy 311.07867 -317.002508)
			(xy 311.043177 -317.0366) (xy 311.002674 -317.064556) (xy 310.958212 -317.085654) (xy 310.910941 -317.099346)
			(xy 310.862086 -317.105278) (xy 310.812911 -317.103297) (xy 310.764692 -317.093453) (xy 310.718676 -317.076001)
			(xy 310.676055 -317.051394) (xy 310.637934 -317.020269) (xy 310.605299 -316.983432) (xy 310.578996 -316.941836)
			(xy 310.559705 -316.89656) (xy 310.547928 -316.848776) (xy 310.543968 -316.799722) (xy 310.20512 -316.799722)
			(xy 310.204625 -316.824329) (xy 310.19673 -316.872906) (xy 310.181146 -316.919587) (xy 310.158275 -316.963164)
			(xy 310.12871 -317.002508) (xy 310.093217 -317.0366) (xy 310.052714 -317.064556) (xy 310.008252 -317.085654)
			(xy 309.960981 -317.099346) (xy 309.912126 -317.105278) (xy 309.862951 -317.103297) (xy 309.814732 -317.093453)
			(xy 309.768716 -317.076001) (xy 309.726095 -317.051394) (xy 309.687974 -317.020269) (xy 309.655339 -316.983432)
			(xy 309.629036 -316.941836) (xy 309.609745 -316.89656) (xy 309.597968 -316.848776) (xy 309.594008 -316.799722)
			(xy 309.25516 -316.799722) (xy 309.254665 -316.824329) (xy 309.24677 -316.872906) (xy 309.231186 -316.919587)
			(xy 309.208315 -316.963164) (xy 309.17875 -317.002508) (xy 309.143257 -317.0366) (xy 309.102754 -317.064556)
			(xy 309.058292 -317.085654) (xy 309.011021 -317.099346) (xy 308.962166 -317.105278) (xy 308.912991 -317.103297)
			(xy 308.864772 -317.093453) (xy 308.818756 -317.076001) (xy 308.776135 -317.051394) (xy 308.738014 -317.020269)
			(xy 308.705379 -316.983432) (xy 308.679076 -316.941836) (xy 308.659785 -316.89656) (xy 308.648008 -316.848776)
			(xy 308.644048 -316.799722) (xy 308.3052 -316.799722) (xy 308.304705 -316.824329) (xy 308.29681 -316.872906)
			(xy 308.281226 -316.919587) (xy 308.258355 -316.963164) (xy 308.22879 -317.002508) (xy 308.193297 -317.0366)
			(xy 308.152794 -317.064556) (xy 308.108332 -317.085654) (xy 308.061061 -317.099346) (xy 308.012206 -317.105278)
			(xy 307.963031 -317.103297) (xy 307.914812 -317.093453) (xy 307.868796 -317.076001) (xy 307.826175 -317.051394)
			(xy 307.788054 -317.020269) (xy 307.755419 -316.983432) (xy 307.729116 -316.941836) (xy 307.709825 -316.89656)
			(xy 307.698048 -316.848776) (xy 307.694088 -316.799722) (xy 307.355707 -316.799722) (xy 307.351539 -316.850031)
			(xy 307.339142 -316.89899) (xy 307.318856 -316.94524) (xy 307.291235 -316.987521) (xy 307.257031 -317.02468)
			(xy 307.217179 -317.055702) (xy 307.172764 -317.079742) (xy 307.124998 -317.096145) (xy 307.075184 -317.104462)
			(xy 307.049932 -317.10503) (xy 307.018182 -317.103252) (xy 307.00726 -317.102236) (xy 306.98694 -317.10884)
			(xy 306.922678 -317.166752) (xy 306.915157 -317.174292) (xy 306.906472 -317.193711) (xy 306.905914 -317.204344)
			(xy 306.905914 -317.274702) (xy 306.90576 -317.28842) (xy 306.90347 -317.31576) (xy 306.901342 -317.329312)
			(xy 306.89931 -317.34125) (xy 306.906422 -317.363856) (xy 306.97932 -317.44031) (xy 307.001672 -317.448184)
			(xy 307.01361 -317.446914) (xy 307.022654 -317.445867) (xy 307.040828 -317.444725) (xy 307.049932 -317.444628)
			(xy 307.073922 -317.445077) (xy 307.121312 -317.452588) (xy 307.166943 -317.467419) (xy 307.209692 -317.489207)
			(xy 307.248506 -317.517414) (xy 307.28243 -317.551345) (xy 307.310629 -317.590166) (xy 307.332407 -317.63292)
			(xy 307.347228 -317.678554) (xy 307.354729 -317.725945) (xy 307.35524 -317.749936) (xy 307.355142 -317.75904)
			(xy 307.353999 -317.777213) (xy 307.352954 -317.786258) (xy 307.351684 -317.79845) (xy 307.359558 -317.820802)
			(xy 307.436012 -317.8937) (xy 307.458618 -317.900812) (xy 307.470556 -317.89878) (xy 307.484044 -317.89665)
			(xy 307.511257 -317.894362) (xy 307.524912 -317.894208) (xy 307.538566 -317.894368) (xy 307.56578 -317.896653)
			(xy 307.579268 -317.89878) (xy 307.591206 -317.900812) (xy 307.613812 -317.8937) (xy 307.690266 -317.820802)
			(xy 307.69814 -317.79845) (xy 307.69687 -317.786258) (xy 307.695821 -317.777214) (xy 307.694675 -317.75904)
			(xy 307.694584 -317.749936) (xy 307.695106 -317.724681) (xy 307.703419 -317.674859) (xy 307.71982 -317.627085)
			(xy 307.743861 -317.582662) (xy 307.774885 -317.542802) (xy 307.812047 -317.508592) (xy 307.854333 -317.480966)
			(xy 307.900589 -317.460676) (xy 307.949554 -317.448276) (xy 307.999892 -317.444105) (xy 308.05023 -317.448276)
			(xy 308.099195 -317.460676) (xy 308.145451 -317.480966) (xy 308.187737 -317.508592) (xy 308.224899 -317.542802)
			(xy 308.255923 -317.582662) (xy 308.279964 -317.627085) (xy 308.296365 -317.674859) (xy 308.304678 -317.724681)
			(xy 308.3052 -317.749936) (xy 308.305016 -317.764119) (xy 308.302349 -317.792359) (xy 308.299866 -317.806324)
			(xy 308.29758 -317.81877) (xy 308.304946 -317.842392) (xy 308.382416 -317.919862) (xy 308.406038 -317.927228)
			(xy 308.418484 -317.924942) (xy 308.446491 -317.920313) (xy 308.503253 -317.920313) (xy 308.53126 -317.924942)
			(xy 308.543706 -317.927228) (xy 308.567328 -317.919862) (xy 308.644798 -317.842392) (xy 308.652164 -317.81877)
			(xy 308.649878 -317.806324) (xy 308.647391 -317.792359) (xy 308.644715 -317.764119) (xy 308.644544 -317.749936)
			(xy 308.645066 -317.724681) (xy 308.653379 -317.674859) (xy 308.66978 -317.627085) (xy 308.693821 -317.582662)
			(xy 308.724845 -317.542802) (xy 308.762007 -317.508592) (xy 308.804293 -317.480966) (xy 308.850549 -317.460676)
			(xy 308.899514 -317.448276) (xy 308.949852 -317.444105) (xy 309.00019 -317.448276) (xy 309.049155 -317.460676)
			(xy 309.095411 -317.480966) (xy 309.137697 -317.508592) (xy 309.174859 -317.542802) (xy 309.205883 -317.582662)
			(xy 309.229924 -317.627085) (xy 309.246325 -317.674859) (xy 309.254638 -317.724681) (xy 309.25516 -317.749936)
			(xy 309.255062 -317.75904) (xy 309.253919 -317.777213) (xy 309.252874 -317.786258) (xy 309.251604 -317.79845)
			(xy 309.259478 -317.820802) (xy 309.335932 -317.8937) (xy 309.358538 -317.900812) (xy 309.370476 -317.89878)
			(xy 309.383964 -317.89665) (xy 309.411178 -317.894365) (xy 309.424832 -317.894208) (xy 309.438486 -317.894369)
			(xy 309.465699 -317.896655) (xy 309.479188 -317.89878) (xy 309.491126 -317.900812) (xy 309.513732 -317.8937)
			(xy 309.590186 -317.820802) (xy 309.59806 -317.79845) (xy 309.59679 -317.786258) (xy 309.59574 -317.777214)
			(xy 309.594595 -317.75904) (xy 309.594504 -317.749936) (xy 309.595026 -317.724681) (xy 309.603339 -317.674859)
			(xy 309.61974 -317.627085) (xy 309.643781 -317.582662) (xy 309.674805 -317.542802) (xy 309.711967 -317.508592)
			(xy 309.754253 -317.480966) (xy 309.800509 -317.460676) (xy 309.849474 -317.448276) (xy 309.899812 -317.444105)
			(xy 309.95015 -317.448276) (xy 309.999115 -317.460676) (xy 310.045371 -317.480966) (xy 310.087657 -317.508592)
			(xy 310.124819 -317.542802) (xy 310.155843 -317.582662) (xy 310.179884 -317.627085) (xy 310.196285 -317.674859)
			(xy 310.204598 -317.724681) (xy 310.20512 -317.749936) (xy 310.204936 -317.764119) (xy 310.202269 -317.792359)
			(xy 310.199786 -317.806324) (xy 310.1975 -317.81877) (xy 310.204866 -317.842392) (xy 310.282336 -317.919862)
			(xy 310.305958 -317.927228) (xy 310.318404 -317.924942) (xy 310.346411 -317.920313) (xy 310.403173 -317.920313)
			(xy 310.43118 -317.924942) (xy 310.443626 -317.927228) (xy 310.467248 -317.919862) (xy 310.544718 -317.842392)
			(xy 310.552084 -317.81877) (xy 310.549798 -317.806324) (xy 310.547311 -317.792359) (xy 310.544636 -317.764119)
			(xy 310.544464 -317.749936) (xy 310.544986 -317.724681) (xy 310.553299 -317.674859) (xy 310.5697 -317.627085)
			(xy 310.593741 -317.582662) (xy 310.624765 -317.542802) (xy 310.661927 -317.508592) (xy 310.704213 -317.480966)
			(xy 310.750469 -317.460676) (xy 310.799434 -317.448276) (xy 310.849772 -317.444105) (xy 310.90011 -317.448276)
			(xy 310.949075 -317.460676) (xy 310.995331 -317.480966) (xy 311.037617 -317.508592) (xy 311.074779 -317.542802)
			(xy 311.105803 -317.582662) (xy 311.129844 -317.627085) (xy 311.146245 -317.674859) (xy 311.154558 -317.724681)
			(xy 311.15508 -317.749936) (xy 311.154982 -317.75904) (xy 311.153839 -317.777213) (xy 311.152794 -317.786258)
			(xy 311.151524 -317.79845) (xy 311.159398 -317.820802) (xy 311.235852 -317.8937) (xy 311.258458 -317.900812)
			(xy 311.270396 -317.89878) (xy 311.283884 -317.896647) (xy 311.311097 -317.894355) (xy 311.324752 -317.894208)
			(xy 311.338406 -317.894369) (xy 311.365619 -317.896657) (xy 311.379108 -317.89878) (xy 311.391046 -317.900812)
			(xy 311.413652 -317.8937) (xy 311.490106 -317.820802) (xy 311.49798 -317.79845) (xy 311.49671 -317.786258)
			(xy 311.49566 -317.777214) (xy 311.494514 -317.75904) (xy 311.494424 -317.749936) (xy 311.494946 -317.724681)
			(xy 311.503259 -317.674859) (xy 311.51966 -317.627085) (xy 311.543701 -317.582662) (xy 311.574725 -317.542802)
			(xy 311.611887 -317.508592) (xy 311.654173 -317.480966) (xy 311.700429 -317.460676) (xy 311.749394 -317.448276)
			(xy 311.799732 -317.444105) (xy 311.85007 -317.448276) (xy 311.899035 -317.460676) (xy 311.945291 -317.480966)
			(xy 311.987577 -317.508592) (xy 312.024739 -317.542802) (xy 312.055763 -317.582662) (xy 312.079804 -317.627085)
			(xy 312.096205 -317.674859) (xy 312.104518 -317.724681) (xy 312.10504 -317.749936) (xy 312.104856 -317.764119)
			(xy 312.102189 -317.792359) (xy 312.099706 -317.806324) (xy 312.09742 -317.81877) (xy 312.104786 -317.842392)
			(xy 312.182256 -317.919862) (xy 312.205878 -317.927228) (xy 312.218324 -317.924942) (xy 312.246331 -317.920313)
			(xy 312.303093 -317.920313) (xy 312.3311 -317.924942) (xy 312.343546 -317.927228) (xy 312.367168 -317.919862)
			(xy 312.444638 -317.842392) (xy 312.452004 -317.81877) (xy 312.449718 -317.806324) (xy 312.447231 -317.792359)
			(xy 312.444556 -317.764119) (xy 312.444384 -317.749936) (xy 312.444906 -317.724681) (xy 312.453219 -317.674859)
			(xy 312.46962 -317.627085) (xy 312.493661 -317.582662) (xy 312.524685 -317.542802) (xy 312.561847 -317.508592)
			(xy 312.604133 -317.480966) (xy 312.650389 -317.460676) (xy 312.699354 -317.448276) (xy 312.749692 -317.444105)
			(xy 312.80003 -317.448276) (xy 312.848995 -317.460676) (xy 312.895251 -317.480966) (xy 312.937537 -317.508592)
			(xy 312.974699 -317.542802) (xy 313.005723 -317.582662) (xy 313.029764 -317.627085) (xy 313.046165 -317.674859)
			(xy 313.054478 -317.724681) (xy 313.055 -317.749936) (xy 313.054902 -317.75904) (xy 313.053759 -317.777213)
			(xy 313.052714 -317.786258) (xy 313.051444 -317.79845) (xy 313.059318 -317.820802) (xy 313.135772 -317.8937)
			(xy 313.158378 -317.900812) (xy 313.170316 -317.89878) (xy 313.183804 -317.896648) (xy 313.211017 -317.894357)
			(xy 313.224672 -317.894208) (xy 313.23839 -317.89436) (xy 313.26573 -317.896646) (xy 313.279282 -317.89878)
			(xy 313.29122 -317.900812) (xy 313.313826 -317.8937) (xy 313.39028 -317.820802) (xy 313.398154 -317.79845)
			(xy 313.396884 -317.786512) (xy 313.395829 -317.777404) (xy 313.394685 -317.759104) (xy 313.394598 -317.749936)
			(xy 313.39512 -317.724681) (xy 313.403433 -317.674859) (xy 313.419834 -317.627085) (xy 313.443875 -317.582662)
			(xy 313.474899 -317.542802) (xy 313.512061 -317.508592) (xy 313.554347 -317.480966) (xy 313.600603 -317.460676)
			(xy 313.649568 -317.448276) (xy 313.699906 -317.444105) (xy 313.750244 -317.448276) (xy 313.799209 -317.460676)
			(xy 313.845465 -317.480966) (xy 313.887751 -317.508592) (xy 313.924913 -317.542802) (xy 313.955937 -317.582662)
			(xy 313.979978 -317.627085) (xy 313.996379 -317.674859) (xy 314.004692 -317.724681) (xy 314.005214 -317.749936)
			(xy 314.00503 -317.764119) (xy 314.002363 -317.792359) (xy 313.99988 -317.806324) (xy 313.997594 -317.81877)
			(xy 314.00496 -317.842392) (xy 314.08243 -317.919862) (xy 314.106052 -317.927228) (xy 314.118498 -317.924942)
			(xy 314.146505 -317.920313) (xy 314.203267 -317.920313) (xy 314.231274 -317.924942) (xy 314.24372 -317.927228)
			(xy 314.267342 -317.919862) (xy 314.344812 -317.842392) (xy 314.352178 -317.81877) (xy 314.349892 -317.806324)
			(xy 314.347405 -317.792359) (xy 314.34473 -317.764119) (xy 314.344558 -317.749936) (xy 314.34508 -317.724681)
			(xy 314.353393 -317.674859) (xy 314.369794 -317.627085) (xy 314.393835 -317.582662) (xy 314.424859 -317.542802)
			(xy 314.462021 -317.508592) (xy 314.504307 -317.480966) (xy 314.550563 -317.460676) (xy 314.599528 -317.448276)
			(xy 314.649866 -317.444105) (xy 314.700204 -317.448276) (xy 314.749169 -317.460676) (xy 314.795425 -317.480966)
			(xy 314.837711 -317.508592) (xy 314.874873 -317.542802) (xy 314.905897 -317.582662) (xy 314.929938 -317.627085)
			(xy 314.946339 -317.674859) (xy 314.954652 -317.724681) (xy 314.955174 -317.749936) (xy 314.95508 -317.759104)
			(xy 314.953935 -317.777404) (xy 314.952888 -317.786512) (xy 314.951618 -317.79845) (xy 314.959492 -317.820802)
			(xy 315.035946 -317.8937) (xy 315.058552 -317.900812) (xy 315.07049 -317.89878) (xy 315.095643 -317.89505)
			(xy 315.146488 -317.894445) (xy 315.196827 -317.901626) (xy 315.245474 -317.916424) (xy 315.291284 -317.938492)
			(xy 315.333179 -317.967309) (xy 315.370171 -318.002196) (xy 315.401389 -318.042333) (xy 315.426099 -318.086774)
			(xy 315.443718 -318.134472) (xy 315.453832 -318.184305) (xy 315.455554 -318.209676) (xy 315.455554 -318.20993)
			(xy 315.456446 -318.219508) (xy 315.464415 -318.236998) (xy 315.471048 -318.243966) (xy 315.516514 -318.287654)
			(xy 315.517022 -318.288162) (xy 315.522356 -318.292988) (xy 315.529596 -318.299227) (xy 315.547352 -318.306256)
			(xy 315.5569 -318.306704) (xy 316.666118 -318.306704)
		)
		(stroke
			(width 0)
			(type solid)
		)
		(fill yes)
		(layer "In7.Cu")
		(net "P0V8_PEX2")
	)
)
